(kicad_pcb
	(version 20260206)
	(generator "pcbnew")
	(generator_version "10.0")
	(general
		(thickness 1.6)
		(legacy_teardrops no)
	)
	(paper "A4")
	(layers
		(0 "F.Cu" signal "TOP")
		(4 "In1.Cu" signal "GND")
		(6 "In2.Cu" signal "VCC")
		(8 "In3.Cu" signal "VCC1")
		(10 "In4.Cu" signal "GND1")
		(12 "In5.Cu" signal "IN1")
		(14 "In6.Cu" signal "GND2")
		(16 "In7.Cu" signal "IN2")
		(18 "In8.Cu" signal "GND3")
		(20 "In9.Cu" signal "IN3")
		(22 "In10.Cu" signal "GND4")
		(24 "In11.Cu" signal "IN4")
		(26 "In12.Cu" signal "GND5")
		(28 "In13.Cu" signal "IN5")
		(30 "In14.Cu" signal "GND6")
		(32 "In15.Cu" signal "IN6")
		(34 "In16.Cu" signal "GND7")
		(2 "B.Cu" signal "BOTTOM")
		(9 "F.Adhes" user "F.Adhesive")
		(11 "B.Adhes" user "B.Adhesive")
		(13 "F.Paste" user "Package Geometry/Pastemask Top")
		(15 "B.Paste" user "Package Geometry/Pastemask Bottom")
		(5 "F.SilkS" user "Ref Des/Silkscreen Top")
		(7 "B.SilkS" user "Ref Des/Silkscreen Bottom")
		(1 "F.Mask" user "Board Geometry/Soldermask Top")
		(3 "B.Mask" user "Board Geometry/Soldermask Bottom")
		(17 "Dwgs.User" user "User.Drawings")
		(19 "Cmts.User" user "User.Comments")
		(21 "Eco1.User" user "User.Eco1")
		(23 "Eco2.User" user "User.Eco2")
		(25 "Edge.Cuts" user "Board Geometry/Outline")
		(27 "Margin" user)
		(31 "F.CrtYd" user "Package Geometry/Place Bound Top")
		(29 "B.CrtYd" user "Package Geometry/Place Bound Bottom")
		(35 "F.Fab" user "Ref Des/Assembly Top")
		(33 "B.Fab" user "Ref Des/Assembly Bottom")
	)
	(setup
		(pad_to_mask_clearance 0)
		(allow_soldermask_bridges_in_footprints no)
		(tenting
			(front yes)
			(back yes)
		)
		(covering
			(front no)
			(back no)
		)
		(plugging
			(front no)
			(back no)
		)
		(capping no)
		(filling no)
		(pcbplotparams
			(layerselection 0x00000000_00000000_55555555_5755f5ff)
			(plot_on_all_layers_selection 0x00000000_00000000_00000000_00000000)
			(disableapertmacros no)
			(usegerberextensions no)
			(usegerberattributes yes)
			(usegerberadvancedattributes yes)
			(creategerberjobfile yes)
			(dashed_line_dash_ratio 12)
			(dashed_line_gap_ratio 3)
			(svgprecision 4)
			(plotframeref no)
			(mode 1)
			(useauxorigin no)
			(pdf_front_fp_property_popups yes)
			(pdf_back_fp_property_popups yes)
			(pdf_metadata yes)
			(pdf_single_document no)
			(dxfpolygonmode yes)
			(dxfimperialunits yes)
			(dxfusepcbnewfont yes)
			(psnegative no)
			(psa4output no)
			(plot_black_and_white yes)
			(sketchpadsonfab no)
			(plotpadnumbers no)
			(hidednponfab no)
			(sketchdnponfab yes)
			(crossoutdnponfab yes)
			(subtractmaskfromsilk no)
			(outputformat 1)
			(mirror no)
			(drillshape 1)
			(scaleselection 1)
			(outputdirectory "")
		)
	)
	(footprint ""
		(layer "B.Cu")
		(at 278.064214 -145.284952 180)
		(property "Reference" "C911"
			(at 0 0 0)
			(layer "B.SilkS")
			(hide yes)
			(effects
				(font
					(size 1.27 1.27)
				)
				(justify mirror)
			)
		)
		(property "Value" ""
			(at 0 0 0)
			(layer "B.Fab")
			(effects
				(font
					(size 1.27 1.27)
				)
				(justify mirror)
			)
		)
		(duplicate_pad_numbers_are_jumpers no)
		(fp_line
			(start 0.299974 0.150114)
			(end 0.299974 -0.150114)
			(stroke
				(width 0.1)
				(type default)
			)
			(layer "B.Fab")
		)
		(fp_line
			(start 0.299974 -0.150114)
			(end -0.299974 -0.150114)
			(stroke
				(width 0.1)
				(type default)
			)
			(layer "B.Fab")
		)
		(fp_line
			(start -0.299974 0.150114)
			(end 0.299974 0.150114)
			(stroke
				(width 0.1)
				(type default)
			)
			(layer "B.Fab")
		)
		(fp_line
			(start -0.299974 -0.150114)
			(end -0.299974 0.150114)
			(stroke
				(width 0.1)
				(type default)
			)
			(layer "B.Fab")
		)
		(pad "1" smd rect
			(at 0.2667 0)
			(size 0.3048 0.381)
			(layers "B.Cu" "B.Mask" "B.Paste")
			(net "P12V_NIC4")
		)
		(pad "2" smd rect
			(at -0.2667 0)
			(size 0.3048 0.381)
			(layers "B.Cu" "B.Mask" "B.Paste")
			(net "GND")
		)
	)
	(footprint ""
		(layer "B.Cu")
		(at 46.355 -297.32478)
		(property "Reference" "C3028"
			(at 0 0 0)
			(layer "B.SilkS")
			(hide yes)
			(effects
				(font
					(size 1.27 1.27)
				)
				(justify mirror)
			)
		)
		(property "Value" ""
			(at 0 0 0)
			(layer "B.Fab")
			(effects
				(font
					(size 1.27 1.27)
				)
				(justify mirror)
			)
		)
		(duplicate_pad_numbers_are_jumpers no)
		(fp_line
			(start -0.299974 -0.150114)
			(end -0.299974 0.150114)
			(stroke
				(width 0.1)
				(type default)
			)
			(layer "B.Fab")
		)
		(fp_line
			(start -0.299974 0.150114)
			(end 0.299974 0.150114)
			(stroke
				(width 0.1)
				(type default)
			)
			(layer "B.Fab")
		)
		(fp_line
			(start 0.299974 -0.150114)
			(end -0.299974 -0.150114)
			(stroke
				(width 0.1)
				(type default)
			)
			(layer "B.Fab")
		)
		(fp_line
			(start 0.299974 0.150114)
			(end 0.299974 -0.150114)
			(stroke
				(width 0.1)
				(type default)
			)
			(layer "B.Fab")
		)
		(pad "1" smd rect
			(at 0.2667 0 180)
			(size 0.3048 0.381)
			(layers "B.Cu" "B.Mask" "B.Paste")
			(net "PCEPLL2_VDDA18_PEX0")
		)
		(pad "2" smd rect
			(at -0.2667 0 180)
			(size 0.3048 0.381)
			(layers "B.Cu" "B.Mask" "B.Paste")
			(net "GND")
		)
	)
	(footprint ""
		(layer "B.Cu")
		(at 234.13466 -207.02016 -90)
		(property "Reference" "R4860"
			(at 0 0 90)
			(layer "B.SilkS")
			(hide yes)
			(effects
				(font
					(size 1.27 1.27)
				)
				(justify mirror)
			)
		)
		(property "Value" ""
			(at 0 0 90)
			(layer "B.Fab")
			(effects
				(font
					(size 1.27 1.27)
				)
				(justify mirror)
			)
		)
		(duplicate_pad_numbers_are_jumpers no)
		(fp_line
			(start -0.7874 0.4064)
			(end 0.7874 0.4064)
			(stroke
				(width 0.1524)
				(type default)
			)
			(layer "B.SilkS")
		)
		(fp_line
			(start 0.7874 0.4064)
			(end 0.7874 -0.4064)
			(stroke
				(width 0.1524)
				(type default)
			)
			(layer "B.SilkS")
		)
		(fp_line
			(start -0.7874 -0.4064)
			(end -0.7874 0.4064)
			(stroke
				(width 0.1524)
				(type default)
			)
			(layer "B.SilkS")
		)
		(fp_line
			(start 0.7874 -0.4064)
			(end -0.7874 -0.4064)
			(stroke
				(width 0.1524)
				(type default)
			)
			(layer "B.SilkS")
		)
		(fp_line
			(start -0.67945 0.3048)
			(end -0.120396 0.3048)
			(stroke
				(width 0.1)
				(type default)
			)
			(layer "B.Fab")
		)
		(fp_line
			(start -0.120396 0.3048)
			(end -0.120396 0.2794)
			(stroke
				(width 0.1)
				(type default)
			)
			(layer "B.Fab")
		)
		(fp_line
			(start 0.12065 0.3048)
			(end 0.67945 0.3048)
			(stroke
				(width 0.1)
				(type default)
			)
			(layer "B.Fab")
		)
		(fp_line
			(start 0.67945 0.3048)
			(end 0.67945 -0.305054)
			(stroke
				(width 0.1)
				(type default)
			)
			(layer "B.Fab")
		)
		(fp_line
			(start -0.120396 0.2794)
			(end 0.12065 0.2794)
			(stroke
				(width 0.1)
				(type default)
			)
			(layer "B.Fab")
		)
		(fp_line
			(start 0.12065 0.2794)
			(end 0.12065 0.3048)
			(stroke
				(width 0.1)
				(type default)
			)
			(layer "B.Fab")
		)
		(fp_line
			(start -0.12065 -0.2794)
			(end -0.12065 -0.3048)
			(stroke
				(width 0.1)
				(type default)
			)
			(layer "B.Fab")
		)
		(fp_line
			(start 0.12065 -0.2794)
			(end -0.12065 -0.2794)
			(stroke
				(width 0.1)
				(type default)
			)
			(layer "B.Fab")
		)
		(fp_line
			(start -0.67945 -0.3048)
			(end -0.67945 0.3048)
			(stroke
				(width 0.1)
				(type default)
			)
			(layer "B.Fab")
		)
		(fp_line
			(start -0.12065 -0.3048)
			(end -0.67945 -0.3048)
			(stroke
				(width 0.1)
				(type default)
			)
			(layer "B.Fab")
		)
		(fp_line
			(start 0.12065 -0.305054)
			(end 0.12065 -0.2794)
			(stroke
				(width 0.1)
				(type default)
			)
			(layer "B.Fab")
		)
		(fp_line
			(start 0.67945 -0.305054)
			(end 0.12065 -0.305054)
			(stroke
				(width 0.1)
				(type default)
			)
			(layer "B.Fab")
		)
		(pad "1" smd circle
			(at 0.40005 0 90)
			(size 0 0)
			(layers "B.Cu" "B.Mask" "B.Paste")
			(net "CLK_25M_BIC")
		)
		(pad "2" smd circle
			(at -0.40005 0 90)
			(size 0 0)
			(layers "B.Cu" "B.Mask" "B.Paste")
			(net "CLK_25M_BIC_CLKIN")
		)
	)
	(footprint ""
		(layer "B.Cu")
		(at 67.249802 -290.199826 90)
		(property "Reference" "C1169"
			(at 0 0 90)
			(layer "B.SilkS")
			(hide yes)
			(effects
				(font
					(size 1.27 1.27)
				)
				(justify mirror)
			)
		)
		(property "Value" ""
			(at 0 0 90)
			(layer "B.Fab")
			(effects
				(font
					(size 1.27 1.27)
				)
				(justify mirror)
			)
		)
		(duplicate_pad_numbers_are_jumpers no)
		(fp_line
			(start 0.299974 -0.150114)
			(end -0.299974 -0.150114)
			(stroke
				(width 0.1)
				(type default)
			)
			(layer "B.Fab")
		)
		(fp_line
			(start -0.299974 -0.150114)
			(end -0.299974 0.150114)
			(stroke
				(width 0.1)
				(type default)
			)
			(layer "B.Fab")
		)
		(fp_line
			(start 0.299974 0.150114)
			(end 0.299974 -0.150114)
			(stroke
				(width 0.1)
				(type default)
			)
			(layer "B.Fab")
		)
		(fp_line
			(start -0.299974 0.150114)
			(end 0.299974 0.150114)
			(stroke
				(width 0.1)
				(type default)
			)
			(layer "B.Fab")
		)
		(pad "1" smd rect
			(at 0.2667 0 270)
			(size 0.3048 0.381)
			(layers "B.Cu" "B.Mask" "B.Paste")
			(net "P0V8_SERDES_VDDA_PEX0")
		)
		(pad "2" smd rect
			(at -0.2667 0 270)
			(size 0.3048 0.381)
			(layers "B.Cu" "B.Mask" "B.Paste")
			(net "GND")
		)
	)
	(footprint ""
		(layer "B.Cu")
		(at 307.923692 -289.724846 90)
		(property "Reference" "R965"
			(at 0 0 90)
			(layer "B.SilkS")
			(hide yes)
			(effects
				(font
					(size 1.27 1.27)
				)
				(justify mirror)
			)
		)
		(property "Value" ""
			(at 0 0 90)
			(layer "B.Fab")
			(effects
				(font
					(size 1.27 1.27)
				)
				(justify mirror)
			)
		)
		(duplicate_pad_numbers_are_jumpers no)
		(fp_line
			(start 0.7874 -0.4064)
			(end -0.7874 -0.4064)
			(stroke
				(width 0.1524)
				(type default)
			)
			(layer "B.SilkS")
		)
		(fp_line
			(start -0.7874 -0.4064)
			(end -0.7874 0.4064)
			(stroke
				(width 0.1524)
				(type default)
			)
			(layer "B.SilkS")
		)
		(fp_line
			(start 0.7874 0.4064)
			(end 0.7874 -0.4064)
			(stroke
				(width 0.1524)
				(type default)
			)
			(layer "B.SilkS")
		)
		(fp_line
			(start -0.7874 0.4064)
			(end 0.7874 0.4064)
			(stroke
				(width 0.1524)
				(type default)
			)
			(layer "B.SilkS")
		)
		(fp_line
			(start 0.67945 -0.305054)
			(end 0.12065 -0.305054)
			(stroke
				(width 0.1)
				(type default)
			)
			(layer "B.Fab")
		)
		(fp_line
			(start 0.12065 -0.305054)
			(end 0.12065 -0.2794)
			(stroke
				(width 0.1)
				(type default)
			)
			(layer "B.Fab")
		)
		(fp_line
			(start -0.12065 -0.3048)
			(end -0.67945 -0.3048)
			(stroke
				(width 0.1)
				(type default)
			)
			(layer "B.Fab")
		)
		(fp_line
			(start -0.67945 -0.3048)
			(end -0.67945 0.3048)
			(stroke
				(width 0.1)
				(type default)
			)
			(layer "B.Fab")
		)
		(fp_line
			(start 0.12065 -0.2794)
			(end -0.12065 -0.2794)
			(stroke
				(width 0.1)
				(type default)
			)
			(layer "B.Fab")
		)
		(fp_line
			(start -0.12065 -0.2794)
			(end -0.12065 -0.3048)
			(stroke
				(width 0.1)
				(type default)
			)
			(layer "B.Fab")
		)
		(fp_line
			(start 0.12065 0.2794)
			(end 0.12065 0.3048)
			(stroke
				(width 0.1)
				(type default)
			)
			(layer "B.Fab")
		)
		(fp_line
			(start -0.120396 0.2794)
			(end 0.12065 0.2794)
			(stroke
				(width 0.1)
				(type default)
			)
			(layer "B.Fab")
		)
		(fp_line
			(start 0.67945 0.3048)
			(end 0.67945 -0.305054)
			(stroke
				(width 0.1)
				(type default)
			)
			(layer "B.Fab")
		)
		(fp_line
			(start 0.12065 0.3048)
			(end 0.67945 0.3048)
			(stroke
				(width 0.1)
				(type default)
			)
			(layer "B.Fab")
		)
		(fp_line
			(start -0.120396 0.3048)
			(end -0.120396 0.2794)
			(stroke
				(width 0.1)
				(type default)
			)
			(layer "B.Fab")
		)
		(fp_line
			(start -0.67945 0.3048)
			(end -0.120396 0.3048)
			(stroke
				(width 0.1)
				(type default)
			)
			(layer "B.Fab")
		)
		(pad "1" smd circle
			(at 0.40005 0 270)
			(size 0 0)
			(layers "B.Cu" "B.Mask" "B.Paste")
			(net "UART_PEX2_SDB_TX")
		)
		(pad "2" smd circle
			(at -0.40005 0 270)
			(size 0 0)
			(layers "B.Cu" "B.Mask" "B.Paste")
			(net "UART_PEX2_SDB_R_TX")
		)
	)
	(footprint ""
		(layer "B.Cu")
		(at 113.121186 -284.796738 -90)
		(property "Reference" "PC60"
			(at 0 0 90)
			(layer "B.SilkS")
			(hide yes)
			(effects
				(font
					(size 1.27 1.27)
				)
				(justify mirror)
			)
		)
		(property "Value" ""
			(at 0 0 90)
			(layer "B.Fab")
			(effects
				(font
					(size 1.27 1.27)
				)
				(justify mirror)
			)
		)
		(duplicate_pad_numbers_are_jumpers no)
		(fp_line
			(start -1.524 0.762)
			(end 1.524 0.762)
			(stroke
				(width 0.1524)
				(type default)
			)
			(layer "B.SilkS")
		)
		(fp_line
			(start 1.524 0.762)
			(end 1.524 -0.762)
			(stroke
				(width 0.1524)
				(type default)
			)
			(layer "B.SilkS")
		)
		(fp_line
			(start -1.524 -0.762)
			(end -1.524 0.762)
			(stroke
				(width 0.1524)
				(type default)
			)
			(layer "B.SilkS")
		)
		(fp_line
			(start 1.524 -0.762)
			(end -1.524 -0.762)
			(stroke
				(width 0.1524)
				(type default)
			)
			(layer "B.SilkS")
		)
		(fp_line
			(start -1.1049 0.724916)
			(end -1.1049 -0.724916)
			(stroke
				(width 0.1)
				(type default)
			)
			(layer "B.Fab")
		)
		(fp_line
			(start 1.1049 0.724916)
			(end -1.1049 0.724916)
			(stroke
				(width 0.1)
				(type default)
			)
			(layer "B.Fab")
		)
		(fp_line
			(start -1.1049 -0.724916)
			(end 1.1049 -0.724916)
			(stroke
				(width 0.1)
				(type default)
			)
			(layer "B.Fab")
		)
		(fp_line
			(start 1.1049 -0.724916)
			(end 1.1049 0.724916)
			(stroke
				(width 0.1)
				(type default)
			)
			(layer "B.Fab")
		)
		(pad "1" smd rect
			(at 0.889 0 270)
			(size 1.016 1.27)
			(layers "B.Cu" "B.Mask" "B.Paste")
			(net "SW_P12V_P0V8_PEX0_FLT")
		)
		(pad "2" smd rect
			(at -0.889 0 270)
			(size 1.016 1.27)
			(layers "B.Cu" "B.Mask" "B.Paste")
			(net "GND")
		)
	)
	(footprint ""
		(layer "B.Cu")
		(at 105.380536 -392.988292)
		(property "Reference" "C3634"
			(at 0 0 0)
			(layer "B.SilkS")
			(hide yes)
			(effects
				(font
					(size 1.27 1.27)
				)
				(justify mirror)
			)
		)
		(property "Value" ""
			(at 0 0 0)
			(layer "B.Fab")
			(effects
				(font
					(size 1.27 1.27)
				)
				(justify mirror)
			)
		)
		(duplicate_pad_numbers_are_jumpers no)
		(fp_line
			(start -0.7874 -0.4064)
			(end -0.7874 0.4064)
			(stroke
				(width 0.1524)
				(type default)
			)
			(layer "B.SilkS")
		)
		(fp_line
			(start -0.7874 0.4064)
			(end 0.7874 0.4064)
			(stroke
				(width 0.1524)
				(type default)
			)
			(layer "B.SilkS")
		)
		(fp_line
			(start 0.7874 -0.4064)
			(end -0.7874 -0.4064)
			(stroke
				(width 0.1524)
				(type default)
			)
			(layer "B.SilkS")
		)
		(fp_line
			(start 0.7874 0.4064)
			(end 0.7874 -0.4064)
			(stroke
				(width 0.1524)
				(type default)
			)
			(layer "B.SilkS")
		)
		(fp_line
			(start -0.67945 -0.3048)
			(end -0.67945 0.3048)
			(stroke
				(width 0.1)
				(type default)
			)
			(layer "B.Fab")
		)
		(fp_line
			(start -0.67945 0.3048)
			(end -0.120396 0.3048)
			(stroke
				(width 0.1)
				(type default)
			)
			(layer "B.Fab")
		)
		(fp_line
			(start -0.12065 -0.3048)
			(end -0.67945 -0.3048)
			(stroke
				(width 0.1)
				(type default)
			)
			(layer "B.Fab")
		)
		(fp_line
			(start -0.12065 -0.2794)
			(end -0.12065 -0.3048)
			(stroke
				(width 0.1)
				(type default)
			)
			(layer "B.Fab")
		)
		(fp_line
			(start -0.120396 0.2794)
			(end 0.12065 0.2794)
			(stroke
				(width 0.1)
				(type default)
			)
			(layer "B.Fab")
		)
		(fp_line
			(start -0.120396 0.3048)
			(end -0.120396 0.2794)
			(stroke
				(width 0.1)
				(type default)
			)
			(layer "B.Fab")
		)
		(fp_line
			(start 0.12065 -0.305054)
			(end 0.12065 -0.2794)
			(stroke
				(width 0.1)
				(type default)
			)
			(layer "B.Fab")
		)
		(fp_line
			(start 0.12065 -0.2794)
			(end -0.12065 -0.2794)
			(stroke
				(width 0.1)
				(type default)
			)
			(layer "B.Fab")
		)
		(fp_line
			(start 0.12065 0.2794)
			(end 0.12065 0.3048)
			(stroke
				(width 0.1)
				(type default)
			)
			(layer "B.Fab")
		)
		(fp_line
			(start 0.12065 0.3048)
			(end 0.67945 0.3048)
			(stroke
				(width 0.1)
				(type default)
			)
			(layer "B.Fab")
		)
		(fp_line
			(start 0.67945 -0.305054)
			(end 0.12065 -0.305054)
			(stroke
				(width 0.1)
				(type default)
			)
			(layer "B.Fab")
		)
		(fp_line
			(start 0.67945 0.3048)
			(end 0.67945 -0.305054)
			(stroke
				(width 0.1)
				(type default)
			)
			(layer "B.Fab")
		)
		(pad "1" smd circle
			(at 0.40005 0 180)
			(size 0 0)
			(layers "B.Cu" "B.Mask" "B.Paste")
			(net "P3V3_BIC_USB_HUB")
		)
		(pad "2" smd circle
			(at -0.40005 0 180)
			(size 0 0)
			(layers "B.Cu" "B.Mask" "B.Paste")
			(net "GND")
		)
	)
	(footprint ""
		(layer "B.Cu")
		(at 232.083864 -204.44206 -90)
		(property "Reference" "R5526"
			(at 0 0 90)
			(layer "B.SilkS")
			(hide yes)
			(effects
				(font
					(size 1.27 1.27)
				)
				(justify mirror)
			)
		)
		(property "Value" ""
			(at 0 0 90)
			(layer "B.Fab")
			(effects
				(font
					(size 1.27 1.27)
				)
				(justify mirror)
			)
		)
		(duplicate_pad_numbers_are_jumpers no)
		(fp_line
			(start -0.7874 0.4064)
			(end 0.7874 0.4064)
			(stroke
				(width 0.1524)
				(type default)
			)
			(layer "B.SilkS")
		)
		(fp_line
			(start 0.7874 0.4064)
			(end 0.7874 -0.4064)
			(stroke
				(width 0.1524)
				(type default)
			)
			(layer "B.SilkS")
		)
		(fp_line
			(start -0.7874 -0.4064)
			(end -0.7874 0.4064)
			(stroke
				(width 0.1524)
				(type default)
			)
			(layer "B.SilkS")
		)
		(fp_line
			(start 0.7874 -0.4064)
			(end -0.7874 -0.4064)
			(stroke
				(width 0.1524)
				(type default)
			)
			(layer "B.SilkS")
		)
		(fp_line
			(start -0.67945 0.3048)
			(end -0.120396 0.3048)
			(stroke
				(width 0.1)
				(type default)
			)
			(layer "B.Fab")
		)
		(fp_line
			(start -0.120396 0.3048)
			(end -0.120396 0.2794)
			(stroke
				(width 0.1)
				(type default)
			)
			(layer "B.Fab")
		)
		(fp_line
			(start 0.12065 0.3048)
			(end 0.67945 0.3048)
			(stroke
				(width 0.1)
				(type default)
			)
			(layer "B.Fab")
		)
		(fp_line
			(start 0.67945 0.3048)
			(end 0.67945 -0.305054)
			(stroke
				(width 0.1)
				(type default)
			)
			(layer "B.Fab")
		)
		(fp_line
			(start -0.120396 0.2794)
			(end 0.12065 0.2794)
			(stroke
				(width 0.1)
				(type default)
			)
			(layer "B.Fab")
		)
		(fp_line
			(start 0.12065 0.2794)
			(end 0.12065 0.3048)
			(stroke
				(width 0.1)
				(type default)
			)
			(layer "B.Fab")
		)
		(fp_line
			(start -0.12065 -0.2794)
			(end -0.12065 -0.3048)
			(stroke
				(width 0.1)
				(type default)
			)
			(layer "B.Fab")
		)
		(fp_line
			(start 0.12065 -0.2794)
			(end -0.12065 -0.2794)
			(stroke
				(width 0.1)
				(type default)
			)
			(layer "B.Fab")
		)
		(fp_line
			(start -0.67945 -0.3048)
			(end -0.67945 0.3048)
			(stroke
				(width 0.1)
				(type default)
			)
			(layer "B.Fab")
		)
		(fp_line
			(start -0.12065 -0.3048)
			(end -0.67945 -0.3048)
			(stroke
				(width 0.1)
				(type default)
			)
			(layer "B.Fab")
		)
		(fp_line
			(start 0.12065 -0.305054)
			(end 0.12065 -0.2794)
			(stroke
				(width 0.1)
				(type default)
			)
			(layer "B.Fab")
		)
		(fp_line
			(start 0.67945 -0.305054)
			(end 0.12065 -0.305054)
			(stroke
				(width 0.1)
				(type default)
			)
			(layer "B.Fab")
		)
		(pad "1" smd circle
			(at 0.40005 0 90)
			(size 0 0)
			(layers "B.Cu" "B.Mask" "B.Paste")
			(net "GND")
		)
		(pad "2" smd circle
			(at -0.40005 0 90)
			(size 0 0)
			(layers "B.Cu" "B.Mask" "B.Paste")
			(net "BIC_FWSPIMISO")
		)
	)
	(footprint ""
		(layer "B.Cu")
		(at 173.850046 -292.099746 90)
		(property "Reference" "C1488"
			(at 0 0 90)
			(layer "B.SilkS")
			(hide yes)
			(effects
				(font
					(size 1.27 1.27)
				)
				(justify mirror)
			)
		)
		(property "Value" ""
			(at 0 0 90)
			(layer "B.Fab")
			(effects
				(font
					(size 1.27 1.27)
				)
				(justify mirror)
			)
		)
		(duplicate_pad_numbers_are_jumpers no)
		(fp_line
			(start 0.299974 -0.150114)
			(end -0.299974 -0.150114)
			(stroke
				(width 0.1)
				(type default)
			)
			(layer "B.Fab")
		)
		(fp_line
			(start -0.299974 -0.150114)
			(end -0.299974 0.150114)
			(stroke
				(width 0.1)
				(type default)
			)
			(layer "B.Fab")
		)
		(fp_line
			(start 0.299974 0.150114)
			(end 0.299974 -0.150114)
			(stroke
				(width 0.1)
				(type default)
			)
			(layer "B.Fab")
		)
		(fp_line
			(start -0.299974 0.150114)
			(end 0.299974 0.150114)
			(stroke
				(width 0.1)
				(type default)
			)
			(layer "B.Fab")
		)
		(pad "1" smd rect
			(at 0.2667 0 270)
			(size 0.3048 0.381)
			(layers "B.Cu" "B.Mask" "B.Paste")
			(net "P0V8_SERDES_VDDA_PEX1")
		)
		(pad "2" smd rect
			(at -0.2667 0 270)
			(size 0.3048 0.381)
			(layers "B.Cu" "B.Mask" "B.Paste")
			(net "GND")
		)
	)
	(footprint ""
		(layer "B.Cu")
		(at 419.349936 -294.4749 180)
		(property "Reference" "C3464"
			(at 0 0 0)
			(layer "B.SilkS")
			(hide yes)
			(effects
				(font
					(size 1.27 1.27)
				)
				(justify mirror)
			)
		)
		(property "Value" ""
			(at 0 0 0)
			(layer "B.Fab")
			(effects
				(font
					(size 1.27 1.27)
				)
				(justify mirror)
			)
		)
		(duplicate_pad_numbers_are_jumpers no)
		(fp_line
			(start 0.299974 0.150114)
			(end 0.299974 -0.150114)
			(stroke
				(width 0.1)
				(type default)
			)
			(layer "B.Fab")
		)
		(fp_line
			(start 0.299974 -0.150114)
			(end -0.299974 -0.150114)
			(stroke
				(width 0.1)
				(type default)
			)
			(layer "B.Fab")
		)
		(fp_line
			(start -0.299974 0.150114)
			(end 0.299974 0.150114)
			(stroke
				(width 0.1)
				(type default)
			)
			(layer "B.Fab")
		)
		(fp_line
			(start -0.299974 -0.150114)
			(end -0.299974 0.150114)
			(stroke
				(width 0.1)
				(type default)
			)
			(layer "B.Fab")
		)
		(pad "1" smd rect
			(at 0.2667 0)
			(size 0.3048 0.381)
			(layers "B.Cu" "B.Mask" "B.Paste")
			(net "P1V25_PEX3")
		)
		(pad "2" smd rect
			(at -0.2667 0)
			(size 0.3048 0.381)
			(layers "B.Cu" "B.Mask" "B.Paste")
			(net "GND")
		)
	)
	(footprint ""
		(layer "B.Cu")
		(at 411.750002 -290.199826 90)
		(property "Reference" "C1966"
			(at 0 0 90)
			(layer "B.SilkS")
			(hide yes)
			(effects
				(font
					(size 1.27 1.27)
				)
				(justify mirror)
			)
		)
		(property "Value" ""
			(at 0 0 90)
			(layer "B.Fab")
			(effects
				(font
					(size 1.27 1.27)
				)
				(justify mirror)
			)
		)
		(duplicate_pad_numbers_are_jumpers no)
		(fp_line
			(start 0.299974 -0.150114)
			(end -0.299974 -0.150114)
			(stroke
				(width 0.1)
				(type default)
			)
			(layer "B.Fab")
		)
		(fp_line
			(start -0.299974 -0.150114)
			(end -0.299974 0.150114)
			(stroke
				(width 0.1)
				(type default)
			)
			(layer "B.Fab")
		)
		(fp_line
			(start 0.299974 0.150114)
			(end 0.299974 -0.150114)
			(stroke
				(width 0.1)
				(type default)
			)
			(layer "B.Fab")
		)
		(fp_line
			(start -0.299974 0.150114)
			(end 0.299974 0.150114)
			(stroke
				(width 0.1)
				(type default)
			)
			(layer "B.Fab")
		)
		(pad "1" smd rect
			(at 0.2667 0 270)
			(size 0.3048 0.381)
			(layers "B.Cu" "B.Mask" "B.Paste")
			(net "P0V8_SERDES_VDDA_PEX3")
		)
		(pad "2" smd rect
			(at -0.2667 0 270)
			(size 0.3048 0.381)
			(layers "B.Cu" "B.Mask" "B.Paste")
			(net "GND")
		)
	)
	(footprint ""
		(layer "B.Cu")
		(at 177.174906 -305.399948 -90)
		(property "Reference" "C3143"
			(at 0 0 90)
			(layer "B.SilkS")
			(hide yes)
			(effects
				(font
					(size 1.27 1.27)
				)
				(justify mirror)
			)
		)
		(property "Value" ""
			(at 0 0 90)
			(layer "B.Fab")
			(effects
				(font
					(size 1.27 1.27)
				)
				(justify mirror)
			)
		)
		(duplicate_pad_numbers_are_jumpers no)
		(fp_line
			(start -0.299974 0.150114)
			(end 0.299974 0.150114)
			(stroke
				(width 0.1)
				(type default)
			)
			(layer "B.Fab")
		)
		(fp_line
			(start 0.299974 0.150114)
			(end 0.299974 -0.150114)
			(stroke
				(width 0.1)
				(type default)
			)
			(layer "B.Fab")
		)
		(fp_line
			(start -0.299974 -0.150114)
			(end -0.299974 0.150114)
			(stroke
				(width 0.1)
				(type default)
			)
			(layer "B.Fab")
		)
		(fp_line
			(start 0.299974 -0.150114)
			(end -0.299974 -0.150114)
			(stroke
				(width 0.1)
				(type default)
			)
			(layer "B.Fab")
		)
		(pad "1" smd rect
			(at 0.2667 0 90)
			(size 0.3048 0.381)
			(layers "B.Cu" "B.Mask" "B.Paste")
			(net "P1V25_SERDES_VDDPLL_PEX1")
		)
		(pad "2" smd rect
			(at -0.2667 0 90)
			(size 0.3048 0.381)
			(layers "B.Cu" "B.Mask" "B.Paste")
			(net "GND")
		)
	)
	(footprint ""
		(layer "B.Cu")
		(at 293.74973 -301.599854 -90)
		(property "Reference" "C1735"
			(at 0 0 90)
			(layer "B.SilkS")
			(hide yes)
			(effects
				(font
					(size 1.27 1.27)
				)
				(justify mirror)
			)
		)
		(property "Value" ""
			(at 0 0 90)
			(layer "B.Fab")
			(effects
				(font
					(size 1.27 1.27)
				)
				(justify mirror)
			)
		)
		(duplicate_pad_numbers_are_jumpers no)
		(fp_line
			(start -0.299974 0.150114)
			(end 0.299974 0.150114)
			(stroke
				(width 0.1)
				(type default)
			)
			(layer "B.Fab")
		)
		(fp_line
			(start 0.299974 0.150114)
			(end 0.299974 -0.150114)
			(stroke
				(width 0.1)
				(type default)
			)
			(layer "B.Fab")
		)
		(fp_line
			(start -0.299974 -0.150114)
			(end -0.299974 0.150114)
			(stroke
				(width 0.1)
				(type default)
			)
			(layer "B.Fab")
		)
		(fp_line
			(start 0.299974 -0.150114)
			(end -0.299974 -0.150114)
			(stroke
				(width 0.1)
				(type default)
			)
			(layer "B.Fab")
		)
		(pad "1" smd rect
			(at 0.2667 0 90)
			(size 0.3048 0.381)
			(layers "B.Cu" "B.Mask" "B.Paste")
			(net "P0V8_SERDES_VDDA_PEX2")
		)
		(pad "2" smd rect
			(at -0.2667 0 90)
			(size 0.3048 0.381)
			(layers "B.Cu" "B.Mask" "B.Paste")
			(net "GND")
		)
	)
	(footprint ""
		(layer "B.Cu")
		(at 413.649922 -301.599854 -90)
		(property "Reference" "C1946"
			(at 0 0 90)
			(layer "B.SilkS")
			(hide yes)
			(effects
				(font
					(size 1.27 1.27)
				)
				(justify mirror)
			)
		)
		(property "Value" ""
			(at 0 0 90)
			(layer "B.Fab")
			(effects
				(font
					(size 1.27 1.27)
				)
				(justify mirror)
			)
		)
		(duplicate_pad_numbers_are_jumpers no)
		(fp_line
			(start -0.299974 0.150114)
			(end 0.299974 0.150114)
			(stroke
				(width 0.1)
				(type default)
			)
			(layer "B.Fab")
		)
		(fp_line
			(start 0.299974 0.150114)
			(end 0.299974 -0.150114)
			(stroke
				(width 0.1)
				(type default)
			)
			(layer "B.Fab")
		)
		(fp_line
			(start -0.299974 -0.150114)
			(end -0.299974 0.150114)
			(stroke
				(width 0.1)
				(type default)
			)
			(layer "B.Fab")
		)
		(fp_line
			(start 0.299974 -0.150114)
			(end -0.299974 -0.150114)
			(stroke
				(width 0.1)
				(type default)
			)
			(layer "B.Fab")
		)
		(pad "1" smd rect
			(at 0.2667 0 90)
			(size 0.3048 0.381)
			(layers "B.Cu" "B.Mask" "B.Paste")
			(net "P0V8_SERDES_VDDA_PEX3")
		)
		(pad "2" smd rect
			(at -0.2667 0 90)
			(size 0.3048 0.381)
			(layers "B.Cu" "B.Mask" "B.Paste")
			(net "GND")
		)
	)
	(footprint ""
		(layer "B.Cu")
		(at 63.449962 -303.499774 -90)
		(property "Reference" "C2910"
			(at 0 0 90)
			(layer "B.SilkS")
			(hide yes)
			(effects
				(font
					(size 1.27 1.27)
				)
				(justify mirror)
			)
		)
		(property "Value" ""
			(at 0 0 90)
			(layer "B.Fab")
			(effects
				(font
					(size 1.27 1.27)
				)
				(justify mirror)
			)
		)
		(duplicate_pad_numbers_are_jumpers no)
		(fp_line
			(start -0.299974 0.150114)
			(end 0.299974 0.150114)
			(stroke
				(width 0.1)
				(type default)
			)
			(layer "B.Fab")
		)
		(fp_line
			(start 0.299974 0.150114)
			(end 0.299974 -0.150114)
			(stroke
				(width 0.1)
				(type default)
			)
			(layer "B.Fab")
		)
		(fp_line
			(start -0.299974 -0.150114)
			(end -0.299974 0.150114)
			(stroke
				(width 0.1)
				(type default)
			)
			(layer "B.Fab")
		)
		(fp_line
			(start 0.299974 -0.150114)
			(end -0.299974 -0.150114)
			(stroke
				(width 0.1)
				(type default)
			)
			(layer "B.Fab")
		)
		(pad "1" smd rect
			(at 0.2667 0 90)
			(size 0.3048 0.381)
			(layers "B.Cu" "B.Mask" "B.Paste")
			(net "P1V25_PEX0")
		)
		(pad "2" smd rect
			(at -0.2667 0 90)
			(size 0.3048 0.381)
			(layers "B.Cu" "B.Mask" "B.Paste")
			(net "GND")
		)
	)
	(footprint ""
		(layer "B.Cu")
		(at 309.741824 -95.989648 180)
		(property "Reference" "R266"
			(at 0 0 0)
			(layer "B.SilkS")
			(hide yes)
			(effects
				(font
					(size 1.27 1.27)
				)
				(justify mirror)
			)
		)
		(property "Value" ""
			(at 0 0 0)
			(layer "B.Fab")
			(effects
				(font
					(size 1.27 1.27)
				)
				(justify mirror)
			)
		)
		(duplicate_pad_numbers_are_jumpers no)
		(fp_line
			(start 0.7874 0.4064)
			(end 0.7874 -0.4064)
			(stroke
				(width 0.1524)
				(type default)
			)
			(layer "B.SilkS")
		)
		(fp_line
			(start 0.7874 -0.4064)
			(end -0.7874 -0.4064)
			(stroke
				(width 0.1524)
				(type default)
			)
			(layer "B.SilkS")
		)
		(fp_line
			(start -0.7874 0.4064)
			(end 0.7874 0.4064)
			(stroke
				(width 0.1524)
				(type default)
			)
			(layer "B.SilkS")
		)
		(fp_line
			(start -0.7874 -0.4064)
			(end -0.7874 0.4064)
			(stroke
				(width 0.1524)
				(type default)
			)
			(layer "B.SilkS")
		)
		(fp_line
			(start 0.67945 0.3048)
			(end 0.67945 -0.305054)
			(stroke
				(width 0.1)
				(type default)
			)
			(layer "B.Fab")
		)
		(fp_line
			(start 0.67945 -0.305054)
			(end 0.12065 -0.305054)
			(stroke
				(width 0.1)
				(type default)
			)
			(layer "B.Fab")
		)
		(fp_line
			(start 0.12065 0.3048)
			(end 0.67945 0.3048)
			(stroke
				(width 0.1)
				(type default)
			)
			(layer "B.Fab")
		)
		(fp_line
			(start 0.12065 0.2794)
			(end 0.12065 0.3048)
			(stroke
				(width 0.1)
				(type default)
			)
			(layer "B.Fab")
		)
		(fp_line
			(start 0.12065 -0.2794)
			(end -0.12065 -0.2794)
			(stroke
				(width 0.1)
				(type default)
			)
			(layer "B.Fab")
		)
		(fp_line
			(start 0.12065 -0.305054)
			(end 0.12065 -0.2794)
			(stroke
				(width 0.1)
				(type default)
			)
			(layer "B.Fab")
		)
		(fp_line
			(start -0.120396 0.3048)
			(end -0.120396 0.2794)
			(stroke
				(width 0.1)
				(type default)
			)
			(layer "B.Fab")
		)
		(fp_line
			(start -0.120396 0.2794)
			(end 0.12065 0.2794)
			(stroke
				(width 0.1)
				(type default)
			)
			(layer "B.Fab")
		)
		(fp_line
			(start -0.12065 -0.2794)
			(end -0.12065 -0.3048)
			(stroke
				(width 0.1)
				(type default)
			)
			(layer "B.Fab")
		)
		(fp_line
			(start -0.12065 -0.3048)
			(end -0.67945 -0.3048)
			(stroke
				(width 0.1)
				(type default)
			)
			(layer "B.Fab")
		)
		(fp_line
			(start -0.67945 0.3048)
			(end -0.120396 0.3048)
			(stroke
				(width 0.1)
				(type default)
			)
			(layer "B.Fab")
		)
		(fp_line
			(start -0.67945 -0.3048)
			(end -0.67945 0.3048)
			(stroke
				(width 0.1)
				(type default)
			)
			(layer "B.Fab")
		)
		(pad "1" smd circle
			(at 0.40005 0)
			(size 0 0)
			(layers "B.Cu" "B.Mask" "B.Paste")
			(net "NIC5_LD_N")
		)
		(pad "2" smd circle
			(at -0.40005 0)
			(size 0 0)
			(layers "B.Cu" "B.Mask" "B.Paste")
			(net "P3V3_NIC5")
		)
	)
	(footprint ""
		(layer "B.Cu")
		(at 307.923692 -291.624766 90)
		(property "Reference" "R996"
			(at 0 0 90)
			(layer "B.SilkS")
			(hide yes)
			(effects
				(font
					(size 1.27 1.27)
				)
				(justify mirror)
			)
		)
		(property "Value" ""
			(at 0 0 90)
			(layer "B.Fab")
			(effects
				(font
					(size 1.27 1.27)
				)
				(justify mirror)
			)
		)
		(duplicate_pad_numbers_are_jumpers no)
		(fp_line
			(start 0.7874 -0.4064)
			(end -0.7874 -0.4064)
			(stroke
				(width 0.1524)
				(type default)
			)
			(layer "B.SilkS")
		)
		(fp_line
			(start -0.7874 -0.4064)
			(end -0.7874 0.4064)
			(stroke
				(width 0.1524)
				(type default)
			)
			(layer "B.SilkS")
		)
		(fp_line
			(start 0.7874 0.4064)
			(end 0.7874 -0.4064)
			(stroke
				(width 0.1524)
				(type default)
			)
			(layer "B.SilkS")
		)
		(fp_line
			(start -0.7874 0.4064)
			(end 0.7874 0.4064)
			(stroke
				(width 0.1524)
				(type default)
			)
			(layer "B.SilkS")
		)
		(fp_line
			(start 0.67945 -0.305054)
			(end 0.12065 -0.305054)
			(stroke
				(width 0.1)
				(type default)
			)
			(layer "B.Fab")
		)
		(fp_line
			(start 0.12065 -0.305054)
			(end 0.12065 -0.2794)
			(stroke
				(width 0.1)
				(type default)
			)
			(layer "B.Fab")
		)
		(fp_line
			(start -0.12065 -0.3048)
			(end -0.67945 -0.3048)
			(stroke
				(width 0.1)
				(type default)
			)
			(layer "B.Fab")
		)
		(fp_line
			(start -0.67945 -0.3048)
			(end -0.67945 0.3048)
			(stroke
				(width 0.1)
				(type default)
			)
			(layer "B.Fab")
		)
		(fp_line
			(start 0.12065 -0.2794)
			(end -0.12065 -0.2794)
			(stroke
				(width 0.1)
				(type default)
			)
			(layer "B.Fab")
		)
		(fp_line
			(start -0.12065 -0.2794)
			(end -0.12065 -0.3048)
			(stroke
				(width 0.1)
				(type default)
			)
			(layer "B.Fab")
		)
		(fp_line
			(start 0.12065 0.2794)
			(end 0.12065 0.3048)
			(stroke
				(width 0.1)
				(type default)
			)
			(layer "B.Fab")
		)
		(fp_line
			(start -0.120396 0.2794)
			(end 0.12065 0.2794)
			(stroke
				(width 0.1)
				(type default)
			)
			(layer "B.Fab")
		)
		(fp_line
			(start 0.67945 0.3048)
			(end 0.67945 -0.305054)
			(stroke
				(width 0.1)
				(type default)
			)
			(layer "B.Fab")
		)
		(fp_line
			(start 0.12065 0.3048)
			(end 0.67945 0.3048)
			(stroke
				(width 0.1)
				(type default)
			)
			(layer "B.Fab")
		)
		(fp_line
			(start -0.120396 0.3048)
			(end -0.120396 0.2794)
			(stroke
				(width 0.1)
				(type default)
			)
			(layer "B.Fab")
		)
		(fp_line
			(start -0.67945 0.3048)
			(end -0.120396 0.3048)
			(stroke
				(width 0.1)
				(type default)
			)
			(layer "B.Fab")
		)
		(pad "1" smd circle
			(at 0.40005 0 270)
			(size 0 0)
			(layers "B.Cu" "B.Mask" "B.Paste")
			(net "UART_PEX2_CLI_TX")
		)
		(pad "2" smd circle
			(at -0.40005 0 270)
			(size 0 0)
			(layers "B.Cu" "B.Mask" "B.Paste")
			(net "UART_PEX2_CLI_R_TX")
		)
	)
	(footprint ""
		(layer "B.Cu")
		(at 104.960674 -284.796738 -90)
		(property "Reference" "PC77"
			(at 0 0 90)
			(layer "B.SilkS")
			(hide yes)
			(effects
				(font
					(size 1.27 1.27)
				)
				(justify mirror)
			)
		)
		(property "Value" ""
			(at 0 0 90)
			(layer "B.Fab")
			(effects
				(font
					(size 1.27 1.27)
				)
				(justify mirror)
			)
		)
		(duplicate_pad_numbers_are_jumpers no)
		(fp_line
			(start -1.524 0.762)
			(end 1.524 0.762)
			(stroke
				(width 0.1524)
				(type default)
			)
			(layer "B.SilkS")
		)
		(fp_line
			(start 1.524 0.762)
			(end 1.524 -0.762)
			(stroke
				(width 0.1524)
				(type default)
			)
			(layer "B.SilkS")
		)
		(fp_line
			(start -1.524 -0.762)
			(end -1.524 0.762)
			(stroke
				(width 0.1524)
				(type default)
			)
			(layer "B.SilkS")
		)
		(fp_line
			(start 1.524 -0.762)
			(end -1.524 -0.762)
			(stroke
				(width 0.1524)
				(type default)
			)
			(layer "B.SilkS")
		)
		(fp_line
			(start -1.1049 0.724916)
			(end -1.1049 -0.724916)
			(stroke
				(width 0.1)
				(type default)
			)
			(layer "B.Fab")
		)
		(fp_line
			(start 1.1049 0.724916)
			(end -1.1049 0.724916)
			(stroke
				(width 0.1)
				(type default)
			)
			(layer "B.Fab")
		)
		(fp_line
			(start -1.1049 -0.724916)
			(end 1.1049 -0.724916)
			(stroke
				(width 0.1)
				(type default)
			)
			(layer "B.Fab")
		)
		(fp_line
			(start 1.1049 -0.724916)
			(end 1.1049 0.724916)
			(stroke
				(width 0.1)
				(type default)
			)
			(layer "B.Fab")
		)
		(pad "1" smd rect
			(at 0.889 0 270)
			(size 1.016 1.27)
			(layers "B.Cu" "B.Mask" "B.Paste")
			(net "SW_P12V_P0V8_PEX0_FLT")
		)
		(pad "2" smd rect
			(at -0.889 0 270)
			(size 1.016 1.27)
			(layers "B.Cu" "B.Mask" "B.Paste")
			(net "GND")
		)
	)
	(footprint ""
		(layer "B.Cu")
		(at 452.08444 -286.034988)
		(property "Reference" "PC275"
			(at 0 0 0)
			(layer "B.SilkS")
			(hide yes)
			(effects
				(font
					(size 1.27 1.27)
				)
				(justify mirror)
			)
		)
		(property "Value" ""
			(at 0 0 0)
			(layer "B.Fab")
			(effects
				(font
					(size 1.27 1.27)
				)
				(justify mirror)
			)
		)
		(duplicate_pad_numbers_are_jumpers no)
		(fp_line
			(start -1.524 -0.762)
			(end -1.524 0.762)
			(stroke
				(width 0.1524)
				(type default)
			)
			(layer "B.SilkS")
		)
		(fp_line
			(start -1.524 0.762)
			(end 1.524 0.762)
			(stroke
				(width 0.1524)
				(type default)
			)
			(layer "B.SilkS")
		)
		(fp_line
			(start 1.524 -0.762)
			(end -1.524 -0.762)
			(stroke
				(width 0.1524)
				(type default)
			)
			(layer "B.SilkS")
		)
		(fp_line
			(start 1.524 0.762)
			(end 1.524 -0.762)
			(stroke
				(width 0.1524)
				(type default)
			)
			(layer "B.SilkS")
		)
		(fp_line
			(start -1.1049 -0.724916)
			(end 1.1049 -0.724916)
			(stroke
				(width 0.1)
				(type default)
			)
			(layer "B.Fab")
		)
		(fp_line
			(start -1.1049 0.724916)
			(end -1.1049 -0.724916)
			(stroke
				(width 0.1)
				(type default)
			)
			(layer "B.Fab")
		)
		(fp_line
			(start 1.1049 -0.724916)
			(end 1.1049 0.724916)
			(stroke
				(width 0.1)
				(type default)
			)
			(layer "B.Fab")
		)
		(fp_line
			(start 1.1049 0.724916)
			(end -1.1049 0.724916)
			(stroke
				(width 0.1)
				(type default)
			)
			(layer "B.Fab")
		)
		(pad "1" smd rect
			(at 0.889 0)
			(size 1.016 1.27)
			(layers "B.Cu" "B.Mask" "B.Paste")
			(net "P1V25_PEX3_R")
		)
		(pad "2" smd rect
			(at -0.889 0)
			(size 1.016 1.27)
			(layers "B.Cu" "B.Mask" "B.Paste")
			(net "GND")
		)
	)
	(footprint ""
		(layer "B.Cu")
		(at 45.864272 -144.421352 180)
		(property "Reference" "C849"
			(at 0 0 0)
			(layer "B.SilkS")
			(hide yes)
			(effects
				(font
					(size 1.27 1.27)
				)
				(justify mirror)
			)
		)
		(property "Value" ""
			(at 0 0 0)
			(layer "B.Fab")
			(effects
				(font
					(size 1.27 1.27)
				)
				(justify mirror)
			)
		)
		(duplicate_pad_numbers_are_jumpers no)
		(fp_line
			(start 0.299974 0.150114)
			(end 0.299974 -0.150114)
			(stroke
				(width 0.1)
				(type default)
			)
			(layer "B.Fab")
		)
		(fp_line
			(start 0.299974 -0.150114)
			(end -0.299974 -0.150114)
			(stroke
				(width 0.1)
				(type default)
			)
			(layer "B.Fab")
		)
		(fp_line
			(start -0.299974 0.150114)
			(end 0.299974 0.150114)
			(stroke
				(width 0.1)
				(type default)
			)
			(layer "B.Fab")
		)
		(fp_line
			(start -0.299974 -0.150114)
			(end -0.299974 0.150114)
			(stroke
				(width 0.1)
				(type default)
			)
			(layer "B.Fab")
		)
		(pad "1" smd rect
			(at 0.2667 0)
			(size 0.3048 0.381)
			(layers "B.Cu" "B.Mask" "B.Paste")
			(net "P12V_NIC0")
		)
		(pad "2" smd rect
			(at -0.2667 0)
			(size 0.3048 0.381)
			(layers "B.Cu" "B.Mask" "B.Paste")
			(net "GND")
		)
	)
	(footprint ""
		(layer "B.Cu")
		(at 110.694216 -137.56386 90)
		(property "Reference" "PC34"
			(at 0 0 90)
			(layer "B.SilkS")
			(hide yes)
			(effects
				(font
					(size 1.27 1.27)
				)
				(justify mirror)
			)
		)
		(property "Value" ""
			(at 0 0 90)
			(layer "B.Fab")
			(effects
				(font
					(size 1.27 1.27)
				)
				(justify mirror)
			)
		)
		(duplicate_pad_numbers_are_jumpers no)
		(fp_line
			(start 1.524 -0.762)
			(end -1.524 -0.762)
			(stroke
				(width 0.1524)
				(type default)
			)
			(layer "B.SilkS")
		)
		(fp_line
			(start -1.524 -0.762)
			(end -1.524 0.762)
			(stroke
				(width 0.1524)
				(type default)
			)
			(layer "B.SilkS")
		)
		(fp_line
			(start 1.524 0.762)
			(end 1.524 -0.762)
			(stroke
				(width 0.1524)
				(type default)
			)
			(layer "B.SilkS")
		)
		(fp_line
			(start -1.524 0.762)
			(end 1.524 0.762)
			(stroke
				(width 0.1524)
				(type default)
			)
			(layer "B.SilkS")
		)
		(fp_line
			(start 1.1049 -0.724916)
			(end 1.1049 0.724916)
			(stroke
				(width 0.1)
				(type default)
			)
			(layer "B.Fab")
		)
		(fp_line
			(start -1.1049 -0.724916)
			(end 1.1049 -0.724916)
			(stroke
				(width 0.1)
				(type default)
			)
			(layer "B.Fab")
		)
		(fp_line
			(start 1.1049 0.724916)
			(end -1.1049 0.724916)
			(stroke
				(width 0.1)
				(type default)
			)
			(layer "B.Fab")
		)
		(fp_line
			(start -1.1049 0.724916)
			(end -1.1049 -0.724916)
			(stroke
				(width 0.1)
				(type default)
			)
			(layer "B.Fab")
		)
		(pad "1" smd rect
			(at 0.889 0 90)
			(size 1.016 1.27)
			(layers "B.Cu" "B.Mask" "B.Paste")
			(net "P3V3_AUX")
		)
		(pad "2" smd rect
			(at -0.889 0 90)
			(size 1.016 1.27)
			(layers "B.Cu" "B.Mask" "B.Paste")
			(net "GND")
		)
	)
	(footprint ""
		(layer "B.Cu")
		(at 122.689366 -313.620404)
		(property "Reference" "L27"
			(at 0 0 0)
			(layer "B.SilkS")
			(hide yes)
			(effects
				(font
					(size 1.27 1.27)
				)
				(justify mirror)
			)
		)
		(property "Value" ""
			(at 0 0 0)
			(layer "B.Fab")
			(effects
				(font
					(size 1.27 1.27)
				)
				(justify mirror)
			)
		)
		(duplicate_pad_numbers_are_jumpers no)
		(fp_line
			(start -2.248154 -4.9911)
			(end 2.248154 -4.9911)
			(stroke
				(width 0.1524)
				(type default)
			)
			(layer "B.SilkS")
		)
		(fp_line
			(start -2.248154 -1.794764)
			(end -2.248154 -4.9911)
			(stroke
				(width 0.1524)
				(type default)
			)
			(layer "B.SilkS")
		)
		(fp_line
			(start -2.248154 4.9911)
			(end -2.248154 2.100834)
			(stroke
				(width 0.1524)
				(type default)
			)
			(layer "B.SilkS")
		)
		(fp_line
			(start 2.248154 -4.9911)
			(end 2.248154 -1.794764)
			(stroke
				(width 0.1524)
				(type default)
			)
			(layer "B.SilkS")
		)
		(fp_line
			(start 2.248154 2.100834)
			(end 2.248154 4.9911)
			(stroke
				(width 0.1524)
				(type default)
			)
			(layer "B.SilkS")
		)
		(fp_line
			(start 2.248154 4.9911)
			(end -2.248154 4.9911)
			(stroke
				(width 0.1524)
				(type default)
			)
			(layer "B.SilkS")
		)
		(fp_line
			(start -1.700022 -0.899922)
			(end 1.700022 -0.899922)
			(stroke
				(width 0.1)
				(type default)
			)
			(layer "B.Fab")
		)
		(fp_line
			(start -1.700022 0.899922)
			(end -1.700022 -0.899922)
			(stroke
				(width 0.1)
				(type default)
			)
			(layer "B.Fab")
		)
		(fp_line
			(start 1.700022 -0.899922)
			(end 1.700022 0.899922)
			(stroke
				(width 0.1)
				(type default)
			)
			(layer "B.Fab")
		)
		(fp_line
			(start 1.700022 0.899922)
			(end -1.700022 0.899922)
			(stroke
				(width 0.1)
				(type default)
			)
			(layer "B.Fab")
		)
		(pad "1" smd rect
			(at 1.575054 0 180)
			(size 1.1684 9.8044)
			(layers "B.Cu" "B.Mask" "B.Paste")
			(net "P0V8_PEX1")
		)
		(pad "2" smd rect
			(at -1.575054 0 180)
			(size 1.1684 9.8044)
			(layers "B.Cu" "B.Mask" "B.Paste")
			(net "P0V8_SERDES_VDDA_PEX1")
		)
	)
	(footprint ""
		(layer "B.Cu")
		(at 135.387842 -182.052468 90)
		(property "Reference" "R1123"
			(at 0 0 90)
			(layer "B.SilkS")
			(hide yes)
			(effects
				(font
					(size 1.27 1.27)
				)
				(justify mirror)
			)
		)
		(property "Value" ""
			(at 0 0 90)
			(layer "B.Fab")
			(effects
				(font
					(size 1.27 1.27)
				)
				(justify mirror)
			)
		)
		(duplicate_pad_numbers_are_jumpers no)
		(fp_line
			(start 0.7874 -0.4064)
			(end -0.7874 -0.4064)
			(stroke
				(width 0.1524)
				(type default)
			)
			(layer "B.SilkS")
		)
		(fp_line
			(start -0.7874 -0.4064)
			(end -0.7874 0.4064)
			(stroke
				(width 0.1524)
				(type default)
			)
			(layer "B.SilkS")
		)
		(fp_line
			(start 0.7874 0.4064)
			(end 0.7874 -0.4064)
			(stroke
				(width 0.1524)
				(type default)
			)
			(layer "B.SilkS")
		)
		(fp_line
			(start -0.7874 0.4064)
			(end 0.7874 0.4064)
			(stroke
				(width 0.1524)
				(type default)
			)
			(layer "B.SilkS")
		)
		(fp_line
			(start 0.67945 -0.305054)
			(end 0.12065 -0.305054)
			(stroke
				(width 0.1)
				(type default)
			)
			(layer "B.Fab")
		)
		(fp_line
			(start 0.12065 -0.305054)
			(end 0.12065 -0.2794)
			(stroke
				(width 0.1)
				(type default)
			)
			(layer "B.Fab")
		)
		(fp_line
			(start -0.12065 -0.3048)
			(end -0.67945 -0.3048)
			(stroke
				(width 0.1)
				(type default)
			)
			(layer "B.Fab")
		)
		(fp_line
			(start -0.67945 -0.3048)
			(end -0.67945 0.3048)
			(stroke
				(width 0.1)
				(type default)
			)
			(layer "B.Fab")
		)
		(fp_line
			(start 0.12065 -0.2794)
			(end -0.12065 -0.2794)
			(stroke
				(width 0.1)
				(type default)
			)
			(layer "B.Fab")
		)
		(fp_line
			(start -0.12065 -0.2794)
			(end -0.12065 -0.3048)
			(stroke
				(width 0.1)
				(type default)
			)
			(layer "B.Fab")
		)
		(fp_line
			(start 0.12065 0.2794)
			(end 0.12065 0.3048)
			(stroke
				(width 0.1)
				(type default)
			)
			(layer "B.Fab")
		)
		(fp_line
			(start -0.120396 0.2794)
			(end 0.12065 0.2794)
			(stroke
				(width 0.1)
				(type default)
			)
			(layer "B.Fab")
		)
		(fp_line
			(start 0.67945 0.3048)
			(end 0.67945 -0.305054)
			(stroke
				(width 0.1)
				(type default)
			)
			(layer "B.Fab")
		)
		(fp_line
			(start 0.12065 0.3048)
			(end 0.67945 0.3048)
			(stroke
				(width 0.1)
				(type default)
			)
			(layer "B.Fab")
		)
		(fp_line
			(start -0.120396 0.3048)
			(end -0.120396 0.2794)
			(stroke
				(width 0.1)
				(type default)
			)
			(layer "B.Fab")
		)
		(fp_line
			(start -0.67945 0.3048)
			(end -0.120396 0.3048)
			(stroke
				(width 0.1)
				(type default)
			)
			(layer "B.Fab")
		)
		(pad "1" smd circle
			(at 0.40005 0 270)
			(size 0 0)
			(layers "B.Cu" "B.Mask" "B.Paste")
			(net "GND")
		)
		(pad "2" smd circle
			(at -0.40005 0 270)
			(size 0 0)
			(layers "B.Cu" "B.Mask" "B.Paste")
			(net "FM_DB2000QL_SMB_SA1")
		)
	)
	(footprint ""
		(layer "B.Cu")
		(at 162.455098 -300.1772)
		(property "Reference" "C3199"
			(at 0 0 0)
			(layer "B.SilkS")
			(hide yes)
			(effects
				(font
					(size 1.27 1.27)
				)
				(justify mirror)
			)
		)
		(property "Value" ""
			(at 0 0 0)
			(layer "B.Fab")
			(effects
				(font
					(size 1.27 1.27)
				)
				(justify mirror)
			)
		)
		(duplicate_pad_numbers_are_jumpers no)
		(fp_line
			(start -0.299974 -0.150114)
			(end -0.299974 0.150114)
			(stroke
				(width 0.1)
				(type default)
			)
			(layer "B.Fab")
		)
		(fp_line
			(start -0.299974 0.150114)
			(end 0.299974 0.150114)
			(stroke
				(width 0.1)
				(type default)
			)
			(layer "B.Fab")
		)
		(fp_line
			(start 0.299974 -0.150114)
			(end -0.299974 -0.150114)
			(stroke
				(width 0.1)
				(type default)
			)
			(layer "B.Fab")
		)
		(fp_line
			(start 0.299974 0.150114)
			(end 0.299974 -0.150114)
			(stroke
				(width 0.1)
				(type default)
			)
			(layer "B.Fab")
		)
		(pad "1" smd rect
			(at 0.2667 0 180)
			(size 0.3048 0.381)
			(layers "B.Cu" "B.Mask" "B.Paste")
			(net "PCEPLL1_VDDA18_PEX1")
		)
		(pad "2" smd rect
			(at -0.2667 0 180)
			(size 0.3048 0.381)
			(layers "B.Cu" "B.Mask" "B.Paste")
			(net "GND")
		)
	)
	(footprint ""
		(layer "B.Cu")
		(at 301.607474 -221.694502 -90)
		(property "Reference" "R1860"
			(at 0 0 90)
			(layer "B.SilkS")
			(hide yes)
			(effects
				(font
					(size 1.27 1.27)
				)
				(justify mirror)
			)
		)
		(property "Value" ""
			(at 0 0 90)
			(layer "B.Fab")
			(effects
				(font
					(size 1.27 1.27)
				)
				(justify mirror)
			)
		)
		(duplicate_pad_numbers_are_jumpers no)
		(fp_line
			(start -0.7874 0.4064)
			(end 0.7874 0.4064)
			(stroke
				(width 0.1524)
				(type default)
			)
			(layer "B.SilkS")
		)
		(fp_line
			(start 0.7874 0.4064)
			(end 0.7874 -0.4064)
			(stroke
				(width 0.1524)
				(type default)
			)
			(layer "B.SilkS")
		)
		(fp_line
			(start -0.7874 -0.4064)
			(end -0.7874 0.4064)
			(stroke
				(width 0.1524)
				(type default)
			)
			(layer "B.SilkS")
		)
		(fp_line
			(start 0.7874 -0.4064)
			(end -0.7874 -0.4064)
			(stroke
				(width 0.1524)
				(type default)
			)
			(layer "B.SilkS")
		)
		(fp_line
			(start -0.67945 0.3048)
			(end -0.120396 0.3048)
			(stroke
				(width 0.1)
				(type default)
			)
			(layer "B.Fab")
		)
		(fp_line
			(start -0.120396 0.3048)
			(end -0.120396 0.2794)
			(stroke
				(width 0.1)
				(type default)
			)
			(layer "B.Fab")
		)
		(fp_line
			(start 0.12065 0.3048)
			(end 0.67945 0.3048)
			(stroke
				(width 0.1)
				(type default)
			)
			(layer "B.Fab")
		)
		(fp_line
			(start 0.67945 0.3048)
			(end 0.67945 -0.305054)
			(stroke
				(width 0.1)
				(type default)
			)
			(layer "B.Fab")
		)
		(fp_line
			(start -0.120396 0.2794)
			(end 0.12065 0.2794)
			(stroke
				(width 0.1)
				(type default)
			)
			(layer "B.Fab")
		)
		(fp_line
			(start 0.12065 0.2794)
			(end 0.12065 0.3048)
			(stroke
				(width 0.1)
				(type default)
			)
			(layer "B.Fab")
		)
		(fp_line
			(start -0.12065 -0.2794)
			(end -0.12065 -0.3048)
			(stroke
				(width 0.1)
				(type default)
			)
			(layer "B.Fab")
		)
		(fp_line
			(start 0.12065 -0.2794)
			(end -0.12065 -0.2794)
			(stroke
				(width 0.1)
				(type default)
			)
			(layer "B.Fab")
		)
		(fp_line
			(start -0.67945 -0.3048)
			(end -0.67945 0.3048)
			(stroke
				(width 0.1)
				(type default)
			)
			(layer "B.Fab")
		)
		(fp_line
			(start -0.12065 -0.3048)
			(end -0.67945 -0.3048)
			(stroke
				(width 0.1)
				(type default)
			)
			(layer "B.Fab")
		)
		(fp_line
			(start 0.12065 -0.305054)
			(end 0.12065 -0.2794)
			(stroke
				(width 0.1)
				(type default)
			)
			(layer "B.Fab")
		)
		(fp_line
			(start 0.67945 -0.305054)
			(end 0.12065 -0.305054)
			(stroke
				(width 0.1)
				(type default)
			)
			(layer "B.Fab")
		)
		(pad "1" smd circle
			(at 0.40005 0 90)
			(size 0 0)
			(layers "B.Cu" "B.Mask" "B.Paste")
			(net "P3V3_AUX")
		)
		(pad "2" smd circle
			(at -0.40005 0 90)
			(size 0 0)
			(layers "B.Cu" "B.Mask" "B.Paste")
			(net "RST_GPU_PERST_2_N")
		)
	)
	(footprint ""
		(layer "B.Cu")
		(at 69.624956 -304.241454 90)
		(property "Reference" "C3014"
			(at 0 0 90)
			(layer "B.SilkS")
			(hide yes)
			(effects
				(font
					(size 1.27 1.27)
				)
				(justify mirror)
			)
		)
		(property "Value" ""
			(at 0 0 90)
			(layer "B.Fab")
			(effects
				(font
					(size 1.27 1.27)
				)
				(justify mirror)
			)
		)
		(duplicate_pad_numbers_are_jumpers no)
		(fp_line
			(start 0.299974 -0.150114)
			(end -0.299974 -0.150114)
			(stroke
				(width 0.1)
				(type default)
			)
			(layer "B.Fab")
		)
		(fp_line
			(start -0.299974 -0.150114)
			(end -0.299974 0.150114)
			(stroke
				(width 0.1)
				(type default)
			)
			(layer "B.Fab")
		)
		(fp_line
			(start 0.299974 0.150114)
			(end 0.299974 -0.150114)
			(stroke
				(width 0.1)
				(type default)
			)
			(layer "B.Fab")
		)
		(fp_line
			(start -0.299974 0.150114)
			(end 0.299974 0.150114)
			(stroke
				(width 0.1)
				(type default)
			)
			(layer "B.Fab")
		)
		(pad "1" smd rect
			(at 0.2667 0 270)
			(size 0.3048 0.381)
			(layers "B.Cu" "B.Mask" "B.Paste")
			(net "P1V8_VDDA_PEX0")
		)
		(pad "2" smd rect
			(at -0.2667 0 270)
			(size 0.3048 0.381)
			(layers "B.Cu" "B.Mask" "B.Paste")
			(net "GND")
		)
	)
	(footprint ""
		(layer "B.Cu")
		(at 217.705686 -272.617438)
		(property "Reference" "C4288"
			(at 0 0 0)
			(layer "B.SilkS")
			(hide yes)
			(effects
				(font
					(size 1.27 1.27)
				)
				(justify mirror)
			)
		)
		(property "Value" ""
			(at 0 0 0)
			(layer "B.Fab")
			(effects
				(font
					(size 1.27 1.27)
				)
				(justify mirror)
			)
		)
		(duplicate_pad_numbers_are_jumpers no)
		(fp_line
			(start -1.2954 -0.5842)
			(end -1.2954 0.5842)
			(stroke
				(width 0.1524)
				(type default)
			)
			(layer "B.SilkS")
		)
		(fp_line
			(start -1.2954 0.5842)
			(end 1.2954 0.5842)
			(stroke
				(width 0.1524)
				(type default)
			)
			(layer "B.SilkS")
		)
		(fp_line
			(start 1.2954 -0.5842)
			(end -1.2954 -0.5842)
			(stroke
				(width 0.1524)
				(type default)
			)
			(layer "B.SilkS")
		)
		(fp_line
			(start 1.2954 0.5842)
			(end 1.2954 -0.5842)
			(stroke
				(width 0.1524)
				(type default)
			)
			(layer "B.SilkS")
		)
		(fp_line
			(start -1.1938 -0.4064)
			(end -1.1938 0.4064)
			(stroke
				(width 0.1)
				(type default)
			)
			(layer "B.Fab")
		)
		(fp_line
			(start -1.1938 0.4064)
			(end -0.8636 0.4064)
			(stroke
				(width 0.1)
				(type default)
			)
			(layer "B.Fab")
		)
		(fp_line
			(start -0.8636 -0.4572)
			(end -0.8636 -0.4064)
			(stroke
				(width 0.1)
				(type default)
			)
			(layer "B.Fab")
		)
		(fp_line
			(start -0.8636 -0.4064)
			(end -1.1938 -0.4064)
			(stroke
				(width 0.1)
				(type default)
			)
			(layer "B.Fab")
		)
		(fp_line
			(start -0.8636 0.4064)
			(end -0.8636 0.4572)
			(stroke
				(width 0.1)
				(type default)
			)
			(layer "B.Fab")
		)
		(fp_line
			(start -0.8636 0.4572)
			(end 0.8636 0.4572)
			(stroke
				(width 0.1)
				(type default)
			)
			(layer "B.Fab")
		)
		(fp_line
			(start 0.8636 -0.4572)
			(end -0.8636 -0.4572)
			(stroke
				(width 0.1)
				(type default)
			)
			(layer "B.Fab")
		)
		(fp_line
			(start 0.8636 -0.4064)
			(end 0.8636 -0.4572)
			(stroke
				(width 0.1)
				(type default)
			)
			(layer "B.Fab")
		)
		(fp_line
			(start 0.8636 0.4064)
			(end 1.1938 0.4064)
			(stroke
				(width 0.1)
				(type default)
			)
			(layer "B.Fab")
		)
		(fp_line
			(start 0.8636 0.4572)
			(end 0.8636 0.4064)
			(stroke
				(width 0.1)
				(type default)
			)
			(layer "B.Fab")
		)
		(fp_line
			(start 1.1938 -0.4064)
			(end 0.8636 -0.4064)
			(stroke
				(width 0.1)
				(type default)
			)
			(layer "B.Fab")
		)
		(fp_line
			(start 1.1938 0.4064)
			(end 1.1938 -0.4064)
			(stroke
				(width 0.1)
				(type default)
			)
			(layer "B.Fab")
		)
		(pad "1" smd rect
			(at 0.7366 0 270)
			(size 0.7112 0.8128)
			(layers "B.Cu" "B.Mask" "B.Paste")
			(net "P1V25_PEX1")
		)
		(pad "2" smd rect
			(at -0.7366 0 270)
			(size 0.7112 0.8128)
			(layers "B.Cu" "B.Mask" "B.Paste")
			(net "GND")
		)
	)
	(footprint ""
		(layer "B.Cu")
		(at 68.408042 -299.224954 180)
		(property "Reference" "C1164"
			(at 0 0 0)
			(layer "B.SilkS")
			(hide yes)
			(effects
				(font
					(size 1.27 1.27)
				)
				(justify mirror)
			)
		)
		(property "Value" ""
			(at 0 0 0)
			(layer "B.Fab")
			(effects
				(font
					(size 1.27 1.27)
				)
				(justify mirror)
			)
		)
		(duplicate_pad_numbers_are_jumpers no)
		(fp_line
			(start 0.299974 0.150114)
			(end 0.299974 -0.150114)
			(stroke
				(width 0.1)
				(type default)
			)
			(layer "B.Fab")
		)
		(fp_line
			(start 0.299974 -0.150114)
			(end -0.299974 -0.150114)
			(stroke
				(width 0.1)
				(type default)
			)
			(layer "B.Fab")
		)
		(fp_line
			(start -0.299974 0.150114)
			(end 0.299974 0.150114)
			(stroke
				(width 0.1)
				(type default)
			)
			(layer "B.Fab")
		)
		(fp_line
			(start -0.299974 -0.150114)
			(end -0.299974 0.150114)
			(stroke
				(width 0.1)
				(type default)
			)
			(layer "B.Fab")
		)
		(pad "1" smd rect
			(at 0.2667 0)
			(size 0.3048 0.381)
			(layers "B.Cu" "B.Mask" "B.Paste")
			(net "P0V8_SERDES_VDDA_PEX0")
		)
		(pad "2" smd rect
			(at -0.2667 0)
			(size 0.3048 0.381)
			(layers "B.Cu" "B.Mask" "B.Paste")
			(net "GND")
		)
	)
	(footprint ""
		(layer "B.Cu")
		(at 46.355 -300.1772)
		(property "Reference" "C3025"
			(at 0 0 0)
			(layer "B.SilkS")
			(hide yes)
			(effects
				(font
					(size 1.27 1.27)
				)
				(justify mirror)
			)
		)
		(property "Value" ""
			(at 0 0 0)
			(layer "B.Fab")
			(effects
				(font
					(size 1.27 1.27)
				)
				(justify mirror)
			)
		)
		(duplicate_pad_numbers_are_jumpers no)
		(fp_line
			(start -0.299974 -0.150114)
			(end -0.299974 0.150114)
			(stroke
				(width 0.1)
				(type default)
			)
			(layer "B.Fab")
		)
		(fp_line
			(start -0.299974 0.150114)
			(end 0.299974 0.150114)
			(stroke
				(width 0.1)
				(type default)
			)
			(layer "B.Fab")
		)
		(fp_line
			(start 0.299974 -0.150114)
			(end -0.299974 -0.150114)
			(stroke
				(width 0.1)
				(type default)
			)
			(layer "B.Fab")
		)
		(fp_line
			(start 0.299974 0.150114)
			(end 0.299974 -0.150114)
			(stroke
				(width 0.1)
				(type default)
			)
			(layer "B.Fab")
		)
		(pad "1" smd rect
			(at 0.2667 0 180)
			(size 0.3048 0.381)
			(layers "B.Cu" "B.Mask" "B.Paste")
			(net "PCEPLL1_VDDA18_PEX0")
		)
		(pad "2" smd rect
			(at -0.2667 0 180)
			(size 0.3048 0.381)
			(layers "B.Cu" "B.Mask" "B.Paste")
			(net "GND")
		)
	)
	(footprint ""
		(layer "B.Cu")
		(at 460.169006 -291.823648 180)
		(property "Reference" "PC999"
			(at 0 0 0)
			(layer "B.SilkS")
			(hide yes)
			(effects
				(font
					(size 1.27 1.27)
				)
				(justify mirror)
			)
		)
		(property "Value" ""
			(at 0 0 0)
			(layer "B.Fab")
			(effects
				(font
					(size 1.27 1.27)
				)
				(justify mirror)
			)
		)
		(duplicate_pad_numbers_are_jumpers no)
		(fp_line
			(start 1.524 0.762)
			(end 1.524 -0.762)
			(stroke
				(width 0.1524)
				(type default)
			)
			(layer "B.SilkS")
		)
		(fp_line
			(start 1.524 -0.762)
			(end -1.524 -0.762)
			(stroke
				(width 0.1524)
				(type default)
			)
			(layer "B.SilkS")
		)
		(fp_line
			(start -1.524 0.762)
			(end 1.524 0.762)
			(stroke
				(width 0.1524)
				(type default)
			)
			(layer "B.SilkS")
		)
		(fp_line
			(start -1.524 -0.762)
			(end -1.524 0.762)
			(stroke
				(width 0.1524)
				(type default)
			)
			(layer "B.SilkS")
		)
		(fp_line
			(start 1.1049 0.724916)
			(end -1.1049 0.724916)
			(stroke
				(width 0.1)
				(type default)
			)
			(layer "B.Fab")
		)
		(fp_line
			(start 1.1049 -0.724916)
			(end 1.1049 0.724916)
			(stroke
				(width 0.1)
				(type default)
			)
			(layer "B.Fab")
		)
		(fp_line
			(start -1.1049 0.724916)
			(end -1.1049 -0.724916)
			(stroke
				(width 0.1)
				(type default)
			)
			(layer "B.Fab")
		)
		(fp_line
			(start -1.1049 -0.724916)
			(end 1.1049 -0.724916)
			(stroke
				(width 0.1)
				(type default)
			)
			(layer "B.Fab")
		)
		(pad "1" smd rect
			(at 0.889 0 180)
			(size 1.016 1.27)
			(layers "B.Cu" "B.Mask" "B.Paste")
			(net "P1V25_PEX3_R")
		)
		(pad "2" smd rect
			(at -0.889 0 180)
			(size 1.016 1.27)
			(layers "B.Cu" "B.Mask" "B.Paste")
			(net "GND")
		)
	)
	(footprint ""
		(layer "B.Cu")
		(at 133.030214 -206.666846 -90)
		(property "Reference" "C2586"
			(at 0 0 90)
			(layer "B.SilkS")
			(hide yes)
			(effects
				(font
					(size 1.27 1.27)
				)
				(justify mirror)
			)
		)
		(property "Value" ""
			(at 0 0 90)
			(layer "B.Fab")
			(effects
				(font
					(size 1.27 1.27)
				)
				(justify mirror)
			)
		)
		(duplicate_pad_numbers_are_jumpers no)
		(fp_line
			(start -1.2954 0.5842)
			(end 1.2954 0.5842)
			(stroke
				(width 0.1524)
				(type default)
			)
			(layer "B.SilkS")
		)
		(fp_line
			(start 1.2954 0.5842)
			(end 1.2954 -0.5842)
			(stroke
				(width 0.1524)
				(type default)
			)
			(layer "B.SilkS")
		)
		(fp_line
			(start -1.2954 -0.5842)
			(end -1.2954 0.5842)
			(stroke
				(width 0.1524)
				(type default)
			)
			(layer "B.SilkS")
		)
		(fp_line
			(start 1.2954 -0.5842)
			(end -1.2954 -0.5842)
			(stroke
				(width 0.1524)
				(type default)
			)
			(layer "B.SilkS")
		)
		(fp_line
			(start -0.8636 0.4572)
			(end 0.8636 0.4572)
			(stroke
				(width 0.1)
				(type default)
			)
			(layer "B.Fab")
		)
		(fp_line
			(start 0.8636 0.4572)
			(end 0.8636 0.4064)
			(stroke
				(width 0.1)
				(type default)
			)
			(layer "B.Fab")
		)
		(fp_line
			(start -1.1938 0.4064)
			(end -0.8636 0.4064)
			(stroke
				(width 0.1)
				(type default)
			)
			(layer "B.Fab")
		)
		(fp_line
			(start -0.8636 0.4064)
			(end -0.8636 0.4572)
			(stroke
				(width 0.1)
				(type default)
			)
			(layer "B.Fab")
		)
		(fp_line
			(start 0.8636 0.4064)
			(end 1.1938 0.4064)
			(stroke
				(width 0.1)
				(type default)
			)
			(layer "B.Fab")
		)
		(fp_line
			(start 1.1938 0.4064)
			(end 1.1938 -0.4064)
			(stroke
				(width 0.1)
				(type default)
			)
			(layer "B.Fab")
		)
		(fp_line
			(start -1.1938 -0.4064)
			(end -1.1938 0.4064)
			(stroke
				(width 0.1)
				(type default)
			)
			(layer "B.Fab")
		)
		(fp_line
			(start -0.8636 -0.4064)
			(end -1.1938 -0.4064)
			(stroke
				(width 0.1)
				(type default)
			)
			(layer "B.Fab")
		)
		(fp_line
			(start 0.8636 -0.4064)
			(end 0.8636 -0.4572)
			(stroke
				(width 0.1)
				(type default)
			)
			(layer "B.Fab")
		)
		(fp_line
			(start 1.1938 -0.4064)
			(end 0.8636 -0.4064)
			(stroke
				(width 0.1)
				(type default)
			)
			(layer "B.Fab")
		)
		(fp_line
			(start -0.8636 -0.4572)
			(end -0.8636 -0.4064)
			(stroke
				(width 0.1)
				(type default)
			)
			(layer "B.Fab")
		)
		(fp_line
			(start 0.8636 -0.4572)
			(end -0.8636 -0.4572)
			(stroke
				(width 0.1)
				(type default)
			)
			(layer "B.Fab")
		)
		(pad "1" smd rect
			(at 0.7366 0 180)
			(size 0.7112 0.8128)
			(layers "B.Cu" "B.Mask" "B.Paste")
			(net "P3V3_AUX")
		)
		(pad "2" smd rect
			(at -0.7366 0 180)
			(size 0.7112 0.8128)
			(layers "B.Cu" "B.Mask" "B.Paste")
			(net "GND")
		)
	)
	(footprint ""
		(layer "B.Cu")
		(at 397.49984 -300.174914)
		(property "Reference" "C1894"
			(at 0 0 0)
			(layer "B.SilkS")
			(hide yes)
			(effects
				(font
					(size 1.27 1.27)
				)
				(justify mirror)
			)
		)
		(property "Value" ""
			(at 0 0 0)
			(layer "B.Fab")
			(effects
				(font
					(size 1.27 1.27)
				)
				(justify mirror)
			)
		)
		(duplicate_pad_numbers_are_jumpers no)
		(fp_line
			(start -0.299974 -0.150114)
			(end -0.299974 0.150114)
			(stroke
				(width 0.1)
				(type default)
			)
			(layer "B.Fab")
		)
		(fp_line
			(start -0.299974 0.150114)
			(end 0.299974 0.150114)
			(stroke
				(width 0.1)
				(type default)
			)
			(layer "B.Fab")
		)
		(fp_line
			(start 0.299974 -0.150114)
			(end -0.299974 -0.150114)
			(stroke
				(width 0.1)
				(type default)
			)
			(layer "B.Fab")
		)
		(fp_line
			(start 0.299974 0.150114)
			(end 0.299974 -0.150114)
			(stroke
				(width 0.1)
				(type default)
			)
			(layer "B.Fab")
		)
		(pad "1" smd rect
			(at 0.2667 0 180)
			(size 0.3048 0.381)
			(layers "B.Cu" "B.Mask" "B.Paste")
			(net "P0V8_PEX3")
		)
		(pad "2" smd rect
			(at -0.2667 0 180)
			(size 0.3048 0.381)
			(layers "B.Cu" "B.Mask" "B.Paste")
			(net "GND")
		)
	)
	(footprint ""
		(layer "B.Cu")
		(at 416.708082 -299.224954 180)
		(property "Reference" "C1931"
			(at 0 0 0)
			(layer "B.SilkS")
			(hide yes)
			(effects
				(font
					(size 1.27 1.27)
				)
				(justify mirror)
			)
		)
		(property "Value" ""
			(at 0 0 0)
			(layer "B.Fab")
			(effects
				(font
					(size 1.27 1.27)
				)
				(justify mirror)
			)
		)
		(duplicate_pad_numbers_are_jumpers no)
		(fp_line
			(start 0.299974 0.150114)
			(end 0.299974 -0.150114)
			(stroke
				(width 0.1)
				(type default)
			)
			(layer "B.Fab")
		)
		(fp_line
			(start 0.299974 -0.150114)
			(end -0.299974 -0.150114)
			(stroke
				(width 0.1)
				(type default)
			)
			(layer "B.Fab")
		)
		(fp_line
			(start -0.299974 0.150114)
			(end 0.299974 0.150114)
			(stroke
				(width 0.1)
				(type default)
			)
			(layer "B.Fab")
		)
		(fp_line
			(start -0.299974 -0.150114)
			(end -0.299974 0.150114)
			(stroke
				(width 0.1)
				(type default)
			)
			(layer "B.Fab")
		)
		(pad "1" smd rect
			(at 0.2667 0)
			(size 0.3048 0.381)
			(layers "B.Cu" "B.Mask" "B.Paste")
			(net "P0V8_SERDES_VDDA_PEX3")
		)
		(pad "2" smd rect
			(at -0.2667 0)
			(size 0.3048 0.381)
			(layers "B.Cu" "B.Mask" "B.Paste")
			(net "GND")
		)
	)
	(footprint ""
		(layer "B.Cu")
		(at 104.932734 -237.306612 -90)
		(property "Reference" "PC1003"
			(at 0 0 90)
			(layer "B.SilkS")
			(hide yes)
			(effects
				(font
					(size 1.27 1.27)
				)
				(justify mirror)
			)
		)
		(property "Value" ""
			(at 0 0 90)
			(layer "B.Fab")
			(effects
				(font
					(size 1.27 1.27)
				)
				(justify mirror)
			)
		)
		(duplicate_pad_numbers_are_jumpers no)
		(fp_line
			(start -1.524 0.762)
			(end 1.524 0.762)
			(stroke
				(width 0.1524)
				(type default)
			)
			(layer "B.SilkS")
		)
		(fp_line
			(start 1.524 0.762)
			(end 1.524 -0.762)
			(stroke
				(width 0.1524)
				(type default)
			)
			(layer "B.SilkS")
		)
		(fp_line
			(start -1.524 -0.762)
			(end -1.524 0.762)
			(stroke
				(width 0.1524)
				(type default)
			)
			(layer "B.SilkS")
		)
		(fp_line
			(start 1.524 -0.762)
			(end -1.524 -0.762)
			(stroke
				(width 0.1524)
				(type default)
			)
			(layer "B.SilkS")
		)
		(fp_line
			(start -1.1049 0.724916)
			(end -1.1049 -0.724916)
			(stroke
				(width 0.1)
				(type default)
			)
			(layer "B.Fab")
		)
		(fp_line
			(start 1.1049 0.724916)
			(end -1.1049 0.724916)
			(stroke
				(width 0.1)
				(type default)
			)
			(layer "B.Fab")
		)
		(fp_line
			(start -1.1049 -0.724916)
			(end 1.1049 -0.724916)
			(stroke
				(width 0.1)
				(type default)
			)
			(layer "B.Fab")
		)
		(fp_line
			(start 1.1049 -0.724916)
			(end 1.1049 0.724916)
			(stroke
				(width 0.1)
				(type default)
			)
			(layer "B.Fab")
		)
		(pad "1" smd rect
			(at 0.889 0 270)
			(size 1.016 1.27)
			(layers "B.Cu" "B.Mask" "B.Paste")
			(net "P1V8_PEX_R")
		)
		(pad "2" smd rect
			(at -0.889 0 270)
			(size 1.016 1.27)
			(layers "B.Cu" "B.Mask" "B.Paste")
			(net "GND")
		)
	)
	(footprint ""
		(layer "B.Cu")
		(at 322.512182 -219.956888 90)
		(property "Reference" "R6284"
			(at 0 0 90)
			(layer "B.SilkS")
			(hide yes)
			(effects
				(font
					(size 1.27 1.27)
				)
				(justify mirror)
			)
		)
		(property "Value" ""
			(at 0 0 90)
			(layer "B.Fab")
			(effects
				(font
					(size 1.27 1.27)
				)
				(justify mirror)
			)
		)
		(duplicate_pad_numbers_are_jumpers no)
		(fp_line
			(start 0.7874 -0.4064)
			(end -0.7874 -0.4064)
			(stroke
				(width 0.1524)
				(type default)
			)
			(layer "B.SilkS")
		)
		(fp_line
			(start -0.7874 -0.4064)
			(end -0.7874 0.4064)
			(stroke
				(width 0.1524)
				(type default)
			)
			(layer "B.SilkS")
		)
		(fp_line
			(start 0.7874 0.4064)
			(end 0.7874 -0.4064)
			(stroke
				(width 0.1524)
				(type default)
			)
			(layer "B.SilkS")
		)
		(fp_line
			(start -0.7874 0.4064)
			(end 0.7874 0.4064)
			(stroke
				(width 0.1524)
				(type default)
			)
			(layer "B.SilkS")
		)
		(fp_line
			(start 0.67945 -0.305054)
			(end 0.12065 -0.305054)
			(stroke
				(width 0.1)
				(type default)
			)
			(layer "B.Fab")
		)
		(fp_line
			(start 0.12065 -0.305054)
			(end 0.12065 -0.2794)
			(stroke
				(width 0.1)
				(type default)
			)
			(layer "B.Fab")
		)
		(fp_line
			(start -0.12065 -0.3048)
			(end -0.67945 -0.3048)
			(stroke
				(width 0.1)
				(type default)
			)
			(layer "B.Fab")
		)
		(fp_line
			(start -0.67945 -0.3048)
			(end -0.67945 0.3048)
			(stroke
				(width 0.1)
				(type default)
			)
			(layer "B.Fab")
		)
		(fp_line
			(start 0.12065 -0.2794)
			(end -0.12065 -0.2794)
			(stroke
				(width 0.1)
				(type default)
			)
			(layer "B.Fab")
		)
		(fp_line
			(start -0.12065 -0.2794)
			(end -0.12065 -0.3048)
			(stroke
				(width 0.1)
				(type default)
			)
			(layer "B.Fab")
		)
		(fp_line
			(start 0.12065 0.2794)
			(end 0.12065 0.3048)
			(stroke
				(width 0.1)
				(type default)
			)
			(layer "B.Fab")
		)
		(fp_line
			(start -0.120396 0.2794)
			(end 0.12065 0.2794)
			(stroke
				(width 0.1)
				(type default)
			)
			(layer "B.Fab")
		)
		(fp_line
			(start 0.67945 0.3048)
			(end 0.67945 -0.305054)
			(stroke
				(width 0.1)
				(type default)
			)
			(layer "B.Fab")
		)
		(fp_line
			(start 0.12065 0.3048)
			(end 0.67945 0.3048)
			(stroke
				(width 0.1)
				(type default)
			)
			(layer "B.Fab")
		)
		(fp_line
			(start -0.120396 0.3048)
			(end -0.120396 0.2794)
			(stroke
				(width 0.1)
				(type default)
			)
			(layer "B.Fab")
		)
		(fp_line
			(start -0.67945 0.3048)
			(end -0.120396 0.3048)
			(stroke
				(width 0.1)
				(type default)
			)
			(layer "B.Fab")
		)
		(pad "1" smd circle
			(at 0.40005 0 270)
			(size 0 0)
			(layers "B.Cu" "B.Mask" "B.Paste")
			(net "JTAG_FPGA_R_TDO")
		)
		(pad "2" smd circle
			(at -0.40005 0 270)
			(size 0 0)
			(layers "B.Cu" "B.Mask" "B.Paste")
			(net "JTAG_FPGA_TDO")
		)
	)
	(footprint ""
		(layer "B.Cu")
		(at 406.049988 -292.099746 90)
		(property "Reference" "C1997"
			(at 0 0 90)
			(layer "B.SilkS")
			(hide yes)
			(effects
				(font
					(size 1.27 1.27)
				)
				(justify mirror)
			)
		)
		(property "Value" ""
			(at 0 0 90)
			(layer "B.Fab")
			(effects
				(font
					(size 1.27 1.27)
				)
				(justify mirror)
			)
		)
		(duplicate_pad_numbers_are_jumpers no)
		(fp_line
			(start 0.299974 -0.150114)
			(end -0.299974 -0.150114)
			(stroke
				(width 0.1)
				(type default)
			)
			(layer "B.Fab")
		)
		(fp_line
			(start -0.299974 -0.150114)
			(end -0.299974 0.150114)
			(stroke
				(width 0.1)
				(type default)
			)
			(layer "B.Fab")
		)
		(fp_line
			(start 0.299974 0.150114)
			(end 0.299974 -0.150114)
			(stroke
				(width 0.1)
				(type default)
			)
			(layer "B.Fab")
		)
		(fp_line
			(start -0.299974 0.150114)
			(end 0.299974 0.150114)
			(stroke
				(width 0.1)
				(type default)
			)
			(layer "B.Fab")
		)
		(pad "1" smd rect
			(at 0.2667 0 270)
			(size 0.3048 0.381)
			(layers "B.Cu" "B.Mask" "B.Paste")
			(net "P0V8_SERDES_VDDA_PEX3")
		)
		(pad "2" smd rect
			(at -0.2667 0 270)
			(size 0.3048 0.381)
			(layers "B.Cu" "B.Mask" "B.Paste")
			(net "GND")
		)
	)
	(footprint ""
		(layer "B.Cu")
		(at 177.42027 -195.874386)
		(property "Reference" "R1034"
			(at 0 0 0)
			(layer "B.SilkS")
			(hide yes)
			(effects
				(font
					(size 1.27 1.27)
				)
				(justify mirror)
			)
		)
		(property "Value" ""
			(at 0 0 0)
			(layer "B.Fab")
			(effects
				(font
					(size 1.27 1.27)
				)
				(justify mirror)
			)
		)
		(duplicate_pad_numbers_are_jumpers no)
		(fp_line
			(start -0.7874 -0.4064)
			(end -0.7874 0.4064)
			(stroke
				(width 0.1524)
				(type default)
			)
			(layer "B.SilkS")
		)
		(fp_line
			(start -0.7874 0.4064)
			(end 0.7874 0.4064)
			(stroke
				(width 0.1524)
				(type default)
			)
			(layer "B.SilkS")
		)
		(fp_line
			(start 0.7874 -0.4064)
			(end -0.7874 -0.4064)
			(stroke
				(width 0.1524)
				(type default)
			)
			(layer "B.SilkS")
		)
		(fp_line
			(start 0.7874 0.4064)
			(end 0.7874 -0.4064)
			(stroke
				(width 0.1524)
				(type default)
			)
			(layer "B.SilkS")
		)
		(fp_line
			(start -0.67945 -0.3048)
			(end -0.67945 0.3048)
			(stroke
				(width 0.1)
				(type default)
			)
			(layer "B.Fab")
		)
		(fp_line
			(start -0.67945 0.3048)
			(end -0.120396 0.3048)
			(stroke
				(width 0.1)
				(type default)
			)
			(layer "B.Fab")
		)
		(fp_line
			(start -0.12065 -0.3048)
			(end -0.67945 -0.3048)
			(stroke
				(width 0.1)
				(type default)
			)
			(layer "B.Fab")
		)
		(fp_line
			(start -0.12065 -0.2794)
			(end -0.12065 -0.3048)
			(stroke
				(width 0.1)
				(type default)
			)
			(layer "B.Fab")
		)
		(fp_line
			(start -0.120396 0.2794)
			(end 0.12065 0.2794)
			(stroke
				(width 0.1)
				(type default)
			)
			(layer "B.Fab")
		)
		(fp_line
			(start -0.120396 0.3048)
			(end -0.120396 0.2794)
			(stroke
				(width 0.1)
				(type default)
			)
			(layer "B.Fab")
		)
		(fp_line
			(start 0.12065 -0.305054)
			(end 0.12065 -0.2794)
			(stroke
				(width 0.1)
				(type default)
			)
			(layer "B.Fab")
		)
		(fp_line
			(start 0.12065 -0.2794)
			(end -0.12065 -0.2794)
			(stroke
				(width 0.1)
				(type default)
			)
			(layer "B.Fab")
		)
		(fp_line
			(start 0.12065 0.2794)
			(end 0.12065 0.3048)
			(stroke
				(width 0.1)
				(type default)
			)
			(layer "B.Fab")
		)
		(fp_line
			(start 0.12065 0.3048)
			(end 0.67945 0.3048)
			(stroke
				(width 0.1)
				(type default)
			)
			(layer "B.Fab")
		)
		(fp_line
			(start 0.67945 -0.305054)
			(end 0.12065 -0.305054)
			(stroke
				(width 0.1)
				(type default)
			)
			(layer "B.Fab")
		)
		(fp_line
			(start 0.67945 0.3048)
			(end 0.67945 -0.305054)
			(stroke
				(width 0.1)
				(type default)
			)
			(layer "B.Fab")
		)
		(pad "1" smd circle
			(at 0.40005 0 180)
			(size 0 0)
			(layers "B.Cu" "B.Mask" "B.Paste")
			(net "GND")
		)
		(pad "2" smd circle
			(at -0.40005 0 180)
			(size 0 0)
			(layers "B.Cu" "B.Mask" "B.Paste")
			(net "SPI_BIC1_CLK_LS01_DIR2")
		)
	)
	(footprint ""
		(layer "B.Cu")
		(at 394.64996 -290.674806)
		(property "Reference" "C3523"
			(at 0 0 0)
			(layer "B.SilkS")
			(hide yes)
			(effects
				(font
					(size 1.27 1.27)
				)
				(justify mirror)
			)
		)
		(property "Value" ""
			(at 0 0 0)
			(layer "B.Fab")
			(effects
				(font
					(size 1.27 1.27)
				)
				(justify mirror)
			)
		)
		(duplicate_pad_numbers_are_jumpers no)
		(fp_line
			(start -0.299974 -0.150114)
			(end -0.299974 0.150114)
			(stroke
				(width 0.1)
				(type default)
			)
			(layer "B.Fab")
		)
		(fp_line
			(start -0.299974 0.150114)
			(end 0.299974 0.150114)
			(stroke
				(width 0.1)
				(type default)
			)
			(layer "B.Fab")
		)
		(fp_line
			(start 0.299974 -0.150114)
			(end -0.299974 -0.150114)
			(stroke
				(width 0.1)
				(type default)
			)
			(layer "B.Fab")
		)
		(fp_line
			(start 0.299974 0.150114)
			(end 0.299974 -0.150114)
			(stroke
				(width 0.1)
				(type default)
			)
			(layer "B.Fab")
		)
		(pad "1" smd rect
			(at 0.2667 0 180)
			(size 0.3048 0.381)
			(layers "B.Cu" "B.Mask" "B.Paste")
			(net "P1V8_PEX")
		)
		(pad "2" smd rect
			(at -0.2667 0 180)
			(size 0.3048 0.381)
			(layers "B.Cu" "B.Mask" "B.Paste")
			(net "GND")
		)
	)
	(footprint ""
		(layer "B.Cu")
		(at 248.353834 -223.937068 90)
		(property "Reference" "R3478"
			(at 0 0 90)
			(layer "B.SilkS")
			(hide yes)
			(effects
				(font
					(size 1.27 1.27)
				)
				(justify mirror)
			)
		)
		(property "Value" ""
			(at 0 0 90)
			(layer "B.Fab")
			(effects
				(font
					(size 1.27 1.27)
				)
				(justify mirror)
			)
		)
		(duplicate_pad_numbers_are_jumpers no)
		(fp_line
			(start 0.7874 -0.4064)
			(end -0.7874 -0.4064)
			(stroke
				(width 0.1524)
				(type default)
			)
			(layer "B.SilkS")
		)
		(fp_line
			(start -0.7874 -0.4064)
			(end -0.7874 0.4064)
			(stroke
				(width 0.1524)
				(type default)
			)
			(layer "B.SilkS")
		)
		(fp_line
			(start 0.7874 0.4064)
			(end 0.7874 -0.4064)
			(stroke
				(width 0.1524)
				(type default)
			)
			(layer "B.SilkS")
		)
		(fp_line
			(start -0.7874 0.4064)
			(end 0.7874 0.4064)
			(stroke
				(width 0.1524)
				(type default)
			)
			(layer "B.SilkS")
		)
		(fp_line
			(start 0.67945 -0.305054)
			(end 0.12065 -0.305054)
			(stroke
				(width 0.1)
				(type default)
			)
			(layer "B.Fab")
		)
		(fp_line
			(start 0.12065 -0.305054)
			(end 0.12065 -0.2794)
			(stroke
				(width 0.1)
				(type default)
			)
			(layer "B.Fab")
		)
		(fp_line
			(start -0.12065 -0.3048)
			(end -0.67945 -0.3048)
			(stroke
				(width 0.1)
				(type default)
			)
			(layer "B.Fab")
		)
		(fp_line
			(start -0.67945 -0.3048)
			(end -0.67945 0.3048)
			(stroke
				(width 0.1)
				(type default)
			)
			(layer "B.Fab")
		)
		(fp_line
			(start 0.12065 -0.2794)
			(end -0.12065 -0.2794)
			(stroke
				(width 0.1)
				(type default)
			)
			(layer "B.Fab")
		)
		(fp_line
			(start -0.12065 -0.2794)
			(end -0.12065 -0.3048)
			(stroke
				(width 0.1)
				(type default)
			)
			(layer "B.Fab")
		)
		(fp_line
			(start 0.12065 0.2794)
			(end 0.12065 0.3048)
			(stroke
				(width 0.1)
				(type default)
			)
			(layer "B.Fab")
		)
		(fp_line
			(start -0.120396 0.2794)
			(end 0.12065 0.2794)
			(stroke
				(width 0.1)
				(type default)
			)
			(layer "B.Fab")
		)
		(fp_line
			(start 0.67945 0.3048)
			(end 0.67945 -0.305054)
			(stroke
				(width 0.1)
				(type default)
			)
			(layer "B.Fab")
		)
		(fp_line
			(start 0.12065 0.3048)
			(end 0.67945 0.3048)
			(stroke
				(width 0.1)
				(type default)
			)
			(layer "B.Fab")
		)
		(fp_line
			(start -0.120396 0.3048)
			(end -0.120396 0.2794)
			(stroke
				(width 0.1)
				(type default)
			)
			(layer "B.Fab")
		)
		(fp_line
			(start -0.67945 0.3048)
			(end -0.120396 0.3048)
			(stroke
				(width 0.1)
				(type default)
			)
			(layer "B.Fab")
		)
		(pad "1" smd circle
			(at 0.40005 0 270)
			(size 0 0)
			(layers "B.Cu" "B.Mask" "B.Paste")
			(net "SPI_MUX_PEX2_EN_N")
		)
		(pad "2" smd circle
			(at -0.40005 0 270)
			(size 0 0)
			(layers "B.Cu" "B.Mask" "B.Paste")
			(net "GND")
		)
	)
	(footprint ""
		(layer "B.Cu")
		(at 204.377036 -363.00029)
		(property "Reference" "R495"
			(at 0 0 0)
			(layer "B.SilkS")
			(hide yes)
			(effects
				(font
					(size 1.27 1.27)
				)
				(justify mirror)
			)
		)
		(property "Value" ""
			(at 0 0 0)
			(layer "B.Fab")
			(effects
				(font
					(size 1.27 1.27)
				)
				(justify mirror)
			)
		)
		(duplicate_pad_numbers_are_jumpers no)
		(fp_line
			(start -0.7874 -0.4064)
			(end -0.7874 0.4064)
			(stroke
				(width 0.1524)
				(type default)
			)
			(layer "B.SilkS")
		)
		(fp_line
			(start -0.7874 0.4064)
			(end 0.7874 0.4064)
			(stroke
				(width 0.1524)
				(type default)
			)
			(layer "B.SilkS")
		)
		(fp_line
			(start 0.7874 -0.4064)
			(end -0.7874 -0.4064)
			(stroke
				(width 0.1524)
				(type default)
			)
			(layer "B.SilkS")
		)
		(fp_line
			(start 0.7874 0.4064)
			(end 0.7874 -0.4064)
			(stroke
				(width 0.1524)
				(type default)
			)
			(layer "B.SilkS")
		)
		(fp_line
			(start -0.67945 -0.3048)
			(end -0.67945 0.3048)
			(stroke
				(width 0.1)
				(type default)
			)
			(layer "B.Fab")
		)
		(fp_line
			(start -0.67945 0.3048)
			(end -0.120396 0.3048)
			(stroke
				(width 0.1)
				(type default)
			)
			(layer "B.Fab")
		)
		(fp_line
			(start -0.12065 -0.3048)
			(end -0.67945 -0.3048)
			(stroke
				(width 0.1)
				(type default)
			)
			(layer "B.Fab")
		)
		(fp_line
			(start -0.12065 -0.2794)
			(end -0.12065 -0.3048)
			(stroke
				(width 0.1)
				(type default)
			)
			(layer "B.Fab")
		)
		(fp_line
			(start -0.120396 0.2794)
			(end 0.12065 0.2794)
			(stroke
				(width 0.1)
				(type default)
			)
			(layer "B.Fab")
		)
		(fp_line
			(start -0.120396 0.3048)
			(end -0.120396 0.2794)
			(stroke
				(width 0.1)
				(type default)
			)
			(layer "B.Fab")
		)
		(fp_line
			(start 0.12065 -0.305054)
			(end 0.12065 -0.2794)
			(stroke
				(width 0.1)
				(type default)
			)
			(layer "B.Fab")
		)
		(fp_line
			(start 0.12065 -0.2794)
			(end -0.12065 -0.2794)
			(stroke
				(width 0.1)
				(type default)
			)
			(layer "B.Fab")
		)
		(fp_line
			(start 0.12065 0.2794)
			(end 0.12065 0.3048)
			(stroke
				(width 0.1)
				(type default)
			)
			(layer "B.Fab")
		)
		(fp_line
			(start 0.12065 0.3048)
			(end 0.67945 0.3048)
			(stroke
				(width 0.1)
				(type default)
			)
			(layer "B.Fab")
		)
		(fp_line
			(start 0.67945 -0.305054)
			(end 0.12065 -0.305054)
			(stroke
				(width 0.1)
				(type default)
			)
			(layer "B.Fab")
		)
		(fp_line
			(start 0.67945 0.3048)
			(end 0.67945 -0.305054)
			(stroke
				(width 0.1)
				(type default)
			)
			(layer "B.Fab")
		)
		(pad "1" smd circle
			(at 0.40005 0 180)
			(size 0 0)
			(layers "B.Cu" "B.Mask" "B.Paste")
			(net "HSC_P12V_EN")
		)
		(pad "2" smd circle
			(at -0.40005 0 180)
			(size 0 0)
			(layers "B.Cu" "B.Mask" "B.Paste")
			(net "GND")
		)
	)
	(footprint ""
		(layer "B.Cu")
		(at 184.772046 -112.421924 180)
		(property "Reference" "R162"
			(at 0 0 0)
			(layer "B.SilkS")
			(hide yes)
			(effects
				(font
					(size 1.27 1.27)
				)
				(justify mirror)
			)
		)
		(property "Value" ""
			(at 0 0 0)
			(layer "B.Fab")
			(effects
				(font
					(size 1.27 1.27)
				)
				(justify mirror)
			)
		)
		(duplicate_pad_numbers_are_jumpers no)
		(fp_line
			(start 0.7874 0.4064)
			(end 0.7874 -0.4064)
			(stroke
				(width 0.1524)
				(type default)
			)
			(layer "B.SilkS")
		)
		(fp_line
			(start 0.7874 -0.4064)
			(end -0.7874 -0.4064)
			(stroke
				(width 0.1524)
				(type default)
			)
			(layer "B.SilkS")
		)
		(fp_line
			(start -0.7874 0.4064)
			(end 0.7874 0.4064)
			(stroke
				(width 0.1524)
				(type default)
			)
			(layer "B.SilkS")
		)
		(fp_line
			(start -0.7874 -0.4064)
			(end -0.7874 0.4064)
			(stroke
				(width 0.1524)
				(type default)
			)
			(layer "B.SilkS")
		)
		(fp_line
			(start 0.67945 0.3048)
			(end 0.67945 -0.305054)
			(stroke
				(width 0.1)
				(type default)
			)
			(layer "B.Fab")
		)
		(fp_line
			(start 0.67945 -0.305054)
			(end 0.12065 -0.305054)
			(stroke
				(width 0.1)
				(type default)
			)
			(layer "B.Fab")
		)
		(fp_line
			(start 0.12065 0.3048)
			(end 0.67945 0.3048)
			(stroke
				(width 0.1)
				(type default)
			)
			(layer "B.Fab")
		)
		(fp_line
			(start 0.12065 0.2794)
			(end 0.12065 0.3048)
			(stroke
				(width 0.1)
				(type default)
			)
			(layer "B.Fab")
		)
		(fp_line
			(start 0.12065 -0.2794)
			(end -0.12065 -0.2794)
			(stroke
				(width 0.1)
				(type default)
			)
			(layer "B.Fab")
		)
		(fp_line
			(start 0.12065 -0.305054)
			(end 0.12065 -0.2794)
			(stroke
				(width 0.1)
				(type default)
			)
			(layer "B.Fab")
		)
		(fp_line
			(start -0.120396 0.3048)
			(end -0.120396 0.2794)
			(stroke
				(width 0.1)
				(type default)
			)
			(layer "B.Fab")
		)
		(fp_line
			(start -0.120396 0.2794)
			(end 0.12065 0.2794)
			(stroke
				(width 0.1)
				(type default)
			)
			(layer "B.Fab")
		)
		(fp_line
			(start -0.12065 -0.2794)
			(end -0.12065 -0.3048)
			(stroke
				(width 0.1)
				(type default)
			)
			(layer "B.Fab")
		)
		(fp_line
			(start -0.12065 -0.3048)
			(end -0.67945 -0.3048)
			(stroke
				(width 0.1)
				(type default)
			)
			(layer "B.Fab")
		)
		(fp_line
			(start -0.67945 0.3048)
			(end -0.120396 0.3048)
			(stroke
				(width 0.1)
				(type default)
			)
			(layer "B.Fab")
		)
		(fp_line
			(start -0.67945 -0.3048)
			(end -0.67945 0.3048)
			(stroke
				(width 0.1)
				(type default)
			)
			(layer "B.Fab")
		)
		(pad "1" smd circle
			(at 0.40005 0)
			(size 0 0)
			(layers "B.Cu" "B.Mask" "B.Paste")
			(net "SMB_NIC3_R_SCL")
		)
		(pad "2" smd circle
			(at -0.40005 0)
			(size 0 0)
			(layers "B.Cu" "B.Mask" "B.Paste")
			(net "P3V3_NIC3")
		)
	)
	(footprint ""
		(layer "B.Cu")
		(at 348.98838 -318.542416 180)
		(property "Reference" "C4309"
			(at 0 0 0)
			(layer "B.SilkS")
			(hide yes)
			(effects
				(font
					(size 1.27 1.27)
				)
				(justify mirror)
			)
		)
		(property "Value" ""
			(at 0 0 0)
			(layer "B.Fab")
			(effects
				(font
					(size 1.27 1.27)
				)
				(justify mirror)
			)
		)
		(duplicate_pad_numbers_are_jumpers no)
		(fp_line
			(start 0.299974 0.150114)
			(end 0.299974 -0.150114)
			(stroke
				(width 0.1)
				(type default)
			)
			(layer "B.Fab")
		)
		(fp_line
			(start 0.299974 -0.150114)
			(end -0.299974 -0.150114)
			(stroke
				(width 0.1)
				(type default)
			)
			(layer "B.Fab")
		)
		(fp_line
			(start -0.299974 0.150114)
			(end 0.299974 0.150114)
			(stroke
				(width 0.1)
				(type default)
			)
			(layer "B.Fab")
		)
		(fp_line
			(start -0.299974 -0.150114)
			(end -0.299974 0.150114)
			(stroke
				(width 0.1)
				(type default)
			)
			(layer "B.Fab")
		)
		(pad "1" smd rect
			(at 0.2667 0)
			(size 0.3048 0.381)
			(layers "B.Cu" "B.Mask" "B.Paste")
			(net "P0V8_SERDES_VDDA_PEX2")
		)
		(pad "2" smd rect
			(at -0.2667 0)
			(size 0.3048 0.381)
			(layers "B.Cu" "B.Mask" "B.Paste")
			(net "GND")
		)
	)
	(footprint ""
		(layer "B.Cu")
		(at 237.903512 -234.728004 90)
		(property "Reference" "R6195"
			(at 0 0 90)
			(layer "B.SilkS")
			(hide yes)
			(effects
				(font
					(size 1.27 1.27)
				)
				(justify mirror)
			)
		)
		(property "Value" ""
			(at 0 0 90)
			(layer "B.Fab")
			(effects
				(font
					(size 1.27 1.27)
				)
				(justify mirror)
			)
		)
		(duplicate_pad_numbers_are_jumpers no)
		(fp_line
			(start 0.7874 -0.4064)
			(end -0.7874 -0.4064)
			(stroke
				(width 0.1524)
				(type default)
			)
			(layer "B.SilkS")
		)
		(fp_line
			(start -0.7874 -0.4064)
			(end -0.7874 0.4064)
			(stroke
				(width 0.1524)
				(type default)
			)
			(layer "B.SilkS")
		)
		(fp_line
			(start 0.7874 0.4064)
			(end 0.7874 -0.4064)
			(stroke
				(width 0.1524)
				(type default)
			)
			(layer "B.SilkS")
		)
		(fp_line
			(start -0.7874 0.4064)
			(end 0.7874 0.4064)
			(stroke
				(width 0.1524)
				(type default)
			)
			(layer "B.SilkS")
		)
		(fp_line
			(start 0.67945 -0.305054)
			(end 0.12065 -0.305054)
			(stroke
				(width 0.1)
				(type default)
			)
			(layer "B.Fab")
		)
		(fp_line
			(start 0.12065 -0.305054)
			(end 0.12065 -0.2794)
			(stroke
				(width 0.1)
				(type default)
			)
			(layer "B.Fab")
		)
		(fp_line
			(start -0.12065 -0.3048)
			(end -0.67945 -0.3048)
			(stroke
				(width 0.1)
				(type default)
			)
			(layer "B.Fab")
		)
		(fp_line
			(start -0.67945 -0.3048)
			(end -0.67945 0.3048)
			(stroke
				(width 0.1)
				(type default)
			)
			(layer "B.Fab")
		)
		(fp_line
			(start 0.12065 -0.2794)
			(end -0.12065 -0.2794)
			(stroke
				(width 0.1)
				(type default)
			)
			(layer "B.Fab")
		)
		(fp_line
			(start -0.12065 -0.2794)
			(end -0.12065 -0.3048)
			(stroke
				(width 0.1)
				(type default)
			)
			(layer "B.Fab")
		)
		(fp_line
			(start 0.12065 0.2794)
			(end 0.12065 0.3048)
			(stroke
				(width 0.1)
				(type default)
			)
			(layer "B.Fab")
		)
		(fp_line
			(start -0.120396 0.2794)
			(end 0.12065 0.2794)
			(stroke
				(width 0.1)
				(type default)
			)
			(layer "B.Fab")
		)
		(fp_line
			(start 0.67945 0.3048)
			(end 0.67945 -0.305054)
			(stroke
				(width 0.1)
				(type default)
			)
			(layer "B.Fab")
		)
		(fp_line
			(start 0.12065 0.3048)
			(end 0.67945 0.3048)
			(stroke
				(width 0.1)
				(type default)
			)
			(layer "B.Fab")
		)
		(fp_line
			(start -0.120396 0.3048)
			(end -0.120396 0.2794)
			(stroke
				(width 0.1)
				(type default)
			)
			(layer "B.Fab")
		)
		(fp_line
			(start -0.67945 0.3048)
			(end -0.120396 0.3048)
			(stroke
				(width 0.1)
				(type default)
			)
			(layer "B.Fab")
		)
		(pad "1" smd circle
			(at 0.40005 0 270)
			(size 0 0)
			(layers "B.Cu" "B.Mask" "B.Paste")
			(net "GND")
		)
		(pad "2" smd circle
			(at -0.40005 0 270)
			(size 0 0)
			(layers "B.Cu" "B.Mask" "B.Paste")
			(net "SSD13_PWRDIS_BIC_R")
		)
	)
	(footprint ""
		(layer "B.Cu")
		(at 404.149814 -301.599854 -90)
		(property "Reference" "C1986"
			(at 0 0 90)
			(layer "B.SilkS")
			(hide yes)
			(effects
				(font
					(size 1.27 1.27)
				)
				(justify mirror)
			)
		)
		(property "Value" ""
			(at 0 0 90)
			(layer "B.Fab")
			(effects
				(font
					(size 1.27 1.27)
				)
				(justify mirror)
			)
		)
		(duplicate_pad_numbers_are_jumpers no)
		(fp_line
			(start -0.299974 0.150114)
			(end 0.299974 0.150114)
			(stroke
				(width 0.1)
				(type default)
			)
			(layer "B.Fab")
		)
		(fp_line
			(start 0.299974 0.150114)
			(end 0.299974 -0.150114)
			(stroke
				(width 0.1)
				(type default)
			)
			(layer "B.Fab")
		)
		(fp_line
			(start -0.299974 -0.150114)
			(end -0.299974 0.150114)
			(stroke
				(width 0.1)
				(type default)
			)
			(layer "B.Fab")
		)
		(fp_line
			(start 0.299974 -0.150114)
			(end -0.299974 -0.150114)
			(stroke
				(width 0.1)
				(type default)
			)
			(layer "B.Fab")
		)
		(pad "1" smd rect
			(at 0.2667 0 90)
			(size 0.3048 0.381)
			(layers "B.Cu" "B.Mask" "B.Paste")
			(net "P0V8_SERDES_VDDA_PEX3")
		)
		(pad "2" smd rect
			(at -0.2667 0 90)
			(size 0.3048 0.381)
			(layers "B.Cu" "B.Mask" "B.Paste")
			(net "GND")
		)
	)
	(footprint ""
		(layer "B.Cu")
		(at 229.867714 -214.704168 90)
		(property "Reference" "C2007"
			(at 0 0 90)
			(layer "B.SilkS")
			(hide yes)
			(effects
				(font
					(size 1.27 1.27)
				)
				(justify mirror)
			)
		)
		(property "Value" ""
			(at 0 0 90)
			(layer "B.Fab")
			(effects
				(font
					(size 1.27 1.27)
				)
				(justify mirror)
			)
		)
		(duplicate_pad_numbers_are_jumpers no)
		(fp_line
			(start 0.69215 -0.2921)
			(end -0.69215 -0.2921)
			(stroke
				(width 0.1524)
				(type default)
			)
			(layer "B.SilkS")
		)
		(fp_line
			(start -0.69215 -0.2921)
			(end -0.69215 0.2921)
			(stroke
				(width 0.1524)
				(type default)
			)
			(layer "B.SilkS")
		)
		(fp_line
			(start 0.69215 0.2921)
			(end 0.69215 -0.2921)
			(stroke
				(width 0.1524)
				(type default)
			)
			(layer "B.SilkS")
		)
		(fp_line
			(start -0.69215 0.2921)
			(end 0.69215 0.2921)
			(stroke
				(width 0.1524)
				(type default)
			)
			(layer "B.SilkS")
		)
		(fp_line
			(start 0.51435 -0.2794)
			(end -0.51435 -0.2794)
			(stroke
				(width 0.1)
				(type default)
			)
			(layer "B.Fab")
		)
		(fp_line
			(start -0.51435 -0.2794)
			(end -0.51435 0.2794)
			(stroke
				(width 0.1)
				(type default)
			)
			(layer "B.Fab")
		)
		(fp_line
			(start 0.51435 0.2794)
			(end 0.51435 -0.2794)
			(stroke
				(width 0.1)
				(type default)
			)
			(layer "B.Fab")
		)
		(fp_line
			(start -0.51435 0.2794)
			(end 0.51435 0.2794)
			(stroke
				(width 0.1)
				(type default)
			)
			(layer "B.Fab")
		)
		(pad "1" smd circle
			(at 0.40005 0 270)
			(size 0 0)
			(layers "B.Cu" "B.Mask" "B.Paste")
			(net "P3V3_AUX")
		)
		(pad "2" smd circle
			(at -0.40005 0 270)
			(size 0 0)
			(layers "B.Cu" "B.Mask" "B.Paste")
			(net "GND")
		)
		(zone
			(layer "B.Cu")
			(hatch none 0.5)
			(connect_pads
				(clearance 0)
			)
			(min_thickness 0.25)
			(keepout
				(tracks not_allowed)
				(vias allowed)
				(pads allowed)
				(copperpour not_allowed)
				(footprints allowed)
			)
			(placement
				(enabled no)
				(sheetname "")
			)
			(fill
				(thermal_gap 0.5)
				(thermal_bridge_width 0.5)
				(island_removal_mode 0)
			)
			(polygon
				(pts
					(xy 229.955344 -214.894668) (xy 230.01351 -214.803228) (xy 230.01351 -214.603838) (xy 229.955344 -214.513668)
					(xy 229.780084 -214.513668) (xy 229.721664 -214.603838) (xy 229.721664 -214.803228) (xy 229.77983 -214.894668)
				)
			)
		)
	)
	(footprint ""
		(layer "B.Cu")
		(at 378.069602 -243.428012 180)
		(property "Reference" "R935"
			(at 0 0 0)
			(layer "B.SilkS")
			(hide yes)
			(effects
				(font
					(size 1.27 1.27)
				)
				(justify mirror)
			)
		)
		(property "Value" ""
			(at 0 0 0)
			(layer "B.Fab")
			(effects
				(font
					(size 1.27 1.27)
				)
				(justify mirror)
			)
		)
		(duplicate_pad_numbers_are_jumpers no)
		(fp_line
			(start 0.7874 0.4064)
			(end 0.7874 -0.4064)
			(stroke
				(width 0.1524)
				(type default)
			)
			(layer "B.SilkS")
		)
		(fp_line
			(start 0.7874 -0.4064)
			(end -0.7874 -0.4064)
			(stroke
				(width 0.1524)
				(type default)
			)
			(layer "B.SilkS")
		)
		(fp_line
			(start -0.7874 0.4064)
			(end 0.7874 0.4064)
			(stroke
				(width 0.1524)
				(type default)
			)
			(layer "B.SilkS")
		)
		(fp_line
			(start -0.7874 -0.4064)
			(end -0.7874 0.4064)
			(stroke
				(width 0.1524)
				(type default)
			)
			(layer "B.SilkS")
		)
		(fp_line
			(start 0.67945 0.3048)
			(end 0.67945 -0.305054)
			(stroke
				(width 0.1)
				(type default)
			)
			(layer "B.Fab")
		)
		(fp_line
			(start 0.67945 -0.305054)
			(end 0.12065 -0.305054)
			(stroke
				(width 0.1)
				(type default)
			)
			(layer "B.Fab")
		)
		(fp_line
			(start 0.12065 0.3048)
			(end 0.67945 0.3048)
			(stroke
				(width 0.1)
				(type default)
			)
			(layer "B.Fab")
		)
		(fp_line
			(start 0.12065 0.2794)
			(end 0.12065 0.3048)
			(stroke
				(width 0.1)
				(type default)
			)
			(layer "B.Fab")
		)
		(fp_line
			(start 0.12065 -0.2794)
			(end -0.12065 -0.2794)
			(stroke
				(width 0.1)
				(type default)
			)
			(layer "B.Fab")
		)
		(fp_line
			(start 0.12065 -0.305054)
			(end 0.12065 -0.2794)
			(stroke
				(width 0.1)
				(type default)
			)
			(layer "B.Fab")
		)
		(fp_line
			(start -0.120396 0.3048)
			(end -0.120396 0.2794)
			(stroke
				(width 0.1)
				(type default)
			)
			(layer "B.Fab")
		)
		(fp_line
			(start -0.120396 0.2794)
			(end 0.12065 0.2794)
			(stroke
				(width 0.1)
				(type default)
			)
			(layer "B.Fab")
		)
		(fp_line
			(start -0.12065 -0.2794)
			(end -0.12065 -0.3048)
			(stroke
				(width 0.1)
				(type default)
			)
			(layer "B.Fab")
		)
		(fp_line
			(start -0.12065 -0.3048)
			(end -0.67945 -0.3048)
			(stroke
				(width 0.1)
				(type default)
			)
			(layer "B.Fab")
		)
		(fp_line
			(start -0.67945 0.3048)
			(end -0.120396 0.3048)
			(stroke
				(width 0.1)
				(type default)
			)
			(layer "B.Fab")
		)
		(fp_line
			(start -0.67945 -0.3048)
			(end -0.67945 0.3048)
			(stroke
				(width 0.1)
				(type default)
			)
			(layer "B.Fab")
		)
		(pad "1" smd circle
			(at 0.40005 0)
			(size 0 0)
			(layers "B.Cu" "B.Mask" "B.Paste")
			(net "UART_PEX0_SDB_BUF_R_TX")
		)
		(pad "2" smd circle
			(at -0.40005 0)
			(size 0 0)
			(layers "B.Cu" "B.Mask" "B.Paste")
			(net "UART_PEX0_SDB_BUF_TX")
		)
	)
	(footprint ""
		(layer "B.Cu")
		(at 166.725092 -297.79976 -90)
		(property "Reference" "C1388"
			(at 0 0 90)
			(layer "B.SilkS")
			(hide yes)
			(effects
				(font
					(size 1.27 1.27)
				)
				(justify mirror)
			)
		)
		(property "Value" ""
			(at 0 0 90)
			(layer "B.Fab")
			(effects
				(font
					(size 1.27 1.27)
				)
				(justify mirror)
			)
		)
		(duplicate_pad_numbers_are_jumpers no)
		(fp_line
			(start -0.299974 0.150114)
			(end 0.299974 0.150114)
			(stroke
				(width 0.1)
				(type default)
			)
			(layer "B.Fab")
		)
		(fp_line
			(start 0.299974 0.150114)
			(end 0.299974 -0.150114)
			(stroke
				(width 0.1)
				(type default)
			)
			(layer "B.Fab")
		)
		(fp_line
			(start -0.299974 -0.150114)
			(end -0.299974 0.150114)
			(stroke
				(width 0.1)
				(type default)
			)
			(layer "B.Fab")
		)
		(fp_line
			(start 0.299974 -0.150114)
			(end -0.299974 -0.150114)
			(stroke
				(width 0.1)
				(type default)
			)
			(layer "B.Fab")
		)
		(pad "1" smd rect
			(at 0.2667 0 90)
			(size 0.3048 0.381)
			(layers "B.Cu" "B.Mask" "B.Paste")
			(net "P0V8_PEX1")
		)
		(pad "2" smd rect
			(at -0.2667 0 90)
			(size 0.3048 0.381)
			(layers "B.Cu" "B.Mask" "B.Paste")
			(net "GND")
		)
	)
	(footprint ""
		(layer "B.Cu")
		(at 13.513054 -286.940752 180)
		(property "Reference" "PC989"
			(at 0 0 0)
			(layer "B.SilkS")
			(hide yes)
			(effects
				(font
					(size 1.27 1.27)
				)
				(justify mirror)
			)
		)
		(property "Value" ""
			(at 0 0 0)
			(layer "B.Fab")
			(effects
				(font
					(size 1.27 1.27)
				)
				(justify mirror)
			)
		)
		(duplicate_pad_numbers_are_jumpers no)
		(fp_line
			(start 1.524 0.762)
			(end 1.524 -0.762)
			(stroke
				(width 0.1524)
				(type default)
			)
			(layer "B.SilkS")
		)
		(fp_line
			(start 1.524 -0.762)
			(end -1.524 -0.762)
			(stroke
				(width 0.1524)
				(type default)
			)
			(layer "B.SilkS")
		)
		(fp_line
			(start -1.524 0.762)
			(end 1.524 0.762)
			(stroke
				(width 0.1524)
				(type default)
			)
			(layer "B.SilkS")
		)
		(fp_line
			(start -1.524 -0.762)
			(end -1.524 0.762)
			(stroke
				(width 0.1524)
				(type default)
			)
			(layer "B.SilkS")
		)
		(fp_line
			(start 1.1049 0.724916)
			(end -1.1049 0.724916)
			(stroke
				(width 0.1)
				(type default)
			)
			(layer "B.Fab")
		)
		(fp_line
			(start 1.1049 -0.724916)
			(end 1.1049 0.724916)
			(stroke
				(width 0.1)
				(type default)
			)
			(layer "B.Fab")
		)
		(fp_line
			(start -1.1049 0.724916)
			(end -1.1049 -0.724916)
			(stroke
				(width 0.1)
				(type default)
			)
			(layer "B.Fab")
		)
		(fp_line
			(start -1.1049 -0.724916)
			(end 1.1049 -0.724916)
			(stroke
				(width 0.1)
				(type default)
			)
			(layer "B.Fab")
		)
		(pad "1" smd rect
			(at 0.889 0 180)
			(size 1.016 1.27)
			(layers "B.Cu" "B.Mask" "B.Paste")
			(net "P1V25_PEX0_R")
		)
		(pad "2" smd rect
			(at -0.889 0 180)
			(size 1.016 1.27)
			(layers "B.Cu" "B.Mask" "B.Paste")
			(net "GND")
		)
	)
	(footprint ""
		(layer "B.Cu")
		(at 288.206942 -138.557 90)
		(property "Reference" "C918"
			(at 0 0 90)
			(layer "B.SilkS")
			(hide yes)
			(effects
				(font
					(size 1.27 1.27)
				)
				(justify mirror)
			)
		)
		(property "Value" ""
			(at 0 0 90)
			(layer "B.Fab")
			(effects
				(font
					(size 1.27 1.27)
				)
				(justify mirror)
			)
		)
		(duplicate_pad_numbers_are_jumpers no)
		(fp_line
			(start 0.7874 -0.4064)
			(end -0.7874 -0.4064)
			(stroke
				(width 0.1524)
				(type default)
			)
			(layer "B.SilkS")
		)
		(fp_line
			(start -0.7874 -0.4064)
			(end -0.7874 0.4064)
			(stroke
				(width 0.1524)
				(type default)
			)
			(layer "B.SilkS")
		)
		(fp_line
			(start 0.7874 0.4064)
			(end 0.7874 -0.4064)
			(stroke
				(width 0.1524)
				(type default)
			)
			(layer "B.SilkS")
		)
		(fp_line
			(start -0.7874 0.4064)
			(end 0.7874 0.4064)
			(stroke
				(width 0.1524)
				(type default)
			)
			(layer "B.SilkS")
		)
		(fp_line
			(start 0.67945 -0.305054)
			(end 0.12065 -0.305054)
			(stroke
				(width 0.1)
				(type default)
			)
			(layer "B.Fab")
		)
		(fp_line
			(start 0.12065 -0.305054)
			(end 0.12065 -0.2794)
			(stroke
				(width 0.1)
				(type default)
			)
			(layer "B.Fab")
		)
		(fp_line
			(start -0.12065 -0.3048)
			(end -0.67945 -0.3048)
			(stroke
				(width 0.1)
				(type default)
			)
			(layer "B.Fab")
		)
		(fp_line
			(start -0.67945 -0.3048)
			(end -0.67945 0.3048)
			(stroke
				(width 0.1)
				(type default)
			)
			(layer "B.Fab")
		)
		(fp_line
			(start 0.12065 -0.2794)
			(end -0.12065 -0.2794)
			(stroke
				(width 0.1)
				(type default)
			)
			(layer "B.Fab")
		)
		(fp_line
			(start -0.12065 -0.2794)
			(end -0.12065 -0.3048)
			(stroke
				(width 0.1)
				(type default)
			)
			(layer "B.Fab")
		)
		(fp_line
			(start 0.12065 0.2794)
			(end 0.12065 0.3048)
			(stroke
				(width 0.1)
				(type default)
			)
			(layer "B.Fab")
		)
		(fp_line
			(start -0.120396 0.2794)
			(end 0.12065 0.2794)
			(stroke
				(width 0.1)
				(type default)
			)
			(layer "B.Fab")
		)
		(fp_line
			(start 0.67945 0.3048)
			(end 0.67945 -0.305054)
			(stroke
				(width 0.1)
				(type default)
			)
			(layer "B.Fab")
		)
		(fp_line
			(start 0.12065 0.3048)
			(end 0.67945 0.3048)
			(stroke
				(width 0.1)
				(type default)
			)
			(layer "B.Fab")
		)
		(fp_line
			(start -0.120396 0.3048)
			(end -0.120396 0.2794)
			(stroke
				(width 0.1)
				(type default)
			)
			(layer "B.Fab")
		)
		(fp_line
			(start -0.67945 0.3048)
			(end -0.120396 0.3048)
			(stroke
				(width 0.1)
				(type default)
			)
			(layer "B.Fab")
		)
		(pad "1" smd circle
			(at 0.40005 0 270)
			(size 0 0)
			(layers "B.Cu" "B.Mask" "B.Paste")
			(net "P3V3_AUX")
		)
		(pad "2" smd circle
			(at -0.40005 0 270)
			(size 0 0)
			(layers "B.Cu" "B.Mask" "B.Paste")
			(net "GND")
		)
	)
	(footprint ""
		(layer "B.Cu")
		(at 124.731526 -282.170124 90)
		(property "Reference" "R6764"
			(at 0 0 90)
			(layer "B.SilkS")
			(hide yes)
			(effects
				(font
					(size 1.27 1.27)
				)
				(justify mirror)
			)
		)
		(property "Value" ""
			(at 0 0 90)
			(layer "B.Fab")
			(effects
				(font
					(size 1.27 1.27)
				)
				(justify mirror)
			)
		)
		(duplicate_pad_numbers_are_jumpers no)
		(fp_line
			(start 0.7874 -0.4064)
			(end -0.7874 -0.4064)
			(stroke
				(width 0.1524)
				(type default)
			)
			(layer "B.SilkS")
		)
		(fp_line
			(start -0.7874 -0.4064)
			(end -0.7874 0.4064)
			(stroke
				(width 0.1524)
				(type default)
			)
			(layer "B.SilkS")
		)
		(fp_line
			(start 0.7874 0.4064)
			(end 0.7874 -0.4064)
			(stroke
				(width 0.1524)
				(type default)
			)
			(layer "B.SilkS")
		)
		(fp_line
			(start -0.7874 0.4064)
			(end 0.7874 0.4064)
			(stroke
				(width 0.1524)
				(type default)
			)
			(layer "B.SilkS")
		)
		(fp_line
			(start 0.67945 -0.305054)
			(end 0.12065 -0.305054)
			(stroke
				(width 0.1)
				(type default)
			)
			(layer "B.Fab")
		)
		(fp_line
			(start 0.12065 -0.305054)
			(end 0.12065 -0.2794)
			(stroke
				(width 0.1)
				(type default)
			)
			(layer "B.Fab")
		)
		(fp_line
			(start -0.12065 -0.3048)
			(end -0.67945 -0.3048)
			(stroke
				(width 0.1)
				(type default)
			)
			(layer "B.Fab")
		)
		(fp_line
			(start -0.67945 -0.3048)
			(end -0.67945 0.3048)
			(stroke
				(width 0.1)
				(type default)
			)
			(layer "B.Fab")
		)
		(fp_line
			(start 0.12065 -0.2794)
			(end -0.12065 -0.2794)
			(stroke
				(width 0.1)
				(type default)
			)
			(layer "B.Fab")
		)
		(fp_line
			(start -0.12065 -0.2794)
			(end -0.12065 -0.3048)
			(stroke
				(width 0.1)
				(type default)
			)
			(layer "B.Fab")
		)
		(fp_line
			(start 0.12065 0.2794)
			(end 0.12065 0.3048)
			(stroke
				(width 0.1)
				(type default)
			)
			(layer "B.Fab")
		)
		(fp_line
			(start -0.120396 0.2794)
			(end 0.12065 0.2794)
			(stroke
				(width 0.1)
				(type default)
			)
			(layer "B.Fab")
		)
		(fp_line
			(start 0.67945 0.3048)
			(end 0.67945 -0.305054)
			(stroke
				(width 0.1)
				(type default)
			)
			(layer "B.Fab")
		)
		(fp_line
			(start 0.12065 0.3048)
			(end 0.67945 0.3048)
			(stroke
				(width 0.1)
				(type default)
			)
			(layer "B.Fab")
		)
		(fp_line
			(start -0.120396 0.3048)
			(end -0.120396 0.2794)
			(stroke
				(width 0.1)
				(type default)
			)
			(layer "B.Fab")
		)
		(fp_line
			(start -0.67945 0.3048)
			(end -0.120396 0.3048)
			(stroke
				(width 0.1)
				(type default)
			)
			(layer "B.Fab")
		)
		(pad "1" smd circle
			(at 0.40005 0 270)
			(size 0 0)
			(layers "B.Cu" "B.Mask" "B.Paste")
			(net "P0V8_PEX1_VCC1")
		)
		(pad "2" smd circle
			(at -0.40005 0 270)
			(size 0 0)
			(layers "B.Cu" "B.Mask" "B.Paste")
			(net "P0V8_PEX0_EN3")
		)
	)
	(footprint ""
		(layer "B.Cu")
		(at 108.171996 -325.148194 -90)
		(property "Reference" "C4215"
			(at 0 0 90)
			(layer "B.SilkS")
			(hide yes)
			(effects
				(font
					(size 1.27 1.27)
				)
				(justify mirror)
			)
		)
		(property "Value" ""
			(at 0 0 90)
			(layer "B.Fab")
			(effects
				(font
					(size 1.27 1.27)
				)
				(justify mirror)
			)
		)
		(duplicate_pad_numbers_are_jumpers no)
		(fp_line
			(start -1.2954 0.5842)
			(end 1.2954 0.5842)
			(stroke
				(width 0.1524)
				(type default)
			)
			(layer "B.SilkS")
		)
		(fp_line
			(start 1.2954 0.5842)
			(end 1.2954 -0.5842)
			(stroke
				(width 0.1524)
				(type default)
			)
			(layer "B.SilkS")
		)
		(fp_line
			(start -1.2954 -0.5842)
			(end -1.2954 0.5842)
			(stroke
				(width 0.1524)
				(type default)
			)
			(layer "B.SilkS")
		)
		(fp_line
			(start 1.2954 -0.5842)
			(end -1.2954 -0.5842)
			(stroke
				(width 0.1524)
				(type default)
			)
			(layer "B.SilkS")
		)
		(fp_line
			(start -0.8636 0.4572)
			(end 0.8636 0.4572)
			(stroke
				(width 0.1)
				(type default)
			)
			(layer "B.Fab")
		)
		(fp_line
			(start 0.8636 0.4572)
			(end 0.8636 0.4064)
			(stroke
				(width 0.1)
				(type default)
			)
			(layer "B.Fab")
		)
		(fp_line
			(start -1.1938 0.4064)
			(end -0.8636 0.4064)
			(stroke
				(width 0.1)
				(type default)
			)
			(layer "B.Fab")
		)
		(fp_line
			(start -0.8636 0.4064)
			(end -0.8636 0.4572)
			(stroke
				(width 0.1)
				(type default)
			)
			(layer "B.Fab")
		)
		(fp_line
			(start 0.8636 0.4064)
			(end 1.1938 0.4064)
			(stroke
				(width 0.1)
				(type default)
			)
			(layer "B.Fab")
		)
		(fp_line
			(start 1.1938 0.4064)
			(end 1.1938 -0.4064)
			(stroke
				(width 0.1)
				(type default)
			)
			(layer "B.Fab")
		)
		(fp_line
			(start -1.1938 -0.4064)
			(end -1.1938 0.4064)
			(stroke
				(width 0.1)
				(type default)
			)
			(layer "B.Fab")
		)
		(fp_line
			(start -0.8636 -0.4064)
			(end -1.1938 -0.4064)
			(stroke
				(width 0.1)
				(type default)
			)
			(layer "B.Fab")
		)
		(fp_line
			(start 0.8636 -0.4064)
			(end 0.8636 -0.4572)
			(stroke
				(width 0.1)
				(type default)
			)
			(layer "B.Fab")
		)
		(fp_line
			(start 1.1938 -0.4064)
			(end 0.8636 -0.4064)
			(stroke
				(width 0.1)
				(type default)
			)
			(layer "B.Fab")
		)
		(fp_line
			(start -0.8636 -0.4572)
			(end -0.8636 -0.4064)
			(stroke
				(width 0.1)
				(type default)
			)
			(layer "B.Fab")
		)
		(fp_line
			(start 0.8636 -0.4572)
			(end -0.8636 -0.4572)
			(stroke
				(width 0.1)
				(type default)
			)
			(layer "B.Fab")
		)
		(pad "1" smd rect
			(at 0.7366 0 180)
			(size 0.7112 0.8128)
			(layers "B.Cu" "B.Mask" "B.Paste")
			(net "P0V8_SERDES_VDDA_PEX0_C9")
		)
		(pad "2" smd rect
			(at -0.7366 0 180)
			(size 0.7112 0.8128)
			(layers "B.Cu" "B.Mask" "B.Paste")
			(net "GND")
		)
	)
	(footprint ""
		(layer "B.Cu")
		(at 12.458446 -214.304372 90)
		(property "Reference" "R6565"
			(at 0 0 90)
			(layer "B.SilkS")
			(hide yes)
			(effects
				(font
					(size 1.27 1.27)
				)
				(justify mirror)
			)
		)
		(property "Value" ""
			(at 0 0 90)
			(layer "B.Fab")
			(effects
				(font
					(size 1.27 1.27)
				)
				(justify mirror)
			)
		)
		(duplicate_pad_numbers_are_jumpers no)
		(fp_line
			(start 0.7874 -0.4064)
			(end -0.7874 -0.4064)
			(stroke
				(width 0.1524)
				(type default)
			)
			(layer "B.SilkS")
		)
		(fp_line
			(start -0.7874 -0.4064)
			(end -0.7874 0.4064)
			(stroke
				(width 0.1524)
				(type default)
			)
			(layer "B.SilkS")
		)
		(fp_line
			(start 0.7874 0.4064)
			(end 0.7874 -0.4064)
			(stroke
				(width 0.1524)
				(type default)
			)
			(layer "B.SilkS")
		)
		(fp_line
			(start -0.7874 0.4064)
			(end 0.7874 0.4064)
			(stroke
				(width 0.1524)
				(type default)
			)
			(layer "B.SilkS")
		)
		(fp_line
			(start 0.67945 -0.305054)
			(end 0.12065 -0.305054)
			(stroke
				(width 0.1)
				(type default)
			)
			(layer "B.Fab")
		)
		(fp_line
			(start 0.12065 -0.305054)
			(end 0.12065 -0.2794)
			(stroke
				(width 0.1)
				(type default)
			)
			(layer "B.Fab")
		)
		(fp_line
			(start -0.12065 -0.3048)
			(end -0.67945 -0.3048)
			(stroke
				(width 0.1)
				(type default)
			)
			(layer "B.Fab")
		)
		(fp_line
			(start -0.67945 -0.3048)
			(end -0.67945 0.3048)
			(stroke
				(width 0.1)
				(type default)
			)
			(layer "B.Fab")
		)
		(fp_line
			(start 0.12065 -0.2794)
			(end -0.12065 -0.2794)
			(stroke
				(width 0.1)
				(type default)
			)
			(layer "B.Fab")
		)
		(fp_line
			(start -0.12065 -0.2794)
			(end -0.12065 -0.3048)
			(stroke
				(width 0.1)
				(type default)
			)
			(layer "B.Fab")
		)
		(fp_line
			(start 0.12065 0.2794)
			(end 0.12065 0.3048)
			(stroke
				(width 0.1)
				(type default)
			)
			(layer "B.Fab")
		)
		(fp_line
			(start -0.120396 0.2794)
			(end 0.12065 0.2794)
			(stroke
				(width 0.1)
				(type default)
			)
			(layer "B.Fab")
		)
		(fp_line
			(start 0.67945 0.3048)
			(end 0.67945 -0.305054)
			(stroke
				(width 0.1)
				(type default)
			)
			(layer "B.Fab")
		)
		(fp_line
			(start 0.12065 0.3048)
			(end 0.67945 0.3048)
			(stroke
				(width 0.1)
				(type default)
			)
			(layer "B.Fab")
		)
		(fp_line
			(start -0.120396 0.3048)
			(end -0.120396 0.2794)
			(stroke
				(width 0.1)
				(type default)
			)
			(layer "B.Fab")
		)
		(fp_line
			(start -0.67945 0.3048)
			(end -0.120396 0.3048)
			(stroke
				(width 0.1)
				(type default)
			)
			(layer "B.Fab")
		)
		(pad "1" smd circle
			(at 0.40005 0 270)
			(size 0 0)
			(layers "B.Cu" "B.Mask" "B.Paste")
			(net "P3V3_AUX")
		)
		(pad "2" smd circle
			(at -0.40005 0 270)
			(size 0 0)
			(layers "B.Cu" "B.Mask" "B.Paste")
			(net "PEX0_P1V8_PLL_EN")
		)
	)
	(footprint ""
		(layer "B.Cu")
		(at 132.25399 -223.937068 90)
		(property "Reference" "R3459"
			(at 0 0 90)
			(layer "B.SilkS")
			(hide yes)
			(effects
				(font
					(size 1.27 1.27)
				)
				(justify mirror)
			)
		)
		(property "Value" ""
			(at 0 0 90)
			(layer "B.Fab")
			(effects
				(font
					(size 1.27 1.27)
				)
				(justify mirror)
			)
		)
		(duplicate_pad_numbers_are_jumpers no)
		(fp_line
			(start 0.7874 -0.4064)
			(end -0.7874 -0.4064)
			(stroke
				(width 0.1524)
				(type default)
			)
			(layer "B.SilkS")
		)
		(fp_line
			(start -0.7874 -0.4064)
			(end -0.7874 0.4064)
			(stroke
				(width 0.1524)
				(type default)
			)
			(layer "B.SilkS")
		)
		(fp_line
			(start 0.7874 0.4064)
			(end 0.7874 -0.4064)
			(stroke
				(width 0.1524)
				(type default)
			)
			(layer "B.SilkS")
		)
		(fp_line
			(start -0.7874 0.4064)
			(end 0.7874 0.4064)
			(stroke
				(width 0.1524)
				(type default)
			)
			(layer "B.SilkS")
		)
		(fp_line
			(start 0.67945 -0.305054)
			(end 0.12065 -0.305054)
			(stroke
				(width 0.1)
				(type default)
			)
			(layer "B.Fab")
		)
		(fp_line
			(start 0.12065 -0.305054)
			(end 0.12065 -0.2794)
			(stroke
				(width 0.1)
				(type default)
			)
			(layer "B.Fab")
		)
		(fp_line
			(start -0.12065 -0.3048)
			(end -0.67945 -0.3048)
			(stroke
				(width 0.1)
				(type default)
			)
			(layer "B.Fab")
		)
		(fp_line
			(start -0.67945 -0.3048)
			(end -0.67945 0.3048)
			(stroke
				(width 0.1)
				(type default)
			)
			(layer "B.Fab")
		)
		(fp_line
			(start 0.12065 -0.2794)
			(end -0.12065 -0.2794)
			(stroke
				(width 0.1)
				(type default)
			)
			(layer "B.Fab")
		)
		(fp_line
			(start -0.12065 -0.2794)
			(end -0.12065 -0.3048)
			(stroke
				(width 0.1)
				(type default)
			)
			(layer "B.Fab")
		)
		(fp_line
			(start 0.12065 0.2794)
			(end 0.12065 0.3048)
			(stroke
				(width 0.1)
				(type default)
			)
			(layer "B.Fab")
		)
		(fp_line
			(start -0.120396 0.2794)
			(end 0.12065 0.2794)
			(stroke
				(width 0.1)
				(type default)
			)
			(layer "B.Fab")
		)
		(fp_line
			(start 0.67945 0.3048)
			(end 0.67945 -0.305054)
			(stroke
				(width 0.1)
				(type default)
			)
			(layer "B.Fab")
		)
		(fp_line
			(start 0.12065 0.3048)
			(end 0.67945 0.3048)
			(stroke
				(width 0.1)
				(type default)
			)
			(layer "B.Fab")
		)
		(fp_line
			(start -0.120396 0.3048)
			(end -0.120396 0.2794)
			(stroke
				(width 0.1)
				(type default)
			)
			(layer "B.Fab")
		)
		(fp_line
			(start -0.67945 0.3048)
			(end -0.120396 0.3048)
			(stroke
				(width 0.1)
				(type default)
			)
			(layer "B.Fab")
		)
		(pad "1" smd circle
			(at 0.40005 0 270)
			(size 0 0)
			(layers "B.Cu" "B.Mask" "B.Paste")
			(net "SPI_MUX_PEX1_EN_N")
		)
		(pad "2" smd circle
			(at -0.40005 0 270)
			(size 0 0)
			(layers "B.Cu" "B.Mask" "B.Paste")
			(net "GND")
		)
	)
	(footprint ""
		(layer "B.Cu")
		(at 283.345636 -296.37482)
		(property "Reference" "C1628"
			(at 0 0 0)
			(layer "B.SilkS")
			(hide yes)
			(effects
				(font
					(size 1.27 1.27)
				)
				(justify mirror)
			)
		)
		(property "Value" ""
			(at 0 0 0)
			(layer "B.Fab")
			(effects
				(font
					(size 1.27 1.27)
				)
				(justify mirror)
			)
		)
		(duplicate_pad_numbers_are_jumpers no)
		(fp_line
			(start -0.299974 -0.150114)
			(end -0.299974 0.150114)
			(stroke
				(width 0.1)
				(type default)
			)
			(layer "B.Fab")
		)
		(fp_line
			(start -0.299974 0.150114)
			(end 0.299974 0.150114)
			(stroke
				(width 0.1)
				(type default)
			)
			(layer "B.Fab")
		)
		(fp_line
			(start 0.299974 -0.150114)
			(end -0.299974 -0.150114)
			(stroke
				(width 0.1)
				(type default)
			)
			(layer "B.Fab")
		)
		(fp_line
			(start 0.299974 0.150114)
			(end 0.299974 -0.150114)
			(stroke
				(width 0.1)
				(type default)
			)
			(layer "B.Fab")
		)
		(pad "1" smd rect
			(at 0.2667 0 180)
			(size 0.3048 0.381)
			(layers "B.Cu" "B.Mask" "B.Paste")
			(net "P0V8_PEX2")
		)
		(pad "2" smd rect
			(at -0.2667 0 180)
			(size 0.3048 0.381)
			(layers "B.Cu" "B.Mask" "B.Paste")
			(net "GND")
		)
	)
	(footprint ""
		(layer "B.Cu")
		(at 418.399976 -289.724846 180)
		(property "Reference" "C3528"
			(at 0 0 0)
			(layer "B.SilkS")
			(hide yes)
			(effects
				(font
					(size 1.27 1.27)
				)
				(justify mirror)
			)
		)
		(property "Value" ""
			(at 0 0 0)
			(layer "B.Fab")
			(effects
				(font
					(size 1.27 1.27)
				)
				(justify mirror)
			)
		)
		(duplicate_pad_numbers_are_jumpers no)
		(fp_line
			(start 0.299974 0.150114)
			(end 0.299974 -0.150114)
			(stroke
				(width 0.1)
				(type default)
			)
			(layer "B.Fab")
		)
		(fp_line
			(start 0.299974 -0.150114)
			(end -0.299974 -0.150114)
			(stroke
				(width 0.1)
				(type default)
			)
			(layer "B.Fab")
		)
		(fp_line
			(start -0.299974 0.150114)
			(end 0.299974 0.150114)
			(stroke
				(width 0.1)
				(type default)
			)
			(layer "B.Fab")
		)
		(fp_line
			(start -0.299974 -0.150114)
			(end -0.299974 0.150114)
			(stroke
				(width 0.1)
				(type default)
			)
			(layer "B.Fab")
		)
		(pad "1" smd rect
			(at 0.2667 0)
			(size 0.3048 0.381)
			(layers "B.Cu" "B.Mask" "B.Paste")
			(net "P1V8_PEX")
		)
		(pad "2" smd rect
			(at -0.2667 0)
			(size 0.3048 0.381)
			(layers "B.Cu" "B.Mask" "B.Paste")
			(net "GND")
		)
	)
	(footprint ""
		(layer "B.Cu")
		(at 348.477586 -254.55372 180)
		(property "Reference" "PR116"
			(at 0 0 0)
			(layer "B.SilkS")
			(hide yes)
			(effects
				(font
					(size 1.27 1.27)
				)
				(justify mirror)
			)
		)
		(property "Value" ""
			(at 0 0 0)
			(layer "B.Fab")
			(effects
				(font
					(size 1.27 1.27)
				)
				(justify mirror)
			)
		)
		(duplicate_pad_numbers_are_jumpers no)
		(fp_line
			(start 0.7874 0.4064)
			(end 0.7874 -0.4064)
			(stroke
				(width 0.1524)
				(type default)
			)
			(layer "B.SilkS")
		)
		(fp_line
			(start 0.7874 -0.4064)
			(end -0.7874 -0.4064)
			(stroke
				(width 0.1524)
				(type default)
			)
			(layer "B.SilkS")
		)
		(fp_line
			(start -0.7874 0.4064)
			(end 0.7874 0.4064)
			(stroke
				(width 0.1524)
				(type default)
			)
			(layer "B.SilkS")
		)
		(fp_line
			(start -0.7874 -0.4064)
			(end -0.7874 0.4064)
			(stroke
				(width 0.1524)
				(type default)
			)
			(layer "B.SilkS")
		)
		(fp_line
			(start 0.67945 0.3048)
			(end 0.67945 -0.305054)
			(stroke
				(width 0.1)
				(type default)
			)
			(layer "B.Fab")
		)
		(fp_line
			(start 0.67945 -0.305054)
			(end 0.12065 -0.305054)
			(stroke
				(width 0.1)
				(type default)
			)
			(layer "B.Fab")
		)
		(fp_line
			(start 0.12065 0.3048)
			(end 0.67945 0.3048)
			(stroke
				(width 0.1)
				(type default)
			)
			(layer "B.Fab")
		)
		(fp_line
			(start 0.12065 0.2794)
			(end 0.12065 0.3048)
			(stroke
				(width 0.1)
				(type default)
			)
			(layer "B.Fab")
		)
		(fp_line
			(start 0.12065 -0.2794)
			(end -0.12065 -0.2794)
			(stroke
				(width 0.1)
				(type default)
			)
			(layer "B.Fab")
		)
		(fp_line
			(start 0.12065 -0.305054)
			(end 0.12065 -0.2794)
			(stroke
				(width 0.1)
				(type default)
			)
			(layer "B.Fab")
		)
		(fp_line
			(start -0.120396 0.3048)
			(end -0.120396 0.2794)
			(stroke
				(width 0.1)
				(type default)
			)
			(layer "B.Fab")
		)
		(fp_line
			(start -0.120396 0.2794)
			(end 0.12065 0.2794)
			(stroke
				(width 0.1)
				(type default)
			)
			(layer "B.Fab")
		)
		(fp_line
			(start -0.12065 -0.2794)
			(end -0.12065 -0.3048)
			(stroke
				(width 0.1)
				(type default)
			)
			(layer "B.Fab")
		)
		(fp_line
			(start -0.12065 -0.3048)
			(end -0.67945 -0.3048)
			(stroke
				(width 0.1)
				(type default)
			)
			(layer "B.Fab")
		)
		(fp_line
			(start -0.67945 0.3048)
			(end -0.120396 0.3048)
			(stroke
				(width 0.1)
				(type default)
			)
			(layer "B.Fab")
		)
		(fp_line
			(start -0.67945 -0.3048)
			(end -0.67945 0.3048)
			(stroke
				(width 0.1)
				(type default)
			)
			(layer "B.Fab")
		)
		(pad "1" smd circle
			(at 0.40005 0)
			(size 0 0)
			(layers "B.Cu" "B.Mask" "B.Paste")
			(net "P3V3_AUX")
		)
		(pad "2" smd circle
			(at -0.40005 0)
			(size 0 0)
			(layers "B.Cu" "B.Mask" "B.Paste")
			(net "P0V8_PEX2_VDD")
		)
	)
	(footprint ""
		(layer "B.Cu")
		(at 286.149796 -301.599854 -90)
		(property "Reference" "C1714"
			(at 0 0 90)
			(layer "B.SilkS")
			(hide yes)
			(effects
				(font
					(size 1.27 1.27)
				)
				(justify mirror)
			)
		)
		(property "Value" ""
			(at 0 0 90)
			(layer "B.Fab")
			(effects
				(font
					(size 1.27 1.27)
				)
				(justify mirror)
			)
		)
		(duplicate_pad_numbers_are_jumpers no)
		(fp_line
			(start -0.299974 0.150114)
			(end 0.299974 0.150114)
			(stroke
				(width 0.1)
				(type default)
			)
			(layer "B.Fab")
		)
		(fp_line
			(start 0.299974 0.150114)
			(end 0.299974 -0.150114)
			(stroke
				(width 0.1)
				(type default)
			)
			(layer "B.Fab")
		)
		(fp_line
			(start -0.299974 -0.150114)
			(end -0.299974 0.150114)
			(stroke
				(width 0.1)
				(type default)
			)
			(layer "B.Fab")
		)
		(fp_line
			(start 0.299974 -0.150114)
			(end -0.299974 -0.150114)
			(stroke
				(width 0.1)
				(type default)
			)
			(layer "B.Fab")
		)
		(pad "1" smd rect
			(at 0.2667 0 90)
			(size 0.3048 0.381)
			(layers "B.Cu" "B.Mask" "B.Paste")
			(net "P0V8_SERDES_VDDA_PEX2")
		)
		(pad "2" smd rect
			(at -0.2667 0 90)
			(size 0.3048 0.381)
			(layers "B.Cu" "B.Mask" "B.Paste")
			(net "GND")
		)
	)
	(footprint ""
		(layer "B.Cu")
		(at 346.65031 -256.226564 -90)
		(property "Reference" "PR146"
			(at 0 0 90)
			(layer "B.SilkS")
			(hide yes)
			(effects
				(font
					(size 1.27 1.27)
				)
				(justify mirror)
			)
		)
		(property "Value" ""
			(at 0 0 90)
			(layer "B.Fab")
			(effects
				(font
					(size 1.27 1.27)
				)
				(justify mirror)
			)
		)
		(duplicate_pad_numbers_are_jumpers no)
		(fp_line
			(start -0.7874 0.4064)
			(end 0.7874 0.4064)
			(stroke
				(width 0.1524)
				(type default)
			)
			(layer "B.SilkS")
		)
		(fp_line
			(start 0.7874 0.4064)
			(end 0.7874 -0.4064)
			(stroke
				(width 0.1524)
				(type default)
			)
			(layer "B.SilkS")
		)
		(fp_line
			(start -0.7874 -0.4064)
			(end -0.7874 0.4064)
			(stroke
				(width 0.1524)
				(type default)
			)
			(layer "B.SilkS")
		)
		(fp_line
			(start 0.7874 -0.4064)
			(end -0.7874 -0.4064)
			(stroke
				(width 0.1524)
				(type default)
			)
			(layer "B.SilkS")
		)
		(fp_line
			(start -0.67945 0.3048)
			(end -0.120396 0.3048)
			(stroke
				(width 0.1)
				(type default)
			)
			(layer "B.Fab")
		)
		(fp_line
			(start -0.120396 0.3048)
			(end -0.120396 0.2794)
			(stroke
				(width 0.1)
				(type default)
			)
			(layer "B.Fab")
		)
		(fp_line
			(start 0.12065 0.3048)
			(end 0.67945 0.3048)
			(stroke
				(width 0.1)
				(type default)
			)
			(layer "B.Fab")
		)
		(fp_line
			(start 0.67945 0.3048)
			(end 0.67945 -0.305054)
			(stroke
				(width 0.1)
				(type default)
			)
			(layer "B.Fab")
		)
		(fp_line
			(start -0.120396 0.2794)
			(end 0.12065 0.2794)
			(stroke
				(width 0.1)
				(type default)
			)
			(layer "B.Fab")
		)
		(fp_line
			(start 0.12065 0.2794)
			(end 0.12065 0.3048)
			(stroke
				(width 0.1)
				(type default)
			)
			(layer "B.Fab")
		)
		(fp_line
			(start -0.12065 -0.2794)
			(end -0.12065 -0.3048)
			(stroke
				(width 0.1)
				(type default)
			)
			(layer "B.Fab")
		)
		(fp_line
			(start 0.12065 -0.2794)
			(end -0.12065 -0.2794)
			(stroke
				(width 0.1)
				(type default)
			)
			(layer "B.Fab")
		)
		(fp_line
			(start -0.67945 -0.3048)
			(end -0.67945 0.3048)
			(stroke
				(width 0.1)
				(type default)
			)
			(layer "B.Fab")
		)
		(fp_line
			(start -0.12065 -0.3048)
			(end -0.67945 -0.3048)
			(stroke
				(width 0.1)
				(type default)
			)
			(layer "B.Fab")
		)
		(fp_line
			(start 0.12065 -0.305054)
			(end 0.12065 -0.2794)
			(stroke
				(width 0.1)
				(type default)
			)
			(layer "B.Fab")
		)
		(fp_line
			(start 0.67945 -0.305054)
			(end 0.12065 -0.305054)
			(stroke
				(width 0.1)
				(type default)
			)
			(layer "B.Fab")
		)
		(pad "1" smd circle
			(at 0.40005 0 90)
			(size 0 0)
			(layers "B.Cu" "B.Mask" "B.Paste")
			(net "P12V_AUX")
		)
		(pad "2" smd circle
			(at -0.40005 0 90)
			(size 0 0)
			(layers "B.Cu" "B.Mask" "B.Paste")
			(net "P0V8_PEX2_VINSEN")
		)
	)
	(footprint ""
		(layer "B.Cu")
		(at 281.755342 -156.0576)
		(property "Reference" "R232"
			(at 0 0 0)
			(layer "B.SilkS")
			(hide yes)
			(effects
				(font
					(size 1.27 1.27)
				)
				(justify mirror)
			)
		)
		(property "Value" ""
			(at 0 0 0)
			(layer "B.Fab")
			(effects
				(font
					(size 1.27 1.27)
				)
				(justify mirror)
			)
		)
		(duplicate_pad_numbers_are_jumpers no)
		(fp_line
			(start -0.7874 -0.4064)
			(end -0.7874 0.4064)
			(stroke
				(width 0.1524)
				(type default)
			)
			(layer "B.SilkS")
		)
		(fp_line
			(start -0.7874 0.4064)
			(end 0.7874 0.4064)
			(stroke
				(width 0.1524)
				(type default)
			)
			(layer "B.SilkS")
		)
		(fp_line
			(start 0.7874 -0.4064)
			(end -0.7874 -0.4064)
			(stroke
				(width 0.1524)
				(type default)
			)
			(layer "B.SilkS")
		)
		(fp_line
			(start 0.7874 0.4064)
			(end 0.7874 -0.4064)
			(stroke
				(width 0.1524)
				(type default)
			)
			(layer "B.SilkS")
		)
		(fp_line
			(start -0.67945 -0.3048)
			(end -0.67945 0.3048)
			(stroke
				(width 0.1)
				(type default)
			)
			(layer "B.Fab")
		)
		(fp_line
			(start -0.67945 0.3048)
			(end -0.120396 0.3048)
			(stroke
				(width 0.1)
				(type default)
			)
			(layer "B.Fab")
		)
		(fp_line
			(start -0.12065 -0.3048)
			(end -0.67945 -0.3048)
			(stroke
				(width 0.1)
				(type default)
			)
			(layer "B.Fab")
		)
		(fp_line
			(start -0.12065 -0.2794)
			(end -0.12065 -0.3048)
			(stroke
				(width 0.1)
				(type default)
			)
			(layer "B.Fab")
		)
		(fp_line
			(start -0.120396 0.2794)
			(end 0.12065 0.2794)
			(stroke
				(width 0.1)
				(type default)
			)
			(layer "B.Fab")
		)
		(fp_line
			(start -0.120396 0.3048)
			(end -0.120396 0.2794)
			(stroke
				(width 0.1)
				(type default)
			)
			(layer "B.Fab")
		)
		(fp_line
			(start 0.12065 -0.305054)
			(end 0.12065 -0.2794)
			(stroke
				(width 0.1)
				(type default)
			)
			(layer "B.Fab")
		)
		(fp_line
			(start 0.12065 -0.2794)
			(end -0.12065 -0.2794)
			(stroke
				(width 0.1)
				(type default)
			)
			(layer "B.Fab")
		)
		(fp_line
			(start 0.12065 0.2794)
			(end 0.12065 0.3048)
			(stroke
				(width 0.1)
				(type default)
			)
			(layer "B.Fab")
		)
		(fp_line
			(start 0.12065 0.3048)
			(end 0.67945 0.3048)
			(stroke
				(width 0.1)
				(type default)
			)
			(layer "B.Fab")
		)
		(fp_line
			(start 0.67945 -0.305054)
			(end 0.12065 -0.305054)
			(stroke
				(width 0.1)
				(type default)
			)
			(layer "B.Fab")
		)
		(fp_line
			(start 0.67945 0.3048)
			(end 0.67945 -0.305054)
			(stroke
				(width 0.1)
				(type default)
			)
			(layer "B.Fab")
		)
		(pad "1" smd circle
			(at 0.40005 0 180)
			(size 0 0)
			(layers "B.Cu" "B.Mask" "B.Paste")
			(net "NIC4_SLOT_ID1")
		)
		(pad "2" smd circle
			(at -0.40005 0 180)
			(size 0 0)
			(layers "B.Cu" "B.Mask" "B.Paste")
			(net "GND")
		)
	)
	(footprint ""
		(layer "B.Cu")
		(at 232.620312 -208.809082)
		(property "Reference" "R6152"
			(at 0 0 0)
			(layer "B.SilkS")
			(hide yes)
			(effects
				(font
					(size 1.27 1.27)
				)
				(justify mirror)
			)
		)
		(property "Value" ""
			(at 0 0 0)
			(layer "B.Fab")
			(effects
				(font
					(size 1.27 1.27)
				)
				(justify mirror)
			)
		)
		(duplicate_pad_numbers_are_jumpers no)
		(fp_line
			(start -0.7874 -0.4064)
			(end -0.7874 0.4064)
			(stroke
				(width 0.1524)
				(type default)
			)
			(layer "B.SilkS")
		)
		(fp_line
			(start -0.7874 0.4064)
			(end 0.7874 0.4064)
			(stroke
				(width 0.1524)
				(type default)
			)
			(layer "B.SilkS")
		)
		(fp_line
			(start 0.7874 -0.4064)
			(end -0.7874 -0.4064)
			(stroke
				(width 0.1524)
				(type default)
			)
			(layer "B.SilkS")
		)
		(fp_line
			(start 0.7874 0.4064)
			(end 0.7874 -0.4064)
			(stroke
				(width 0.1524)
				(type default)
			)
			(layer "B.SilkS")
		)
		(fp_line
			(start -0.67945 -0.3048)
			(end -0.67945 0.3048)
			(stroke
				(width 0.1)
				(type default)
			)
			(layer "B.Fab")
		)
		(fp_line
			(start -0.67945 0.3048)
			(end -0.120396 0.3048)
			(stroke
				(width 0.1)
				(type default)
			)
			(layer "B.Fab")
		)
		(fp_line
			(start -0.12065 -0.3048)
			(end -0.67945 -0.3048)
			(stroke
				(width 0.1)
				(type default)
			)
			(layer "B.Fab")
		)
		(fp_line
			(start -0.12065 -0.2794)
			(end -0.12065 -0.3048)
			(stroke
				(width 0.1)
				(type default)
			)
			(layer "B.Fab")
		)
		(fp_line
			(start -0.120396 0.2794)
			(end 0.12065 0.2794)
			(stroke
				(width 0.1)
				(type default)
			)
			(layer "B.Fab")
		)
		(fp_line
			(start -0.120396 0.3048)
			(end -0.120396 0.2794)
			(stroke
				(width 0.1)
				(type default)
			)
			(layer "B.Fab")
		)
		(fp_line
			(start 0.12065 -0.305054)
			(end 0.12065 -0.2794)
			(stroke
				(width 0.1)
				(type default)
			)
			(layer "B.Fab")
		)
		(fp_line
			(start 0.12065 -0.2794)
			(end -0.12065 -0.2794)
			(stroke
				(width 0.1)
				(type default)
			)
			(layer "B.Fab")
		)
		(fp_line
			(start 0.12065 0.2794)
			(end 0.12065 0.3048)
			(stroke
				(width 0.1)
				(type default)
			)
			(layer "B.Fab")
		)
		(fp_line
			(start 0.12065 0.3048)
			(end 0.67945 0.3048)
			(stroke
				(width 0.1)
				(type default)
			)
			(layer "B.Fab")
		)
		(fp_line
			(start 0.67945 -0.305054)
			(end 0.12065 -0.305054)
			(stroke
				(width 0.1)
				(type default)
			)
			(layer "B.Fab")
		)
		(fp_line
			(start 0.67945 0.3048)
			(end 0.67945 -0.305054)
			(stroke
				(width 0.1)
				(type default)
			)
			(layer "B.Fab")
		)
		(pad "1" smd circle
			(at 0.40005 0 180)
			(size 0 0)
			(layers "B.Cu" "B.Mask" "B.Paste")
			(net "BIC_SPI1DQ3")
		)
		(pad "2" smd circle
			(at -0.40005 0 180)
			(size 0 0)
			(layers "B.Cu" "B.Mask" "B.Paste")
			(net "P3V3_AUX")
		)
	)
	(footprint ""
		(layer "B.Cu")
		(at 305.471576 -114.592608)
		(property "Reference" "C929"
			(at 0 0 0)
			(layer "B.SilkS")
			(hide yes)
			(effects
				(font
					(size 1.27 1.27)
				)
				(justify mirror)
			)
		)
		(property "Value" ""
			(at 0 0 0)
			(layer "B.Fab")
			(effects
				(font
					(size 1.27 1.27)
				)
				(justify mirror)
			)
		)
		(duplicate_pad_numbers_are_jumpers no)
		(fp_line
			(start -0.7874 -0.4064)
			(end -0.7874 0.4064)
			(stroke
				(width 0.1524)
				(type default)
			)
			(layer "B.SilkS")
		)
		(fp_line
			(start -0.7874 0.4064)
			(end 0.7874 0.4064)
			(stroke
				(width 0.1524)
				(type default)
			)
			(layer "B.SilkS")
		)
		(fp_line
			(start 0.7874 -0.4064)
			(end -0.7874 -0.4064)
			(stroke
				(width 0.1524)
				(type default)
			)
			(layer "B.SilkS")
		)
		(fp_line
			(start 0.7874 0.4064)
			(end 0.7874 -0.4064)
			(stroke
				(width 0.1524)
				(type default)
			)
			(layer "B.SilkS")
		)
		(fp_line
			(start -0.67945 -0.3048)
			(end -0.67945 0.3048)
			(stroke
				(width 0.1)
				(type default)
			)
			(layer "B.Fab")
		)
		(fp_line
			(start -0.67945 0.3048)
			(end -0.120396 0.3048)
			(stroke
				(width 0.1)
				(type default)
			)
			(layer "B.Fab")
		)
		(fp_line
			(start -0.12065 -0.3048)
			(end -0.67945 -0.3048)
			(stroke
				(width 0.1)
				(type default)
			)
			(layer "B.Fab")
		)
		(fp_line
			(start -0.12065 -0.2794)
			(end -0.12065 -0.3048)
			(stroke
				(width 0.1)
				(type default)
			)
			(layer "B.Fab")
		)
		(fp_line
			(start -0.120396 0.2794)
			(end 0.12065 0.2794)
			(stroke
				(width 0.1)
				(type default)
			)
			(layer "B.Fab")
		)
		(fp_line
			(start -0.120396 0.3048)
			(end -0.120396 0.2794)
			(stroke
				(width 0.1)
				(type default)
			)
			(layer "B.Fab")
		)
		(fp_line
			(start 0.12065 -0.305054)
			(end 0.12065 -0.2794)
			(stroke
				(width 0.1)
				(type default)
			)
			(layer "B.Fab")
		)
		(fp_line
			(start 0.12065 -0.2794)
			(end -0.12065 -0.2794)
			(stroke
				(width 0.1)
				(type default)
			)
			(layer "B.Fab")
		)
		(fp_line
			(start 0.12065 0.2794)
			(end 0.12065 0.3048)
			(stroke
				(width 0.1)
				(type default)
			)
			(layer "B.Fab")
		)
		(fp_line
			(start 0.12065 0.3048)
			(end 0.67945 0.3048)
			(stroke
				(width 0.1)
				(type default)
			)
			(layer "B.Fab")
		)
		(fp_line
			(start 0.67945 -0.305054)
			(end 0.12065 -0.305054)
			(stroke
				(width 0.1)
				(type default)
			)
			(layer "B.Fab")
		)
		(fp_line
			(start 0.67945 0.3048)
			(end 0.67945 -0.305054)
			(stroke
				(width 0.1)
				(type default)
			)
			(layer "B.Fab")
		)
		(pad "1" smd circle
			(at 0.40005 0 180)
			(size 0 0)
			(layers "B.Cu" "B.Mask" "B.Paste")
			(net "P3V3_NIC5")
		)
		(pad "2" smd circle
			(at -0.40005 0 180)
			(size 0 0)
			(layers "B.Cu" "B.Mask" "B.Paste")
			(net "GND")
		)
	)
	(footprint ""
		(layer "B.Cu")
		(at 421.700198 -110.115096)
		(property "Reference" "C954"
			(at 0 0 0)
			(layer "B.SilkS")
			(hide yes)
			(effects
				(font
					(size 1.27 1.27)
				)
				(justify mirror)
			)
		)
		(property "Value" ""
			(at 0 0 0)
			(layer "B.Fab")
			(effects
				(font
					(size 1.27 1.27)
				)
				(justify mirror)
			)
		)
		(duplicate_pad_numbers_are_jumpers no)
		(fp_line
			(start -0.299974 -0.150114)
			(end -0.299974 0.150114)
			(stroke
				(width 0.1)
				(type default)
			)
			(layer "B.Fab")
		)
		(fp_line
			(start -0.299974 0.150114)
			(end 0.299974 0.150114)
			(stroke
				(width 0.1)
				(type default)
			)
			(layer "B.Fab")
		)
		(fp_line
			(start 0.299974 -0.150114)
			(end -0.299974 -0.150114)
			(stroke
				(width 0.1)
				(type default)
			)
			(layer "B.Fab")
		)
		(fp_line
			(start 0.299974 0.150114)
			(end 0.299974 -0.150114)
			(stroke
				(width 0.1)
				(type default)
			)
			(layer "B.Fab")
		)
		(pad "1" smd rect
			(at 0.2667 0 180)
			(size 0.3048 0.381)
			(layers "B.Cu" "B.Mask" "B.Paste")
			(net "P12V_NIC7")
		)
		(pad "2" smd rect
			(at -0.2667 0 180)
			(size 0.3048 0.381)
			(layers "B.Cu" "B.Mask" "B.Paste")
			(net "GND")
		)
	)
	(footprint ""
		(layer "B.Cu")
		(at 66.299842 -290.199826 90)
		(property "Reference" "C1172"
			(at 0 0 90)
			(layer "B.SilkS")
			(hide yes)
			(effects
				(font
					(size 1.27 1.27)
				)
				(justify mirror)
			)
		)
		(property "Value" ""
			(at 0 0 90)
			(layer "B.Fab")
			(effects
				(font
					(size 1.27 1.27)
				)
				(justify mirror)
			)
		)
		(duplicate_pad_numbers_are_jumpers no)
		(fp_line
			(start 0.299974 -0.150114)
			(end -0.299974 -0.150114)
			(stroke
				(width 0.1)
				(type default)
			)
			(layer "B.Fab")
		)
		(fp_line
			(start -0.299974 -0.150114)
			(end -0.299974 0.150114)
			(stroke
				(width 0.1)
				(type default)
			)
			(layer "B.Fab")
		)
		(fp_line
			(start 0.299974 0.150114)
			(end 0.299974 -0.150114)
			(stroke
				(width 0.1)
				(type default)
			)
			(layer "B.Fab")
		)
		(fp_line
			(start -0.299974 0.150114)
			(end 0.299974 0.150114)
			(stroke
				(width 0.1)
				(type default)
			)
			(layer "B.Fab")
		)
		(pad "1" smd rect
			(at 0.2667 0 270)
			(size 0.3048 0.381)
			(layers "B.Cu" "B.Mask" "B.Paste")
			(net "P0V8_SERDES_VDDA_PEX0")
		)
		(pad "2" smd rect
			(at -0.2667 0 270)
			(size 0.3048 0.381)
			(layers "B.Cu" "B.Mask" "B.Paste")
			(net "GND")
		)
	)
	(footprint ""
		(layer "B.Cu")
		(at 255.374902 -228.346 90)
		(property "Reference" "R3480"
			(at 0 0 90)
			(layer "B.SilkS")
			(hide yes)
			(effects
				(font
					(size 1.27 1.27)
				)
				(justify mirror)
			)
		)
		(property "Value" ""
			(at 0 0 90)
			(layer "B.Fab")
			(effects
				(font
					(size 1.27 1.27)
				)
				(justify mirror)
			)
		)
		(duplicate_pad_numbers_are_jumpers no)
		(fp_line
			(start 0.7874 -0.4064)
			(end -0.7874 -0.4064)
			(stroke
				(width 0.1524)
				(type default)
			)
			(layer "B.SilkS")
		)
		(fp_line
			(start -0.7874 -0.4064)
			(end -0.7874 0.4064)
			(stroke
				(width 0.1524)
				(type default)
			)
			(layer "B.SilkS")
		)
		(fp_line
			(start 0.7874 0.4064)
			(end 0.7874 -0.4064)
			(stroke
				(width 0.1524)
				(type default)
			)
			(layer "B.SilkS")
		)
		(fp_line
			(start -0.7874 0.4064)
			(end 0.7874 0.4064)
			(stroke
				(width 0.1524)
				(type default)
			)
			(layer "B.SilkS")
		)
		(fp_line
			(start 0.67945 -0.305054)
			(end 0.12065 -0.305054)
			(stroke
				(width 0.1)
				(type default)
			)
			(layer "B.Fab")
		)
		(fp_line
			(start 0.12065 -0.305054)
			(end 0.12065 -0.2794)
			(stroke
				(width 0.1)
				(type default)
			)
			(layer "B.Fab")
		)
		(fp_line
			(start -0.12065 -0.3048)
			(end -0.67945 -0.3048)
			(stroke
				(width 0.1)
				(type default)
			)
			(layer "B.Fab")
		)
		(fp_line
			(start -0.67945 -0.3048)
			(end -0.67945 0.3048)
			(stroke
				(width 0.1)
				(type default)
			)
			(layer "B.Fab")
		)
		(fp_line
			(start 0.12065 -0.2794)
			(end -0.12065 -0.2794)
			(stroke
				(width 0.1)
				(type default)
			)
			(layer "B.Fab")
		)
		(fp_line
			(start -0.12065 -0.2794)
			(end -0.12065 -0.3048)
			(stroke
				(width 0.1)
				(type default)
			)
			(layer "B.Fab")
		)
		(fp_line
			(start 0.12065 0.2794)
			(end 0.12065 0.3048)
			(stroke
				(width 0.1)
				(type default)
			)
			(layer "B.Fab")
		)
		(fp_line
			(start -0.120396 0.2794)
			(end 0.12065 0.2794)
			(stroke
				(width 0.1)
				(type default)
			)
			(layer "B.Fab")
		)
		(fp_line
			(start 0.67945 0.3048)
			(end 0.67945 -0.305054)
			(stroke
				(width 0.1)
				(type default)
			)
			(layer "B.Fab")
		)
		(fp_line
			(start 0.12065 0.3048)
			(end 0.67945 0.3048)
			(stroke
				(width 0.1)
				(type default)
			)
			(layer "B.Fab")
		)
		(fp_line
			(start -0.120396 0.3048)
			(end -0.120396 0.2794)
			(stroke
				(width 0.1)
				(type default)
			)
			(layer "B.Fab")
		)
		(fp_line
			(start -0.67945 0.3048)
			(end -0.120396 0.3048)
			(stroke
				(width 0.1)
				(type default)
			)
			(layer "B.Fab")
		)
		(pad "1" smd circle
			(at 0.40005 0 270)
			(size 0 0)
			(layers "B.Cu" "B.Mask" "B.Paste")
			(net "SPI_PEX2_SDIO1_MUX_R")
		)
		(pad "2" smd circle
			(at -0.40005 0 270)
			(size 0 0)
			(layers "B.Cu" "B.Mask" "B.Paste")
			(net "SPI_PEX2_SDIO1_MUX")
		)
	)
	(footprint ""
		(layer "B.Cu")
		(at 117.95379 -260.39572 -90)
		(property "Reference" "PR90"
			(at 0 0 90)
			(layer "B.SilkS")
			(hide yes)
			(effects
				(font
					(size 1.27 1.27)
				)
				(justify mirror)
			)
		)
		(property "Value" ""
			(at 0 0 90)
			(layer "B.Fab")
			(effects
				(font
					(size 1.27 1.27)
				)
				(justify mirror)
			)
		)
		(duplicate_pad_numbers_are_jumpers no)
		(fp_line
			(start -0.7874 0.4064)
			(end 0.7874 0.4064)
			(stroke
				(width 0.1524)
				(type default)
			)
			(layer "B.SilkS")
		)
		(fp_line
			(start 0.7874 0.4064)
			(end 0.7874 -0.4064)
			(stroke
				(width 0.1524)
				(type default)
			)
			(layer "B.SilkS")
		)
		(fp_line
			(start -0.7874 -0.4064)
			(end -0.7874 0.4064)
			(stroke
				(width 0.1524)
				(type default)
			)
			(layer "B.SilkS")
		)
		(fp_line
			(start 0.7874 -0.4064)
			(end -0.7874 -0.4064)
			(stroke
				(width 0.1524)
				(type default)
			)
			(layer "B.SilkS")
		)
		(fp_line
			(start -0.67945 0.3048)
			(end -0.120396 0.3048)
			(stroke
				(width 0.1)
				(type default)
			)
			(layer "B.Fab")
		)
		(fp_line
			(start -0.120396 0.3048)
			(end -0.120396 0.2794)
			(stroke
				(width 0.1)
				(type default)
			)
			(layer "B.Fab")
		)
		(fp_line
			(start 0.12065 0.3048)
			(end 0.67945 0.3048)
			(stroke
				(width 0.1)
				(type default)
			)
			(layer "B.Fab")
		)
		(fp_line
			(start 0.67945 0.3048)
			(end 0.67945 -0.305054)
			(stroke
				(width 0.1)
				(type default)
			)
			(layer "B.Fab")
		)
		(fp_line
			(start -0.120396 0.2794)
			(end 0.12065 0.2794)
			(stroke
				(width 0.1)
				(type default)
			)
			(layer "B.Fab")
		)
		(fp_line
			(start 0.12065 0.2794)
			(end 0.12065 0.3048)
			(stroke
				(width 0.1)
				(type default)
			)
			(layer "B.Fab")
		)
		(fp_line
			(start -0.12065 -0.2794)
			(end -0.12065 -0.3048)
			(stroke
				(width 0.1)
				(type default)
			)
			(layer "B.Fab")
		)
		(fp_line
			(start 0.12065 -0.2794)
			(end -0.12065 -0.2794)
			(stroke
				(width 0.1)
				(type default)
			)
			(layer "B.Fab")
		)
		(fp_line
			(start -0.67945 -0.3048)
			(end -0.67945 0.3048)
			(stroke
				(width 0.1)
				(type default)
			)
			(layer "B.Fab")
		)
		(fp_line
			(start -0.12065 -0.3048)
			(end -0.67945 -0.3048)
			(stroke
				(width 0.1)
				(type default)
			)
			(layer "B.Fab")
		)
		(fp_line
			(start 0.12065 -0.305054)
			(end 0.12065 -0.2794)
			(stroke
				(width 0.1)
				(type default)
			)
			(layer "B.Fab")
		)
		(fp_line
			(start 0.67945 -0.305054)
			(end 0.12065 -0.305054)
			(stroke
				(width 0.1)
				(type default)
			)
			(layer "B.Fab")
		)
		(pad "1" smd circle
			(at 0.40005 0 90)
			(size 0 0)
			(layers "B.Cu" "B.Mask" "B.Paste")
			(net "P0V8_PEX1_TSEN_R")
		)
		(pad "2" smd circle
			(at -0.40005 0 90)
			(size 0 0)
			(layers "B.Cu" "B.Mask" "B.Paste")
			(net "P0V8_PEX1_TSEN")
		)
	)
	(footprint ""
		(layer "B.Cu")
		(at 54.36997 -305.399948 -90)
		(property "Reference" "C2973"
			(at 0 0 90)
			(layer "B.SilkS")
			(hide yes)
			(effects
				(font
					(size 1.27 1.27)
				)
				(justify mirror)
			)
		)
		(property "Value" ""
			(at 0 0 90)
			(layer "B.Fab")
			(effects
				(font
					(size 1.27 1.27)
				)
				(justify mirror)
			)
		)
		(duplicate_pad_numbers_are_jumpers no)
		(fp_line
			(start -0.299974 0.150114)
			(end 0.299974 0.150114)
			(stroke
				(width 0.1)
				(type default)
			)
			(layer "B.Fab")
		)
		(fp_line
			(start 0.299974 0.150114)
			(end 0.299974 -0.150114)
			(stroke
				(width 0.1)
				(type default)
			)
			(layer "B.Fab")
		)
		(fp_line
			(start -0.299974 -0.150114)
			(end -0.299974 0.150114)
			(stroke
				(width 0.1)
				(type default)
			)
			(layer "B.Fab")
		)
		(fp_line
			(start 0.299974 -0.150114)
			(end -0.299974 -0.150114)
			(stroke
				(width 0.1)
				(type default)
			)
			(layer "B.Fab")
		)
		(pad "1" smd rect
			(at 0.2667 0 90)
			(size 0.3048 0.381)
			(layers "B.Cu" "B.Mask" "B.Paste")
			(net "P1V25_SERDES_VDDPLL_PEX0")
		)
		(pad "2" smd rect
			(at -0.2667 0 90)
			(size 0.3048 0.381)
			(layers "B.Cu" "B.Mask" "B.Paste")
			(net "GND")
		)
	)
	(footprint ""
		(layer "B.Cu")
		(at 117.653054 -163.598098)
		(property "Reference" "R823"
			(at 0 0 0)
			(layer "B.SilkS")
			(hide yes)
			(effects
				(font
					(size 1.27 1.27)
				)
				(justify mirror)
			)
		)
		(property "Value" ""
			(at 0 0 0)
			(layer "B.Fab")
			(effects
				(font
					(size 1.27 1.27)
				)
				(justify mirror)
			)
		)
		(duplicate_pad_numbers_are_jumpers no)
		(fp_line
			(start -0.7874 -0.4064)
			(end -0.7874 0.4064)
			(stroke
				(width 0.1524)
				(type default)
			)
			(layer "B.SilkS")
		)
		(fp_line
			(start -0.7874 0.4064)
			(end 0.7874 0.4064)
			(stroke
				(width 0.1524)
				(type default)
			)
			(layer "B.SilkS")
		)
		(fp_line
			(start 0.7874 -0.4064)
			(end -0.7874 -0.4064)
			(stroke
				(width 0.1524)
				(type default)
			)
			(layer "B.SilkS")
		)
		(fp_line
			(start 0.7874 0.4064)
			(end 0.7874 -0.4064)
			(stroke
				(width 0.1524)
				(type default)
			)
			(layer "B.SilkS")
		)
		(fp_line
			(start -0.67945 -0.3048)
			(end -0.67945 0.3048)
			(stroke
				(width 0.1)
				(type default)
			)
			(layer "B.Fab")
		)
		(fp_line
			(start -0.67945 0.3048)
			(end -0.120396 0.3048)
			(stroke
				(width 0.1)
				(type default)
			)
			(layer "B.Fab")
		)
		(fp_line
			(start -0.12065 -0.3048)
			(end -0.67945 -0.3048)
			(stroke
				(width 0.1)
				(type default)
			)
			(layer "B.Fab")
		)
		(fp_line
			(start -0.12065 -0.2794)
			(end -0.12065 -0.3048)
			(stroke
				(width 0.1)
				(type default)
			)
			(layer "B.Fab")
		)
		(fp_line
			(start -0.120396 0.2794)
			(end 0.12065 0.2794)
			(stroke
				(width 0.1)
				(type default)
			)
			(layer "B.Fab")
		)
		(fp_line
			(start -0.120396 0.3048)
			(end -0.120396 0.2794)
			(stroke
				(width 0.1)
				(type default)
			)
			(layer "B.Fab")
		)
		(fp_line
			(start 0.12065 -0.305054)
			(end 0.12065 -0.2794)
			(stroke
				(width 0.1)
				(type default)
			)
			(layer "B.Fab")
		)
		(fp_line
			(start 0.12065 -0.2794)
			(end -0.12065 -0.2794)
			(stroke
				(width 0.1)
				(type default)
			)
			(layer "B.Fab")
		)
		(fp_line
			(start 0.12065 0.2794)
			(end 0.12065 0.3048)
			(stroke
				(width 0.1)
				(type default)
			)
			(layer "B.Fab")
		)
		(fp_line
			(start 0.12065 0.3048)
			(end 0.67945 0.3048)
			(stroke
				(width 0.1)
				(type default)
			)
			(layer "B.Fab")
		)
		(fp_line
			(start 0.67945 -0.305054)
			(end 0.12065 -0.305054)
			(stroke
				(width 0.1)
				(type default)
			)
			(layer "B.Fab")
		)
		(fp_line
			(start 0.67945 0.3048)
			(end 0.67945 -0.305054)
			(stroke
				(width 0.1)
				(type default)
			)
			(layer "B.Fab")
		)
		(pad "1" smd circle
			(at 0.40005 0 180)
			(size 0 0)
			(layers "B.Cu" "B.Mask" "B.Paste")
			(net "P3V3_AUX_VCC")
		)
		(pad "2" smd circle
			(at -0.40005 0 180)
			(size 0 0)
			(layers "B.Cu" "B.Mask" "B.Paste")
			(net "PWRGD_P3V3_AUX")
		)
	)
	(footprint ""
		(layer "B.Cu")
		(at 165.655244 -153.0096)
		(property "Reference" "R121"
			(at 0 0 0)
			(layer "B.SilkS")
			(hide yes)
			(effects
				(font
					(size 1.27 1.27)
				)
				(justify mirror)
			)
		)
		(property "Value" ""
			(at 0 0 0)
			(layer "B.Fab")
			(effects
				(font
					(size 1.27 1.27)
				)
				(justify mirror)
			)
		)
		(duplicate_pad_numbers_are_jumpers no)
		(fp_line
			(start -0.7874 -0.4064)
			(end -0.7874 0.4064)
			(stroke
				(width 0.1524)
				(type default)
			)
			(layer "B.SilkS")
		)
		(fp_line
			(start -0.7874 0.4064)
			(end 0.7874 0.4064)
			(stroke
				(width 0.1524)
				(type default)
			)
			(layer "B.SilkS")
		)
		(fp_line
			(start 0.7874 -0.4064)
			(end -0.7874 -0.4064)
			(stroke
				(width 0.1524)
				(type default)
			)
			(layer "B.SilkS")
		)
		(fp_line
			(start 0.7874 0.4064)
			(end 0.7874 -0.4064)
			(stroke
				(width 0.1524)
				(type default)
			)
			(layer "B.SilkS")
		)
		(fp_line
			(start -0.67945 -0.3048)
			(end -0.67945 0.3048)
			(stroke
				(width 0.1)
				(type default)
			)
			(layer "B.Fab")
		)
		(fp_line
			(start -0.67945 0.3048)
			(end -0.120396 0.3048)
			(stroke
				(width 0.1)
				(type default)
			)
			(layer "B.Fab")
		)
		(fp_line
			(start -0.12065 -0.3048)
			(end -0.67945 -0.3048)
			(stroke
				(width 0.1)
				(type default)
			)
			(layer "B.Fab")
		)
		(fp_line
			(start -0.12065 -0.2794)
			(end -0.12065 -0.3048)
			(stroke
				(width 0.1)
				(type default)
			)
			(layer "B.Fab")
		)
		(fp_line
			(start -0.120396 0.2794)
			(end 0.12065 0.2794)
			(stroke
				(width 0.1)
				(type default)
			)
			(layer "B.Fab")
		)
		(fp_line
			(start -0.120396 0.3048)
			(end -0.120396 0.2794)
			(stroke
				(width 0.1)
				(type default)
			)
			(layer "B.Fab")
		)
		(fp_line
			(start 0.12065 -0.305054)
			(end 0.12065 -0.2794)
			(stroke
				(width 0.1)
				(type default)
			)
			(layer "B.Fab")
		)
		(fp_line
			(start 0.12065 -0.2794)
			(end -0.12065 -0.2794)
			(stroke
				(width 0.1)
				(type default)
			)
			(layer "B.Fab")
		)
		(fp_line
			(start 0.12065 0.2794)
			(end 0.12065 0.3048)
			(stroke
				(width 0.1)
				(type default)
			)
			(layer "B.Fab")
		)
		(fp_line
			(start 0.12065 0.3048)
			(end 0.67945 0.3048)
			(stroke
				(width 0.1)
				(type default)
			)
			(layer "B.Fab")
		)
		(fp_line
			(start 0.67945 -0.305054)
			(end 0.12065 -0.305054)
			(stroke
				(width 0.1)
				(type default)
			)
			(layer "B.Fab")
		)
		(fp_line
			(start 0.67945 0.3048)
			(end 0.67945 -0.305054)
			(stroke
				(width 0.1)
				(type default)
			)
			(layer "B.Fab")
		)
		(pad "1" smd circle
			(at 0.40005 0 180)
			(size 0 0)
			(layers "B.Cu" "B.Mask" "B.Paste")
			(net "NCSI_NIC2_TXD1")
		)
		(pad "2" smd circle
			(at -0.40005 0 180)
			(size 0 0)
			(layers "B.Cu" "B.Mask" "B.Paste")
			(net "GND")
		)
	)
	(footprint ""
		(layer "B.Cu")
		(at 361.44327 -277.644352 180)
		(property "Reference" "PC6620"
			(at 0 0 0)
			(layer "B.SilkS")
			(hide yes)
			(effects
				(font
					(size 1.27 1.27)
				)
				(justify mirror)
			)
		)
		(property "Value" ""
			(at 0 0 0)
			(layer "B.Fab")
			(effects
				(font
					(size 1.27 1.27)
				)
				(justify mirror)
			)
		)
		(duplicate_pad_numbers_are_jumpers no)
		(fp_line
			(start 1.524 0.762)
			(end 1.524 -0.762)
			(stroke
				(width 0.1524)
				(type default)
			)
			(layer "B.SilkS")
		)
		(fp_line
			(start 1.524 -0.762)
			(end -1.524 -0.762)
			(stroke
				(width 0.1524)
				(type default)
			)
			(layer "B.SilkS")
		)
		(fp_line
			(start -1.524 0.762)
			(end 1.524 0.762)
			(stroke
				(width 0.1524)
				(type default)
			)
			(layer "B.SilkS")
		)
		(fp_line
			(start -1.524 -0.762)
			(end -1.524 0.762)
			(stroke
				(width 0.1524)
				(type default)
			)
			(layer "B.SilkS")
		)
		(fp_line
			(start 1.1049 0.724916)
			(end -1.1049 0.724916)
			(stroke
				(width 0.1)
				(type default)
			)
			(layer "B.Fab")
		)
		(fp_line
			(start 1.1049 -0.724916)
			(end 1.1049 0.724916)
			(stroke
				(width 0.1)
				(type default)
			)
			(layer "B.Fab")
		)
		(fp_line
			(start -1.1049 0.724916)
			(end -1.1049 -0.724916)
			(stroke
				(width 0.1)
				(type default)
			)
			(layer "B.Fab")
		)
		(fp_line
			(start -1.1049 -0.724916)
			(end 1.1049 -0.724916)
			(stroke
				(width 0.1)
				(type default)
			)
			(layer "B.Fab")
		)
		(pad "1" smd rect
			(at 0.889 0 180)
			(size 1.016 1.27)
			(layers "B.Cu" "B.Mask" "B.Paste")
			(net "SW_P12V_P0V8_PEX3_FLT")
		)
		(pad "2" smd rect
			(at -0.889 0 180)
			(size 1.016 1.27)
			(layers "B.Cu" "B.Mask" "B.Paste")
			(net "GND")
		)
	)
	(footprint ""
		(layer "B.Cu")
		(at 323.316346 -238.175038)
		(property "Reference" "Q124"
			(at 1.4478 -1.819148 0)
			(unlocked yes)
			(layer "B.SilkS")
			(effects
				(font
					(size 0.7874 0.5842)
					(thickness 0.1524)
				)
				(justify left mirror)
			)
		)
		(property "Value" ""
			(at 0 0 0)
			(layer "B.Fab")
			(effects
				(font
					(size 1.27 1.27)
				)
				(justify mirror)
			)
		)
		(duplicate_pad_numbers_are_jumpers no)
		(fp_line
			(start -1.335278 -1.100074)
			(end 1.335278 -1.100074)
			(stroke
				(width 0.1524)
				(type default)
			)
			(layer "B.SilkS")
		)
		(fp_line
			(start -1.335278 1.100074)
			(end -1.335278 -1.100074)
			(stroke
				(width 0.1524)
				(type default)
			)
			(layer "B.SilkS")
		)
		(fp_line
			(start 1.335278 -1.100074)
			(end 1.335278 1.100074)
			(stroke
				(width 0.1524)
				(type default)
			)
			(layer "B.SilkS")
		)
		(fp_line
			(start 1.335278 1.100074)
			(end -1.335278 1.100074)
			(stroke
				(width 0.1524)
				(type default)
			)
			(layer "B.SilkS")
		)
		(fp_line
			(start -0.674878 -1.100074)
			(end 0.674878 -1.100074)
			(stroke
				(width 0.1)
				(type default)
			)
			(layer "B.Fab")
		)
		(fp_line
			(start -0.674878 1.100074)
			(end -0.674878 -1.100074)
			(stroke
				(width 0.1)
				(type default)
			)
			(layer "B.Fab")
		)
		(fp_line
			(start 0.674878 -1.100074)
			(end 0.674878 1.100074)
			(stroke
				(width 0.1)
				(type default)
			)
			(layer "B.Fab")
		)
		(fp_line
			(start 0.674878 1.100074)
			(end -0.674878 1.100074)
			(stroke
				(width 0.1)
				(type default)
			)
			(layer "B.Fab")
		)
		(pad "D" smd rect
			(at -0.8001 0 270)
			(size 0.6096 0.8128)
			(layers "B.Cu" "B.Mask" "B.Paste")
			(net "PWRGD_P3V3_AUX_MUX_N")
		)
		(pad "G" smd rect
			(at 0.8001 -0.649986 270)
			(size 0.6096 0.8128)
			(layers "B.Cu" "B.Mask" "B.Paste")
			(net "PWRGD_P3V3_AUX_R")
		)
		(pad "S" smd rect
			(at 0.8001 0.649986 270)
			(size 0.6096 0.8128)
			(layers "B.Cu" "B.Mask" "B.Paste")
			(net "GND")
		)
	)
	(footprint ""
		(layer "B.Cu")
		(at 173.375066 -305.399948 -90)
		(property "Reference" "C3147"
			(at 0 0 90)
			(layer "B.SilkS")
			(hide yes)
			(effects
				(font
					(size 1.27 1.27)
				)
				(justify mirror)
			)
		)
		(property "Value" ""
			(at 0 0 90)
			(layer "B.Fab")
			(effects
				(font
					(size 1.27 1.27)
				)
				(justify mirror)
			)
		)
		(duplicate_pad_numbers_are_jumpers no)
		(fp_line
			(start -0.299974 0.150114)
			(end 0.299974 0.150114)
			(stroke
				(width 0.1)
				(type default)
			)
			(layer "B.Fab")
		)
		(fp_line
			(start 0.299974 0.150114)
			(end 0.299974 -0.150114)
			(stroke
				(width 0.1)
				(type default)
			)
			(layer "B.Fab")
		)
		(fp_line
			(start -0.299974 -0.150114)
			(end -0.299974 0.150114)
			(stroke
				(width 0.1)
				(type default)
			)
			(layer "B.Fab")
		)
		(fp_line
			(start 0.299974 -0.150114)
			(end -0.299974 -0.150114)
			(stroke
				(width 0.1)
				(type default)
			)
			(layer "B.Fab")
		)
		(pad "1" smd rect
			(at 0.2667 0 90)
			(size 0.3048 0.381)
			(layers "B.Cu" "B.Mask" "B.Paste")
			(net "P1V25_SERDES_VDDPLL_PEX1")
		)
		(pad "2" smd rect
			(at -0.2667 0 90)
			(size 0.3048 0.381)
			(layers "B.Cu" "B.Mask" "B.Paste")
			(net "GND")
		)
	)
	(footprint ""
		(layer "B.Cu")
		(at 62.499748 -290.199826 90)
		(property "Reference" "C1240"
			(at 0 0 90)
			(layer "B.SilkS")
			(hide yes)
			(effects
				(font
					(size 1.27 1.27)
				)
				(justify mirror)
			)
		)
		(property "Value" ""
			(at 0 0 90)
			(layer "B.Fab")
			(effects
				(font
					(size 1.27 1.27)
				)
				(justify mirror)
			)
		)
		(duplicate_pad_numbers_are_jumpers no)
		(fp_line
			(start 0.299974 -0.150114)
			(end -0.299974 -0.150114)
			(stroke
				(width 0.1)
				(type default)
			)
			(layer "B.Fab")
		)
		(fp_line
			(start -0.299974 -0.150114)
			(end -0.299974 0.150114)
			(stroke
				(width 0.1)
				(type default)
			)
			(layer "B.Fab")
		)
		(fp_line
			(start 0.299974 0.150114)
			(end 0.299974 -0.150114)
			(stroke
				(width 0.1)
				(type default)
			)
			(layer "B.Fab")
		)
		(fp_line
			(start -0.299974 0.150114)
			(end 0.299974 0.150114)
			(stroke
				(width 0.1)
				(type default)
			)
			(layer "B.Fab")
		)
		(pad "1" smd rect
			(at 0.2667 0 270)
			(size 0.3048 0.381)
			(layers "B.Cu" "B.Mask" "B.Paste")
			(net "P0V8_SERDES_VDDA_PEX0")
		)
		(pad "2" smd rect
			(at -0.2667 0 270)
			(size 0.3048 0.381)
			(layers "B.Cu" "B.Mask" "B.Paste")
			(net "GND")
		)
	)
	(footprint ""
		(layer "B.Cu")
		(at 127.034544 -303.649634 -90)
		(property "Reference" "PC117"
			(at 0 0 90)
			(layer "B.SilkS")
			(hide yes)
			(effects
				(font
					(size 1.27 1.27)
				)
				(justify mirror)
			)
		)
		(property "Value" ""
			(at 0 0 90)
			(layer "B.Fab")
			(effects
				(font
					(size 1.27 1.27)
				)
				(justify mirror)
			)
		)
		(duplicate_pad_numbers_are_jumpers no)
		(fp_line
			(start -1.524 0.762)
			(end 1.524 0.762)
			(stroke
				(width 0.1524)
				(type default)
			)
			(layer "B.SilkS")
		)
		(fp_line
			(start 1.524 0.762)
			(end 1.524 -0.762)
			(stroke
				(width 0.1524)
				(type default)
			)
			(layer "B.SilkS")
		)
		(fp_line
			(start -1.524 -0.762)
			(end -1.524 0.762)
			(stroke
				(width 0.1524)
				(type default)
			)
			(layer "B.SilkS")
		)
		(fp_line
			(start 1.524 -0.762)
			(end -1.524 -0.762)
			(stroke
				(width 0.1524)
				(type default)
			)
			(layer "B.SilkS")
		)
		(fp_line
			(start -1.1049 0.724916)
			(end -1.1049 -0.724916)
			(stroke
				(width 0.1)
				(type default)
			)
			(layer "B.Fab")
		)
		(fp_line
			(start 1.1049 0.724916)
			(end -1.1049 0.724916)
			(stroke
				(width 0.1)
				(type default)
			)
			(layer "B.Fab")
		)
		(fp_line
			(start -1.1049 -0.724916)
			(end 1.1049 -0.724916)
			(stroke
				(width 0.1)
				(type default)
			)
			(layer "B.Fab")
		)
		(fp_line
			(start 1.1049 -0.724916)
			(end 1.1049 0.724916)
			(stroke
				(width 0.1)
				(type default)
			)
			(layer "B.Fab")
		)
		(pad "1" smd rect
			(at 0.889 0 270)
			(size 1.016 1.27)
			(layers "B.Cu" "B.Mask" "B.Paste")
			(net "P0V8_PEX1")
		)
		(pad "2" smd rect
			(at -0.889 0 270)
			(size 1.016 1.27)
			(layers "B.Cu" "B.Mask" "B.Paste")
			(net "GND")
		)
	)
	(footprint ""
		(layer "B.Cu")
		(at 415.549842 -301.599854 -90)
		(property "Reference" "C1950"
			(at 0 0 90)
			(layer "B.SilkS")
			(hide yes)
			(effects
				(font
					(size 1.27 1.27)
				)
				(justify mirror)
			)
		)
		(property "Value" ""
			(at 0 0 90)
			(layer "B.Fab")
			(effects
				(font
					(size 1.27 1.27)
				)
				(justify mirror)
			)
		)
		(duplicate_pad_numbers_are_jumpers no)
		(fp_line
			(start -0.299974 0.150114)
			(end 0.299974 0.150114)
			(stroke
				(width 0.1)
				(type default)
			)
			(layer "B.Fab")
		)
		(fp_line
			(start 0.299974 0.150114)
			(end 0.299974 -0.150114)
			(stroke
				(width 0.1)
				(type default)
			)
			(layer "B.Fab")
		)
		(fp_line
			(start -0.299974 -0.150114)
			(end -0.299974 0.150114)
			(stroke
				(width 0.1)
				(type default)
			)
			(layer "B.Fab")
		)
		(fp_line
			(start 0.299974 -0.150114)
			(end -0.299974 -0.150114)
			(stroke
				(width 0.1)
				(type default)
			)
			(layer "B.Fab")
		)
		(pad "1" smd rect
			(at 0.2667 0 90)
			(size 0.3048 0.381)
			(layers "B.Cu" "B.Mask" "B.Paste")
			(net "P0V8_SERDES_VDDA_PEX3")
		)
		(pad "2" smd rect
			(at -0.2667 0 90)
			(size 0.3048 0.381)
			(layers "B.Cu" "B.Mask" "B.Paste")
			(net "GND")
		)
	)
	(footprint ""
		(layer "B.Cu")
		(at 303.249838 -297.32478 180)
		(property "Reference" "C3258"
			(at 0 0 0)
			(layer "B.SilkS")
			(hide yes)
			(effects
				(font
					(size 1.27 1.27)
				)
				(justify mirror)
			)
		)
		(property "Value" ""
			(at 0 0 0)
			(layer "B.Fab")
			(effects
				(font
					(size 1.27 1.27)
				)
				(justify mirror)
			)
		)
		(duplicate_pad_numbers_are_jumpers no)
		(fp_line
			(start 0.299974 0.150114)
			(end 0.299974 -0.150114)
			(stroke
				(width 0.1)
				(type default)
			)
			(layer "B.Fab")
		)
		(fp_line
			(start 0.299974 -0.150114)
			(end -0.299974 -0.150114)
			(stroke
				(width 0.1)
				(type default)
			)
			(layer "B.Fab")
		)
		(fp_line
			(start -0.299974 0.150114)
			(end 0.299974 0.150114)
			(stroke
				(width 0.1)
				(type default)
			)
			(layer "B.Fab")
		)
		(fp_line
			(start -0.299974 -0.150114)
			(end -0.299974 0.150114)
			(stroke
				(width 0.1)
				(type default)
			)
			(layer "B.Fab")
		)
		(pad "1" smd rect
			(at 0.2667 0)
			(size 0.3048 0.381)
			(layers "B.Cu" "B.Mask" "B.Paste")
			(net "P1V25_PEX2")
		)
		(pad "2" smd rect
			(at -0.2667 0)
			(size 0.3048 0.381)
			(layers "B.Cu" "B.Mask" "B.Paste")
			(net "GND")
		)
	)
	(footprint ""
		(layer "B.Cu")
		(at 297.103038 -202.16114 90)
		(property "Reference" "R1037"
			(at 0 0 90)
			(layer "B.SilkS")
			(hide yes)
			(effects
				(font
					(size 1.27 1.27)
				)
				(justify mirror)
			)
		)
		(property "Value" ""
			(at 0 0 90)
			(layer "B.Fab")
			(effects
				(font
					(size 1.27 1.27)
				)
				(justify mirror)
			)
		)
		(duplicate_pad_numbers_are_jumpers no)
		(fp_line
			(start 0.7874 -0.4064)
			(end -0.7874 -0.4064)
			(stroke
				(width 0.1524)
				(type default)
			)
			(layer "B.SilkS")
		)
		(fp_line
			(start -0.7874 -0.4064)
			(end -0.7874 0.4064)
			(stroke
				(width 0.1524)
				(type default)
			)
			(layer "B.SilkS")
		)
		(fp_line
			(start 0.7874 0.4064)
			(end 0.7874 -0.4064)
			(stroke
				(width 0.1524)
				(type default)
			)
			(layer "B.SilkS")
		)
		(fp_line
			(start -0.7874 0.4064)
			(end 0.7874 0.4064)
			(stroke
				(width 0.1524)
				(type default)
			)
			(layer "B.SilkS")
		)
		(fp_line
			(start 0.67945 -0.305054)
			(end 0.12065 -0.305054)
			(stroke
				(width 0.1)
				(type default)
			)
			(layer "B.Fab")
		)
		(fp_line
			(start 0.12065 -0.305054)
			(end 0.12065 -0.2794)
			(stroke
				(width 0.1)
				(type default)
			)
			(layer "B.Fab")
		)
		(fp_line
			(start -0.12065 -0.3048)
			(end -0.67945 -0.3048)
			(stroke
				(width 0.1)
				(type default)
			)
			(layer "B.Fab")
		)
		(fp_line
			(start -0.67945 -0.3048)
			(end -0.67945 0.3048)
			(stroke
				(width 0.1)
				(type default)
			)
			(layer "B.Fab")
		)
		(fp_line
			(start 0.12065 -0.2794)
			(end -0.12065 -0.2794)
			(stroke
				(width 0.1)
				(type default)
			)
			(layer "B.Fab")
		)
		(fp_line
			(start -0.12065 -0.2794)
			(end -0.12065 -0.3048)
			(stroke
				(width 0.1)
				(type default)
			)
			(layer "B.Fab")
		)
		(fp_line
			(start 0.12065 0.2794)
			(end 0.12065 0.3048)
			(stroke
				(width 0.1)
				(type default)
			)
			(layer "B.Fab")
		)
		(fp_line
			(start -0.120396 0.2794)
			(end 0.12065 0.2794)
			(stroke
				(width 0.1)
				(type default)
			)
			(layer "B.Fab")
		)
		(fp_line
			(start 0.67945 0.3048)
			(end 0.67945 -0.305054)
			(stroke
				(width 0.1)
				(type default)
			)
			(layer "B.Fab")
		)
		(fp_line
			(start 0.12065 0.3048)
			(end 0.67945 0.3048)
			(stroke
				(width 0.1)
				(type default)
			)
			(layer "B.Fab")
		)
		(fp_line
			(start -0.120396 0.3048)
			(end -0.120396 0.2794)
			(stroke
				(width 0.1)
				(type default)
			)
			(layer "B.Fab")
		)
		(fp_line
			(start -0.67945 0.3048)
			(end -0.120396 0.3048)
			(stroke
				(width 0.1)
				(type default)
			)
			(layer "B.Fab")
		)
		(pad "1" smd circle
			(at 0.40005 0 270)
			(size 0 0)
			(layers "B.Cu" "B.Mask" "B.Paste")
			(net "SPI_BIC1_CS0_LS23_N_DIR1")
		)
		(pad "2" smd circle
			(at -0.40005 0 270)
			(size 0 0)
			(layers "B.Cu" "B.Mask" "B.Paste")
			(net "P1V8_PEX")
		)
	)
	(footprint ""
		(layer "B.Cu")
		(at 327.523856 -223.977708 180)
		(property "Reference" "R6415"
			(at 0 0 0)
			(layer "B.SilkS")
			(hide yes)
			(effects
				(font
					(size 1.27 1.27)
				)
				(justify mirror)
			)
		)
		(property "Value" ""
			(at 0 0 0)
			(layer "B.Fab")
			(effects
				(font
					(size 1.27 1.27)
				)
				(justify mirror)
			)
		)
		(duplicate_pad_numbers_are_jumpers no)
		(fp_line
			(start 0.7874 0.4064)
			(end 0.7874 -0.4064)
			(stroke
				(width 0.1524)
				(type default)
			)
			(layer "B.SilkS")
		)
		(fp_line
			(start 0.7874 -0.4064)
			(end -0.7874 -0.4064)
			(stroke
				(width 0.1524)
				(type default)
			)
			(layer "B.SilkS")
		)
		(fp_line
			(start -0.7874 0.4064)
			(end 0.7874 0.4064)
			(stroke
				(width 0.1524)
				(type default)
			)
			(layer "B.SilkS")
		)
		(fp_line
			(start -0.7874 -0.4064)
			(end -0.7874 0.4064)
			(stroke
				(width 0.1524)
				(type default)
			)
			(layer "B.SilkS")
		)
		(fp_line
			(start 0.67945 0.3048)
			(end 0.67945 -0.305054)
			(stroke
				(width 0.1)
				(type default)
			)
			(layer "B.Fab")
		)
		(fp_line
			(start 0.67945 -0.305054)
			(end 0.12065 -0.305054)
			(stroke
				(width 0.1)
				(type default)
			)
			(layer "B.Fab")
		)
		(fp_line
			(start 0.12065 0.3048)
			(end 0.67945 0.3048)
			(stroke
				(width 0.1)
				(type default)
			)
			(layer "B.Fab")
		)
		(fp_line
			(start 0.12065 0.2794)
			(end 0.12065 0.3048)
			(stroke
				(width 0.1)
				(type default)
			)
			(layer "B.Fab")
		)
		(fp_line
			(start 0.12065 -0.2794)
			(end -0.12065 -0.2794)
			(stroke
				(width 0.1)
				(type default)
			)
			(layer "B.Fab")
		)
		(fp_line
			(start 0.12065 -0.305054)
			(end 0.12065 -0.2794)
			(stroke
				(width 0.1)
				(type default)
			)
			(layer "B.Fab")
		)
		(fp_line
			(start -0.120396 0.3048)
			(end -0.120396 0.2794)
			(stroke
				(width 0.1)
				(type default)
			)
			(layer "B.Fab")
		)
		(fp_line
			(start -0.120396 0.2794)
			(end 0.12065 0.2794)
			(stroke
				(width 0.1)
				(type default)
			)
			(layer "B.Fab")
		)
		(fp_line
			(start -0.12065 -0.2794)
			(end -0.12065 -0.3048)
			(stroke
				(width 0.1)
				(type default)
			)
			(layer "B.Fab")
		)
		(fp_line
			(start -0.12065 -0.3048)
			(end -0.67945 -0.3048)
			(stroke
				(width 0.1)
				(type default)
			)
			(layer "B.Fab")
		)
		(fp_line
			(start -0.67945 0.3048)
			(end -0.120396 0.3048)
			(stroke
				(width 0.1)
				(type default)
			)
			(layer "B.Fab")
		)
		(fp_line
			(start -0.67945 -0.3048)
			(end -0.67945 0.3048)
			(stroke
				(width 0.1)
				(type default)
			)
			(layer "B.Fab")
		)
		(pad "1" smd circle
			(at 0.40005 0)
			(size 0 0)
			(layers "B.Cu" "B.Mask" "B.Paste")
			(net "GND")
		)
		(pad "2" smd circle
			(at -0.40005 0)
			(size 0 0)
			(layers "B.Cu" "B.Mask" "B.Paste")
			(net "FM_SYS_THROTTLE")
		)
	)
	(footprint ""
		(layer "B.Cu")
		(at 293.27475 -286.399732 90)
		(property "Reference" "C3304"
			(at 0 0 90)
			(layer "B.SilkS")
			(hide yes)
			(effects
				(font
					(size 1.27 1.27)
				)
				(justify mirror)
			)
		)
		(property "Value" ""
			(at 0 0 90)
			(layer "B.Fab")
			(effects
				(font
					(size 1.27 1.27)
				)
				(justify mirror)
			)
		)
		(duplicate_pad_numbers_are_jumpers no)
		(fp_line
			(start 0.299974 -0.150114)
			(end -0.299974 -0.150114)
			(stroke
				(width 0.1)
				(type default)
			)
			(layer "B.Fab")
		)
		(fp_line
			(start -0.299974 -0.150114)
			(end -0.299974 0.150114)
			(stroke
				(width 0.1)
				(type default)
			)
			(layer "B.Fab")
		)
		(fp_line
			(start 0.299974 0.150114)
			(end 0.299974 -0.150114)
			(stroke
				(width 0.1)
				(type default)
			)
			(layer "B.Fab")
		)
		(fp_line
			(start -0.299974 0.150114)
			(end 0.299974 0.150114)
			(stroke
				(width 0.1)
				(type default)
			)
			(layer "B.Fab")
		)
		(pad "1" smd rect
			(at 0.2667 0 270)
			(size 0.3048 0.381)
			(layers "B.Cu" "B.Mask" "B.Paste")
			(net "P1V25_SERDES_VDDPLL_PEX2")
		)
		(pad "2" smd rect
			(at -0.2667 0 270)
			(size 0.3048 0.381)
			(layers "B.Cu" "B.Mask" "B.Paste")
			(net "GND")
		)
	)
	(footprint ""
		(layer "B.Cu")
		(at 291.84981 -301.599854 -90)
		(property "Reference" "C1728"
			(at 0 0 90)
			(layer "B.SilkS")
			(hide yes)
			(effects
				(font
					(size 1.27 1.27)
				)
				(justify mirror)
			)
		)
		(property "Value" ""
			(at 0 0 90)
			(layer "B.Fab")
			(effects
				(font
					(size 1.27 1.27)
				)
				(justify mirror)
			)
		)
		(duplicate_pad_numbers_are_jumpers no)
		(fp_line
			(start -0.299974 0.150114)
			(end 0.299974 0.150114)
			(stroke
				(width 0.1)
				(type default)
			)
			(layer "B.Fab")
		)
		(fp_line
			(start 0.299974 0.150114)
			(end 0.299974 -0.150114)
			(stroke
				(width 0.1)
				(type default)
			)
			(layer "B.Fab")
		)
		(fp_line
			(start -0.299974 -0.150114)
			(end -0.299974 0.150114)
			(stroke
				(width 0.1)
				(type default)
			)
			(layer "B.Fab")
		)
		(fp_line
			(start 0.299974 -0.150114)
			(end -0.299974 -0.150114)
			(stroke
				(width 0.1)
				(type default)
			)
			(layer "B.Fab")
		)
		(pad "1" smd rect
			(at 0.2667 0 90)
			(size 0.3048 0.381)
			(layers "B.Cu" "B.Mask" "B.Paste")
			(net "P0V8_SERDES_VDDA_PEX2")
		)
		(pad "2" smd rect
			(at -0.2667 0 90)
			(size 0.3048 0.381)
			(layers "B.Cu" "B.Mask" "B.Paste")
			(net "GND")
		)
	)
	(footprint ""
		(layer "B.Cu")
		(at 145.804382 -226.78263 180)
		(property "Reference" "R6165"
			(at 0 0 0)
			(layer "B.SilkS")
			(hide yes)
			(effects
				(font
					(size 1.27 1.27)
				)
				(justify mirror)
			)
		)
		(property "Value" ""
			(at 0 0 0)
			(layer "B.Fab")
			(effects
				(font
					(size 1.27 1.27)
				)
				(justify mirror)
			)
		)
		(duplicate_pad_numbers_are_jumpers no)
		(fp_line
			(start 0.7874 0.4064)
			(end 0.7874 -0.4064)
			(stroke
				(width 0.1524)
				(type default)
			)
			(layer "B.SilkS")
		)
		(fp_line
			(start 0.7874 -0.4064)
			(end -0.7874 -0.4064)
			(stroke
				(width 0.1524)
				(type default)
			)
			(layer "B.SilkS")
		)
		(fp_line
			(start -0.7874 0.4064)
			(end 0.7874 0.4064)
			(stroke
				(width 0.1524)
				(type default)
			)
			(layer "B.SilkS")
		)
		(fp_line
			(start -0.7874 -0.4064)
			(end -0.7874 0.4064)
			(stroke
				(width 0.1524)
				(type default)
			)
			(layer "B.SilkS")
		)
		(fp_line
			(start 0.67945 0.3048)
			(end 0.67945 -0.305054)
			(stroke
				(width 0.1)
				(type default)
			)
			(layer "B.Fab")
		)
		(fp_line
			(start 0.67945 -0.305054)
			(end 0.12065 -0.305054)
			(stroke
				(width 0.1)
				(type default)
			)
			(layer "B.Fab")
		)
		(fp_line
			(start 0.12065 0.3048)
			(end 0.67945 0.3048)
			(stroke
				(width 0.1)
				(type default)
			)
			(layer "B.Fab")
		)
		(fp_line
			(start 0.12065 0.2794)
			(end 0.12065 0.3048)
			(stroke
				(width 0.1)
				(type default)
			)
			(layer "B.Fab")
		)
		(fp_line
			(start 0.12065 -0.2794)
			(end -0.12065 -0.2794)
			(stroke
				(width 0.1)
				(type default)
			)
			(layer "B.Fab")
		)
		(fp_line
			(start 0.12065 -0.305054)
			(end 0.12065 -0.2794)
			(stroke
				(width 0.1)
				(type default)
			)
			(layer "B.Fab")
		)
		(fp_line
			(start -0.120396 0.3048)
			(end -0.120396 0.2794)
			(stroke
				(width 0.1)
				(type default)
			)
			(layer "B.Fab")
		)
		(fp_line
			(start -0.120396 0.2794)
			(end 0.12065 0.2794)
			(stroke
				(width 0.1)
				(type default)
			)
			(layer "B.Fab")
		)
		(fp_line
			(start -0.12065 -0.2794)
			(end -0.12065 -0.3048)
			(stroke
				(width 0.1)
				(type default)
			)
			(layer "B.Fab")
		)
		(fp_line
			(start -0.12065 -0.3048)
			(end -0.67945 -0.3048)
			(stroke
				(width 0.1)
				(type default)
			)
			(layer "B.Fab")
		)
		(fp_line
			(start -0.67945 0.3048)
			(end -0.120396 0.3048)
			(stroke
				(width 0.1)
				(type default)
			)
			(layer "B.Fab")
		)
		(fp_line
			(start -0.67945 -0.3048)
			(end -0.67945 0.3048)
			(stroke
				(width 0.1)
				(type default)
			)
			(layer "B.Fab")
		)
		(pad "1" smd circle
			(at 0.40005 0)
			(size 0 0)
			(layers "B.Cu" "B.Mask" "B.Paste")
			(net "SPI_PEX1_RST_R_N")
		)
		(pad "2" smd circle
			(at -0.40005 0)
			(size 0 0)
			(layers "B.Cu" "B.Mask" "B.Paste")
			(net "SPI_PEX1_RST_N")
		)
	)
	(footprint ""
		(layer "B.Cu")
		(at 204.373226 -361.988608 180)
		(property "Reference" "R494"
			(at 0 0 0)
			(layer "B.SilkS")
			(hide yes)
			(effects
				(font
					(size 1.27 1.27)
				)
				(justify mirror)
			)
		)
		(property "Value" ""
			(at 0 0 0)
			(layer "B.Fab")
			(effects
				(font
					(size 1.27 1.27)
				)
				(justify mirror)
			)
		)
		(duplicate_pad_numbers_are_jumpers no)
		(fp_line
			(start 0.7874 0.4064)
			(end 0.7874 -0.4064)
			(stroke
				(width 0.1524)
				(type default)
			)
			(layer "B.SilkS")
		)
		(fp_line
			(start 0.7874 -0.4064)
			(end -0.7874 -0.4064)
			(stroke
				(width 0.1524)
				(type default)
			)
			(layer "B.SilkS")
		)
		(fp_line
			(start -0.7874 0.4064)
			(end 0.7874 0.4064)
			(stroke
				(width 0.1524)
				(type default)
			)
			(layer "B.SilkS")
		)
		(fp_line
			(start -0.7874 -0.4064)
			(end -0.7874 0.4064)
			(stroke
				(width 0.1524)
				(type default)
			)
			(layer "B.SilkS")
		)
		(fp_line
			(start 0.67945 0.3048)
			(end 0.67945 -0.305054)
			(stroke
				(width 0.1)
				(type default)
			)
			(layer "B.Fab")
		)
		(fp_line
			(start 0.67945 -0.305054)
			(end 0.12065 -0.305054)
			(stroke
				(width 0.1)
				(type default)
			)
			(layer "B.Fab")
		)
		(fp_line
			(start 0.12065 0.3048)
			(end 0.67945 0.3048)
			(stroke
				(width 0.1)
				(type default)
			)
			(layer "B.Fab")
		)
		(fp_line
			(start 0.12065 0.2794)
			(end 0.12065 0.3048)
			(stroke
				(width 0.1)
				(type default)
			)
			(layer "B.Fab")
		)
		(fp_line
			(start 0.12065 -0.2794)
			(end -0.12065 -0.2794)
			(stroke
				(width 0.1)
				(type default)
			)
			(layer "B.Fab")
		)
		(fp_line
			(start 0.12065 -0.305054)
			(end 0.12065 -0.2794)
			(stroke
				(width 0.1)
				(type default)
			)
			(layer "B.Fab")
		)
		(fp_line
			(start -0.120396 0.3048)
			(end -0.120396 0.2794)
			(stroke
				(width 0.1)
				(type default)
			)
			(layer "B.Fab")
		)
		(fp_line
			(start -0.120396 0.2794)
			(end 0.12065 0.2794)
			(stroke
				(width 0.1)
				(type default)
			)
			(layer "B.Fab")
		)
		(fp_line
			(start -0.12065 -0.2794)
			(end -0.12065 -0.3048)
			(stroke
				(width 0.1)
				(type default)
			)
			(layer "B.Fab")
		)
		(fp_line
			(start -0.12065 -0.3048)
			(end -0.67945 -0.3048)
			(stroke
				(width 0.1)
				(type default)
			)
			(layer "B.Fab")
		)
		(fp_line
			(start -0.67945 0.3048)
			(end -0.120396 0.3048)
			(stroke
				(width 0.1)
				(type default)
			)
			(layer "B.Fab")
		)
		(fp_line
			(start -0.67945 -0.3048)
			(end -0.67945 0.3048)
			(stroke
				(width 0.1)
				(type default)
			)
			(layer "B.Fab")
		)
		(pad "1" smd circle
			(at 0.40005 0)
			(size 0 0)
			(layers "B.Cu" "B.Mask" "B.Paste")
			(net "P12V_STBY_FUSE")
		)
		(pad "2" smd circle
			(at -0.40005 0)
			(size 0 0)
			(layers "B.Cu" "B.Mask" "B.Paste")
			(net "HSC_P12V_EN")
		)
	)
	(footprint ""
		(layer "B.Cu")
		(at 61.722 -296.3926)
		(property "Reference" "C1107"
			(at 0 0 0)
			(layer "B.SilkS")
			(hide yes)
			(effects
				(font
					(size 1.27 1.27)
				)
				(justify mirror)
			)
		)
		(property "Value" ""
			(at 0 0 0)
			(layer "B.Fab")
			(effects
				(font
					(size 1.27 1.27)
				)
				(justify mirror)
			)
		)
		(duplicate_pad_numbers_are_jumpers no)
		(fp_line
			(start -0.299974 -0.150114)
			(end -0.299974 0.150114)
			(stroke
				(width 0.1)
				(type default)
			)
			(layer "B.Fab")
		)
		(fp_line
			(start -0.299974 0.150114)
			(end 0.299974 0.150114)
			(stroke
				(width 0.1)
				(type default)
			)
			(layer "B.Fab")
		)
		(fp_line
			(start 0.299974 -0.150114)
			(end -0.299974 -0.150114)
			(stroke
				(width 0.1)
				(type default)
			)
			(layer "B.Fab")
		)
		(fp_line
			(start 0.299974 0.150114)
			(end 0.299974 -0.150114)
			(stroke
				(width 0.1)
				(type default)
			)
			(layer "B.Fab")
		)
		(pad "1" smd rect
			(at 0.2667 0 180)
			(size 0.3048 0.381)
			(layers "B.Cu" "B.Mask" "B.Paste")
			(net "P0V8_PEX0")
		)
		(pad "2" smd rect
			(at -0.2667 0 180)
			(size 0.3048 0.381)
			(layers "B.Cu" "B.Mask" "B.Paste")
			(net "GND")
		)
	)
	(footprint ""
		(layer "B.Cu")
		(at 121.437654 -321.387978 -90)
		(property "Reference" "R6485"
			(at 0 0 90)
			(layer "B.SilkS")
			(hide yes)
			(effects
				(font
					(size 1.27 1.27)
				)
				(justify mirror)
			)
		)
		(property "Value" ""
			(at 0 0 90)
			(layer "B.Fab")
			(effects
				(font
					(size 1.27 1.27)
				)
				(justify mirror)
			)
		)
		(duplicate_pad_numbers_are_jumpers no)
		(fp_line
			(start -0.7874 0.4064)
			(end 0.7874 0.4064)
			(stroke
				(width 0.1524)
				(type default)
			)
			(layer "B.SilkS")
		)
		(fp_line
			(start 0.7874 0.4064)
			(end 0.7874 -0.4064)
			(stroke
				(width 0.1524)
				(type default)
			)
			(layer "B.SilkS")
		)
		(fp_line
			(start -0.7874 -0.4064)
			(end -0.7874 0.4064)
			(stroke
				(width 0.1524)
				(type default)
			)
			(layer "B.SilkS")
		)
		(fp_line
			(start 0.7874 -0.4064)
			(end -0.7874 -0.4064)
			(stroke
				(width 0.1524)
				(type default)
			)
			(layer "B.SilkS")
		)
		(fp_line
			(start -0.67945 0.3048)
			(end -0.120396 0.3048)
			(stroke
				(width 0.1)
				(type default)
			)
			(layer "B.Fab")
		)
		(fp_line
			(start -0.120396 0.3048)
			(end -0.120396 0.2794)
			(stroke
				(width 0.1)
				(type default)
			)
			(layer "B.Fab")
		)
		(fp_line
			(start 0.12065 0.3048)
			(end 0.67945 0.3048)
			(stroke
				(width 0.1)
				(type default)
			)
			(layer "B.Fab")
		)
		(fp_line
			(start 0.67945 0.3048)
			(end 0.67945 -0.305054)
			(stroke
				(width 0.1)
				(type default)
			)
			(layer "B.Fab")
		)
		(fp_line
			(start -0.120396 0.2794)
			(end 0.12065 0.2794)
			(stroke
				(width 0.1)
				(type default)
			)
			(layer "B.Fab")
		)
		(fp_line
			(start 0.12065 0.2794)
			(end 0.12065 0.3048)
			(stroke
				(width 0.1)
				(type default)
			)
			(layer "B.Fab")
		)
		(fp_line
			(start -0.12065 -0.2794)
			(end -0.12065 -0.3048)
			(stroke
				(width 0.1)
				(type default)
			)
			(layer "B.Fab")
		)
		(fp_line
			(start 0.12065 -0.2794)
			(end -0.12065 -0.2794)
			(stroke
				(width 0.1)
				(type default)
			)
			(layer "B.Fab")
		)
		(fp_line
			(start -0.67945 -0.3048)
			(end -0.67945 0.3048)
			(stroke
				(width 0.1)
				(type default)
			)
			(layer "B.Fab")
		)
		(fp_line
			(start -0.12065 -0.3048)
			(end -0.67945 -0.3048)
			(stroke
				(width 0.1)
				(type default)
			)
			(layer "B.Fab")
		)
		(fp_line
			(start 0.12065 -0.305054)
			(end 0.12065 -0.2794)
			(stroke
				(width 0.1)
				(type default)
			)
			(layer "B.Fab")
		)
		(fp_line
			(start 0.67945 -0.305054)
			(end 0.12065 -0.305054)
			(stroke
				(width 0.1)
				(type default)
			)
			(layer "B.Fab")
		)
		(pad "1" smd circle
			(at 0.40005 0 90)
			(size 0 0)
			(layers "B.Cu" "B.Mask" "B.Paste")
			(net "P0V8_SERDES_VDDA_PEX1")
		)
		(pad "2" smd circle
			(at -0.40005 0 90)
			(size 0 0)
			(layers "B.Cu" "B.Mask" "B.Paste")
			(net "P0V8_SERDES_VDDA_PEX1_C8")
		)
	)
	(footprint ""
		(layer "B.Cu")
		(at 362.459016 -319.545462 -90)
		(property "Reference" "L77"
			(at 0 0 90)
			(layer "B.SilkS")
			(hide yes)
			(effects
				(font
					(size 1.27 1.27)
				)
				(justify mirror)
			)
		)
		(property "Value" ""
			(at 0 0 90)
			(layer "B.Fab")
			(effects
				(font
					(size 1.27 1.27)
				)
				(justify mirror)
			)
		)
		(duplicate_pad_numbers_are_jumpers no)
		(fp_line
			(start 2.248154 4.9911)
			(end -0.653542 4.9911)
			(stroke
				(width 0.1524)
				(type default)
			)
			(layer "B.SilkS")
		)
		(fp_line
			(start 2.248154 1.961896)
			(end 2.248154 4.9911)
			(stroke
				(width 0.1524)
				(type default)
			)
			(layer "B.SilkS")
		)
		(fp_line
			(start -2.248154 -4.9911)
			(end 2.248154 -4.9911)
			(stroke
				(width 0.1524)
				(type default)
			)
			(layer "B.SilkS")
		)
		(fp_line
			(start 2.248154 -4.9911)
			(end 2.248154 -2.275332)
			(stroke
				(width 0.1524)
				(type default)
			)
			(layer "B.SilkS")
		)
		(fp_line
			(start -1.700022 0.899922)
			(end -1.700022 -0.899922)
			(stroke
				(width 0.1)
				(type default)
			)
			(layer "B.Fab")
		)
		(fp_line
			(start 1.700022 0.899922)
			(end -1.700022 0.899922)
			(stroke
				(width 0.1)
				(type default)
			)
			(layer "B.Fab")
		)
		(fp_line
			(start -1.700022 -0.899922)
			(end 1.700022 -0.899922)
			(stroke
				(width 0.1)
				(type default)
			)
			(layer "B.Fab")
		)
		(fp_line
			(start 1.700022 -0.899922)
			(end 1.700022 0.899922)
			(stroke
				(width 0.1)
				(type default)
			)
			(layer "B.Fab")
		)
		(pad "1" smd rect
			(at 1.575054 0 90)
			(size 1.1684 9.8044)
			(layers "B.Cu" "B.Mask" "B.Paste")
			(net "P0V8_PEX3")
		)
		(pad "2" smd rect
			(at -1.575054 0 90)
			(size 1.1684 9.8044)
			(layers "B.Cu" "B.Mask" "B.Paste")
			(net "P0V8_SERDES_VDDA_PEX3")
		)
	)
	(footprint ""
		(layer "B.Cu")
		(at 40.173656 -296.9514 180)
		(property "Reference" "R3294"
			(at 0 0 0)
			(layer "B.SilkS")
			(hide yes)
			(effects
				(font
					(size 1.27 1.27)
				)
				(justify mirror)
			)
		)
		(property "Value" ""
			(at 0 0 0)
			(layer "B.Fab")
			(effects
				(font
					(size 1.27 1.27)
				)
				(justify mirror)
			)
		)
		(duplicate_pad_numbers_are_jumpers no)
		(fp_line
			(start 0.7874 0.4064)
			(end 0.7874 -0.4064)
			(stroke
				(width 0.1524)
				(type default)
			)
			(layer "B.SilkS")
		)
		(fp_line
			(start 0.7874 -0.4064)
			(end -0.7874 -0.4064)
			(stroke
				(width 0.1524)
				(type default)
			)
			(layer "B.SilkS")
		)
		(fp_line
			(start -0.7874 0.4064)
			(end 0.7874 0.4064)
			(stroke
				(width 0.1524)
				(type default)
			)
			(layer "B.SilkS")
		)
		(fp_line
			(start -0.7874 -0.4064)
			(end -0.7874 0.4064)
			(stroke
				(width 0.1524)
				(type default)
			)
			(layer "B.SilkS")
		)
		(fp_line
			(start 0.67945 0.3048)
			(end 0.67945 -0.305054)
			(stroke
				(width 0.1)
				(type default)
			)
			(layer "B.Fab")
		)
		(fp_line
			(start 0.67945 -0.305054)
			(end 0.12065 -0.305054)
			(stroke
				(width 0.1)
				(type default)
			)
			(layer "B.Fab")
		)
		(fp_line
			(start 0.12065 0.3048)
			(end 0.67945 0.3048)
			(stroke
				(width 0.1)
				(type default)
			)
			(layer "B.Fab")
		)
		(fp_line
			(start 0.12065 0.2794)
			(end 0.12065 0.3048)
			(stroke
				(width 0.1)
				(type default)
			)
			(layer "B.Fab")
		)
		(fp_line
			(start 0.12065 -0.2794)
			(end -0.12065 -0.2794)
			(stroke
				(width 0.1)
				(type default)
			)
			(layer "B.Fab")
		)
		(fp_line
			(start 0.12065 -0.305054)
			(end 0.12065 -0.2794)
			(stroke
				(width 0.1)
				(type default)
			)
			(layer "B.Fab")
		)
		(fp_line
			(start -0.120396 0.3048)
			(end -0.120396 0.2794)
			(stroke
				(width 0.1)
				(type default)
			)
			(layer "B.Fab")
		)
		(fp_line
			(start -0.120396 0.2794)
			(end 0.12065 0.2794)
			(stroke
				(width 0.1)
				(type default)
			)
			(layer "B.Fab")
		)
		(fp_line
			(start -0.12065 -0.2794)
			(end -0.12065 -0.3048)
			(stroke
				(width 0.1)
				(type default)
			)
			(layer "B.Fab")
		)
		(fp_line
			(start -0.12065 -0.3048)
			(end -0.67945 -0.3048)
			(stroke
				(width 0.1)
				(type default)
			)
			(layer "B.Fab")
		)
		(fp_line
			(start -0.67945 0.3048)
			(end -0.120396 0.3048)
			(stroke
				(width 0.1)
				(type default)
			)
			(layer "B.Fab")
		)
		(fp_line
			(start -0.67945 -0.3048)
			(end -0.67945 0.3048)
			(stroke
				(width 0.1)
				(type default)
			)
			(layer "B.Fab")
		)
		(pad "1" smd circle
			(at 0.40005 0)
			(size 0 0)
			(layers "B.Cu" "B.Mask" "B.Paste")
			(net "SPI_PEX0_SDIO1_R")
		)
		(pad "2" smd circle
			(at -0.40005 0)
			(size 0 0)
			(layers "B.Cu" "B.Mask" "B.Paste")
			(net "SPI_PEX0_SDIO1")
		)
	)
	(footprint ""
		(layer "B.Cu")
		(at 69.149976 -301.124874)
		(property "Reference" "C2991"
			(at 0 0 0)
			(layer "B.SilkS")
			(hide yes)
			(effects
				(font
					(size 1.27 1.27)
				)
				(justify mirror)
			)
		)
		(property "Value" ""
			(at 0 0 0)
			(layer "B.Fab")
			(effects
				(font
					(size 1.27 1.27)
				)
				(justify mirror)
			)
		)
		(duplicate_pad_numbers_are_jumpers no)
		(fp_line
			(start -0.299974 -0.150114)
			(end -0.299974 0.150114)
			(stroke
				(width 0.1)
				(type default)
			)
			(layer "B.Fab")
		)
		(fp_line
			(start -0.299974 0.150114)
			(end 0.299974 0.150114)
			(stroke
				(width 0.1)
				(type default)
			)
			(layer "B.Fab")
		)
		(fp_line
			(start 0.299974 -0.150114)
			(end -0.299974 -0.150114)
			(stroke
				(width 0.1)
				(type default)
			)
			(layer "B.Fab")
		)
		(fp_line
			(start 0.299974 0.150114)
			(end 0.299974 -0.150114)
			(stroke
				(width 0.1)
				(type default)
			)
			(layer "B.Fab")
		)
		(pad "1" smd rect
			(at 0.2667 0 180)
			(size 0.3048 0.381)
			(layers "B.Cu" "B.Mask" "B.Paste")
			(net "P1V8_PEX")
		)
		(pad "2" smd rect
			(at -0.2667 0 180)
			(size 0.3048 0.381)
			(layers "B.Cu" "B.Mask" "B.Paste")
			(net "GND")
		)
	)
	(footprint ""
		(layer "B.Cu")
		(at 47.77486 -294.132 -90)
		(property "Reference" "C3047"
			(at 0 0 90)
			(layer "B.SilkS")
			(hide yes)
			(effects
				(font
					(size 1.27 1.27)
				)
				(justify mirror)
			)
		)
		(property "Value" ""
			(at 0 0 90)
			(layer "B.Fab")
			(effects
				(font
					(size 1.27 1.27)
				)
				(justify mirror)
			)
		)
		(duplicate_pad_numbers_are_jumpers no)
		(fp_line
			(start -0.299974 0.150114)
			(end 0.299974 0.150114)
			(stroke
				(width 0.1)
				(type default)
			)
			(layer "B.Fab")
		)
		(fp_line
			(start 0.299974 0.150114)
			(end 0.299974 -0.150114)
			(stroke
				(width 0.1)
				(type default)
			)
			(layer "B.Fab")
		)
		(fp_line
			(start -0.299974 -0.150114)
			(end -0.299974 0.150114)
			(stroke
				(width 0.1)
				(type default)
			)
			(layer "B.Fab")
		)
		(fp_line
			(start 0.299974 -0.150114)
			(end -0.299974 -0.150114)
			(stroke
				(width 0.1)
				(type default)
			)
			(layer "B.Fab")
		)
		(pad "1" smd rect
			(at 0.2667 0 90)
			(size 0.3048 0.381)
			(layers "B.Cu" "B.Mask" "B.Paste")
			(net "PCEPLL5_VDDA18_PEX0")
		)
		(pad "2" smd rect
			(at -0.2667 0 90)
			(size 0.3048 0.381)
			(layers "B.Cu" "B.Mask" "B.Paste")
			(net "GND")
		)
	)
	(footprint ""
		(layer "B.Cu")
		(at 224.81794 -197.788022 -90)
		(property "Reference" "R1023"
			(at 0 0 90)
			(layer "B.SilkS")
			(hide yes)
			(effects
				(font
					(size 1.27 1.27)
				)
				(justify mirror)
			)
		)
		(property "Value" ""
			(at 0 0 90)
			(layer "B.Fab")
			(effects
				(font
					(size 1.27 1.27)
				)
				(justify mirror)
			)
		)
		(duplicate_pad_numbers_are_jumpers no)
		(fp_line
			(start -0.7874 0.4064)
			(end 0.7874 0.4064)
			(stroke
				(width 0.1524)
				(type default)
			)
			(layer "B.SilkS")
		)
		(fp_line
			(start 0.7874 0.4064)
			(end 0.7874 -0.4064)
			(stroke
				(width 0.1524)
				(type default)
			)
			(layer "B.SilkS")
		)
		(fp_line
			(start -0.7874 -0.4064)
			(end -0.7874 0.4064)
			(stroke
				(width 0.1524)
				(type default)
			)
			(layer "B.SilkS")
		)
		(fp_line
			(start 0.7874 -0.4064)
			(end -0.7874 -0.4064)
			(stroke
				(width 0.1524)
				(type default)
			)
			(layer "B.SilkS")
		)
		(fp_line
			(start -0.67945 0.3048)
			(end -0.120396 0.3048)
			(stroke
				(width 0.1)
				(type default)
			)
			(layer "B.Fab")
		)
		(fp_line
			(start -0.120396 0.3048)
			(end -0.120396 0.2794)
			(stroke
				(width 0.1)
				(type default)
			)
			(layer "B.Fab")
		)
		(fp_line
			(start 0.12065 0.3048)
			(end 0.67945 0.3048)
			(stroke
				(width 0.1)
				(type default)
			)
			(layer "B.Fab")
		)
		(fp_line
			(start 0.67945 0.3048)
			(end 0.67945 -0.305054)
			(stroke
				(width 0.1)
				(type default)
			)
			(layer "B.Fab")
		)
		(fp_line
			(start -0.120396 0.2794)
			(end 0.12065 0.2794)
			(stroke
				(width 0.1)
				(type default)
			)
			(layer "B.Fab")
		)
		(fp_line
			(start 0.12065 0.2794)
			(end 0.12065 0.3048)
			(stroke
				(width 0.1)
				(type default)
			)
			(layer "B.Fab")
		)
		(fp_line
			(start -0.12065 -0.2794)
			(end -0.12065 -0.3048)
			(stroke
				(width 0.1)
				(type default)
			)
			(layer "B.Fab")
		)
		(fp_line
			(start 0.12065 -0.2794)
			(end -0.12065 -0.2794)
			(stroke
				(width 0.1)
				(type default)
			)
			(layer "B.Fab")
		)
		(fp_line
			(start -0.67945 -0.3048)
			(end -0.67945 0.3048)
			(stroke
				(width 0.1)
				(type default)
			)
			(layer "B.Fab")
		)
		(fp_line
			(start -0.12065 -0.3048)
			(end -0.67945 -0.3048)
			(stroke
				(width 0.1)
				(type default)
			)
			(layer "B.Fab")
		)
		(fp_line
			(start 0.12065 -0.305054)
			(end 0.12065 -0.2794)
			(stroke
				(width 0.1)
				(type default)
			)
			(layer "B.Fab")
		)
		(fp_line
			(start 0.67945 -0.305054)
			(end 0.12065 -0.305054)
			(stroke
				(width 0.1)
				(type default)
			)
			(layer "B.Fab")
		)
		(pad "1" smd circle
			(at 0.40005 0 90)
			(size 0 0)
			(layers "B.Cu" "B.Mask" "B.Paste")
			(net "SPI_BIC1_CLK_R")
		)
		(pad "2" smd circle
			(at -0.40005 0 90)
			(size 0 0)
			(layers "B.Cu" "B.Mask" "B.Paste")
			(net "SPI_BIC1_CLK_R5")
		)
	)
	(footprint ""
		(layer "B.Cu")
		(at 168.150032 -301.599854 -90)
		(property "Reference" "C1429"
			(at 0 0 90)
			(layer "B.SilkS")
			(hide yes)
			(effects
				(font
					(size 1.27 1.27)
				)
				(justify mirror)
			)
		)
		(property "Value" ""
			(at 0 0 90)
			(layer "B.Fab")
			(effects
				(font
					(size 1.27 1.27)
				)
				(justify mirror)
			)
		)
		(duplicate_pad_numbers_are_jumpers no)
		(fp_line
			(start -0.299974 0.150114)
			(end 0.299974 0.150114)
			(stroke
				(width 0.1)
				(type default)
			)
			(layer "B.Fab")
		)
		(fp_line
			(start 0.299974 0.150114)
			(end 0.299974 -0.150114)
			(stroke
				(width 0.1)
				(type default)
			)
			(layer "B.Fab")
		)
		(fp_line
			(start -0.299974 -0.150114)
			(end -0.299974 0.150114)
			(stroke
				(width 0.1)
				(type default)
			)
			(layer "B.Fab")
		)
		(fp_line
			(start 0.299974 -0.150114)
			(end -0.299974 -0.150114)
			(stroke
				(width 0.1)
				(type default)
			)
			(layer "B.Fab")
		)
		(pad "1" smd rect
			(at 0.2667 0 90)
			(size 0.3048 0.381)
			(layers "B.Cu" "B.Mask" "B.Paste")
			(net "P0V8_SERDES_VDDA_PEX1")
		)
		(pad "2" smd rect
			(at -0.2667 0 90)
			(size 0.3048 0.381)
			(layers "B.Cu" "B.Mask" "B.Paste")
			(net "GND")
		)
	)
	(footprint ""
		(layer "B.Cu")
		(at 287.099756 -303.499774 -90)
		(property "Reference" "C3263"
			(at 0 0 90)
			(layer "B.SilkS")
			(hide yes)
			(effects
				(font
					(size 1.27 1.27)
				)
				(justify mirror)
			)
		)
		(property "Value" ""
			(at 0 0 90)
			(layer "B.Fab")
			(effects
				(font
					(size 1.27 1.27)
				)
				(justify mirror)
			)
		)
		(duplicate_pad_numbers_are_jumpers no)
		(fp_line
			(start -0.299974 0.150114)
			(end 0.299974 0.150114)
			(stroke
				(width 0.1)
				(type default)
			)
			(layer "B.Fab")
		)
		(fp_line
			(start 0.299974 0.150114)
			(end 0.299974 -0.150114)
			(stroke
				(width 0.1)
				(type default)
			)
			(layer "B.Fab")
		)
		(fp_line
			(start -0.299974 -0.150114)
			(end -0.299974 0.150114)
			(stroke
				(width 0.1)
				(type default)
			)
			(layer "B.Fab")
		)
		(fp_line
			(start 0.299974 -0.150114)
			(end -0.299974 -0.150114)
			(stroke
				(width 0.1)
				(type default)
			)
			(layer "B.Fab")
		)
		(pad "1" smd rect
			(at 0.2667 0 90)
			(size 0.3048 0.381)
			(layers "B.Cu" "B.Mask" "B.Paste")
			(net "P1V25_PEX2")
		)
		(pad "2" smd rect
			(at -0.2667 0 90)
			(size 0.3048 0.381)
			(layers "B.Cu" "B.Mask" "B.Paste")
			(net "GND")
		)
	)
	(footprint ""
		(layer "B.Cu")
		(at 420.508176 -300.174914 180)
		(property "Reference" "C3531"
			(at 0 0 0)
			(layer "B.SilkS")
			(hide yes)
			(effects
				(font
					(size 1.27 1.27)
				)
				(justify mirror)
			)
		)
		(property "Value" ""
			(at 0 0 0)
			(layer "B.Fab")
			(effects
				(font
					(size 1.27 1.27)
				)
				(justify mirror)
			)
		)
		(duplicate_pad_numbers_are_jumpers no)
		(fp_line
			(start 0.299974 0.150114)
			(end 0.299974 -0.150114)
			(stroke
				(width 0.1)
				(type default)
			)
			(layer "B.Fab")
		)
		(fp_line
			(start 0.299974 -0.150114)
			(end -0.299974 -0.150114)
			(stroke
				(width 0.1)
				(type default)
			)
			(layer "B.Fab")
		)
		(fp_line
			(start -0.299974 0.150114)
			(end 0.299974 0.150114)
			(stroke
				(width 0.1)
				(type default)
			)
			(layer "B.Fab")
		)
		(fp_line
			(start -0.299974 -0.150114)
			(end -0.299974 0.150114)
			(stroke
				(width 0.1)
				(type default)
			)
			(layer "B.Fab")
		)
		(pad "1" smd rect
			(at 0.2667 0)
			(size 0.3048 0.381)
			(layers "B.Cu" "B.Mask" "B.Paste")
			(net "P1V8_VDDA_PEX3")
		)
		(pad "2" smd rect
			(at -0.2667 0)
			(size 0.3048 0.381)
			(layers "B.Cu" "B.Mask" "B.Paste")
			(net "GND")
		)
	)
	(footprint ""
		(layer "B.Cu")
		(at 69.00418 -117.723666)
		(property "Reference" "C418"
			(at 0 0 0)
			(layer "B.SilkS")
			(hide yes)
			(effects
				(font
					(size 1.27 1.27)
				)
				(justify mirror)
			)
		)
		(property "Value" ""
			(at 0 0 0)
			(layer "B.Fab")
			(effects
				(font
					(size 1.27 1.27)
				)
				(justify mirror)
			)
		)
		(duplicate_pad_numbers_are_jumpers no)
		(fp_line
			(start -0.7874 -0.4064)
			(end -0.7874 0.4064)
			(stroke
				(width 0.1524)
				(type default)
			)
			(layer "B.SilkS")
		)
		(fp_line
			(start -0.7874 0.4064)
			(end 0.7874 0.4064)
			(stroke
				(width 0.1524)
				(type default)
			)
			(layer "B.SilkS")
		)
		(fp_line
			(start 0.7874 -0.4064)
			(end -0.7874 -0.4064)
			(stroke
				(width 0.1524)
				(type default)
			)
			(layer "B.SilkS")
		)
		(fp_line
			(start 0.7874 0.4064)
			(end 0.7874 -0.4064)
			(stroke
				(width 0.1524)
				(type default)
			)
			(layer "B.SilkS")
		)
		(fp_line
			(start -0.67945 -0.3048)
			(end -0.67945 0.3048)
			(stroke
				(width 0.1)
				(type default)
			)
			(layer "B.Fab")
		)
		(fp_line
			(start -0.67945 0.3048)
			(end -0.120396 0.3048)
			(stroke
				(width 0.1)
				(type default)
			)
			(layer "B.Fab")
		)
		(fp_line
			(start -0.12065 -0.3048)
			(end -0.67945 -0.3048)
			(stroke
				(width 0.1)
				(type default)
			)
			(layer "B.Fab")
		)
		(fp_line
			(start -0.12065 -0.2794)
			(end -0.12065 -0.3048)
			(stroke
				(width 0.1)
				(type default)
			)
			(layer "B.Fab")
		)
		(fp_line
			(start -0.120396 0.2794)
			(end 0.12065 0.2794)
			(stroke
				(width 0.1)
				(type default)
			)
			(layer "B.Fab")
		)
		(fp_line
			(start -0.120396 0.3048)
			(end -0.120396 0.2794)
			(stroke
				(width 0.1)
				(type default)
			)
			(layer "B.Fab")
		)
		(fp_line
			(start 0.12065 -0.305054)
			(end 0.12065 -0.2794)
			(stroke
				(width 0.1)
				(type default)
			)
			(layer "B.Fab")
		)
		(fp_line
			(start 0.12065 -0.2794)
			(end -0.12065 -0.2794)
			(stroke
				(width 0.1)
				(type default)
			)
			(layer "B.Fab")
		)
		(fp_line
			(start 0.12065 0.2794)
			(end 0.12065 0.3048)
			(stroke
				(width 0.1)
				(type default)
			)
			(layer "B.Fab")
		)
		(fp_line
			(start 0.12065 0.3048)
			(end 0.67945 0.3048)
			(stroke
				(width 0.1)
				(type default)
			)
			(layer "B.Fab")
		)
		(fp_line
			(start 0.67945 -0.305054)
			(end 0.12065 -0.305054)
			(stroke
				(width 0.1)
				(type default)
			)
			(layer "B.Fab")
		)
		(fp_line
			(start 0.67945 0.3048)
			(end 0.67945 -0.305054)
			(stroke
				(width 0.1)
				(type default)
			)
			(layer "B.Fab")
		)
		(pad "1" smd circle
			(at 0.40005 0 180)
			(size 0 0)
			(layers "B.Cu" "B.Mask" "B.Paste")
			(net "P3V3_AUX")
		)
		(pad "2" smd circle
			(at -0.40005 0 180)
			(size 0 0)
			(layers "B.Cu" "B.Mask" "B.Paste")
			(net "GND")
		)
	)
	(footprint ""
		(layer "B.Cu")
		(at 128.966214 -202.221846 180)
		(property "Reference" "C2591"
			(at 0 0 0)
			(layer "B.SilkS")
			(hide yes)
			(effects
				(font
					(size 1.27 1.27)
				)
				(justify mirror)
			)
		)
		(property "Value" ""
			(at 0 0 0)
			(layer "B.Fab")
			(effects
				(font
					(size 1.27 1.27)
				)
				(justify mirror)
			)
		)
		(duplicate_pad_numbers_are_jumpers no)
		(fp_line
			(start 0.7874 0.4064)
			(end 0.7874 -0.4064)
			(stroke
				(width 0.1524)
				(type default)
			)
			(layer "B.SilkS")
		)
		(fp_line
			(start 0.7874 -0.4064)
			(end -0.7874 -0.4064)
			(stroke
				(width 0.1524)
				(type default)
			)
			(layer "B.SilkS")
		)
		(fp_line
			(start -0.7874 0.4064)
			(end 0.7874 0.4064)
			(stroke
				(width 0.1524)
				(type default)
			)
			(layer "B.SilkS")
		)
		(fp_line
			(start -0.7874 -0.4064)
			(end -0.7874 0.4064)
			(stroke
				(width 0.1524)
				(type default)
			)
			(layer "B.SilkS")
		)
		(fp_line
			(start 0.67945 0.3048)
			(end 0.67945 -0.305054)
			(stroke
				(width 0.1)
				(type default)
			)
			(layer "B.Fab")
		)
		(fp_line
			(start 0.67945 -0.305054)
			(end 0.12065 -0.305054)
			(stroke
				(width 0.1)
				(type default)
			)
			(layer "B.Fab")
		)
		(fp_line
			(start 0.12065 0.3048)
			(end 0.67945 0.3048)
			(stroke
				(width 0.1)
				(type default)
			)
			(layer "B.Fab")
		)
		(fp_line
			(start 0.12065 0.2794)
			(end 0.12065 0.3048)
			(stroke
				(width 0.1)
				(type default)
			)
			(layer "B.Fab")
		)
		(fp_line
			(start 0.12065 -0.2794)
			(end -0.12065 -0.2794)
			(stroke
				(width 0.1)
				(type default)
			)
			(layer "B.Fab")
		)
		(fp_line
			(start 0.12065 -0.305054)
			(end 0.12065 -0.2794)
			(stroke
				(width 0.1)
				(type default)
			)
			(layer "B.Fab")
		)
		(fp_line
			(start -0.120396 0.3048)
			(end -0.120396 0.2794)
			(stroke
				(width 0.1)
				(type default)
			)
			(layer "B.Fab")
		)
		(fp_line
			(start -0.120396 0.2794)
			(end 0.12065 0.2794)
			(stroke
				(width 0.1)
				(type default)
			)
			(layer "B.Fab")
		)
		(fp_line
			(start -0.12065 -0.2794)
			(end -0.12065 -0.3048)
			(stroke
				(width 0.1)
				(type default)
			)
			(layer "B.Fab")
		)
		(fp_line
			(start -0.12065 -0.3048)
			(end -0.67945 -0.3048)
			(stroke
				(width 0.1)
				(type default)
			)
			(layer "B.Fab")
		)
		(fp_line
			(start -0.67945 0.3048)
			(end -0.120396 0.3048)
			(stroke
				(width 0.1)
				(type default)
			)
			(layer "B.Fab")
		)
		(fp_line
			(start -0.67945 -0.3048)
			(end -0.67945 0.3048)
			(stroke
				(width 0.1)
				(type default)
			)
			(layer "B.Fab")
		)
		(pad "1" smd circle
			(at 0.40005 0)
			(size 0 0)
			(layers "B.Cu" "B.Mask" "B.Paste")
			(net "P3V3_AUX")
		)
		(pad "2" smd circle
			(at -0.40005 0)
			(size 0 0)
			(layers "B.Cu" "B.Mask" "B.Paste")
			(net "GND")
		)
	)
	(footprint ""
		(layer "B.Cu")
		(at 229.867714 -221.904052 90)
		(property "Reference" "C2014"
			(at 0 0 90)
			(layer "B.SilkS")
			(hide yes)
			(effects
				(font
					(size 1.27 1.27)
				)
				(justify mirror)
			)
		)
		(property "Value" ""
			(at 0 0 90)
			(layer "B.Fab")
			(effects
				(font
					(size 1.27 1.27)
				)
				(justify mirror)
			)
		)
		(duplicate_pad_numbers_are_jumpers no)
		(fp_line
			(start 0.69215 -0.2921)
			(end -0.69215 -0.2921)
			(stroke
				(width 0.1524)
				(type default)
			)
			(layer "B.SilkS")
		)
		(fp_line
			(start -0.69215 -0.2921)
			(end -0.69215 0.2921)
			(stroke
				(width 0.1524)
				(type default)
			)
			(layer "B.SilkS")
		)
		(fp_line
			(start 0.69215 0.2921)
			(end 0.69215 -0.2921)
			(stroke
				(width 0.1524)
				(type default)
			)
			(layer "B.SilkS")
		)
		(fp_line
			(start -0.69215 0.2921)
			(end 0.69215 0.2921)
			(stroke
				(width 0.1524)
				(type default)
			)
			(layer "B.SilkS")
		)
		(fp_line
			(start 0.51435 -0.2794)
			(end -0.51435 -0.2794)
			(stroke
				(width 0.1)
				(type default)
			)
			(layer "B.Fab")
		)
		(fp_line
			(start -0.51435 -0.2794)
			(end -0.51435 0.2794)
			(stroke
				(width 0.1)
				(type default)
			)
			(layer "B.Fab")
		)
		(fp_line
			(start 0.51435 0.2794)
			(end 0.51435 -0.2794)
			(stroke
				(width 0.1)
				(type default)
			)
			(layer "B.Fab")
		)
		(fp_line
			(start -0.51435 0.2794)
			(end 0.51435 0.2794)
			(stroke
				(width 0.1)
				(type default)
			)
			(layer "B.Fab")
		)
		(pad "1" smd circle
			(at 0.40005 0 270)
			(size 0 0)
			(layers "B.Cu" "B.Mask" "B.Paste")
			(net "P1V2_AUX")
		)
		(pad "2" smd circle
			(at -0.40005 0 270)
			(size 0 0)
			(layers "B.Cu" "B.Mask" "B.Paste")
			(net "GND")
		)
		(zone
			(layer "B.Cu")
			(hatch none 0.5)
			(connect_pads
				(clearance 0)
			)
			(min_thickness 0.25)
			(keepout
				(tracks not_allowed)
				(vias allowed)
				(pads allowed)
				(copperpour not_allowed)
				(footprints allowed)
			)
			(placement
				(enabled no)
				(sheetname "")
			)
			(fill
				(thermal_gap 0.5)
				(thermal_bridge_width 0.5)
				(island_removal_mode 0)
			)
			(polygon
				(pts
					(xy 229.955344 -222.094552) (xy 230.01351 -222.003112) (xy 230.01351 -221.803722) (xy 229.955344 -221.713552)
					(xy 229.780084 -221.713552) (xy 229.721664 -221.803722) (xy 229.721664 -222.003112) (xy 229.77983 -222.094552)
				)
			)
		)
	)
	(footprint ""
		(layer "B.Cu")
		(at 358.747568 -325.338948 -90)
		(property "Reference" "C4368"
			(at 0 0 90)
			(layer "B.SilkS")
			(hide yes)
			(effects
				(font
					(size 1.27 1.27)
				)
				(justify mirror)
			)
		)
		(property "Value" ""
			(at 0 0 90)
			(layer "B.Fab")
			(effects
				(font
					(size 1.27 1.27)
				)
				(justify mirror)
			)
		)
		(duplicate_pad_numbers_are_jumpers no)
		(fp_line
			(start -1.2954 0.5842)
			(end 1.2954 0.5842)
			(stroke
				(width 0.1524)
				(type default)
			)
			(layer "B.SilkS")
		)
		(fp_line
			(start 1.2954 0.5842)
			(end 1.2954 -0.5842)
			(stroke
				(width 0.1524)
				(type default)
			)
			(layer "B.SilkS")
		)
		(fp_line
			(start -1.2954 -0.5842)
			(end -1.2954 0.5842)
			(stroke
				(width 0.1524)
				(type default)
			)
			(layer "B.SilkS")
		)
		(fp_line
			(start 1.2954 -0.5842)
			(end -1.2954 -0.5842)
			(stroke
				(width 0.1524)
				(type default)
			)
			(layer "B.SilkS")
		)
		(fp_line
			(start -0.8636 0.4572)
			(end 0.8636 0.4572)
			(stroke
				(width 0.1)
				(type default)
			)
			(layer "B.Fab")
		)
		(fp_line
			(start 0.8636 0.4572)
			(end 0.8636 0.4064)
			(stroke
				(width 0.1)
				(type default)
			)
			(layer "B.Fab")
		)
		(fp_line
			(start -1.1938 0.4064)
			(end -0.8636 0.4064)
			(stroke
				(width 0.1)
				(type default)
			)
			(layer "B.Fab")
		)
		(fp_line
			(start -0.8636 0.4064)
			(end -0.8636 0.4572)
			(stroke
				(width 0.1)
				(type default)
			)
			(layer "B.Fab")
		)
		(fp_line
			(start 0.8636 0.4064)
			(end 1.1938 0.4064)
			(stroke
				(width 0.1)
				(type default)
			)
			(layer "B.Fab")
		)
		(fp_line
			(start 1.1938 0.4064)
			(end 1.1938 -0.4064)
			(stroke
				(width 0.1)
				(type default)
			)
			(layer "B.Fab")
		)
		(fp_line
			(start -1.1938 -0.4064)
			(end -1.1938 0.4064)
			(stroke
				(width 0.1)
				(type default)
			)
			(layer "B.Fab")
		)
		(fp_line
			(start -0.8636 -0.4064)
			(end -1.1938 -0.4064)
			(stroke
				(width 0.1)
				(type default)
			)
			(layer "B.Fab")
		)
		(fp_line
			(start 0.8636 -0.4064)
			(end 0.8636 -0.4572)
			(stroke
				(width 0.1)
				(type default)
			)
			(layer "B.Fab")
		)
		(fp_line
			(start 1.1938 -0.4064)
			(end 0.8636 -0.4064)
			(stroke
				(width 0.1)
				(type default)
			)
			(layer "B.Fab")
		)
		(fp_line
			(start -0.8636 -0.4572)
			(end -0.8636 -0.4064)
			(stroke
				(width 0.1)
				(type default)
			)
			(layer "B.Fab")
		)
		(fp_line
			(start 0.8636 -0.4572)
			(end -0.8636 -0.4572)
			(stroke
				(width 0.1)
				(type default)
			)
			(layer "B.Fab")
		)
		(pad "1" smd rect
			(at 0.7366 0 180)
			(size 0.7112 0.8128)
			(layers "B.Cu" "B.Mask" "B.Paste")
			(net "P0V8_SERDES_VDDA_PEX3_C2")
		)
		(pad "2" smd rect
			(at -0.7366 0 180)
			(size 0.7112 0.8128)
			(layers "B.Cu" "B.Mask" "B.Paste")
			(net "GND")
		)
	)
	(footprint ""
		(layer "B.Cu")
		(at 163.874958 -292.9636 90)
		(property "Reference" "C3220"
			(at 0 0 90)
			(layer "B.SilkS")
			(hide yes)
			(effects
				(font
					(size 1.27 1.27)
				)
				(justify mirror)
			)
		)
		(property "Value" ""
			(at 0 0 90)
			(layer "B.Fab")
			(effects
				(font
					(size 1.27 1.27)
				)
				(justify mirror)
			)
		)
		(duplicate_pad_numbers_are_jumpers no)
		(fp_line
			(start 0.299974 -0.150114)
			(end -0.299974 -0.150114)
			(stroke
				(width 0.1)
				(type default)
			)
			(layer "B.Fab")
		)
		(fp_line
			(start -0.299974 -0.150114)
			(end -0.299974 0.150114)
			(stroke
				(width 0.1)
				(type default)
			)
			(layer "B.Fab")
		)
		(fp_line
			(start 0.299974 0.150114)
			(end 0.299974 -0.150114)
			(stroke
				(width 0.1)
				(type default)
			)
			(layer "B.Fab")
		)
		(fp_line
			(start -0.299974 0.150114)
			(end 0.299974 0.150114)
			(stroke
				(width 0.1)
				(type default)
			)
			(layer "B.Fab")
		)
		(pad "1" smd rect
			(at 0.2667 0 270)
			(size 0.3048 0.381)
			(layers "B.Cu" "B.Mask" "B.Paste")
			(net "PCEPLL5_VDDA18_PEX1")
		)
		(pad "2" smd rect
			(at -0.2667 0 270)
			(size 0.3048 0.381)
			(layers "B.Cu" "B.Mask" "B.Paste")
			(net "GND")
		)
	)
	(footprint ""
		(layer "B.Cu")
		(at 109.641894 -321.810888 -90)
		(property "Reference" "R6457"
			(at 0 0 90)
			(layer "B.SilkS")
			(hide yes)
			(effects
				(font
					(size 1.27 1.27)
				)
				(justify mirror)
			)
		)
		(property "Value" ""
			(at 0 0 90)
			(layer "B.Fab")
			(effects
				(font
					(size 1.27 1.27)
				)
				(justify mirror)
			)
		)
		(duplicate_pad_numbers_are_jumpers no)
		(fp_line
			(start -0.7874 0.4064)
			(end 0.7874 0.4064)
			(stroke
				(width 0.1524)
				(type default)
			)
			(layer "B.SilkS")
		)
		(fp_line
			(start 0.7874 0.4064)
			(end 0.7874 -0.4064)
			(stroke
				(width 0.1524)
				(type default)
			)
			(layer "B.SilkS")
		)
		(fp_line
			(start -0.7874 -0.4064)
			(end -0.7874 0.4064)
			(stroke
				(width 0.1524)
				(type default)
			)
			(layer "B.SilkS")
		)
		(fp_line
			(start 0.7874 -0.4064)
			(end -0.7874 -0.4064)
			(stroke
				(width 0.1524)
				(type default)
			)
			(layer "B.SilkS")
		)
		(fp_line
			(start -0.67945 0.3048)
			(end -0.120396 0.3048)
			(stroke
				(width 0.1)
				(type default)
			)
			(layer "B.Fab")
		)
		(fp_line
			(start -0.120396 0.3048)
			(end -0.120396 0.2794)
			(stroke
				(width 0.1)
				(type default)
			)
			(layer "B.Fab")
		)
		(fp_line
			(start 0.12065 0.3048)
			(end 0.67945 0.3048)
			(stroke
				(width 0.1)
				(type default)
			)
			(layer "B.Fab")
		)
		(fp_line
			(start 0.67945 0.3048)
			(end 0.67945 -0.305054)
			(stroke
				(width 0.1)
				(type default)
			)
			(layer "B.Fab")
		)
		(fp_line
			(start -0.120396 0.2794)
			(end 0.12065 0.2794)
			(stroke
				(width 0.1)
				(type default)
			)
			(layer "B.Fab")
		)
		(fp_line
			(start 0.12065 0.2794)
			(end 0.12065 0.3048)
			(stroke
				(width 0.1)
				(type default)
			)
			(layer "B.Fab")
		)
		(fp_line
			(start -0.12065 -0.2794)
			(end -0.12065 -0.3048)
			(stroke
				(width 0.1)
				(type default)
			)
			(layer "B.Fab")
		)
		(fp_line
			(start 0.12065 -0.2794)
			(end -0.12065 -0.2794)
			(stroke
				(width 0.1)
				(type default)
			)
			(layer "B.Fab")
		)
		(fp_line
			(start -0.67945 -0.3048)
			(end -0.67945 0.3048)
			(stroke
				(width 0.1)
				(type default)
			)
			(layer "B.Fab")
		)
		(fp_line
			(start -0.12065 -0.3048)
			(end -0.67945 -0.3048)
			(stroke
				(width 0.1)
				(type default)
			)
			(layer "B.Fab")
		)
		(fp_line
			(start 0.12065 -0.305054)
			(end 0.12065 -0.2794)
			(stroke
				(width 0.1)
				(type default)
			)
			(layer "B.Fab")
		)
		(fp_line
			(start 0.67945 -0.305054)
			(end 0.12065 -0.305054)
			(stroke
				(width 0.1)
				(type default)
			)
			(layer "B.Fab")
		)
		(pad "1" smd circle
			(at 0.40005 0 90)
			(size 0 0)
			(layers "B.Cu" "B.Mask" "B.Paste")
			(net "P0V8_SERDES_VDDA_PEX0")
		)
		(pad "2" smd circle
			(at -0.40005 0 90)
			(size 0 0)
			(layers "B.Cu" "B.Mask" "B.Paste")
			(net "P0V8_SERDES_VDDA_PEX0_C8")
		)
	)
	(footprint ""
		(layer "B.Cu")
		(at 210.782408 -225.68027 -90)
		(property "Reference" "C4491"
			(at 0 0 90)
			(layer "B.SilkS")
			(hide yes)
			(effects
				(font
					(size 1.27 1.27)
				)
				(justify mirror)
			)
		)
		(property "Value" ""
			(at 0 0 90)
			(layer "B.Fab")
			(effects
				(font
					(size 1.27 1.27)
				)
				(justify mirror)
			)
		)
		(duplicate_pad_numbers_are_jumpers no)
		(fp_line
			(start -0.7874 0.4064)
			(end 0.7874 0.4064)
			(stroke
				(width 0.1524)
				(type default)
			)
			(layer "B.SilkS")
		)
		(fp_line
			(start 0.7874 0.4064)
			(end 0.7874 -0.4064)
			(stroke
				(width 0.1524)
				(type default)
			)
			(layer "B.SilkS")
		)
		(fp_line
			(start -0.7874 -0.4064)
			(end -0.7874 0.4064)
			(stroke
				(width 0.1524)
				(type default)
			)
			(layer "B.SilkS")
		)
		(fp_line
			(start 0.7874 -0.4064)
			(end -0.7874 -0.4064)
			(stroke
				(width 0.1524)
				(type default)
			)
			(layer "B.SilkS")
		)
		(fp_line
			(start -0.67945 0.3048)
			(end -0.120396 0.3048)
			(stroke
				(width 0.1)
				(type default)
			)
			(layer "B.Fab")
		)
		(fp_line
			(start -0.120396 0.3048)
			(end -0.120396 0.2794)
			(stroke
				(width 0.1)
				(type default)
			)
			(layer "B.Fab")
		)
		(fp_line
			(start 0.12065 0.3048)
			(end 0.67945 0.3048)
			(stroke
				(width 0.1)
				(type default)
			)
			(layer "B.Fab")
		)
		(fp_line
			(start 0.67945 0.3048)
			(end 0.67945 -0.305054)
			(stroke
				(width 0.1)
				(type default)
			)
			(layer "B.Fab")
		)
		(fp_line
			(start -0.120396 0.2794)
			(end 0.12065 0.2794)
			(stroke
				(width 0.1)
				(type default)
			)
			(layer "B.Fab")
		)
		(fp_line
			(start 0.12065 0.2794)
			(end 0.12065 0.3048)
			(stroke
				(width 0.1)
				(type default)
			)
			(layer "B.Fab")
		)
		(fp_line
			(start -0.12065 -0.2794)
			(end -0.12065 -0.3048)
			(stroke
				(width 0.1)
				(type default)
			)
			(layer "B.Fab")
		)
		(fp_line
			(start 0.12065 -0.2794)
			(end -0.12065 -0.2794)
			(stroke
				(width 0.1)
				(type default)
			)
			(layer "B.Fab")
		)
		(fp_line
			(start -0.67945 -0.3048)
			(end -0.67945 0.3048)
			(stroke
				(width 0.1)
				(type default)
			)
			(layer "B.Fab")
		)
		(fp_line
			(start -0.12065 -0.3048)
			(end -0.67945 -0.3048)
			(stroke
				(width 0.1)
				(type default)
			)
			(layer "B.Fab")
		)
		(fp_line
			(start 0.12065 -0.305054)
			(end 0.12065 -0.2794)
			(stroke
				(width 0.1)
				(type default)
			)
			(layer "B.Fab")
		)
		(fp_line
			(start 0.67945 -0.305054)
			(end 0.12065 -0.305054)
			(stroke
				(width 0.1)
				(type default)
			)
			(layer "B.Fab")
		)
		(pad "1" smd circle
			(at 0.40005 0 90)
			(size 0 0)
			(layers "B.Cu" "B.Mask" "B.Paste")
			(net "ADC_TYPE_ADC_R")
		)
		(pad "2" smd circle
			(at -0.40005 0 90)
			(size 0 0)
			(layers "B.Cu" "B.Mask" "B.Paste")
			(net "GND")
		)
	)
	(footprint ""
		(layer "B.Cu")
		(at 281.608022 -303.024794 180)
		(property "Reference" "C3360"
			(at 0 0 0)
			(layer "B.SilkS")
			(hide yes)
			(effects
				(font
					(size 1.27 1.27)
				)
				(justify mirror)
			)
		)
		(property "Value" ""
			(at 0 0 0)
			(layer "B.Fab")
			(effects
				(font
					(size 1.27 1.27)
				)
				(justify mirror)
			)
		)
		(duplicate_pad_numbers_are_jumpers no)
		(fp_line
			(start 0.299974 0.150114)
			(end 0.299974 -0.150114)
			(stroke
				(width 0.1)
				(type default)
			)
			(layer "B.Fab")
		)
		(fp_line
			(start 0.299974 -0.150114)
			(end -0.299974 -0.150114)
			(stroke
				(width 0.1)
				(type default)
			)
			(layer "B.Fab")
		)
		(fp_line
			(start -0.299974 0.150114)
			(end 0.299974 0.150114)
			(stroke
				(width 0.1)
				(type default)
			)
			(layer "B.Fab")
		)
		(fp_line
			(start -0.299974 -0.150114)
			(end -0.299974 0.150114)
			(stroke
				(width 0.1)
				(type default)
			)
			(layer "B.Fab")
		)
		(pad "1" smd rect
			(at 0.2667 0)
			(size 0.3048 0.381)
			(layers "B.Cu" "B.Mask" "B.Paste")
			(net "P1V8_VDDA_PEX2")
		)
		(pad "2" smd rect
			(at -0.2667 0)
			(size 0.3048 0.381)
			(layers "B.Cu" "B.Mask" "B.Paste")
			(net "GND")
		)
	)
	(footprint ""
		(layer "B.Cu")
		(at 283.720032 -305.399948 -90)
		(property "Reference" "C3326"
			(at 0 0 90)
			(layer "B.SilkS")
			(hide yes)
			(effects
				(font
					(size 1.27 1.27)
				)
				(justify mirror)
			)
		)
		(property "Value" ""
			(at 0 0 90)
			(layer "B.Fab")
			(effects
				(font
					(size 1.27 1.27)
				)
				(justify mirror)
			)
		)
		(duplicate_pad_numbers_are_jumpers no)
		(fp_line
			(start -0.299974 0.150114)
			(end 0.299974 0.150114)
			(stroke
				(width 0.1)
				(type default)
			)
			(layer "B.Fab")
		)
		(fp_line
			(start 0.299974 0.150114)
			(end 0.299974 -0.150114)
			(stroke
				(width 0.1)
				(type default)
			)
			(layer "B.Fab")
		)
		(fp_line
			(start -0.299974 -0.150114)
			(end -0.299974 0.150114)
			(stroke
				(width 0.1)
				(type default)
			)
			(layer "B.Fab")
		)
		(fp_line
			(start 0.299974 -0.150114)
			(end -0.299974 -0.150114)
			(stroke
				(width 0.1)
				(type default)
			)
			(layer "B.Fab")
		)
		(pad "1" smd rect
			(at 0.2667 0 90)
			(size 0.3048 0.381)
			(layers "B.Cu" "B.Mask" "B.Paste")
			(net "P1V25_SERDES_VDDPLL_PEX2")
		)
		(pad "2" smd rect
			(at -0.2667 0 90)
			(size 0.3048 0.381)
			(layers "B.Cu" "B.Mask" "B.Paste")
			(net "GND")
		)
	)
	(footprint ""
		(layer "B.Cu")
		(at 296.599864 -299.699934 -90)
		(property "Reference" "C1722"
			(at 0 0 90)
			(layer "B.SilkS")
			(hide yes)
			(effects
				(font
					(size 1.27 1.27)
				)
				(justify mirror)
			)
		)
		(property "Value" ""
			(at 0 0 90)
			(layer "B.Fab")
			(effects
				(font
					(size 1.27 1.27)
				)
				(justify mirror)
			)
		)
		(duplicate_pad_numbers_are_jumpers no)
		(fp_line
			(start -0.299974 0.150114)
			(end 0.299974 0.150114)
			(stroke
				(width 0.1)
				(type default)
			)
			(layer "B.Fab")
		)
		(fp_line
			(start 0.299974 0.150114)
			(end 0.299974 -0.150114)
			(stroke
				(width 0.1)
				(type default)
			)
			(layer "B.Fab")
		)
		(fp_line
			(start -0.299974 -0.150114)
			(end -0.299974 0.150114)
			(stroke
				(width 0.1)
				(type default)
			)
			(layer "B.Fab")
		)
		(fp_line
			(start 0.299974 -0.150114)
			(end -0.299974 -0.150114)
			(stroke
				(width 0.1)
				(type default)
			)
			(layer "B.Fab")
		)
		(pad "1" smd rect
			(at 0.2667 0 90)
			(size 0.3048 0.381)
			(layers "B.Cu" "B.Mask" "B.Paste")
			(net "P0V8_SERDES_VDDA_PEX2")
		)
		(pad "2" smd rect
			(at -0.2667 0 90)
			(size 0.3048 0.381)
			(layers "B.Cu" "B.Mask" "B.Paste")
			(net "GND")
		)
	)
	(footprint ""
		(layer "B.Cu")
		(at 64.399922 -303.499774 -90)
		(property "Reference" "C2939"
			(at 0 0 90)
			(layer "B.SilkS")
			(hide yes)
			(effects
				(font
					(size 1.27 1.27)
				)
				(justify mirror)
			)
		)
		(property "Value" ""
			(at 0 0 90)
			(layer "B.Fab")
			(effects
				(font
					(size 1.27 1.27)
				)
				(justify mirror)
			)
		)
		(duplicate_pad_numbers_are_jumpers no)
		(fp_line
			(start -0.299974 0.150114)
			(end 0.299974 0.150114)
			(stroke
				(width 0.1)
				(type default)
			)
			(layer "B.Fab")
		)
		(fp_line
			(start 0.299974 0.150114)
			(end 0.299974 -0.150114)
			(stroke
				(width 0.1)
				(type default)
			)
			(layer "B.Fab")
		)
		(fp_line
			(start -0.299974 -0.150114)
			(end -0.299974 0.150114)
			(stroke
				(width 0.1)
				(type default)
			)
			(layer "B.Fab")
		)
		(fp_line
			(start 0.299974 -0.150114)
			(end -0.299974 -0.150114)
			(stroke
				(width 0.1)
				(type default)
			)
			(layer "B.Fab")
		)
		(pad "1" smd rect
			(at 0.2667 0 90)
			(size 0.3048 0.381)
			(layers "B.Cu" "B.Mask" "B.Paste")
			(net "P1V25_PEX0")
		)
		(pad "2" smd rect
			(at -0.2667 0 90)
			(size 0.3048 0.381)
			(layers "B.Cu" "B.Mask" "B.Paste")
			(net "GND")
		)
	)
	(footprint ""
		(layer "B.Cu")
		(at 417.924996 -304.241454 90)
		(property "Reference" "C3529"
			(at 0 0 90)
			(layer "B.SilkS")
			(hide yes)
			(effects
				(font
					(size 1.27 1.27)
				)
				(justify mirror)
			)
		)
		(property "Value" ""
			(at 0 0 90)
			(layer "B.Fab")
			(effects
				(font
					(size 1.27 1.27)
				)
				(justify mirror)
			)
		)
		(duplicate_pad_numbers_are_jumpers no)
		(fp_line
			(start 0.299974 -0.150114)
			(end -0.299974 -0.150114)
			(stroke
				(width 0.1)
				(type default)
			)
			(layer "B.Fab")
		)
		(fp_line
			(start -0.299974 -0.150114)
			(end -0.299974 0.150114)
			(stroke
				(width 0.1)
				(type default)
			)
			(layer "B.Fab")
		)
		(fp_line
			(start 0.299974 0.150114)
			(end 0.299974 -0.150114)
			(stroke
				(width 0.1)
				(type default)
			)
			(layer "B.Fab")
		)
		(fp_line
			(start -0.299974 0.150114)
			(end 0.299974 0.150114)
			(stroke
				(width 0.1)
				(type default)
			)
			(layer "B.Fab")
		)
		(pad "1" smd rect
			(at 0.2667 0 270)
			(size 0.3048 0.381)
			(layers "B.Cu" "B.Mask" "B.Paste")
			(net "P1V8_VDDA_PEX3")
		)
		(pad "2" smd rect
			(at -0.2667 0 270)
			(size 0.3048 0.381)
			(layers "B.Cu" "B.Mask" "B.Paste")
			(net "GND")
		)
	)
	(footprint ""
		(layer "B.Cu")
		(at 109.502956 -325.22414 -90)
		(property "Reference" "C4214"
			(at 0 0 90)
			(layer "B.SilkS")
			(hide yes)
			(effects
				(font
					(size 1.27 1.27)
				)
				(justify mirror)
			)
		)
		(property "Value" ""
			(at 0 0 90)
			(layer "B.Fab")
			(effects
				(font
					(size 1.27 1.27)
				)
				(justify mirror)
			)
		)
		(duplicate_pad_numbers_are_jumpers no)
		(fp_line
			(start -1.2954 0.5842)
			(end 1.2954 0.5842)
			(stroke
				(width 0.1524)
				(type default)
			)
			(layer "B.SilkS")
		)
		(fp_line
			(start 1.2954 0.5842)
			(end 1.2954 -0.5842)
			(stroke
				(width 0.1524)
				(type default)
			)
			(layer "B.SilkS")
		)
		(fp_line
			(start -1.2954 -0.5842)
			(end -1.2954 0.5842)
			(stroke
				(width 0.1524)
				(type default)
			)
			(layer "B.SilkS")
		)
		(fp_line
			(start 1.2954 -0.5842)
			(end -1.2954 -0.5842)
			(stroke
				(width 0.1524)
				(type default)
			)
			(layer "B.SilkS")
		)
		(fp_line
			(start -0.8636 0.4572)
			(end 0.8636 0.4572)
			(stroke
				(width 0.1)
				(type default)
			)
			(layer "B.Fab")
		)
		(fp_line
			(start 0.8636 0.4572)
			(end 0.8636 0.4064)
			(stroke
				(width 0.1)
				(type default)
			)
			(layer "B.Fab")
		)
		(fp_line
			(start -1.1938 0.4064)
			(end -0.8636 0.4064)
			(stroke
				(width 0.1)
				(type default)
			)
			(layer "B.Fab")
		)
		(fp_line
			(start -0.8636 0.4064)
			(end -0.8636 0.4572)
			(stroke
				(width 0.1)
				(type default)
			)
			(layer "B.Fab")
		)
		(fp_line
			(start 0.8636 0.4064)
			(end 1.1938 0.4064)
			(stroke
				(width 0.1)
				(type default)
			)
			(layer "B.Fab")
		)
		(fp_line
			(start 1.1938 0.4064)
			(end 1.1938 -0.4064)
			(stroke
				(width 0.1)
				(type default)
			)
			(layer "B.Fab")
		)
		(fp_line
			(start -1.1938 -0.4064)
			(end -1.1938 0.4064)
			(stroke
				(width 0.1)
				(type default)
			)
			(layer "B.Fab")
		)
		(fp_line
			(start -0.8636 -0.4064)
			(end -1.1938 -0.4064)
			(stroke
				(width 0.1)
				(type default)
			)
			(layer "B.Fab")
		)
		(fp_line
			(start 0.8636 -0.4064)
			(end 0.8636 -0.4572)
			(stroke
				(width 0.1)
				(type default)
			)
			(layer "B.Fab")
		)
		(fp_line
			(start 1.1938 -0.4064)
			(end 0.8636 -0.4064)
			(stroke
				(width 0.1)
				(type default)
			)
			(layer "B.Fab")
		)
		(fp_line
			(start -0.8636 -0.4572)
			(end -0.8636 -0.4064)
			(stroke
				(width 0.1)
				(type default)
			)
			(layer "B.Fab")
		)
		(fp_line
			(start 0.8636 -0.4572)
			(end -0.8636 -0.4572)
			(stroke
				(width 0.1)
				(type default)
			)
			(layer "B.Fab")
		)
		(pad "1" smd rect
			(at 0.7366 0 180)
			(size 0.7112 0.8128)
			(layers "B.Cu" "B.Mask" "B.Paste")
			(net "P0V8_SERDES_VDDA_PEX0_C8")
		)
		(pad "2" smd rect
			(at -0.7366 0 180)
			(size 0.7112 0.8128)
			(layers "B.Cu" "B.Mask" "B.Paste")
			(net "GND")
		)
	)
	(footprint ""
		(layer "B.Cu")
		(at 3.06578 -275.977858)
		(property "Reference" "C4234"
			(at 0 0 0)
			(layer "B.SilkS")
			(hide yes)
			(effects
				(font
					(size 1.27 1.27)
				)
				(justify mirror)
			)
		)
		(property "Value" ""
			(at 0 0 0)
			(layer "B.Fab")
			(effects
				(font
					(size 1.27 1.27)
				)
				(justify mirror)
			)
		)
		(duplicate_pad_numbers_are_jumpers no)
		(fp_line
			(start -1.2954 -0.5842)
			(end -1.2954 0.5842)
			(stroke
				(width 0.1524)
				(type default)
			)
			(layer "B.SilkS")
		)
		(fp_line
			(start -1.2954 0.5842)
			(end 1.2954 0.5842)
			(stroke
				(width 0.1524)
				(type default)
			)
			(layer "B.SilkS")
		)
		(fp_line
			(start 1.2954 -0.5842)
			(end -1.2954 -0.5842)
			(stroke
				(width 0.1524)
				(type default)
			)
			(layer "B.SilkS")
		)
		(fp_line
			(start 1.2954 0.5842)
			(end 1.2954 -0.5842)
			(stroke
				(width 0.1524)
				(type default)
			)
			(layer "B.SilkS")
		)
		(fp_line
			(start -1.1938 -0.4064)
			(end -1.1938 0.4064)
			(stroke
				(width 0.1)
				(type default)
			)
			(layer "B.Fab")
		)
		(fp_line
			(start -1.1938 0.4064)
			(end -0.8636 0.4064)
			(stroke
				(width 0.1)
				(type default)
			)
			(layer "B.Fab")
		)
		(fp_line
			(start -0.8636 -0.4572)
			(end -0.8636 -0.4064)
			(stroke
				(width 0.1)
				(type default)
			)
			(layer "B.Fab")
		)
		(fp_line
			(start -0.8636 -0.4064)
			(end -1.1938 -0.4064)
			(stroke
				(width 0.1)
				(type default)
			)
			(layer "B.Fab")
		)
		(fp_line
			(start -0.8636 0.4064)
			(end -0.8636 0.4572)
			(stroke
				(width 0.1)
				(type default)
			)
			(layer "B.Fab")
		)
		(fp_line
			(start -0.8636 0.4572)
			(end 0.8636 0.4572)
			(stroke
				(width 0.1)
				(type default)
			)
			(layer "B.Fab")
		)
		(fp_line
			(start 0.8636 -0.4572)
			(end -0.8636 -0.4572)
			(stroke
				(width 0.1)
				(type default)
			)
			(layer "B.Fab")
		)
		(fp_line
			(start 0.8636 -0.4064)
			(end 0.8636 -0.4572)
			(stroke
				(width 0.1)
				(type default)
			)
			(layer "B.Fab")
		)
		(fp_line
			(start 0.8636 0.4064)
			(end 1.1938 0.4064)
			(stroke
				(width 0.1)
				(type default)
			)
			(layer "B.Fab")
		)
		(fp_line
			(start 0.8636 0.4572)
			(end 0.8636 0.4064)
			(stroke
				(width 0.1)
				(type default)
			)
			(layer "B.Fab")
		)
		(fp_line
			(start 1.1938 -0.4064)
			(end 0.8636 -0.4064)
			(stroke
				(width 0.1)
				(type default)
			)
			(layer "B.Fab")
		)
		(fp_line
			(start 1.1938 0.4064)
			(end 1.1938 -0.4064)
			(stroke
				(width 0.1)
				(type default)
			)
			(layer "B.Fab")
		)
		(pad "1" smd rect
			(at 0.7366 0 270)
			(size 0.7112 0.8128)
			(layers "B.Cu" "B.Mask" "B.Paste")
			(net "P1V25_PEX0")
		)
		(pad "2" smd rect
			(at -0.7366 0 270)
			(size 0.7112 0.8128)
			(layers "B.Cu" "B.Mask" "B.Paste")
			(net "GND")
		)
	)
	(footprint ""
		(layer "B.Cu")
		(at 211.569808 -239.851692 90)
		(property "Reference" "R1546"
			(at 0 0 90)
			(layer "B.SilkS")
			(hide yes)
			(effects
				(font
					(size 1.27 1.27)
				)
				(justify mirror)
			)
		)
		(property "Value" ""
			(at 0 0 90)
			(layer "B.Fab")
			(effects
				(font
					(size 1.27 1.27)
				)
				(justify mirror)
			)
		)
		(duplicate_pad_numbers_are_jumpers no)
		(fp_line
			(start 0.7874 -0.4064)
			(end -0.7874 -0.4064)
			(stroke
				(width 0.1524)
				(type default)
			)
			(layer "B.SilkS")
		)
		(fp_line
			(start -0.7874 -0.4064)
			(end -0.7874 0.4064)
			(stroke
				(width 0.1524)
				(type default)
			)
			(layer "B.SilkS")
		)
		(fp_line
			(start 0.7874 0.4064)
			(end 0.7874 -0.4064)
			(stroke
				(width 0.1524)
				(type default)
			)
			(layer "B.SilkS")
		)
		(fp_line
			(start -0.7874 0.4064)
			(end 0.7874 0.4064)
			(stroke
				(width 0.1524)
				(type default)
			)
			(layer "B.SilkS")
		)
		(fp_line
			(start 0.67945 -0.305054)
			(end 0.12065 -0.305054)
			(stroke
				(width 0.1)
				(type default)
			)
			(layer "B.Fab")
		)
		(fp_line
			(start 0.12065 -0.305054)
			(end 0.12065 -0.2794)
			(stroke
				(width 0.1)
				(type default)
			)
			(layer "B.Fab")
		)
		(fp_line
			(start -0.12065 -0.3048)
			(end -0.67945 -0.3048)
			(stroke
				(width 0.1)
				(type default)
			)
			(layer "B.Fab")
		)
		(fp_line
			(start -0.67945 -0.3048)
			(end -0.67945 0.3048)
			(stroke
				(width 0.1)
				(type default)
			)
			(layer "B.Fab")
		)
		(fp_line
			(start 0.12065 -0.2794)
			(end -0.12065 -0.2794)
			(stroke
				(width 0.1)
				(type default)
			)
			(layer "B.Fab")
		)
		(fp_line
			(start -0.12065 -0.2794)
			(end -0.12065 -0.3048)
			(stroke
				(width 0.1)
				(type default)
			)
			(layer "B.Fab")
		)
		(fp_line
			(start 0.12065 0.2794)
			(end 0.12065 0.3048)
			(stroke
				(width 0.1)
				(type default)
			)
			(layer "B.Fab")
		)
		(fp_line
			(start -0.120396 0.2794)
			(end 0.12065 0.2794)
			(stroke
				(width 0.1)
				(type default)
			)
			(layer "B.Fab")
		)
		(fp_line
			(start 0.67945 0.3048)
			(end 0.67945 -0.305054)
			(stroke
				(width 0.1)
				(type default)
			)
			(layer "B.Fab")
		)
		(fp_line
			(start 0.12065 0.3048)
			(end 0.67945 0.3048)
			(stroke
				(width 0.1)
				(type default)
			)
			(layer "B.Fab")
		)
		(fp_line
			(start -0.120396 0.3048)
			(end -0.120396 0.2794)
			(stroke
				(width 0.1)
				(type default)
			)
			(layer "B.Fab")
		)
		(fp_line
			(start -0.67945 0.3048)
			(end -0.120396 0.3048)
			(stroke
				(width 0.1)
				(type default)
			)
			(layer "B.Fab")
		)
		(pad "1" smd circle
			(at 0.40005 0 270)
			(size 0 0)
			(layers "B.Cu" "B.Mask" "B.Paste")
			(net "SMB_PEX_R_SCL")
		)
		(pad "2" smd circle
			(at -0.40005 0 270)
			(size 0 0)
			(layers "B.Cu" "B.Mask" "B.Paste")
			(net "SMB_PEX_LS_SCL")
		)
	)
	(footprint ""
		(layer "B.Cu")
		(at 396.0749 -298.00804 90)
		(property "Reference" "C3590"
			(at 0 0 90)
			(layer "B.SilkS")
			(hide yes)
			(effects
				(font
					(size 1.27 1.27)
				)
				(justify mirror)
			)
		)
		(property "Value" ""
			(at 0 0 90)
			(layer "B.Fab")
			(effects
				(font
					(size 1.27 1.27)
				)
				(justify mirror)
			)
		)
		(duplicate_pad_numbers_are_jumpers no)
		(fp_line
			(start 0.299974 -0.150114)
			(end -0.299974 -0.150114)
			(stroke
				(width 0.1)
				(type default)
			)
			(layer "B.Fab")
		)
		(fp_line
			(start -0.299974 -0.150114)
			(end -0.299974 0.150114)
			(stroke
				(width 0.1)
				(type default)
			)
			(layer "B.Fab")
		)
		(fp_line
			(start 0.299974 0.150114)
			(end 0.299974 -0.150114)
			(stroke
				(width 0.1)
				(type default)
			)
			(layer "B.Fab")
		)
		(fp_line
			(start -0.299974 0.150114)
			(end 0.299974 0.150114)
			(stroke
				(width 0.1)
				(type default)
			)
			(layer "B.Fab")
		)
		(pad "1" smd rect
			(at 0.2667 0 270)
			(size 0.3048 0.381)
			(layers "B.Cu" "B.Mask" "B.Paste")
			(net "SYSPLL_VDDA18_PEX3")
		)
		(pad "2" smd rect
			(at -0.2667 0 270)
			(size 0.3048 0.381)
			(layers "B.Cu" "B.Mask" "B.Paste")
			(net "GND")
		)
	)
	(footprint ""
		(layer "B.Cu")
		(at 174.325026 -293.99992 90)
		(property "Reference" "C1380"
			(at 0 0 90)
			(layer "B.SilkS")
			(hide yes)
			(effects
				(font
					(size 1.27 1.27)
				)
				(justify mirror)
			)
		)
		(property "Value" ""
			(at 0 0 90)
			(layer "B.Fab")
			(effects
				(font
					(size 1.27 1.27)
				)
				(justify mirror)
			)
		)
		(duplicate_pad_numbers_are_jumpers no)
		(fp_line
			(start 0.299974 -0.150114)
			(end -0.299974 -0.150114)
			(stroke
				(width 0.1)
				(type default)
			)
			(layer "B.Fab")
		)
		(fp_line
			(start -0.299974 -0.150114)
			(end -0.299974 0.150114)
			(stroke
				(width 0.1)
				(type default)
			)
			(layer "B.Fab")
		)
		(fp_line
			(start 0.299974 0.150114)
			(end 0.299974 -0.150114)
			(stroke
				(width 0.1)
				(type default)
			)
			(layer "B.Fab")
		)
		(fp_line
			(start -0.299974 0.150114)
			(end 0.299974 0.150114)
			(stroke
				(width 0.1)
				(type default)
			)
			(layer "B.Fab")
		)
		(pad "1" smd rect
			(at 0.2667 0 270)
			(size 0.3048 0.381)
			(layers "B.Cu" "B.Mask" "B.Paste")
			(net "P0V8_PEX1")
		)
		(pad "2" smd rect
			(at -0.2667 0 270)
			(size 0.3048 0.381)
			(layers "B.Cu" "B.Mask" "B.Paste")
			(net "GND")
		)
	)
	(footprint ""
		(layer "B.Cu")
		(at 298.499784 -290.199826 90)
		(property "Reference" "C1682"
			(at 0 0 90)
			(layer "B.SilkS")
			(hide yes)
			(effects
				(font
					(size 1.27 1.27)
				)
				(justify mirror)
			)
		)
		(property "Value" ""
			(at 0 0 90)
			(layer "B.Fab")
			(effects
				(font
					(size 1.27 1.27)
				)
				(justify mirror)
			)
		)
		(duplicate_pad_numbers_are_jumpers no)
		(fp_line
			(start 0.299974 -0.150114)
			(end -0.299974 -0.150114)
			(stroke
				(width 0.1)
				(type default)
			)
			(layer "B.Fab")
		)
		(fp_line
			(start -0.299974 -0.150114)
			(end -0.299974 0.150114)
			(stroke
				(width 0.1)
				(type default)
			)
			(layer "B.Fab")
		)
		(fp_line
			(start 0.299974 0.150114)
			(end 0.299974 -0.150114)
			(stroke
				(width 0.1)
				(type default)
			)
			(layer "B.Fab")
		)
		(fp_line
			(start -0.299974 0.150114)
			(end 0.299974 0.150114)
			(stroke
				(width 0.1)
				(type default)
			)
			(layer "B.Fab")
		)
		(pad "1" smd rect
			(at 0.2667 0 270)
			(size 0.3048 0.381)
			(layers "B.Cu" "B.Mask" "B.Paste")
			(net "P0V8_SERDES_VDDA_PEX2")
		)
		(pad "2" smd rect
			(at -0.2667 0 270)
			(size 0.3048 0.381)
			(layers "B.Cu" "B.Mask" "B.Paste")
			(net "GND")
		)
	)
	(footprint ""
		(layer "B.Cu")
		(at 5.470398 -384.554476 -90)
		(property "Reference" "C4462"
			(at 0 0 90)
			(layer "B.SilkS")
			(hide yes)
			(effects
				(font
					(size 1.27 1.27)
				)
				(justify mirror)
			)
		)
		(property "Value" ""
			(at 0 0 90)
			(layer "B.Fab")
			(effects
				(font
					(size 1.27 1.27)
				)
				(justify mirror)
			)
		)
		(duplicate_pad_numbers_are_jumpers no)
		(fp_line
			(start -0.7874 0.4064)
			(end 0.7874 0.4064)
			(stroke
				(width 0.1524)
				(type default)
			)
			(layer "B.SilkS")
		)
		(fp_line
			(start 0.7874 0.4064)
			(end 0.7874 -0.4064)
			(stroke
				(width 0.1524)
				(type default)
			)
			(layer "B.SilkS")
		)
		(fp_line
			(start -0.7874 -0.4064)
			(end -0.7874 0.4064)
			(stroke
				(width 0.1524)
				(type default)
			)
			(layer "B.SilkS")
		)
		(fp_line
			(start 0.7874 -0.4064)
			(end -0.7874 -0.4064)
			(stroke
				(width 0.1524)
				(type default)
			)
			(layer "B.SilkS")
		)
		(fp_line
			(start -0.67945 0.3048)
			(end -0.120396 0.3048)
			(stroke
				(width 0.1)
				(type default)
			)
			(layer "B.Fab")
		)
		(fp_line
			(start -0.120396 0.3048)
			(end -0.120396 0.2794)
			(stroke
				(width 0.1)
				(type default)
			)
			(layer "B.Fab")
		)
		(fp_line
			(start 0.12065 0.3048)
			(end 0.67945 0.3048)
			(stroke
				(width 0.1)
				(type default)
			)
			(layer "B.Fab")
		)
		(fp_line
			(start 0.67945 0.3048)
			(end 0.67945 -0.305054)
			(stroke
				(width 0.1)
				(type default)
			)
			(layer "B.Fab")
		)
		(fp_line
			(start -0.120396 0.2794)
			(end 0.12065 0.2794)
			(stroke
				(width 0.1)
				(type default)
			)
			(layer "B.Fab")
		)
		(fp_line
			(start 0.12065 0.2794)
			(end 0.12065 0.3048)
			(stroke
				(width 0.1)
				(type default)
			)
			(layer "B.Fab")
		)
		(fp_line
			(start -0.12065 -0.2794)
			(end -0.12065 -0.3048)
			(stroke
				(width 0.1)
				(type default)
			)
			(layer "B.Fab")
		)
		(fp_line
			(start 0.12065 -0.2794)
			(end -0.12065 -0.2794)
			(stroke
				(width 0.1)
				(type default)
			)
			(layer "B.Fab")
		)
		(fp_line
			(start -0.67945 -0.3048)
			(end -0.67945 0.3048)
			(stroke
				(width 0.1)
				(type default)
			)
			(layer "B.Fab")
		)
		(fp_line
			(start -0.12065 -0.3048)
			(end -0.67945 -0.3048)
			(stroke
				(width 0.1)
				(type default)
			)
			(layer "B.Fab")
		)
		(fp_line
			(start 0.12065 -0.305054)
			(end 0.12065 -0.2794)
			(stroke
				(width 0.1)
				(type default)
			)
			(layer "B.Fab")
		)
		(fp_line
			(start 0.67945 -0.305054)
			(end 0.12065 -0.305054)
			(stroke
				(width 0.1)
				(type default)
			)
			(layer "B.Fab")
		)
		(pad "1" smd circle
			(at 0.40005 0 90)
			(size 0 0)
			(layers "B.Cu" "B.Mask" "B.Paste")
			(net "P3V3_USB_8042")
		)
		(pad "2" smd circle
			(at -0.40005 0 90)
			(size 0 0)
			(layers "B.Cu" "B.Mask" "B.Paste")
			(net "GND")
		)
	)
	(footprint ""
		(layer "B.Cu")
		(at 377.725178 -225.092768 90)
		(property "Reference" "R6172"
			(at 0 0 90)
			(layer "B.SilkS")
			(hide yes)
			(effects
				(font
					(size 1.27 1.27)
				)
				(justify mirror)
			)
		)
		(property "Value" ""
			(at 0 0 90)
			(layer "B.Fab")
			(effects
				(font
					(size 1.27 1.27)
				)
				(justify mirror)
			)
		)
		(duplicate_pad_numbers_are_jumpers no)
		(fp_line
			(start 0.7874 -0.4064)
			(end -0.7874 -0.4064)
			(stroke
				(width 0.1524)
				(type default)
			)
			(layer "B.SilkS")
		)
		(fp_line
			(start -0.7874 -0.4064)
			(end -0.7874 0.4064)
			(stroke
				(width 0.1524)
				(type default)
			)
			(layer "B.SilkS")
		)
		(fp_line
			(start 0.7874 0.4064)
			(end 0.7874 -0.4064)
			(stroke
				(width 0.1524)
				(type default)
			)
			(layer "B.SilkS")
		)
		(fp_line
			(start -0.7874 0.4064)
			(end 0.7874 0.4064)
			(stroke
				(width 0.1524)
				(type default)
			)
			(layer "B.SilkS")
		)
		(fp_line
			(start 0.67945 -0.305054)
			(end 0.12065 -0.305054)
			(stroke
				(width 0.1)
				(type default)
			)
			(layer "B.Fab")
		)
		(fp_line
			(start 0.12065 -0.305054)
			(end 0.12065 -0.2794)
			(stroke
				(width 0.1)
				(type default)
			)
			(layer "B.Fab")
		)
		(fp_line
			(start -0.12065 -0.3048)
			(end -0.67945 -0.3048)
			(stroke
				(width 0.1)
				(type default)
			)
			(layer "B.Fab")
		)
		(fp_line
			(start -0.67945 -0.3048)
			(end -0.67945 0.3048)
			(stroke
				(width 0.1)
				(type default)
			)
			(layer "B.Fab")
		)
		(fp_line
			(start 0.12065 -0.2794)
			(end -0.12065 -0.2794)
			(stroke
				(width 0.1)
				(type default)
			)
			(layer "B.Fab")
		)
		(fp_line
			(start -0.12065 -0.2794)
			(end -0.12065 -0.3048)
			(stroke
				(width 0.1)
				(type default)
			)
			(layer "B.Fab")
		)
		(fp_line
			(start 0.12065 0.2794)
			(end 0.12065 0.3048)
			(stroke
				(width 0.1)
				(type default)
			)
			(layer "B.Fab")
		)
		(fp_line
			(start -0.120396 0.2794)
			(end 0.12065 0.2794)
			(stroke
				(width 0.1)
				(type default)
			)
			(layer "B.Fab")
		)
		(fp_line
			(start 0.67945 0.3048)
			(end 0.67945 -0.305054)
			(stroke
				(width 0.1)
				(type default)
			)
			(layer "B.Fab")
		)
		(fp_line
			(start 0.12065 0.3048)
			(end 0.67945 0.3048)
			(stroke
				(width 0.1)
				(type default)
			)
			(layer "B.Fab")
		)
		(fp_line
			(start -0.120396 0.3048)
			(end -0.120396 0.2794)
			(stroke
				(width 0.1)
				(type default)
			)
			(layer "B.Fab")
		)
		(fp_line
			(start -0.67945 0.3048)
			(end -0.120396 0.3048)
			(stroke
				(width 0.1)
				(type default)
			)
			(layer "B.Fab")
		)
		(pad "1" smd circle
			(at 0.40005 0 270)
			(size 0 0)
			(layers "B.Cu" "B.Mask" "B.Paste")
			(net "SPI_PEX3_RST_R_N")
		)
		(pad "2" smd circle
			(at -0.40005 0 270)
			(size 0 0)
			(layers "B.Cu" "B.Mask" "B.Paste")
			(net "P1V8_PEX")
		)
	)
	(footprint ""
		(layer "B.Cu")
		(at 53.630068 -295.221914)
		(property "Reference" "C1100"
			(at 0 0 0)
			(layer "B.SilkS")
			(hide yes)
			(effects
				(font
					(size 1.27 1.27)
				)
				(justify mirror)
			)
		)
		(property "Value" ""
			(at 0 0 0)
			(layer "B.Fab")
			(effects
				(font
					(size 1.27 1.27)
				)
				(justify mirror)
			)
		)
		(duplicate_pad_numbers_are_jumpers no)
		(fp_line
			(start -1.2954 -0.5842)
			(end -1.2954 0.5842)
			(stroke
				(width 0.1524)
				(type default)
			)
			(layer "B.SilkS")
		)
		(fp_line
			(start -1.2954 0.5842)
			(end 1.2954 0.5842)
			(stroke
				(width 0.1524)
				(type default)
			)
			(layer "B.SilkS")
		)
		(fp_line
			(start 1.2954 -0.5842)
			(end -1.2954 -0.5842)
			(stroke
				(width 0.1524)
				(type default)
			)
			(layer "B.SilkS")
		)
		(fp_line
			(start 1.2954 0.5842)
			(end 1.2954 -0.5842)
			(stroke
				(width 0.1524)
				(type default)
			)
			(layer "B.SilkS")
		)
		(fp_line
			(start -1.1938 -0.4064)
			(end -1.1938 0.4064)
			(stroke
				(width 0.1)
				(type default)
			)
			(layer "B.Fab")
		)
		(fp_line
			(start -1.1938 0.4064)
			(end -0.8636 0.4064)
			(stroke
				(width 0.1)
				(type default)
			)
			(layer "B.Fab")
		)
		(fp_line
			(start -0.8636 -0.4572)
			(end -0.8636 -0.4064)
			(stroke
				(width 0.1)
				(type default)
			)
			(layer "B.Fab")
		)
		(fp_line
			(start -0.8636 -0.4064)
			(end -1.1938 -0.4064)
			(stroke
				(width 0.1)
				(type default)
			)
			(layer "B.Fab")
		)
		(fp_line
			(start -0.8636 0.4064)
			(end -0.8636 0.4572)
			(stroke
				(width 0.1)
				(type default)
			)
			(layer "B.Fab")
		)
		(fp_line
			(start -0.8636 0.4572)
			(end 0.8636 0.4572)
			(stroke
				(width 0.1)
				(type default)
			)
			(layer "B.Fab")
		)
		(fp_line
			(start 0.8636 -0.4572)
			(end -0.8636 -0.4572)
			(stroke
				(width 0.1)
				(type default)
			)
			(layer "B.Fab")
		)
		(fp_line
			(start 0.8636 -0.4064)
			(end 0.8636 -0.4572)
			(stroke
				(width 0.1)
				(type default)
			)
			(layer "B.Fab")
		)
		(fp_line
			(start 0.8636 0.4064)
			(end 1.1938 0.4064)
			(stroke
				(width 0.1)
				(type default)
			)
			(layer "B.Fab")
		)
		(fp_line
			(start 0.8636 0.4572)
			(end 0.8636 0.4064)
			(stroke
				(width 0.1)
				(type default)
			)
			(layer "B.Fab")
		)
		(fp_line
			(start 1.1938 -0.4064)
			(end 0.8636 -0.4064)
			(stroke
				(width 0.1)
				(type default)
			)
			(layer "B.Fab")
		)
		(fp_line
			(start 1.1938 0.4064)
			(end 1.1938 -0.4064)
			(stroke
				(width 0.1)
				(type default)
			)
			(layer "B.Fab")
		)
		(pad "1" smd rect
			(at 0.7366 0 270)
			(size 0.7112 0.8128)
			(layers "B.Cu" "B.Mask" "B.Paste")
			(net "P0V8_PEX0")
		)
		(pad "2" smd rect
			(at -0.7366 0 270)
			(size 0.7112 0.8128)
			(layers "B.Cu" "B.Mask" "B.Paste")
			(net "GND")
		)
	)
	(footprint ""
		(layer "B.Cu")
		(at 403.199854 -303.499774 -90)
		(property "Reference" "C3432"
			(at 0 0 90)
			(layer "B.SilkS")
			(hide yes)
			(effects
				(font
					(size 1.27 1.27)
				)
				(justify mirror)
			)
		)
		(property "Value" ""
			(at 0 0 90)
			(layer "B.Fab")
			(effects
				(font
					(size 1.27 1.27)
				)
				(justify mirror)
			)
		)
		(duplicate_pad_numbers_are_jumpers no)
		(fp_line
			(start -0.299974 0.150114)
			(end 0.299974 0.150114)
			(stroke
				(width 0.1)
				(type default)
			)
			(layer "B.Fab")
		)
		(fp_line
			(start 0.299974 0.150114)
			(end 0.299974 -0.150114)
			(stroke
				(width 0.1)
				(type default)
			)
			(layer "B.Fab")
		)
		(fp_line
			(start -0.299974 -0.150114)
			(end -0.299974 0.150114)
			(stroke
				(width 0.1)
				(type default)
			)
			(layer "B.Fab")
		)
		(fp_line
			(start 0.299974 -0.150114)
			(end -0.299974 -0.150114)
			(stroke
				(width 0.1)
				(type default)
			)
			(layer "B.Fab")
		)
		(pad "1" smd rect
			(at 0.2667 0 90)
			(size 0.3048 0.381)
			(layers "B.Cu" "B.Mask" "B.Paste")
			(net "P1V25_PEX3")
		)
		(pad "2" smd rect
			(at -0.2667 0 90)
			(size 0.3048 0.381)
			(layers "B.Cu" "B.Mask" "B.Paste")
			(net "GND")
		)
	)
	(footprint ""
		(layer "B.Cu")
		(at 234.667552 -217.104214 -90)
		(property "Reference" "C2021"
			(at 0 0 90)
			(layer "B.SilkS")
			(hide yes)
			(effects
				(font
					(size 1.27 1.27)
				)
				(justify mirror)
			)
		)
		(property "Value" ""
			(at 0 0 90)
			(layer "B.Fab")
			(effects
				(font
					(size 1.27 1.27)
				)
				(justify mirror)
			)
		)
		(duplicate_pad_numbers_are_jumpers no)
		(fp_line
			(start -0.69215 0.2921)
			(end 0.69215 0.2921)
			(stroke
				(width 0.1524)
				(type default)
			)
			(layer "B.SilkS")
		)
		(fp_line
			(start 0.69215 0.2921)
			(end 0.69215 -0.2921)
			(stroke
				(width 0.1524)
				(type default)
			)
			(layer "B.SilkS")
		)
		(fp_line
			(start -0.69215 -0.2921)
			(end -0.69215 0.2921)
			(stroke
				(width 0.1524)
				(type default)
			)
			(layer "B.SilkS")
		)
		(fp_line
			(start 0.69215 -0.2921)
			(end -0.69215 -0.2921)
			(stroke
				(width 0.1524)
				(type default)
			)
			(layer "B.SilkS")
		)
		(fp_line
			(start -0.51435 0.2794)
			(end 0.51435 0.2794)
			(stroke
				(width 0.1)
				(type default)
			)
			(layer "B.Fab")
		)
		(fp_line
			(start 0.51435 0.2794)
			(end 0.51435 -0.2794)
			(stroke
				(width 0.1)
				(type default)
			)
			(layer "B.Fab")
		)
		(fp_line
			(start -0.51435 -0.2794)
			(end -0.51435 0.2794)
			(stroke
				(width 0.1)
				(type default)
			)
			(layer "B.Fab")
		)
		(fp_line
			(start 0.51435 -0.2794)
			(end -0.51435 -0.2794)
			(stroke
				(width 0.1)
				(type default)
			)
			(layer "B.Fab")
		)
		(pad "1" smd circle
			(at 0.40005 0 90)
			(size 0 0)
			(layers "B.Cu" "B.Mask" "B.Paste")
			(net "P1V2_BIC_PLL")
		)
		(pad "2" smd circle
			(at -0.40005 0 90)
			(size 0 0)
			(layers "B.Cu" "B.Mask" "B.Paste")
			(net "GND")
		)
		(zone
			(layer "B.Cu")
			(hatch none 0.5)
			(connect_pads
				(clearance 0)
			)
			(min_thickness 0.25)
			(keepout
				(tracks not_allowed)
				(vias allowed)
				(pads allowed)
				(copperpour not_allowed)
				(footprints allowed)
			)
			(placement
				(enabled no)
				(sheetname "")
			)
			(fill
				(thermal_gap 0.5)
				(thermal_bridge_width 0.5)
				(island_removal_mode 0)
			)
			(polygon
				(pts
					(xy 234.579922 -216.913714) (xy 234.521756 -217.005154) (xy 234.521756 -217.204544) (xy 234.579922 -217.294714)
					(xy 234.755182 -217.294714) (xy 234.813602 -217.204544) (xy 234.813602 -217.005154) (xy 234.755436 -216.913714)
				)
			)
		)
	)
	(footprint ""
		(layer "B.Cu")
		(at 329.692 -225.5012)
		(property "Reference" "R4165"
			(at 0 0 0)
			(layer "B.SilkS")
			(hide yes)
			(effects
				(font
					(size 1.27 1.27)
				)
				(justify mirror)
			)
		)
		(property "Value" ""
			(at 0 0 0)
			(layer "B.Fab")
			(effects
				(font
					(size 1.27 1.27)
				)
				(justify mirror)
			)
		)
		(duplicate_pad_numbers_are_jumpers no)
		(fp_line
			(start -0.7874 -0.4064)
			(end -0.7874 0.4064)
			(stroke
				(width 0.1524)
				(type default)
			)
			(layer "B.SilkS")
		)
		(fp_line
			(start -0.7874 0.4064)
			(end 0.7874 0.4064)
			(stroke
				(width 0.1524)
				(type default)
			)
			(layer "B.SilkS")
		)
		(fp_line
			(start 0.7874 -0.4064)
			(end -0.7874 -0.4064)
			(stroke
				(width 0.1524)
				(type default)
			)
			(layer "B.SilkS")
		)
		(fp_line
			(start 0.7874 0.4064)
			(end 0.7874 -0.4064)
			(stroke
				(width 0.1524)
				(type default)
			)
			(layer "B.SilkS")
		)
		(fp_line
			(start -0.67945 -0.3048)
			(end -0.67945 0.3048)
			(stroke
				(width 0.1)
				(type default)
			)
			(layer "B.Fab")
		)
		(fp_line
			(start -0.67945 0.3048)
			(end -0.120396 0.3048)
			(stroke
				(width 0.1)
				(type default)
			)
			(layer "B.Fab")
		)
		(fp_line
			(start -0.12065 -0.3048)
			(end -0.67945 -0.3048)
			(stroke
				(width 0.1)
				(type default)
			)
			(layer "B.Fab")
		)
		(fp_line
			(start -0.12065 -0.2794)
			(end -0.12065 -0.3048)
			(stroke
				(width 0.1)
				(type default)
			)
			(layer "B.Fab")
		)
		(fp_line
			(start -0.120396 0.2794)
			(end 0.12065 0.2794)
			(stroke
				(width 0.1)
				(type default)
			)
			(layer "B.Fab")
		)
		(fp_line
			(start -0.120396 0.3048)
			(end -0.120396 0.2794)
			(stroke
				(width 0.1)
				(type default)
			)
			(layer "B.Fab")
		)
		(fp_line
			(start 0.12065 -0.305054)
			(end 0.12065 -0.2794)
			(stroke
				(width 0.1)
				(type default)
			)
			(layer "B.Fab")
		)
		(fp_line
			(start 0.12065 -0.2794)
			(end -0.12065 -0.2794)
			(stroke
				(width 0.1)
				(type default)
			)
			(layer "B.Fab")
		)
		(fp_line
			(start 0.12065 0.2794)
			(end 0.12065 0.3048)
			(stroke
				(width 0.1)
				(type default)
			)
			(layer "B.Fab")
		)
		(fp_line
			(start 0.12065 0.3048)
			(end 0.67945 0.3048)
			(stroke
				(width 0.1)
				(type default)
			)
			(layer "B.Fab")
		)
		(fp_line
			(start 0.67945 -0.305054)
			(end 0.12065 -0.305054)
			(stroke
				(width 0.1)
				(type default)
			)
			(layer "B.Fab")
		)
		(fp_line
			(start 0.67945 0.3048)
			(end 0.67945 -0.305054)
			(stroke
				(width 0.1)
				(type default)
			)
			(layer "B.Fab")
		)
		(pad "1" smd circle
			(at 0.40005 0 180)
			(size 0 0)
			(layers "B.Cu" "B.Mask" "B.Paste")
			(net "PWR_EN_P1V2_AUX")
		)
		(pad "2" smd circle
			(at -0.40005 0 180)
			(size 0 0)
			(layers "B.Cu" "B.Mask" "B.Paste")
			(net "PWR_EN_P1V2_AUX_R")
		)
	)
	(footprint ""
		(layer "B.Cu")
		(at 52.049934 -303.499774 -90)
		(property "Reference" "C2909"
			(at 0 0 90)
			(layer "B.SilkS")
			(hide yes)
			(effects
				(font
					(size 1.27 1.27)
				)
				(justify mirror)
			)
		)
		(property "Value" ""
			(at 0 0 90)
			(layer "B.Fab")
			(effects
				(font
					(size 1.27 1.27)
				)
				(justify mirror)
			)
		)
		(duplicate_pad_numbers_are_jumpers no)
		(fp_line
			(start -0.299974 0.150114)
			(end 0.299974 0.150114)
			(stroke
				(width 0.1)
				(type default)
			)
			(layer "B.Fab")
		)
		(fp_line
			(start 0.299974 0.150114)
			(end 0.299974 -0.150114)
			(stroke
				(width 0.1)
				(type default)
			)
			(layer "B.Fab")
		)
		(fp_line
			(start -0.299974 -0.150114)
			(end -0.299974 0.150114)
			(stroke
				(width 0.1)
				(type default)
			)
			(layer "B.Fab")
		)
		(fp_line
			(start 0.299974 -0.150114)
			(end -0.299974 -0.150114)
			(stroke
				(width 0.1)
				(type default)
			)
			(layer "B.Fab")
		)
		(pad "1" smd rect
			(at 0.2667 0 90)
			(size 0.3048 0.381)
			(layers "B.Cu" "B.Mask" "B.Paste")
			(net "P1V25_PEX0")
		)
		(pad "2" smd rect
			(at -0.2667 0 90)
			(size 0.3048 0.381)
			(layers "B.Cu" "B.Mask" "B.Paste")
			(net "GND")
		)
	)
	(footprint ""
		(layer "B.Cu")
		(at 133.025896 -170.464226)
		(property "Reference" "R1476"
			(at 0 0 0)
			(layer "B.SilkS")
			(hide yes)
			(effects
				(font
					(size 1.27 1.27)
				)
				(justify mirror)
			)
		)
		(property "Value" ""
			(at 0 0 0)
			(layer "B.Fab")
			(effects
				(font
					(size 1.27 1.27)
				)
				(justify mirror)
			)
		)
		(duplicate_pad_numbers_are_jumpers no)
		(fp_line
			(start -0.7874 -0.4064)
			(end -0.7874 0.4064)
			(stroke
				(width 0.1524)
				(type default)
			)
			(layer "B.SilkS")
		)
		(fp_line
			(start -0.7874 0.4064)
			(end 0.7874 0.4064)
			(stroke
				(width 0.1524)
				(type default)
			)
			(layer "B.SilkS")
		)
		(fp_line
			(start 0.7874 -0.4064)
			(end -0.7874 -0.4064)
			(stroke
				(width 0.1524)
				(type default)
			)
			(layer "B.SilkS")
		)
		(fp_line
			(start 0.7874 0.4064)
			(end 0.7874 -0.4064)
			(stroke
				(width 0.1524)
				(type default)
			)
			(layer "B.SilkS")
		)
		(fp_line
			(start -0.67945 -0.3048)
			(end -0.67945 0.3048)
			(stroke
				(width 0.1)
				(type default)
			)
			(layer "B.Fab")
		)
		(fp_line
			(start -0.67945 0.3048)
			(end -0.120396 0.3048)
			(stroke
				(width 0.1)
				(type default)
			)
			(layer "B.Fab")
		)
		(fp_line
			(start -0.12065 -0.3048)
			(end -0.67945 -0.3048)
			(stroke
				(width 0.1)
				(type default)
			)
			(layer "B.Fab")
		)
		(fp_line
			(start -0.12065 -0.2794)
			(end -0.12065 -0.3048)
			(stroke
				(width 0.1)
				(type default)
			)
			(layer "B.Fab")
		)
		(fp_line
			(start -0.120396 0.2794)
			(end 0.12065 0.2794)
			(stroke
				(width 0.1)
				(type default)
			)
			(layer "B.Fab")
		)
		(fp_line
			(start -0.120396 0.3048)
			(end -0.120396 0.2794)
			(stroke
				(width 0.1)
				(type default)
			)
			(layer "B.Fab")
		)
		(fp_line
			(start 0.12065 -0.305054)
			(end 0.12065 -0.2794)
			(stroke
				(width 0.1)
				(type default)
			)
			(layer "B.Fab")
		)
		(fp_line
			(start 0.12065 -0.2794)
			(end -0.12065 -0.2794)
			(stroke
				(width 0.1)
				(type default)
			)
			(layer "B.Fab")
		)
		(fp_line
			(start 0.12065 0.2794)
			(end 0.12065 0.3048)
			(stroke
				(width 0.1)
				(type default)
			)
			(layer "B.Fab")
		)
		(fp_line
			(start 0.12065 0.3048)
			(end 0.67945 0.3048)
			(stroke
				(width 0.1)
				(type default)
			)
			(layer "B.Fab")
		)
		(fp_line
			(start 0.67945 -0.305054)
			(end 0.12065 -0.305054)
			(stroke
				(width 0.1)
				(type default)
			)
			(layer "B.Fab")
		)
		(fp_line
			(start 0.67945 0.3048)
			(end 0.67945 -0.305054)
			(stroke
				(width 0.1)
				(type default)
			)
			(layer "B.Fab")
		)
		(pad "1" smd circle
			(at 0.40005 0 180)
			(size 0 0)
			(layers "B.Cu" "B.Mask" "B.Paste")
			(net "SMB_BMC_9FGL0451E_SCL")
		)
		(pad "2" smd circle
			(at -0.40005 0 180)
			(size 0 0)
			(layers "B.Cu" "B.Mask" "B.Paste")
			(net "SMB_CLK_ISO_R_SCL")
		)
	)
	(footprint ""
		(layer "B.Cu")
		(at 287.519872 -305.399948 -90)
		(property "Reference" "C3310"
			(at 0 0 90)
			(layer "B.SilkS")
			(hide yes)
			(effects
				(font
					(size 1.27 1.27)
				)
				(justify mirror)
			)
		)
		(property "Value" ""
			(at 0 0 90)
			(layer "B.Fab")
			(effects
				(font
					(size 1.27 1.27)
				)
				(justify mirror)
			)
		)
		(duplicate_pad_numbers_are_jumpers no)
		(fp_line
			(start -0.299974 0.150114)
			(end 0.299974 0.150114)
			(stroke
				(width 0.1)
				(type default)
			)
			(layer "B.Fab")
		)
		(fp_line
			(start 0.299974 0.150114)
			(end 0.299974 -0.150114)
			(stroke
				(width 0.1)
				(type default)
			)
			(layer "B.Fab")
		)
		(fp_line
			(start -0.299974 -0.150114)
			(end -0.299974 0.150114)
			(stroke
				(width 0.1)
				(type default)
			)
			(layer "B.Fab")
		)
		(fp_line
			(start 0.299974 -0.150114)
			(end -0.299974 -0.150114)
			(stroke
				(width 0.1)
				(type default)
			)
			(layer "B.Fab")
		)
		(pad "1" smd rect
			(at 0.2667 0 90)
			(size 0.3048 0.381)
			(layers "B.Cu" "B.Mask" "B.Paste")
			(net "P1V25_SERDES_VDDPLL_PEX2")
		)
		(pad "2" smd rect
			(at -0.2667 0 90)
			(size 0.3048 0.381)
			(layers "B.Cu" "B.Mask" "B.Paste")
			(net "GND")
		)
	)
	(footprint ""
		(layer "B.Cu")
		(at 265.66368 -87.364316 180)
		(property "Reference" "C2644"
			(at 0 0 0)
			(layer "B.SilkS")
			(hide yes)
			(effects
				(font
					(size 1.27 1.27)
				)
				(justify mirror)
			)
		)
		(property "Value" ""
			(at 0 0 0)
			(layer "B.Fab")
			(effects
				(font
					(size 1.27 1.27)
				)
				(justify mirror)
			)
		)
		(duplicate_pad_numbers_are_jumpers no)
		(fp_line
			(start 1.2954 0.5842)
			(end 1.2954 -0.5842)
			(stroke
				(width 0.1524)
				(type default)
			)
			(layer "B.SilkS")
		)
		(fp_line
			(start 1.2954 -0.5842)
			(end -1.2954 -0.5842)
			(stroke
				(width 0.1524)
				(type default)
			)
			(layer "B.SilkS")
		)
		(fp_line
			(start -1.2954 0.5842)
			(end 1.2954 0.5842)
			(stroke
				(width 0.1524)
				(type default)
			)
			(layer "B.SilkS")
		)
		(fp_line
			(start -1.2954 -0.5842)
			(end -1.2954 0.5842)
			(stroke
				(width 0.1524)
				(type default)
			)
			(layer "B.SilkS")
		)
		(fp_line
			(start 1.1938 0.4064)
			(end 1.1938 -0.4064)
			(stroke
				(width 0.1)
				(type default)
			)
			(layer "B.Fab")
		)
		(fp_line
			(start 1.1938 -0.4064)
			(end 0.8636 -0.4064)
			(stroke
				(width 0.1)
				(type default)
			)
			(layer "B.Fab")
		)
		(fp_line
			(start 0.8636 0.4572)
			(end 0.8636 0.4064)
			(stroke
				(width 0.1)
				(type default)
			)
			(layer "B.Fab")
		)
		(fp_line
			(start 0.8636 0.4064)
			(end 1.1938 0.4064)
			(stroke
				(width 0.1)
				(type default)
			)
			(layer "B.Fab")
		)
		(fp_line
			(start 0.8636 -0.4064)
			(end 0.8636 -0.4572)
			(stroke
				(width 0.1)
				(type default)
			)
			(layer "B.Fab")
		)
		(fp_line
			(start 0.8636 -0.4572)
			(end -0.8636 -0.4572)
			(stroke
				(width 0.1)
				(type default)
			)
			(layer "B.Fab")
		)
		(fp_line
			(start -0.8636 0.4572)
			(end 0.8636 0.4572)
			(stroke
				(width 0.1)
				(type default)
			)
			(layer "B.Fab")
		)
		(fp_line
			(start -0.8636 0.4064)
			(end -0.8636 0.4572)
			(stroke
				(width 0.1)
				(type default)
			)
			(layer "B.Fab")
		)
		(fp_line
			(start -0.8636 -0.4064)
			(end -1.1938 -0.4064)
			(stroke
				(width 0.1)
				(type default)
			)
			(layer "B.Fab")
		)
		(fp_line
			(start -0.8636 -0.4572)
			(end -0.8636 -0.4064)
			(stroke
				(width 0.1)
				(type default)
			)
			(layer "B.Fab")
		)
		(fp_line
			(start -1.1938 0.4064)
			(end -0.8636 0.4064)
			(stroke
				(width 0.1)
				(type default)
			)
			(layer "B.Fab")
		)
		(fp_line
			(start -1.1938 -0.4064)
			(end -1.1938 0.4064)
			(stroke
				(width 0.1)
				(type default)
			)
			(layer "B.Fab")
		)
		(pad "1" smd rect
			(at 0.7366 0 90)
			(size 0.7112 0.8128)
			(layers "B.Cu" "B.Mask" "B.Paste")
			(net "P3V3_CLK_GEN_VDDMXCK_CK440")
		)
		(pad "2" smd rect
			(at -0.7366 0 90)
			(size 0.7112 0.8128)
			(layers "B.Cu" "B.Mask" "B.Paste")
			(net "GND")
		)
	)
	(footprint ""
		(layer "B.Cu")
		(at 178.599846 -301.599854 -90)
		(property "Reference" "C1473"
			(at 0 0 90)
			(layer "B.SilkS")
			(hide yes)
			(effects
				(font
					(size 1.27 1.27)
				)
				(justify mirror)
			)
		)
		(property "Value" ""
			(at 0 0 90)
			(layer "B.Fab")
			(effects
				(font
					(size 1.27 1.27)
				)
				(justify mirror)
			)
		)
		(duplicate_pad_numbers_are_jumpers no)
		(fp_line
			(start -0.299974 0.150114)
			(end 0.299974 0.150114)
			(stroke
				(width 0.1)
				(type default)
			)
			(layer "B.Fab")
		)
		(fp_line
			(start 0.299974 0.150114)
			(end 0.299974 -0.150114)
			(stroke
				(width 0.1)
				(type default)
			)
			(layer "B.Fab")
		)
		(fp_line
			(start -0.299974 -0.150114)
			(end -0.299974 0.150114)
			(stroke
				(width 0.1)
				(type default)
			)
			(layer "B.Fab")
		)
		(fp_line
			(start 0.299974 -0.150114)
			(end -0.299974 -0.150114)
			(stroke
				(width 0.1)
				(type default)
			)
			(layer "B.Fab")
		)
		(pad "1" smd rect
			(at 0.2667 0 90)
			(size 0.3048 0.381)
			(layers "B.Cu" "B.Mask" "B.Paste")
			(net "P0V8_SERDES_VDDA_PEX1")
		)
		(pad "2" smd rect
			(at -0.2667 0 90)
			(size 0.3048 0.381)
			(layers "B.Cu" "B.Mask" "B.Paste")
			(net "GND")
		)
	)
	(footprint ""
		(layer "B.Cu")
		(at 251.968 -199.39 -90)
		(property "Reference" "R6411"
			(at 0 0 90)
			(layer "B.SilkS")
			(hide yes)
			(effects
				(font
					(size 1.27 1.27)
				)
				(justify mirror)
			)
		)
		(property "Value" ""
			(at 0 0 90)
			(layer "B.Fab")
			(effects
				(font
					(size 1.27 1.27)
				)
				(justify mirror)
			)
		)
		(duplicate_pad_numbers_are_jumpers no)
		(fp_line
			(start -0.7874 0.4064)
			(end 0.7874 0.4064)
			(stroke
				(width 0.1524)
				(type default)
			)
			(layer "B.SilkS")
		)
		(fp_line
			(start 0.7874 0.4064)
			(end 0.7874 -0.4064)
			(stroke
				(width 0.1524)
				(type default)
			)
			(layer "B.SilkS")
		)
		(fp_line
			(start -0.7874 -0.4064)
			(end -0.7874 0.4064)
			(stroke
				(width 0.1524)
				(type default)
			)
			(layer "B.SilkS")
		)
		(fp_line
			(start 0.7874 -0.4064)
			(end -0.7874 -0.4064)
			(stroke
				(width 0.1524)
				(type default)
			)
			(layer "B.SilkS")
		)
		(fp_line
			(start -0.67945 0.3048)
			(end -0.120396 0.3048)
			(stroke
				(width 0.1)
				(type default)
			)
			(layer "B.Fab")
		)
		(fp_line
			(start -0.120396 0.3048)
			(end -0.120396 0.2794)
			(stroke
				(width 0.1)
				(type default)
			)
			(layer "B.Fab")
		)
		(fp_line
			(start 0.12065 0.3048)
			(end 0.67945 0.3048)
			(stroke
				(width 0.1)
				(type default)
			)
			(layer "B.Fab")
		)
		(fp_line
			(start 0.67945 0.3048)
			(end 0.67945 -0.305054)
			(stroke
				(width 0.1)
				(type default)
			)
			(layer "B.Fab")
		)
		(fp_line
			(start -0.120396 0.2794)
			(end 0.12065 0.2794)
			(stroke
				(width 0.1)
				(type default)
			)
			(layer "B.Fab")
		)
		(fp_line
			(start 0.12065 0.2794)
			(end 0.12065 0.3048)
			(stroke
				(width 0.1)
				(type default)
			)
			(layer "B.Fab")
		)
		(fp_line
			(start -0.12065 -0.2794)
			(end -0.12065 -0.3048)
			(stroke
				(width 0.1)
				(type default)
			)
			(layer "B.Fab")
		)
		(fp_line
			(start 0.12065 -0.2794)
			(end -0.12065 -0.2794)
			(stroke
				(width 0.1)
				(type default)
			)
			(layer "B.Fab")
		)
		(fp_line
			(start -0.67945 -0.3048)
			(end -0.67945 0.3048)
			(stroke
				(width 0.1)
				(type default)
			)
			(layer "B.Fab")
		)
		(fp_line
			(start -0.12065 -0.3048)
			(end -0.67945 -0.3048)
			(stroke
				(width 0.1)
				(type default)
			)
			(layer "B.Fab")
		)
		(fp_line
			(start 0.12065 -0.305054)
			(end 0.12065 -0.2794)
			(stroke
				(width 0.1)
				(type default)
			)
			(layer "B.Fab")
		)
		(fp_line
			(start 0.67945 -0.305054)
			(end 0.12065 -0.305054)
			(stroke
				(width 0.1)
				(type default)
			)
			(layer "B.Fab")
		)
		(pad "1" smd circle
			(at 0.40005 0 90)
			(size 0 0)
			(layers "B.Cu" "B.Mask" "B.Paste")
			(net "JTAG_BIC_EN_R")
		)
		(pad "2" smd circle
			(at -0.40005 0 90)
			(size 0 0)
			(layers "B.Cu" "B.Mask" "B.Paste")
			(net "GND")
		)
	)
	(footprint ""
		(layer "B.Cu")
		(at 100.154994 -330.01585 180)
		(property "Reference" "R1227"
			(at 0 0 0)
			(layer "B.SilkS")
			(hide yes)
			(effects
				(font
					(size 1.27 1.27)
				)
				(justify mirror)
			)
		)
		(property "Value" ""
			(at 0 0 0)
			(layer "B.Fab")
			(effects
				(font
					(size 1.27 1.27)
				)
				(justify mirror)
			)
		)
		(duplicate_pad_numbers_are_jumpers no)
		(fp_line
			(start 0.7874 0.4064)
			(end 0.7874 -0.4064)
			(stroke
				(width 0.1524)
				(type default)
			)
			(layer "B.SilkS")
		)
		(fp_line
			(start 0.7874 -0.4064)
			(end -0.7874 -0.4064)
			(stroke
				(width 0.1524)
				(type default)
			)
			(layer "B.SilkS")
		)
		(fp_line
			(start -0.7874 0.4064)
			(end 0.7874 0.4064)
			(stroke
				(width 0.1524)
				(type default)
			)
			(layer "B.SilkS")
		)
		(fp_line
			(start -0.7874 -0.4064)
			(end -0.7874 0.4064)
			(stroke
				(width 0.1524)
				(type default)
			)
			(layer "B.SilkS")
		)
		(fp_line
			(start 0.67945 0.3048)
			(end 0.67945 -0.305054)
			(stroke
				(width 0.1)
				(type default)
			)
			(layer "B.Fab")
		)
		(fp_line
			(start 0.67945 -0.305054)
			(end 0.12065 -0.305054)
			(stroke
				(width 0.1)
				(type default)
			)
			(layer "B.Fab")
		)
		(fp_line
			(start 0.12065 0.3048)
			(end 0.67945 0.3048)
			(stroke
				(width 0.1)
				(type default)
			)
			(layer "B.Fab")
		)
		(fp_line
			(start 0.12065 0.2794)
			(end 0.12065 0.3048)
			(stroke
				(width 0.1)
				(type default)
			)
			(layer "B.Fab")
		)
		(fp_line
			(start 0.12065 -0.2794)
			(end -0.12065 -0.2794)
			(stroke
				(width 0.1)
				(type default)
			)
			(layer "B.Fab")
		)
		(fp_line
			(start 0.12065 -0.305054)
			(end 0.12065 -0.2794)
			(stroke
				(width 0.1)
				(type default)
			)
			(layer "B.Fab")
		)
		(fp_line
			(start -0.120396 0.3048)
			(end -0.120396 0.2794)
			(stroke
				(width 0.1)
				(type default)
			)
			(layer "B.Fab")
		)
		(fp_line
			(start -0.120396 0.2794)
			(end 0.12065 0.2794)
			(stroke
				(width 0.1)
				(type default)
			)
			(layer "B.Fab")
		)
		(fp_line
			(start -0.12065 -0.2794)
			(end -0.12065 -0.3048)
			(stroke
				(width 0.1)
				(type default)
			)
			(layer "B.Fab")
		)
		(fp_line
			(start -0.12065 -0.3048)
			(end -0.67945 -0.3048)
			(stroke
				(width 0.1)
				(type default)
			)
			(layer "B.Fab")
		)
		(fp_line
			(start -0.67945 0.3048)
			(end -0.120396 0.3048)
			(stroke
				(width 0.1)
				(type default)
			)
			(layer "B.Fab")
		)
		(fp_line
			(start -0.67945 -0.3048)
			(end -0.67945 0.3048)
			(stroke
				(width 0.1)
				(type default)
			)
			(layer "B.Fab")
		)
		(pad "1" smd circle
			(at 0.40005 0)
			(size 0 0)
			(layers "B.Cu" "B.Mask" "B.Paste")
			(net "CLK_100M_DB800ZL_PEX1_S0_R_DP")
		)
		(pad "2" smd circle
			(at -0.40005 0)
			(size 0 0)
			(layers "B.Cu" "B.Mask" "B.Paste")
			(net "CLK_100M_DB800ZL_PEX1_S0_DP")
		)
	)
	(footprint ""
		(layer "B.Cu")
		(at 65.824862 -286.399732 90)
		(property "Reference" "C2979"
			(at 0 0 90)
			(layer "B.SilkS")
			(hide yes)
			(effects
				(font
					(size 1.27 1.27)
				)
				(justify mirror)
			)
		)
		(property "Value" ""
			(at 0 0 90)
			(layer "B.Fab")
			(effects
				(font
					(size 1.27 1.27)
				)
				(justify mirror)
			)
		)
		(duplicate_pad_numbers_are_jumpers no)
		(fp_line
			(start 0.299974 -0.150114)
			(end -0.299974 -0.150114)
			(stroke
				(width 0.1)
				(type default)
			)
			(layer "B.Fab")
		)
		(fp_line
			(start -0.299974 -0.150114)
			(end -0.299974 0.150114)
			(stroke
				(width 0.1)
				(type default)
			)
			(layer "B.Fab")
		)
		(fp_line
			(start 0.299974 0.150114)
			(end 0.299974 -0.150114)
			(stroke
				(width 0.1)
				(type default)
			)
			(layer "B.Fab")
		)
		(fp_line
			(start -0.299974 0.150114)
			(end 0.299974 0.150114)
			(stroke
				(width 0.1)
				(type default)
			)
			(layer "B.Fab")
		)
		(pad "1" smd rect
			(at 0.2667 0 270)
			(size 0.3048 0.381)
			(layers "B.Cu" "B.Mask" "B.Paste")
			(net "P1V25_SERDES_VDDPLL_PEX0")
		)
		(pad "2" smd rect
			(at -0.2667 0 270)
			(size 0.3048 0.381)
			(layers "B.Cu" "B.Mask" "B.Paste")
			(net "GND")
		)
	)
	(footprint ""
		(layer "B.Cu")
		(at 236.18952 -285.911544)
		(property "Reference" "PC255"
			(at 0 0 0)
			(layer "B.SilkS")
			(hide yes)
			(effects
				(font
					(size 1.27 1.27)
				)
				(justify mirror)
			)
		)
		(property "Value" ""
			(at 0 0 0)
			(layer "B.Fab")
			(effects
				(font
					(size 1.27 1.27)
				)
				(justify mirror)
			)
		)
		(duplicate_pad_numbers_are_jumpers no)
		(fp_line
			(start -1.524 -0.762)
			(end -1.524 0.762)
			(stroke
				(width 0.1524)
				(type default)
			)
			(layer "B.SilkS")
		)
		(fp_line
			(start -1.524 0.762)
			(end 1.524 0.762)
			(stroke
				(width 0.1524)
				(type default)
			)
			(layer "B.SilkS")
		)
		(fp_line
			(start 1.524 -0.762)
			(end -1.524 -0.762)
			(stroke
				(width 0.1524)
				(type default)
			)
			(layer "B.SilkS")
		)
		(fp_line
			(start 1.524 0.762)
			(end 1.524 -0.762)
			(stroke
				(width 0.1524)
				(type default)
			)
			(layer "B.SilkS")
		)
		(fp_line
			(start -1.1049 -0.724916)
			(end 1.1049 -0.724916)
			(stroke
				(width 0.1)
				(type default)
			)
			(layer "B.Fab")
		)
		(fp_line
			(start -1.1049 0.724916)
			(end -1.1049 -0.724916)
			(stroke
				(width 0.1)
				(type default)
			)
			(layer "B.Fab")
		)
		(fp_line
			(start 1.1049 -0.724916)
			(end 1.1049 0.724916)
			(stroke
				(width 0.1)
				(type default)
			)
			(layer "B.Fab")
		)
		(fp_line
			(start 1.1049 0.724916)
			(end -1.1049 0.724916)
			(stroke
				(width 0.1)
				(type default)
			)
			(layer "B.Fab")
		)
		(pad "1" smd rect
			(at 0.889 0)
			(size 1.016 1.27)
			(layers "B.Cu" "B.Mask" "B.Paste")
			(net "P1V25_PEX2_R")
		)
		(pad "2" smd rect
			(at -0.889 0)
			(size 1.016 1.27)
			(layers "B.Cu" "B.Mask" "B.Paste")
			(net "GND")
		)
	)
	(footprint ""
		(layer "B.Cu")
		(at 409.897326 -109.481366)
		(property "Reference" "R388"
			(at 0 0 0)
			(layer "B.SilkS")
			(hide yes)
			(effects
				(font
					(size 1.27 1.27)
				)
				(justify mirror)
			)
		)
		(property "Value" ""
			(at 0 0 0)
			(layer "B.Fab")
			(effects
				(font
					(size 1.27 1.27)
				)
				(justify mirror)
			)
		)
		(duplicate_pad_numbers_are_jumpers no)
		(fp_line
			(start -0.7874 -0.4064)
			(end -0.7874 0.4064)
			(stroke
				(width 0.1524)
				(type default)
			)
			(layer "B.SilkS")
		)
		(fp_line
			(start -0.7874 0.4064)
			(end 0.7874 0.4064)
			(stroke
				(width 0.1524)
				(type default)
			)
			(layer "B.SilkS")
		)
		(fp_line
			(start 0.7874 -0.4064)
			(end -0.7874 -0.4064)
			(stroke
				(width 0.1524)
				(type default)
			)
			(layer "B.SilkS")
		)
		(fp_line
			(start 0.7874 0.4064)
			(end 0.7874 -0.4064)
			(stroke
				(width 0.1524)
				(type default)
			)
			(layer "B.SilkS")
		)
		(fp_line
			(start -0.67945 -0.3048)
			(end -0.67945 0.3048)
			(stroke
				(width 0.1)
				(type default)
			)
			(layer "B.Fab")
		)
		(fp_line
			(start -0.67945 0.3048)
			(end -0.120396 0.3048)
			(stroke
				(width 0.1)
				(type default)
			)
			(layer "B.Fab")
		)
		(fp_line
			(start -0.12065 -0.3048)
			(end -0.67945 -0.3048)
			(stroke
				(width 0.1)
				(type default)
			)
			(layer "B.Fab")
		)
		(fp_line
			(start -0.12065 -0.2794)
			(end -0.12065 -0.3048)
			(stroke
				(width 0.1)
				(type default)
			)
			(layer "B.Fab")
		)
		(fp_line
			(start -0.120396 0.2794)
			(end 0.12065 0.2794)
			(stroke
				(width 0.1)
				(type default)
			)
			(layer "B.Fab")
		)
		(fp_line
			(start -0.120396 0.3048)
			(end -0.120396 0.2794)
			(stroke
				(width 0.1)
				(type default)
			)
			(layer "B.Fab")
		)
		(fp_line
			(start 0.12065 -0.305054)
			(end 0.12065 -0.2794)
			(stroke
				(width 0.1)
				(type default)
			)
			(layer "B.Fab")
		)
		(fp_line
			(start 0.12065 -0.2794)
			(end -0.12065 -0.2794)
			(stroke
				(width 0.1)
				(type default)
			)
			(layer "B.Fab")
		)
		(fp_line
			(start 0.12065 0.2794)
			(end 0.12065 0.3048)
			(stroke
				(width 0.1)
				(type default)
			)
			(layer "B.Fab")
		)
		(fp_line
			(start 0.12065 0.3048)
			(end 0.67945 0.3048)
			(stroke
				(width 0.1)
				(type default)
			)
			(layer "B.Fab")
		)
		(fp_line
			(start 0.67945 -0.305054)
			(end 0.12065 -0.305054)
			(stroke
				(width 0.1)
				(type default)
			)
			(layer "B.Fab")
		)
		(fp_line
			(start 0.67945 0.3048)
			(end 0.67945 -0.305054)
			(stroke
				(width 0.1)
				(type default)
			)
			(layer "B.Fab")
		)
		(pad "1" smd circle
			(at 0.40005 0 180)
			(size 0 0)
			(layers "B.Cu" "B.Mask" "B.Paste")
			(net "NIC7_BIF1_N")
		)
		(pad "2" smd circle
			(at -0.40005 0 180)
			(size 0 0)
			(layers "B.Cu" "B.Mask" "B.Paste")
			(net "P3V3_AUX")
		)
	)
	(footprint ""
		(layer "B.Cu")
		(at 207.110076 -220.746066)
		(property "Reference" "R6819"
			(at 0 0 0)
			(layer "B.SilkS")
			(hide yes)
			(effects
				(font
					(size 1.27 1.27)
				)
				(justify mirror)
			)
		)
		(property "Value" ""
			(at 0 0 0)
			(layer "B.Fab")
			(effects
				(font
					(size 1.27 1.27)
				)
				(justify mirror)
			)
		)
		(duplicate_pad_numbers_are_jumpers no)
		(fp_line
			(start -0.7874 -0.4064)
			(end -0.7874 0.4064)
			(stroke
				(width 0.1524)
				(type default)
			)
			(layer "B.SilkS")
		)
		(fp_line
			(start -0.7874 0.4064)
			(end 0.7874 0.4064)
			(stroke
				(width 0.1524)
				(type default)
			)
			(layer "B.SilkS")
		)
		(fp_line
			(start 0.7874 -0.4064)
			(end -0.7874 -0.4064)
			(stroke
				(width 0.1524)
				(type default)
			)
			(layer "B.SilkS")
		)
		(fp_line
			(start 0.7874 0.4064)
			(end 0.7874 -0.4064)
			(stroke
				(width 0.1524)
				(type default)
			)
			(layer "B.SilkS")
		)
		(fp_line
			(start -0.67945 -0.3048)
			(end -0.67945 0.3048)
			(stroke
				(width 0.1)
				(type default)
			)
			(layer "B.Fab")
		)
		(fp_line
			(start -0.67945 0.3048)
			(end -0.120396 0.3048)
			(stroke
				(width 0.1)
				(type default)
			)
			(layer "B.Fab")
		)
		(fp_line
			(start -0.12065 -0.3048)
			(end -0.67945 -0.3048)
			(stroke
				(width 0.1)
				(type default)
			)
			(layer "B.Fab")
		)
		(fp_line
			(start -0.12065 -0.2794)
			(end -0.12065 -0.3048)
			(stroke
				(width 0.1)
				(type default)
			)
			(layer "B.Fab")
		)
		(fp_line
			(start -0.120396 0.2794)
			(end 0.12065 0.2794)
			(stroke
				(width 0.1)
				(type default)
			)
			(layer "B.Fab")
		)
		(fp_line
			(start -0.120396 0.3048)
			(end -0.120396 0.2794)
			(stroke
				(width 0.1)
				(type default)
			)
			(layer "B.Fab")
		)
		(fp_line
			(start 0.12065 -0.305054)
			(end 0.12065 -0.2794)
			(stroke
				(width 0.1)
				(type default)
			)
			(layer "B.Fab")
		)
		(fp_line
			(start 0.12065 -0.2794)
			(end -0.12065 -0.2794)
			(stroke
				(width 0.1)
				(type default)
			)
			(layer "B.Fab")
		)
		(fp_line
			(start 0.12065 0.2794)
			(end 0.12065 0.3048)
			(stroke
				(width 0.1)
				(type default)
			)
			(layer "B.Fab")
		)
		(fp_line
			(start 0.12065 0.3048)
			(end 0.67945 0.3048)
			(stroke
				(width 0.1)
				(type default)
			)
			(layer "B.Fab")
		)
		(fp_line
			(start 0.67945 -0.305054)
			(end 0.12065 -0.305054)
			(stroke
				(width 0.1)
				(type default)
			)
			(layer "B.Fab")
		)
		(fp_line
			(start 0.67945 0.3048)
			(end 0.67945 -0.305054)
			(stroke
				(width 0.1)
				(type default)
			)
			(layer "B.Fab")
		)
		(pad "1" smd circle
			(at 0.40005 0 180)
			(size 0 0)
			(layers "B.Cu" "B.Mask" "B.Paste")
			(net "GND")
		)
		(pad "2" smd circle
			(at -0.40005 0 180)
			(size 0 0)
			(layers "B.Cu" "B.Mask" "B.Paste")
			(net "BOARD_TYPE_1_ADC_R")
		)
	)
	(footprint ""
		(layer "B.Cu")
		(at 352.11893 -233.553 90)
		(property "Reference" "R5777"
			(at 0 0 90)
			(layer "B.SilkS")
			(hide yes)
			(effects
				(font
					(size 1.27 1.27)
				)
				(justify mirror)
			)
		)
		(property "Value" ""
			(at 0 0 90)
			(layer "B.Fab")
			(effects
				(font
					(size 1.27 1.27)
				)
				(justify mirror)
			)
		)
		(duplicate_pad_numbers_are_jumpers no)
		(fp_line
			(start 0.7874 -0.4064)
			(end -0.7874 -0.4064)
			(stroke
				(width 0.1524)
				(type default)
			)
			(layer "B.SilkS")
		)
		(fp_line
			(start -0.7874 -0.4064)
			(end -0.7874 0.4064)
			(stroke
				(width 0.1524)
				(type default)
			)
			(layer "B.SilkS")
		)
		(fp_line
			(start 0.7874 0.4064)
			(end 0.7874 -0.4064)
			(stroke
				(width 0.1524)
				(type default)
			)
			(layer "B.SilkS")
		)
		(fp_line
			(start -0.7874 0.4064)
			(end 0.7874 0.4064)
			(stroke
				(width 0.1524)
				(type default)
			)
			(layer "B.SilkS")
		)
		(fp_line
			(start 0.67945 -0.305054)
			(end 0.12065 -0.305054)
			(stroke
				(width 0.1)
				(type default)
			)
			(layer "B.Fab")
		)
		(fp_line
			(start 0.12065 -0.305054)
			(end 0.12065 -0.2794)
			(stroke
				(width 0.1)
				(type default)
			)
			(layer "B.Fab")
		)
		(fp_line
			(start -0.12065 -0.3048)
			(end -0.67945 -0.3048)
			(stroke
				(width 0.1)
				(type default)
			)
			(layer "B.Fab")
		)
		(fp_line
			(start -0.67945 -0.3048)
			(end -0.67945 0.3048)
			(stroke
				(width 0.1)
				(type default)
			)
			(layer "B.Fab")
		)
		(fp_line
			(start 0.12065 -0.2794)
			(end -0.12065 -0.2794)
			(stroke
				(width 0.1)
				(type default)
			)
			(layer "B.Fab")
		)
		(fp_line
			(start -0.12065 -0.2794)
			(end -0.12065 -0.3048)
			(stroke
				(width 0.1)
				(type default)
			)
			(layer "B.Fab")
		)
		(fp_line
			(start 0.12065 0.2794)
			(end 0.12065 0.3048)
			(stroke
				(width 0.1)
				(type default)
			)
			(layer "B.Fab")
		)
		(fp_line
			(start -0.120396 0.2794)
			(end 0.12065 0.2794)
			(stroke
				(width 0.1)
				(type default)
			)
			(layer "B.Fab")
		)
		(fp_line
			(start 0.67945 0.3048)
			(end 0.67945 -0.305054)
			(stroke
				(width 0.1)
				(type default)
			)
			(layer "B.Fab")
		)
		(fp_line
			(start 0.12065 0.3048)
			(end 0.67945 0.3048)
			(stroke
				(width 0.1)
				(type default)
			)
			(layer "B.Fab")
		)
		(fp_line
			(start -0.120396 0.3048)
			(end -0.120396 0.2794)
			(stroke
				(width 0.1)
				(type default)
			)
			(layer "B.Fab")
		)
		(fp_line
			(start -0.67945 0.3048)
			(end -0.120396 0.3048)
			(stroke
				(width 0.1)
				(type default)
			)
			(layer "B.Fab")
		)
		(pad "1" smd circle
			(at 0.40005 0 270)
			(size 0 0)
			(layers "B.Cu" "B.Mask" "B.Paste")
			(net "P3V3_AUX")
		)
		(pad "2" smd circle
			(at -0.40005 0 270)
			(size 0 0)
			(layers "B.Cu" "B.Mask" "B.Paste")
			(net "PU_FPGA_PROGRAMN")
		)
	)
	(footprint ""
		(layer "B.Cu")
		(at 289.94989 -299.699934 -90)
		(property "Reference" "C1747"
			(at 0 0 90)
			(layer "B.SilkS")
			(hide yes)
			(effects
				(font
					(size 1.27 1.27)
				)
				(justify mirror)
			)
		)
		(property "Value" ""
			(at 0 0 90)
			(layer "B.Fab")
			(effects
				(font
					(size 1.27 1.27)
				)
				(justify mirror)
			)
		)
		(duplicate_pad_numbers_are_jumpers no)
		(fp_line
			(start -0.299974 0.150114)
			(end 0.299974 0.150114)
			(stroke
				(width 0.1)
				(type default)
			)
			(layer "B.Fab")
		)
		(fp_line
			(start 0.299974 0.150114)
			(end 0.299974 -0.150114)
			(stroke
				(width 0.1)
				(type default)
			)
			(layer "B.Fab")
		)
		(fp_line
			(start -0.299974 -0.150114)
			(end -0.299974 0.150114)
			(stroke
				(width 0.1)
				(type default)
			)
			(layer "B.Fab")
		)
		(fp_line
			(start 0.299974 -0.150114)
			(end -0.299974 -0.150114)
			(stroke
				(width 0.1)
				(type default)
			)
			(layer "B.Fab")
		)
		(pad "1" smd rect
			(at 0.2667 0 90)
			(size 0.3048 0.381)
			(layers "B.Cu" "B.Mask" "B.Paste")
			(net "P0V8_SERDES_VDDA_PEX2")
		)
		(pad "2" smd rect
			(at -0.2667 0 90)
			(size 0.3048 0.381)
			(layers "B.Cu" "B.Mask" "B.Paste")
			(net "GND")
		)
	)
	(footprint ""
		(layer "B.Cu")
		(at 229.150418 -226.68357)
		(property "Reference" "C4487"
			(at 0 0 0)
			(layer "B.SilkS")
			(hide yes)
			(effects
				(font
					(size 1.27 1.27)
				)
				(justify mirror)
			)
		)
		(property "Value" ""
			(at 0 0 0)
			(layer "B.Fab")
			(effects
				(font
					(size 1.27 1.27)
				)
				(justify mirror)
			)
		)
		(duplicate_pad_numbers_are_jumpers no)
		(fp_line
			(start -0.7874 -0.4064)
			(end -0.7874 0.4064)
			(stroke
				(width 0.1524)
				(type default)
			)
			(layer "B.SilkS")
		)
		(fp_line
			(start -0.7874 0.4064)
			(end 0.7874 0.4064)
			(stroke
				(width 0.1524)
				(type default)
			)
			(layer "B.SilkS")
		)
		(fp_line
			(start 0.7874 -0.4064)
			(end -0.7874 -0.4064)
			(stroke
				(width 0.1524)
				(type default)
			)
			(layer "B.SilkS")
		)
		(fp_line
			(start 0.7874 0.4064)
			(end 0.7874 -0.4064)
			(stroke
				(width 0.1524)
				(type default)
			)
			(layer "B.SilkS")
		)
		(fp_line
			(start -0.67945 -0.3048)
			(end -0.67945 0.3048)
			(stroke
				(width 0.1)
				(type default)
			)
			(layer "B.Fab")
		)
		(fp_line
			(start -0.67945 0.3048)
			(end -0.120396 0.3048)
			(stroke
				(width 0.1)
				(type default)
			)
			(layer "B.Fab")
		)
		(fp_line
			(start -0.12065 -0.3048)
			(end -0.67945 -0.3048)
			(stroke
				(width 0.1)
				(type default)
			)
			(layer "B.Fab")
		)
		(fp_line
			(start -0.12065 -0.2794)
			(end -0.12065 -0.3048)
			(stroke
				(width 0.1)
				(type default)
			)
			(layer "B.Fab")
		)
		(fp_line
			(start -0.120396 0.2794)
			(end 0.12065 0.2794)
			(stroke
				(width 0.1)
				(type default)
			)
			(layer "B.Fab")
		)
		(fp_line
			(start -0.120396 0.3048)
			(end -0.120396 0.2794)
			(stroke
				(width 0.1)
				(type default)
			)
			(layer "B.Fab")
		)
		(fp_line
			(start 0.12065 -0.305054)
			(end 0.12065 -0.2794)
			(stroke
				(width 0.1)
				(type default)
			)
			(layer "B.Fab")
		)
		(fp_line
			(start 0.12065 -0.2794)
			(end -0.12065 -0.2794)
			(stroke
				(width 0.1)
				(type default)
			)
			(layer "B.Fab")
		)
		(fp_line
			(start 0.12065 0.2794)
			(end 0.12065 0.3048)
			(stroke
				(width 0.1)
				(type default)
			)
			(layer "B.Fab")
		)
		(fp_line
			(start 0.12065 0.3048)
			(end 0.67945 0.3048)
			(stroke
				(width 0.1)
				(type default)
			)
			(layer "B.Fab")
		)
		(fp_line
			(start 0.67945 -0.305054)
			(end 0.12065 -0.305054)
			(stroke
				(width 0.1)
				(type default)
			)
			(layer "B.Fab")
		)
		(fp_line
			(start 0.67945 0.3048)
			(end 0.67945 -0.305054)
			(stroke
				(width 0.1)
				(type default)
			)
			(layer "B.Fab")
		)
		(pad "1" smd circle
			(at 0.40005 0 180)
			(size 0 0)
			(layers "B.Cu" "B.Mask" "B.Paste")
			(net "BOARD_TYPE_0_ADC_R")
		)
		(pad "2" smd circle
			(at -0.40005 0 180)
			(size 0 0)
			(layers "B.Cu" "B.Mask" "B.Paste")
			(net "GND")
		)
	)
	(footprint ""
		(layer "B.Cu")
		(at 131.996942 -308.668674 90)
		(property "Reference" "C4265"
			(at 0 0 90)
			(layer "B.SilkS")
			(hide yes)
			(effects
				(font
					(size 1.27 1.27)
				)
				(justify mirror)
			)
		)
		(property "Value" ""
			(at 0 0 90)
			(layer "B.Fab")
			(effects
				(font
					(size 1.27 1.27)
				)
				(justify mirror)
			)
		)
		(duplicate_pad_numbers_are_jumpers no)
		(fp_line
			(start 0.299974 -0.150114)
			(end -0.299974 -0.150114)
			(stroke
				(width 0.1)
				(type default)
			)
			(layer "B.Fab")
		)
		(fp_line
			(start -0.299974 -0.150114)
			(end -0.299974 0.150114)
			(stroke
				(width 0.1)
				(type default)
			)
			(layer "B.Fab")
		)
		(fp_line
			(start 0.299974 0.150114)
			(end 0.299974 -0.150114)
			(stroke
				(width 0.1)
				(type default)
			)
			(layer "B.Fab")
		)
		(fp_line
			(start -0.299974 0.150114)
			(end 0.299974 0.150114)
			(stroke
				(width 0.1)
				(type default)
			)
			(layer "B.Fab")
		)
		(pad "1" smd rect
			(at 0.2667 0 270)
			(size 0.3048 0.381)
			(layers "B.Cu" "B.Mask" "B.Paste")
			(net "P0V8_PEX1")
		)
		(pad "2" smd rect
			(at -0.2667 0 270)
			(size 0.3048 0.381)
			(layers "B.Cu" "B.Mask" "B.Paste")
			(net "GND")
		)
	)
	(footprint ""
		(layer "B.Cu")
		(at 299.924724 -286.399732 90)
		(property "Reference" "C3299"
			(at 0 0 90)
			(layer "B.SilkS")
			(hide yes)
			(effects
				(font
					(size 1.27 1.27)
				)
				(justify mirror)
			)
		)
		(property "Value" ""
			(at 0 0 90)
			(layer "B.Fab")
			(effects
				(font
					(size 1.27 1.27)
				)
				(justify mirror)
			)
		)
		(duplicate_pad_numbers_are_jumpers no)
		(fp_line
			(start 0.299974 -0.150114)
			(end -0.299974 -0.150114)
			(stroke
				(width 0.1)
				(type default)
			)
			(layer "B.Fab")
		)
		(fp_line
			(start -0.299974 -0.150114)
			(end -0.299974 0.150114)
			(stroke
				(width 0.1)
				(type default)
			)
			(layer "B.Fab")
		)
		(fp_line
			(start 0.299974 0.150114)
			(end 0.299974 -0.150114)
			(stroke
				(width 0.1)
				(type default)
			)
			(layer "B.Fab")
		)
		(fp_line
			(start -0.299974 0.150114)
			(end 0.299974 0.150114)
			(stroke
				(width 0.1)
				(type default)
			)
			(layer "B.Fab")
		)
		(pad "1" smd rect
			(at 0.2667 0 270)
			(size 0.3048 0.381)
			(layers "B.Cu" "B.Mask" "B.Paste")
			(net "P1V25_SERDES_VDDPLL_PEX2")
		)
		(pad "2" smd rect
			(at -0.2667 0 270)
			(size 0.3048 0.381)
			(layers "B.Cu" "B.Mask" "B.Paste")
			(net "GND")
		)
	)
	(footprint ""
		(layer "B.Cu")
		(at 133.980682 -152.60066)
		(property "Reference" "R5622"
			(at 0 0 0)
			(layer "B.SilkS")
			(hide yes)
			(effects
				(font
					(size 1.27 1.27)
				)
				(justify mirror)
			)
		)
		(property "Value" ""
			(at 0 0 0)
			(layer "B.Fab")
			(effects
				(font
					(size 1.27 1.27)
				)
				(justify mirror)
			)
		)
		(duplicate_pad_numbers_are_jumpers no)
		(fp_line
			(start -0.7874 -0.4064)
			(end -0.7874 0.4064)
			(stroke
				(width 0.1524)
				(type default)
			)
			(layer "B.SilkS")
		)
		(fp_line
			(start -0.7874 0.4064)
			(end 0.7874 0.4064)
			(stroke
				(width 0.1524)
				(type default)
			)
			(layer "B.SilkS")
		)
		(fp_line
			(start 0.7874 -0.4064)
			(end -0.7874 -0.4064)
			(stroke
				(width 0.1524)
				(type default)
			)
			(layer "B.SilkS")
		)
		(fp_line
			(start 0.7874 0.4064)
			(end 0.7874 -0.4064)
			(stroke
				(width 0.1524)
				(type default)
			)
			(layer "B.SilkS")
		)
		(fp_line
			(start -0.67945 -0.3048)
			(end -0.67945 0.3048)
			(stroke
				(width 0.1)
				(type default)
			)
			(layer "B.Fab")
		)
		(fp_line
			(start -0.67945 0.3048)
			(end -0.120396 0.3048)
			(stroke
				(width 0.1)
				(type default)
			)
			(layer "B.Fab")
		)
		(fp_line
			(start -0.12065 -0.3048)
			(end -0.67945 -0.3048)
			(stroke
				(width 0.1)
				(type default)
			)
			(layer "B.Fab")
		)
		(fp_line
			(start -0.12065 -0.2794)
			(end -0.12065 -0.3048)
			(stroke
				(width 0.1)
				(type default)
			)
			(layer "B.Fab")
		)
		(fp_line
			(start -0.120396 0.2794)
			(end 0.12065 0.2794)
			(stroke
				(width 0.1)
				(type default)
			)
			(layer "B.Fab")
		)
		(fp_line
			(start -0.120396 0.3048)
			(end -0.120396 0.2794)
			(stroke
				(width 0.1)
				(type default)
			)
			(layer "B.Fab")
		)
		(fp_line
			(start 0.12065 -0.305054)
			(end 0.12065 -0.2794)
			(stroke
				(width 0.1)
				(type default)
			)
			(layer "B.Fab")
		)
		(fp_line
			(start 0.12065 -0.2794)
			(end -0.12065 -0.2794)
			(stroke
				(width 0.1)
				(type default)
			)
			(layer "B.Fab")
		)
		(fp_line
			(start 0.12065 0.2794)
			(end 0.12065 0.3048)
			(stroke
				(width 0.1)
				(type default)
			)
			(layer "B.Fab")
		)
		(fp_line
			(start 0.12065 0.3048)
			(end 0.67945 0.3048)
			(stroke
				(width 0.1)
				(type default)
			)
			(layer "B.Fab")
		)
		(fp_line
			(start 0.67945 -0.305054)
			(end 0.12065 -0.305054)
			(stroke
				(width 0.1)
				(type default)
			)
			(layer "B.Fab")
		)
		(fp_line
			(start 0.67945 0.3048)
			(end 0.67945 -0.305054)
			(stroke
				(width 0.1)
				(type default)
			)
			(layer "B.Fab")
		)
		(pad "1" smd circle
			(at 0.40005 0 180)
			(size 0 0)
			(layers "B.Cu" "B.Mask" "B.Paste")
			(net "NIC2_ADC_A0")
		)
		(pad "2" smd circle
			(at -0.40005 0 180)
			(size 0 0)
			(layers "B.Cu" "B.Mask" "B.Paste")
			(net "SMB_NIC2_ADC_SDA")
		)
	)
	(footprint ""
		(layer "B.Cu")
		(at 170.524932 -297.79976 -90)
		(property "Reference" "C1394"
			(at 0 0 90)
			(layer "B.SilkS")
			(hide yes)
			(effects
				(font
					(size 1.27 1.27)
				)
				(justify mirror)
			)
		)
		(property "Value" ""
			(at 0 0 90)
			(layer "B.Fab")
			(effects
				(font
					(size 1.27 1.27)
				)
				(justify mirror)
			)
		)
		(duplicate_pad_numbers_are_jumpers no)
		(fp_line
			(start -0.299974 0.150114)
			(end 0.299974 0.150114)
			(stroke
				(width 0.1)
				(type default)
			)
			(layer "B.Fab")
		)
		(fp_line
			(start 0.299974 0.150114)
			(end 0.299974 -0.150114)
			(stroke
				(width 0.1)
				(type default)
			)
			(layer "B.Fab")
		)
		(fp_line
			(start -0.299974 -0.150114)
			(end -0.299974 0.150114)
			(stroke
				(width 0.1)
				(type default)
			)
			(layer "B.Fab")
		)
		(fp_line
			(start 0.299974 -0.150114)
			(end -0.299974 -0.150114)
			(stroke
				(width 0.1)
				(type default)
			)
			(layer "B.Fab")
		)
		(pad "1" smd rect
			(at 0.2667 0 90)
			(size 0.3048 0.381)
			(layers "B.Cu" "B.Mask" "B.Paste")
			(net "P0V8_PEX1")
		)
		(pad "2" smd rect
			(at -0.2667 0 90)
			(size 0.3048 0.381)
			(layers "B.Cu" "B.Mask" "B.Paste")
			(net "GND")
		)
	)
	(footprint ""
		(layer "B.Cu")
		(at 225.871786 -148.786342 180)
		(property "Reference" "C2800"
			(at 0 0 0)
			(layer "B.SilkS")
			(hide yes)
			(effects
				(font
					(size 1.27 1.27)
				)
				(justify mirror)
			)
		)
		(property "Value" ""
			(at 0 0 0)
			(layer "B.Fab")
			(effects
				(font
					(size 1.27 1.27)
				)
				(justify mirror)
			)
		)
		(duplicate_pad_numbers_are_jumpers no)
		(fp_line
			(start 0.7874 0.4064)
			(end 0.7874 -0.4064)
			(stroke
				(width 0.1524)
				(type default)
			)
			(layer "B.SilkS")
		)
		(fp_line
			(start 0.7874 -0.4064)
			(end -0.7874 -0.4064)
			(stroke
				(width 0.1524)
				(type default)
			)
			(layer "B.SilkS")
		)
		(fp_line
			(start -0.7874 0.4064)
			(end 0.7874 0.4064)
			(stroke
				(width 0.1524)
				(type default)
			)
			(layer "B.SilkS")
		)
		(fp_line
			(start -0.7874 -0.4064)
			(end -0.7874 0.4064)
			(stroke
				(width 0.1524)
				(type default)
			)
			(layer "B.SilkS")
		)
		(fp_line
			(start 0.67945 0.3048)
			(end 0.67945 -0.305054)
			(stroke
				(width 0.1)
				(type default)
			)
			(layer "B.Fab")
		)
		(fp_line
			(start 0.67945 -0.305054)
			(end 0.12065 -0.305054)
			(stroke
				(width 0.1)
				(type default)
			)
			(layer "B.Fab")
		)
		(fp_line
			(start 0.12065 0.3048)
			(end 0.67945 0.3048)
			(stroke
				(width 0.1)
				(type default)
			)
			(layer "B.Fab")
		)
		(fp_line
			(start 0.12065 0.2794)
			(end 0.12065 0.3048)
			(stroke
				(width 0.1)
				(type default)
			)
			(layer "B.Fab")
		)
		(fp_line
			(start 0.12065 -0.2794)
			(end -0.12065 -0.2794)
			(stroke
				(width 0.1)
				(type default)
			)
			(layer "B.Fab")
		)
		(fp_line
			(start 0.12065 -0.305054)
			(end 0.12065 -0.2794)
			(stroke
				(width 0.1)
				(type default)
			)
			(layer "B.Fab")
		)
		(fp_line
			(start -0.120396 0.3048)
			(end -0.120396 0.2794)
			(stroke
				(width 0.1)
				(type default)
			)
			(layer "B.Fab")
		)
		(fp_line
			(start -0.120396 0.2794)
			(end 0.12065 0.2794)
			(stroke
				(width 0.1)
				(type default)
			)
			(layer "B.Fab")
		)
		(fp_line
			(start -0.12065 -0.2794)
			(end -0.12065 -0.3048)
			(stroke
				(width 0.1)
				(type default)
			)
			(layer "B.Fab")
		)
		(fp_line
			(start -0.12065 -0.3048)
			(end -0.67945 -0.3048)
			(stroke
				(width 0.1)
				(type default)
			)
			(layer "B.Fab")
		)
		(fp_line
			(start -0.67945 0.3048)
			(end -0.120396 0.3048)
			(stroke
				(width 0.1)
				(type default)
			)
			(layer "B.Fab")
		)
		(fp_line
			(start -0.67945 -0.3048)
			(end -0.67945 0.3048)
			(stroke
				(width 0.1)
				(type default)
			)
			(layer "B.Fab")
		)
		(pad "1" smd circle
			(at 0.40005 0)
			(size 0 0)
			(layers "B.Cu" "B.Mask" "B.Paste")
			(net "P3V3_CLK_GEN_VDDMXCK_CK440_PEX")
		)
		(pad "2" smd circle
			(at -0.40005 0)
			(size 0 0)
			(layers "B.Cu" "B.Mask" "B.Paste")
			(net "GND")
		)
	)
	(footprint ""
		(layer "B.Cu")
		(at 362.53674 -303.649634 -90)
		(property "Reference" "PR18"
			(at 0 0 90)
			(layer "B.SilkS")
			(hide yes)
			(effects
				(font
					(size 1.27 1.27)
				)
				(justify mirror)
			)
		)
		(property "Value" ""
			(at 0 0 90)
			(layer "B.Fab")
			(effects
				(font
					(size 1.27 1.27)
				)
				(justify mirror)
			)
		)
		(duplicate_pad_numbers_are_jumpers no)
		(fp_line
			(start -1.2954 0.5842)
			(end 1.2954 0.5842)
			(stroke
				(width 0.1524)
				(type default)
			)
			(layer "B.SilkS")
		)
		(fp_line
			(start 1.2954 0.5842)
			(end 1.2954 -0.5842)
			(stroke
				(width 0.1524)
				(type default)
			)
			(layer "B.SilkS")
		)
		(fp_line
			(start -1.2954 -0.5842)
			(end -1.2954 0.5842)
			(stroke
				(width 0.1524)
				(type default)
			)
			(layer "B.SilkS")
		)
		(fp_line
			(start 1.2954 -0.5842)
			(end -1.2954 -0.5842)
			(stroke
				(width 0.1524)
				(type default)
			)
			(layer "B.SilkS")
		)
		(fp_line
			(start -0.8636 0.4572)
			(end 0.8636 0.4572)
			(stroke
				(width 0.1)
				(type default)
			)
			(layer "B.Fab")
		)
		(fp_line
			(start 0.8636 0.4572)
			(end 0.8636 0.4318)
			(stroke
				(width 0.1)
				(type default)
			)
			(layer "B.Fab")
		)
		(fp_line
			(start 0.8636 0.4318)
			(end 0.8636 0.4064)
			(stroke
				(width 0.1)
				(type default)
			)
			(layer "B.Fab")
		)
		(fp_line
			(start -1.1938 0.4064)
			(end -0.8636 0.4064)
			(stroke
				(width 0.1)
				(type default)
			)
			(layer "B.Fab")
		)
		(fp_line
			(start -0.8636 0.4064)
			(end -0.8636 0.4572)
			(stroke
				(width 0.1)
				(type default)
			)
			(layer "B.Fab")
		)
		(fp_line
			(start 0.8636 0.4064)
			(end 1.1938 0.4064)
			(stroke
				(width 0.1)
				(type default)
			)
			(layer "B.Fab")
		)
		(fp_line
			(start 1.1938 0.4064)
			(end 1.1938 -0.406654)
			(stroke
				(width 0.1)
				(type default)
			)
			(layer "B.Fab")
		)
		(fp_line
			(start -1.1938 -0.406654)
			(end -1.1938 0.4064)
			(stroke
				(width 0.1)
				(type default)
			)
			(layer "B.Fab")
		)
		(fp_line
			(start -0.8636 -0.406654)
			(end -1.1938 -0.406654)
			(stroke
				(width 0.1)
				(type default)
			)
			(layer "B.Fab")
		)
		(fp_line
			(start 0.8636 -0.406654)
			(end 0.8636 -0.4572)
			(stroke
				(width 0.1)
				(type default)
			)
			(layer "B.Fab")
		)
		(fp_line
			(start 1.1938 -0.406654)
			(end 0.8636 -0.406654)
			(stroke
				(width 0.1)
				(type default)
			)
			(layer "B.Fab")
		)
		(fp_line
			(start -0.8636 -0.4572)
			(end -0.8636 -0.406654)
			(stroke
				(width 0.1)
				(type default)
			)
			(layer "B.Fab")
		)
		(fp_line
			(start 0.8636 -0.4572)
			(end -0.8636 -0.4572)
			(stroke
				(width 0.1)
				(type default)
			)
			(layer "B.Fab")
		)
		(pad "1" smd rect
			(at 0.7366 0 180)
			(size 0.7112 0.8128)
			(layers "B.Cu" "B.Mask" "B.Paste")
			(net "P0V8_PEX3")
		)
		(pad "2" smd rect
			(at -0.7366 0 180)
			(size 0.7112 0.8128)
			(layers "B.Cu" "B.Mask" "B.Paste")
			(net "GND")
		)
	)
	(footprint ""
		(layer "B.Cu")
		(at 281.399742 -288.774886 180)
		(property "Reference" "C3357"
			(at 0 0 0)
			(layer "B.SilkS")
			(hide yes)
			(effects
				(font
					(size 1.27 1.27)
				)
				(justify mirror)
			)
		)
		(property "Value" ""
			(at 0 0 0)
			(layer "B.Fab")
			(effects
				(font
					(size 1.27 1.27)
				)
				(justify mirror)
			)
		)
		(duplicate_pad_numbers_are_jumpers no)
		(fp_line
			(start 0.299974 0.150114)
			(end 0.299974 -0.150114)
			(stroke
				(width 0.1)
				(type default)
			)
			(layer "B.Fab")
		)
		(fp_line
			(start 0.299974 -0.150114)
			(end -0.299974 -0.150114)
			(stroke
				(width 0.1)
				(type default)
			)
			(layer "B.Fab")
		)
		(fp_line
			(start -0.299974 0.150114)
			(end 0.299974 0.150114)
			(stroke
				(width 0.1)
				(type default)
			)
			(layer "B.Fab")
		)
		(fp_line
			(start -0.299974 -0.150114)
			(end -0.299974 0.150114)
			(stroke
				(width 0.1)
				(type default)
			)
			(layer "B.Fab")
		)
		(pad "1" smd rect
			(at 0.2667 0)
			(size 0.3048 0.381)
			(layers "B.Cu" "B.Mask" "B.Paste")
			(net "P1V8_VDDA_PEX2")
		)
		(pad "2" smd rect
			(at -0.2667 0)
			(size 0.3048 0.381)
			(layers "B.Cu" "B.Mask" "B.Paste")
			(net "GND")
		)
	)
	(footprint ""
		(layer "B.Cu")
		(at 161.964116 -143.608552 180)
		(property "Reference" "C878"
			(at 0 0 0)
			(layer "B.SilkS")
			(hide yes)
			(effects
				(font
					(size 1.27 1.27)
				)
				(justify mirror)
			)
		)
		(property "Value" ""
			(at 0 0 0)
			(layer "B.Fab")
			(effects
				(font
					(size 1.27 1.27)
				)
				(justify mirror)
			)
		)
		(duplicate_pad_numbers_are_jumpers no)
		(fp_line
			(start 0.299974 0.150114)
			(end 0.299974 -0.150114)
			(stroke
				(width 0.1)
				(type default)
			)
			(layer "B.Fab")
		)
		(fp_line
			(start 0.299974 -0.150114)
			(end -0.299974 -0.150114)
			(stroke
				(width 0.1)
				(type default)
			)
			(layer "B.Fab")
		)
		(fp_line
			(start -0.299974 0.150114)
			(end 0.299974 0.150114)
			(stroke
				(width 0.1)
				(type default)
			)
			(layer "B.Fab")
		)
		(fp_line
			(start -0.299974 -0.150114)
			(end -0.299974 0.150114)
			(stroke
				(width 0.1)
				(type default)
			)
			(layer "B.Fab")
		)
		(pad "1" smd rect
			(at 0.2667 0)
			(size 0.3048 0.381)
			(layers "B.Cu" "B.Mask" "B.Paste")
			(net "P12V_NIC2")
		)
		(pad "2" smd rect
			(at -0.2667 0)
			(size 0.3048 0.381)
			(layers "B.Cu" "B.Mask" "B.Paste")
			(net "GND")
		)
	)
	(footprint ""
		(layer "B.Cu")
		(at 398.944084 -138.421618 180)
		(property "Reference" "R330"
			(at 0 0 0)
			(layer "B.SilkS")
			(hide yes)
			(effects
				(font
					(size 1.27 1.27)
				)
				(justify mirror)
			)
		)
		(property "Value" ""
			(at 0 0 0)
			(layer "B.Fab")
			(effects
				(font
					(size 1.27 1.27)
				)
				(justify mirror)
			)
		)
		(duplicate_pad_numbers_are_jumpers no)
		(fp_line
			(start 0.7874 0.4064)
			(end 0.7874 -0.4064)
			(stroke
				(width 0.1524)
				(type default)
			)
			(layer "B.SilkS")
		)
		(fp_line
			(start 0.7874 -0.4064)
			(end -0.7874 -0.4064)
			(stroke
				(width 0.1524)
				(type default)
			)
			(layer "B.SilkS")
		)
		(fp_line
			(start -0.7874 0.4064)
			(end 0.7874 0.4064)
			(stroke
				(width 0.1524)
				(type default)
			)
			(layer "B.SilkS")
		)
		(fp_line
			(start -0.7874 -0.4064)
			(end -0.7874 0.4064)
			(stroke
				(width 0.1524)
				(type default)
			)
			(layer "B.SilkS")
		)
		(fp_line
			(start 0.67945 0.3048)
			(end 0.67945 -0.305054)
			(stroke
				(width 0.1)
				(type default)
			)
			(layer "B.Fab")
		)
		(fp_line
			(start 0.67945 -0.305054)
			(end 0.12065 -0.305054)
			(stroke
				(width 0.1)
				(type default)
			)
			(layer "B.Fab")
		)
		(fp_line
			(start 0.12065 0.3048)
			(end 0.67945 0.3048)
			(stroke
				(width 0.1)
				(type default)
			)
			(layer "B.Fab")
		)
		(fp_line
			(start 0.12065 0.2794)
			(end 0.12065 0.3048)
			(stroke
				(width 0.1)
				(type default)
			)
			(layer "B.Fab")
		)
		(fp_line
			(start 0.12065 -0.2794)
			(end -0.12065 -0.2794)
			(stroke
				(width 0.1)
				(type default)
			)
			(layer "B.Fab")
		)
		(fp_line
			(start 0.12065 -0.305054)
			(end 0.12065 -0.2794)
			(stroke
				(width 0.1)
				(type default)
			)
			(layer "B.Fab")
		)
		(fp_line
			(start -0.120396 0.3048)
			(end -0.120396 0.2794)
			(stroke
				(width 0.1)
				(type default)
			)
			(layer "B.Fab")
		)
		(fp_line
			(start -0.120396 0.2794)
			(end 0.12065 0.2794)
			(stroke
				(width 0.1)
				(type default)
			)
			(layer "B.Fab")
		)
		(fp_line
			(start -0.12065 -0.2794)
			(end -0.12065 -0.3048)
			(stroke
				(width 0.1)
				(type default)
			)
			(layer "B.Fab")
		)
		(fp_line
			(start -0.12065 -0.3048)
			(end -0.67945 -0.3048)
			(stroke
				(width 0.1)
				(type default)
			)
			(layer "B.Fab")
		)
		(fp_line
			(start -0.67945 0.3048)
			(end -0.120396 0.3048)
			(stroke
				(width 0.1)
				(type default)
			)
			(layer "B.Fab")
		)
		(fp_line
			(start -0.67945 -0.3048)
			(end -0.67945 0.3048)
			(stroke
				(width 0.1)
				(type default)
			)
			(layer "B.Fab")
		)
		(pad "1" smd circle
			(at 0.40005 0)
			(size 0 0)
			(layers "B.Cu" "B.Mask" "B.Paste")
			(net "NIC6_AUX_PWR_EN")
		)
		(pad "2" smd circle
			(at -0.40005 0)
			(size 0 0)
			(layers "B.Cu" "B.Mask" "B.Paste")
			(net "GND")
		)
	)
	(footprint ""
		(layer "B.Cu")
		(at 348.107 -233.553 90)
		(property "Reference" "R3595"
			(at 0 0 90)
			(layer "B.SilkS")
			(hide yes)
			(effects
				(font
					(size 1.27 1.27)
				)
				(justify mirror)
			)
		)
		(property "Value" ""
			(at 0 0 90)
			(layer "B.Fab")
			(effects
				(font
					(size 1.27 1.27)
				)
				(justify mirror)
			)
		)
		(duplicate_pad_numbers_are_jumpers no)
		(fp_line
			(start 0.7874 -0.4064)
			(end -0.7874 -0.4064)
			(stroke
				(width 0.1524)
				(type default)
			)
			(layer "B.SilkS")
		)
		(fp_line
			(start -0.7874 -0.4064)
			(end -0.7874 0.4064)
			(stroke
				(width 0.1524)
				(type default)
			)
			(layer "B.SilkS")
		)
		(fp_line
			(start 0.7874 0.4064)
			(end 0.7874 -0.4064)
			(stroke
				(width 0.1524)
				(type default)
			)
			(layer "B.SilkS")
		)
		(fp_line
			(start -0.7874 0.4064)
			(end 0.7874 0.4064)
			(stroke
				(width 0.1524)
				(type default)
			)
			(layer "B.SilkS")
		)
		(fp_line
			(start 0.67945 -0.305054)
			(end 0.12065 -0.305054)
			(stroke
				(width 0.1)
				(type default)
			)
			(layer "B.Fab")
		)
		(fp_line
			(start 0.12065 -0.305054)
			(end 0.12065 -0.2794)
			(stroke
				(width 0.1)
				(type default)
			)
			(layer "B.Fab")
		)
		(fp_line
			(start -0.12065 -0.3048)
			(end -0.67945 -0.3048)
			(stroke
				(width 0.1)
				(type default)
			)
			(layer "B.Fab")
		)
		(fp_line
			(start -0.67945 -0.3048)
			(end -0.67945 0.3048)
			(stroke
				(width 0.1)
				(type default)
			)
			(layer "B.Fab")
		)
		(fp_line
			(start 0.12065 -0.2794)
			(end -0.12065 -0.2794)
			(stroke
				(width 0.1)
				(type default)
			)
			(layer "B.Fab")
		)
		(fp_line
			(start -0.12065 -0.2794)
			(end -0.12065 -0.3048)
			(stroke
				(width 0.1)
				(type default)
			)
			(layer "B.Fab")
		)
		(fp_line
			(start 0.12065 0.2794)
			(end 0.12065 0.3048)
			(stroke
				(width 0.1)
				(type default)
			)
			(layer "B.Fab")
		)
		(fp_line
			(start -0.120396 0.2794)
			(end 0.12065 0.2794)
			(stroke
				(width 0.1)
				(type default)
			)
			(layer "B.Fab")
		)
		(fp_line
			(start 0.67945 0.3048)
			(end 0.67945 -0.305054)
			(stroke
				(width 0.1)
				(type default)
			)
			(layer "B.Fab")
		)
		(fp_line
			(start 0.12065 0.3048)
			(end 0.67945 0.3048)
			(stroke
				(width 0.1)
				(type default)
			)
			(layer "B.Fab")
		)
		(fp_line
			(start -0.120396 0.3048)
			(end -0.120396 0.2794)
			(stroke
				(width 0.1)
				(type default)
			)
			(layer "B.Fab")
		)
		(fp_line
			(start -0.67945 0.3048)
			(end -0.120396 0.3048)
			(stroke
				(width 0.1)
				(type default)
			)
			(layer "B.Fab")
		)
		(pad "1" smd circle
			(at 0.40005 0 270)
			(size 0 0)
			(layers "B.Cu" "B.Mask" "B.Paste")
			(net "RST_SSD7_PERST_R_N")
		)
		(pad "2" smd circle
			(at -0.40005 0 270)
			(size 0 0)
			(layers "B.Cu" "B.Mask" "B.Paste")
			(net "RST_SSD7_PERST_N")
		)
	)
	(footprint ""
		(layer "B.Cu")
		(at 114.833654 -282.251404 180)
		(property "Reference" "PR7166"
			(at 0 0 0)
			(layer "B.SilkS")
			(hide yes)
			(effects
				(font
					(size 1.27 1.27)
				)
				(justify mirror)
			)
		)
		(property "Value" ""
			(at 0 0 0)
			(layer "B.Fab")
			(effects
				(font
					(size 1.27 1.27)
				)
				(justify mirror)
			)
		)
		(duplicate_pad_numbers_are_jumpers no)
		(fp_line
			(start 0.7874 0.4064)
			(end 0.7874 -0.4064)
			(stroke
				(width 0.1524)
				(type default)
			)
			(layer "B.SilkS")
		)
		(fp_line
			(start 0.7874 -0.4064)
			(end -0.7874 -0.4064)
			(stroke
				(width 0.1524)
				(type default)
			)
			(layer "B.SilkS")
		)
		(fp_line
			(start -0.7874 0.4064)
			(end 0.7874 0.4064)
			(stroke
				(width 0.1524)
				(type default)
			)
			(layer "B.SilkS")
		)
		(fp_line
			(start -0.7874 -0.4064)
			(end -0.7874 0.4064)
			(stroke
				(width 0.1524)
				(type default)
			)
			(layer "B.SilkS")
		)
		(fp_line
			(start 0.67945 0.3048)
			(end 0.67945 -0.305054)
			(stroke
				(width 0.1)
				(type default)
			)
			(layer "B.Fab")
		)
		(fp_line
			(start 0.67945 -0.305054)
			(end 0.12065 -0.305054)
			(stroke
				(width 0.1)
				(type default)
			)
			(layer "B.Fab")
		)
		(fp_line
			(start 0.12065 0.3048)
			(end 0.67945 0.3048)
			(stroke
				(width 0.1)
				(type default)
			)
			(layer "B.Fab")
		)
		(fp_line
			(start 0.12065 0.2794)
			(end 0.12065 0.3048)
			(stroke
				(width 0.1)
				(type default)
			)
			(layer "B.Fab")
		)
		(fp_line
			(start 0.12065 -0.2794)
			(end -0.12065 -0.2794)
			(stroke
				(width 0.1)
				(type default)
			)
			(layer "B.Fab")
		)
		(fp_line
			(start 0.12065 -0.305054)
			(end 0.12065 -0.2794)
			(stroke
				(width 0.1)
				(type default)
			)
			(layer "B.Fab")
		)
		(fp_line
			(start -0.120396 0.3048)
			(end -0.120396 0.2794)
			(stroke
				(width 0.1)
				(type default)
			)
			(layer "B.Fab")
		)
		(fp_line
			(start -0.120396 0.2794)
			(end 0.12065 0.2794)
			(stroke
				(width 0.1)
				(type default)
			)
			(layer "B.Fab")
		)
		(fp_line
			(start -0.12065 -0.2794)
			(end -0.12065 -0.3048)
			(stroke
				(width 0.1)
				(type default)
			)
			(layer "B.Fab")
		)
		(fp_line
			(start -0.12065 -0.3048)
			(end -0.67945 -0.3048)
			(stroke
				(width 0.1)
				(type default)
			)
			(layer "B.Fab")
		)
		(fp_line
			(start -0.67945 0.3048)
			(end -0.120396 0.3048)
			(stroke
				(width 0.1)
				(type default)
			)
			(layer "B.Fab")
		)
		(fp_line
			(start -0.67945 -0.3048)
			(end -0.67945 0.3048)
			(stroke
				(width 0.1)
				(type default)
			)
			(layer "B.Fab")
		)
		(pad "1" smd circle
			(at 0.40005 0)
			(size 0 0)
			(layers "B.Cu" "B.Mask" "B.Paste")
			(net "P0V8_PEX0_EN2")
		)
		(pad "2" smd circle
			(at -0.40005 0)
			(size 0 0)
			(layers "B.Cu" "B.Mask" "B.Paste")
			(net "P0V8_PEX0_VCC2")
		)
	)
	(footprint ""
		(layer "B.Cu")
		(at 232.0671 -91.588082 180)
		(property "Reference" "C2616"
			(at 0 0 0)
			(layer "B.SilkS")
			(hide yes)
			(effects
				(font
					(size 1.27 1.27)
				)
				(justify mirror)
			)
		)
		(property "Value" ""
			(at 0 0 0)
			(layer "B.Fab")
			(effects
				(font
					(size 1.27 1.27)
				)
				(justify mirror)
			)
		)
		(duplicate_pad_numbers_are_jumpers no)
		(fp_line
			(start 0.7874 0.4064)
			(end 0.7874 -0.4064)
			(stroke
				(width 0.1524)
				(type default)
			)
			(layer "B.SilkS")
		)
		(fp_line
			(start 0.7874 -0.4064)
			(end -0.7874 -0.4064)
			(stroke
				(width 0.1524)
				(type default)
			)
			(layer "B.SilkS")
		)
		(fp_line
			(start -0.7874 0.4064)
			(end 0.7874 0.4064)
			(stroke
				(width 0.1524)
				(type default)
			)
			(layer "B.SilkS")
		)
		(fp_line
			(start -0.7874 -0.4064)
			(end -0.7874 0.4064)
			(stroke
				(width 0.1524)
				(type default)
			)
			(layer "B.SilkS")
		)
		(fp_line
			(start 0.67945 0.3048)
			(end 0.67945 -0.305054)
			(stroke
				(width 0.1)
				(type default)
			)
			(layer "B.Fab")
		)
		(fp_line
			(start 0.67945 -0.305054)
			(end 0.12065 -0.305054)
			(stroke
				(width 0.1)
				(type default)
			)
			(layer "B.Fab")
		)
		(fp_line
			(start 0.12065 0.3048)
			(end 0.67945 0.3048)
			(stroke
				(width 0.1)
				(type default)
			)
			(layer "B.Fab")
		)
		(fp_line
			(start 0.12065 0.2794)
			(end 0.12065 0.3048)
			(stroke
				(width 0.1)
				(type default)
			)
			(layer "B.Fab")
		)
		(fp_line
			(start 0.12065 -0.2794)
			(end -0.12065 -0.2794)
			(stroke
				(width 0.1)
				(type default)
			)
			(layer "B.Fab")
		)
		(fp_line
			(start 0.12065 -0.305054)
			(end 0.12065 -0.2794)
			(stroke
				(width 0.1)
				(type default)
			)
			(layer "B.Fab")
		)
		(fp_line
			(start -0.120396 0.3048)
			(end -0.120396 0.2794)
			(stroke
				(width 0.1)
				(type default)
			)
			(layer "B.Fab")
		)
		(fp_line
			(start -0.120396 0.2794)
			(end 0.12065 0.2794)
			(stroke
				(width 0.1)
				(type default)
			)
			(layer "B.Fab")
		)
		(fp_line
			(start -0.12065 -0.2794)
			(end -0.12065 -0.3048)
			(stroke
				(width 0.1)
				(type default)
			)
			(layer "B.Fab")
		)
		(fp_line
			(start -0.12065 -0.3048)
			(end -0.67945 -0.3048)
			(stroke
				(width 0.1)
				(type default)
			)
			(layer "B.Fab")
		)
		(fp_line
			(start -0.67945 0.3048)
			(end -0.120396 0.3048)
			(stroke
				(width 0.1)
				(type default)
			)
			(layer "B.Fab")
		)
		(fp_line
			(start -0.67945 -0.3048)
			(end -0.67945 0.3048)
			(stroke
				(width 0.1)
				(type default)
			)
			(layer "B.Fab")
		)
		(pad "1" smd circle
			(at 0.40005 0)
			(size 0 0)
			(layers "B.Cu" "B.Mask" "B.Paste")
			(net "P3V3_PEX_USB_HUB")
		)
		(pad "2" smd circle
			(at -0.40005 0)
			(size 0 0)
			(layers "B.Cu" "B.Mask" "B.Paste")
			(net "GND")
		)
	)
	(footprint ""
		(layer "B.Cu")
		(at 402.249894 -290.199826 90)
		(property "Reference" "C1968"
			(at 0 0 90)
			(layer "B.SilkS")
			(hide yes)
			(effects
				(font
					(size 1.27 1.27)
				)
				(justify mirror)
			)
		)
		(property "Value" ""
			(at 0 0 90)
			(layer "B.Fab")
			(effects
				(font
					(size 1.27 1.27)
				)
				(justify mirror)
			)
		)
		(duplicate_pad_numbers_are_jumpers no)
		(fp_line
			(start 0.299974 -0.150114)
			(end -0.299974 -0.150114)
			(stroke
				(width 0.1)
				(type default)
			)
			(layer "B.Fab")
		)
		(fp_line
			(start -0.299974 -0.150114)
			(end -0.299974 0.150114)
			(stroke
				(width 0.1)
				(type default)
			)
			(layer "B.Fab")
		)
		(fp_line
			(start 0.299974 0.150114)
			(end 0.299974 -0.150114)
			(stroke
				(width 0.1)
				(type default)
			)
			(layer "B.Fab")
		)
		(fp_line
			(start -0.299974 0.150114)
			(end 0.299974 0.150114)
			(stroke
				(width 0.1)
				(type default)
			)
			(layer "B.Fab")
		)
		(pad "1" smd rect
			(at 0.2667 0 270)
			(size 0.3048 0.381)
			(layers "B.Cu" "B.Mask" "B.Paste")
			(net "P0V8_SERDES_VDDA_PEX3")
		)
		(pad "2" smd rect
			(at -0.2667 0 270)
			(size 0.3048 0.381)
			(layers "B.Cu" "B.Mask" "B.Paste")
			(net "GND")
		)
	)
	(footprint ""
		(layer "B.Cu")
		(at 213.106 -198.755 -90)
		(property "Reference" "R6310"
			(at 0 0 90)
			(layer "B.SilkS")
			(hide yes)
			(effects
				(font
					(size 1.27 1.27)
				)
				(justify mirror)
			)
		)
		(property "Value" ""
			(at 0 0 90)
			(layer "B.Fab")
			(effects
				(font
					(size 1.27 1.27)
				)
				(justify mirror)
			)
		)
		(duplicate_pad_numbers_are_jumpers no)
		(fp_line
			(start -0.7874 0.4064)
			(end 0.7874 0.4064)
			(stroke
				(width 0.1524)
				(type default)
			)
			(layer "B.SilkS")
		)
		(fp_line
			(start 0.7874 0.4064)
			(end 0.7874 -0.4064)
			(stroke
				(width 0.1524)
				(type default)
			)
			(layer "B.SilkS")
		)
		(fp_line
			(start -0.7874 -0.4064)
			(end -0.7874 0.4064)
			(stroke
				(width 0.1524)
				(type default)
			)
			(layer "B.SilkS")
		)
		(fp_line
			(start 0.7874 -0.4064)
			(end -0.7874 -0.4064)
			(stroke
				(width 0.1524)
				(type default)
			)
			(layer "B.SilkS")
		)
		(fp_line
			(start -0.67945 0.3048)
			(end -0.120396 0.3048)
			(stroke
				(width 0.1)
				(type default)
			)
			(layer "B.Fab")
		)
		(fp_line
			(start -0.120396 0.3048)
			(end -0.120396 0.2794)
			(stroke
				(width 0.1)
				(type default)
			)
			(layer "B.Fab")
		)
		(fp_line
			(start 0.12065 0.3048)
			(end 0.67945 0.3048)
			(stroke
				(width 0.1)
				(type default)
			)
			(layer "B.Fab")
		)
		(fp_line
			(start 0.67945 0.3048)
			(end 0.67945 -0.305054)
			(stroke
				(width 0.1)
				(type default)
			)
			(layer "B.Fab")
		)
		(fp_line
			(start -0.120396 0.2794)
			(end 0.12065 0.2794)
			(stroke
				(width 0.1)
				(type default)
			)
			(layer "B.Fab")
		)
		(fp_line
			(start 0.12065 0.2794)
			(end 0.12065 0.3048)
			(stroke
				(width 0.1)
				(type default)
			)
			(layer "B.Fab")
		)
		(fp_line
			(start -0.12065 -0.2794)
			(end -0.12065 -0.3048)
			(stroke
				(width 0.1)
				(type default)
			)
			(layer "B.Fab")
		)
		(fp_line
			(start 0.12065 -0.2794)
			(end -0.12065 -0.2794)
			(stroke
				(width 0.1)
				(type default)
			)
			(layer "B.Fab")
		)
		(fp_line
			(start -0.67945 -0.3048)
			(end -0.67945 0.3048)
			(stroke
				(width 0.1)
				(type default)
			)
			(layer "B.Fab")
		)
		(fp_line
			(start -0.12065 -0.3048)
			(end -0.67945 -0.3048)
			(stroke
				(width 0.1)
				(type default)
			)
			(layer "B.Fab")
		)
		(fp_line
			(start 0.12065 -0.305054)
			(end 0.12065 -0.2794)
			(stroke
				(width 0.1)
				(type default)
			)
			(layer "B.Fab")
		)
		(fp_line
			(start 0.67945 -0.305054)
			(end 0.12065 -0.305054)
			(stroke
				(width 0.1)
				(type default)
			)
			(layer "B.Fab")
		)
		(pad "1" smd circle
			(at 0.40005 0 90)
			(size 0 0)
			(layers "B.Cu" "B.Mask" "B.Paste")
			(net "SMB_NIC6_LS_SDA")
		)
		(pad "2" smd circle
			(at -0.40005 0 90)
			(size 0 0)
			(layers "B.Cu" "B.Mask" "B.Paste")
			(net "SMB_NIC6_LS_R_SDA")
		)
	)
	(footprint ""
		(layer "B.Cu")
		(at 235.921296 -93.120718)
		(property "Reference" "C2621"
			(at 0 0 0)
			(layer "B.SilkS")
			(hide yes)
			(effects
				(font
					(size 1.27 1.27)
				)
				(justify mirror)
			)
		)
		(property "Value" ""
			(at 0 0 0)
			(layer "B.Fab")
			(effects
				(font
					(size 1.27 1.27)
				)
				(justify mirror)
			)
		)
		(duplicate_pad_numbers_are_jumpers no)
		(fp_line
			(start -0.7874 -0.4064)
			(end -0.7874 0.4064)
			(stroke
				(width 0.1524)
				(type default)
			)
			(layer "B.SilkS")
		)
		(fp_line
			(start -0.7874 0.4064)
			(end 0.7874 0.4064)
			(stroke
				(width 0.1524)
				(type default)
			)
			(layer "B.SilkS")
		)
		(fp_line
			(start 0.7874 -0.4064)
			(end -0.7874 -0.4064)
			(stroke
				(width 0.1524)
				(type default)
			)
			(layer "B.SilkS")
		)
		(fp_line
			(start 0.7874 0.4064)
			(end 0.7874 -0.4064)
			(stroke
				(width 0.1524)
				(type default)
			)
			(layer "B.SilkS")
		)
		(fp_line
			(start -0.67945 -0.3048)
			(end -0.67945 0.3048)
			(stroke
				(width 0.1)
				(type default)
			)
			(layer "B.Fab")
		)
		(fp_line
			(start -0.67945 0.3048)
			(end -0.120396 0.3048)
			(stroke
				(width 0.1)
				(type default)
			)
			(layer "B.Fab")
		)
		(fp_line
			(start -0.12065 -0.3048)
			(end -0.67945 -0.3048)
			(stroke
				(width 0.1)
				(type default)
			)
			(layer "B.Fab")
		)
		(fp_line
			(start -0.12065 -0.2794)
			(end -0.12065 -0.3048)
			(stroke
				(width 0.1)
				(type default)
			)
			(layer "B.Fab")
		)
		(fp_line
			(start -0.120396 0.2794)
			(end 0.12065 0.2794)
			(stroke
				(width 0.1)
				(type default)
			)
			(layer "B.Fab")
		)
		(fp_line
			(start -0.120396 0.3048)
			(end -0.120396 0.2794)
			(stroke
				(width 0.1)
				(type default)
			)
			(layer "B.Fab")
		)
		(fp_line
			(start 0.12065 -0.305054)
			(end 0.12065 -0.2794)
			(stroke
				(width 0.1)
				(type default)
			)
			(layer "B.Fab")
		)
		(fp_line
			(start 0.12065 -0.2794)
			(end -0.12065 -0.2794)
			(stroke
				(width 0.1)
				(type default)
			)
			(layer "B.Fab")
		)
		(fp_line
			(start 0.12065 0.2794)
			(end 0.12065 0.3048)
			(stroke
				(width 0.1)
				(type default)
			)
			(layer "B.Fab")
		)
		(fp_line
			(start 0.12065 0.3048)
			(end 0.67945 0.3048)
			(stroke
				(width 0.1)
				(type default)
			)
			(layer "B.Fab")
		)
		(fp_line
			(start 0.67945 -0.305054)
			(end 0.12065 -0.305054)
			(stroke
				(width 0.1)
				(type default)
			)
			(layer "B.Fab")
		)
		(fp_line
			(start 0.67945 0.3048)
			(end 0.67945 -0.305054)
			(stroke
				(width 0.1)
				(type default)
			)
			(layer "B.Fab")
		)
		(pad "1" smd circle
			(at 0.40005 0 180)
			(size 0 0)
			(layers "B.Cu" "B.Mask" "B.Paste")
			(net "P3V3_PEX_USB_HUB")
		)
		(pad "2" smd circle
			(at -0.40005 0 180)
			(size 0 0)
			(layers "B.Cu" "B.Mask" "B.Paste")
			(net "GND")
		)
	)
	(footprint ""
		(layer "B.Cu")
		(at 394.164312 -145.284952 180)
		(property "Reference" "C941"
			(at 0 0 0)
			(layer "B.SilkS")
			(hide yes)
			(effects
				(font
					(size 1.27 1.27)
				)
				(justify mirror)
			)
		)
		(property "Value" ""
			(at 0 0 0)
			(layer "B.Fab")
			(effects
				(font
					(size 1.27 1.27)
				)
				(justify mirror)
			)
		)
		(duplicate_pad_numbers_are_jumpers no)
		(fp_line
			(start 0.299974 0.150114)
			(end 0.299974 -0.150114)
			(stroke
				(width 0.1)
				(type default)
			)
			(layer "B.Fab")
		)
		(fp_line
			(start 0.299974 -0.150114)
			(end -0.299974 -0.150114)
			(stroke
				(width 0.1)
				(type default)
			)
			(layer "B.Fab")
		)
		(fp_line
			(start -0.299974 0.150114)
			(end 0.299974 0.150114)
			(stroke
				(width 0.1)
				(type default)
			)
			(layer "B.Fab")
		)
		(fp_line
			(start -0.299974 -0.150114)
			(end -0.299974 0.150114)
			(stroke
				(width 0.1)
				(type default)
			)
			(layer "B.Fab")
		)
		(pad "1" smd rect
			(at 0.2667 0)
			(size 0.3048 0.381)
			(layers "B.Cu" "B.Mask" "B.Paste")
			(net "P12V_NIC6")
		)
		(pad "2" smd rect
			(at -0.2667 0)
			(size 0.3048 0.381)
			(layers "B.Cu" "B.Mask" "B.Paste")
			(net "GND")
		)
	)
	(footprint ""
		(layer "B.Cu")
		(at 419.58641 -117.66169)
		(property "Reference" "R360"
			(at 0 0 0)
			(layer "B.SilkS")
			(hide yes)
			(effects
				(font
					(size 1.27 1.27)
				)
				(justify mirror)
			)
		)
		(property "Value" ""
			(at 0 0 0)
			(layer "B.Fab")
			(effects
				(font
					(size 1.27 1.27)
				)
				(justify mirror)
			)
		)
		(duplicate_pad_numbers_are_jumpers no)
		(fp_line
			(start -0.7874 -0.4064)
			(end -0.7874 0.4064)
			(stroke
				(width 0.1524)
				(type default)
			)
			(layer "B.SilkS")
		)
		(fp_line
			(start -0.7874 0.4064)
			(end 0.7874 0.4064)
			(stroke
				(width 0.1524)
				(type default)
			)
			(layer "B.SilkS")
		)
		(fp_line
			(start 0.7874 -0.4064)
			(end -0.7874 -0.4064)
			(stroke
				(width 0.1524)
				(type default)
			)
			(layer "B.SilkS")
		)
		(fp_line
			(start 0.7874 0.4064)
			(end 0.7874 -0.4064)
			(stroke
				(width 0.1524)
				(type default)
			)
			(layer "B.SilkS")
		)
		(fp_line
			(start -0.67945 -0.3048)
			(end -0.67945 0.3048)
			(stroke
				(width 0.1)
				(type default)
			)
			(layer "B.Fab")
		)
		(fp_line
			(start -0.67945 0.3048)
			(end -0.120396 0.3048)
			(stroke
				(width 0.1)
				(type default)
			)
			(layer "B.Fab")
		)
		(fp_line
			(start -0.12065 -0.3048)
			(end -0.67945 -0.3048)
			(stroke
				(width 0.1)
				(type default)
			)
			(layer "B.Fab")
		)
		(fp_line
			(start -0.12065 -0.2794)
			(end -0.12065 -0.3048)
			(stroke
				(width 0.1)
				(type default)
			)
			(layer "B.Fab")
		)
		(fp_line
			(start -0.120396 0.2794)
			(end 0.12065 0.2794)
			(stroke
				(width 0.1)
				(type default)
			)
			(layer "B.Fab")
		)
		(fp_line
			(start -0.120396 0.3048)
			(end -0.120396 0.2794)
			(stroke
				(width 0.1)
				(type default)
			)
			(layer "B.Fab")
		)
		(fp_line
			(start 0.12065 -0.305054)
			(end 0.12065 -0.2794)
			(stroke
				(width 0.1)
				(type default)
			)
			(layer "B.Fab")
		)
		(fp_line
			(start 0.12065 -0.2794)
			(end -0.12065 -0.2794)
			(stroke
				(width 0.1)
				(type default)
			)
			(layer "B.Fab")
		)
		(fp_line
			(start 0.12065 0.2794)
			(end 0.12065 0.3048)
			(stroke
				(width 0.1)
				(type default)
			)
			(layer "B.Fab")
		)
		(fp_line
			(start 0.12065 0.3048)
			(end 0.67945 0.3048)
			(stroke
				(width 0.1)
				(type default)
			)
			(layer "B.Fab")
		)
		(fp_line
			(start 0.67945 -0.305054)
			(end 0.12065 -0.305054)
			(stroke
				(width 0.1)
				(type default)
			)
			(layer "B.Fab")
		)
		(fp_line
			(start 0.67945 0.3048)
			(end 0.67945 -0.305054)
			(stroke
				(width 0.1)
				(type default)
			)
			(layer "B.Fab")
		)
		(pad "1" smd circle
			(at 0.40005 0 180)
			(size 0 0)
			(layers "B.Cu" "B.Mask" "B.Paste")
			(net "NIC7_AUX_PWR_EN_R")
		)
		(pad "2" smd circle
			(at -0.40005 0 180)
			(size 0 0)
			(layers "B.Cu" "B.Mask" "B.Paste")
			(net "NIC7_AUX_PWR_EN")
		)
	)
	(footprint ""
		(layer "B.Cu")
		(at 291.46119 -204.887068)
		(property "Reference" "R1040"
			(at 0 0 0)
			(layer "B.SilkS")
			(hide yes)
			(effects
				(font
					(size 1.27 1.27)
				)
				(justify mirror)
			)
		)
		(property "Value" ""
			(at 0 0 0)
			(layer "B.Fab")
			(effects
				(font
					(size 1.27 1.27)
				)
				(justify mirror)
			)
		)
		(duplicate_pad_numbers_are_jumpers no)
		(fp_line
			(start -0.7874 -0.4064)
			(end -0.7874 0.4064)
			(stroke
				(width 0.1524)
				(type default)
			)
			(layer "B.SilkS")
		)
		(fp_line
			(start -0.7874 0.4064)
			(end 0.7874 0.4064)
			(stroke
				(width 0.1524)
				(type default)
			)
			(layer "B.SilkS")
		)
		(fp_line
			(start 0.7874 -0.4064)
			(end -0.7874 -0.4064)
			(stroke
				(width 0.1524)
				(type default)
			)
			(layer "B.SilkS")
		)
		(fp_line
			(start 0.7874 0.4064)
			(end 0.7874 -0.4064)
			(stroke
				(width 0.1524)
				(type default)
			)
			(layer "B.SilkS")
		)
		(fp_line
			(start -0.67945 -0.3048)
			(end -0.67945 0.3048)
			(stroke
				(width 0.1)
				(type default)
			)
			(layer "B.Fab")
		)
		(fp_line
			(start -0.67945 0.3048)
			(end -0.120396 0.3048)
			(stroke
				(width 0.1)
				(type default)
			)
			(layer "B.Fab")
		)
		(fp_line
			(start -0.12065 -0.3048)
			(end -0.67945 -0.3048)
			(stroke
				(width 0.1)
				(type default)
			)
			(layer "B.Fab")
		)
		(fp_line
			(start -0.12065 -0.2794)
			(end -0.12065 -0.3048)
			(stroke
				(width 0.1)
				(type default)
			)
			(layer "B.Fab")
		)
		(fp_line
			(start -0.120396 0.2794)
			(end 0.12065 0.2794)
			(stroke
				(width 0.1)
				(type default)
			)
			(layer "B.Fab")
		)
		(fp_line
			(start -0.120396 0.3048)
			(end -0.120396 0.2794)
			(stroke
				(width 0.1)
				(type default)
			)
			(layer "B.Fab")
		)
		(fp_line
			(start 0.12065 -0.305054)
			(end 0.12065 -0.2794)
			(stroke
				(width 0.1)
				(type default)
			)
			(layer "B.Fab")
		)
		(fp_line
			(start 0.12065 -0.2794)
			(end -0.12065 -0.2794)
			(stroke
				(width 0.1)
				(type default)
			)
			(layer "B.Fab")
		)
		(fp_line
			(start 0.12065 0.2794)
			(end 0.12065 0.3048)
			(stroke
				(width 0.1)
				(type default)
			)
			(layer "B.Fab")
		)
		(fp_line
			(start 0.12065 0.3048)
			(end 0.67945 0.3048)
			(stroke
				(width 0.1)
				(type default)
			)
			(layer "B.Fab")
		)
		(fp_line
			(start 0.67945 -0.305054)
			(end 0.12065 -0.305054)
			(stroke
				(width 0.1)
				(type default)
			)
			(layer "B.Fab")
		)
		(fp_line
			(start 0.67945 0.3048)
			(end 0.67945 -0.305054)
			(stroke
				(width 0.1)
				(type default)
			)
			(layer "B.Fab")
		)
		(pad "1" smd circle
			(at 0.40005 0 180)
			(size 0 0)
			(layers "B.Cu" "B.Mask" "B.Paste")
			(net "SPI_BIC1_MISO_LS23_DIR4")
		)
		(pad "2" smd circle
			(at -0.40005 0 180)
			(size 0 0)
			(layers "B.Cu" "B.Mask" "B.Paste")
			(net "P1V8_PEX")
		)
	)
	(footprint ""
		(layer "B.Cu")
		(at 461.712564 -305.7906 -90)
		(property "Reference" "R847"
			(at 0 0 90)
			(layer "B.SilkS")
			(hide yes)
			(effects
				(font
					(size 1.27 1.27)
				)
				(justify mirror)
			)
		)
		(property "Value" ""
			(at 0 0 90)
			(layer "B.Fab")
			(effects
				(font
					(size 1.27 1.27)
				)
				(justify mirror)
			)
		)
		(duplicate_pad_numbers_are_jumpers no)
		(fp_line
			(start -0.7874 0.4064)
			(end 0.7874 0.4064)
			(stroke
				(width 0.1524)
				(type default)
			)
			(layer "B.SilkS")
		)
		(fp_line
			(start 0.7874 0.4064)
			(end 0.7874 -0.4064)
			(stroke
				(width 0.1524)
				(type default)
			)
			(layer "B.SilkS")
		)
		(fp_line
			(start -0.7874 -0.4064)
			(end -0.7874 0.4064)
			(stroke
				(width 0.1524)
				(type default)
			)
			(layer "B.SilkS")
		)
		(fp_line
			(start 0.7874 -0.4064)
			(end -0.7874 -0.4064)
			(stroke
				(width 0.1524)
				(type default)
			)
			(layer "B.SilkS")
		)
		(fp_line
			(start -0.67945 0.3048)
			(end -0.120396 0.3048)
			(stroke
				(width 0.1)
				(type default)
			)
			(layer "B.Fab")
		)
		(fp_line
			(start -0.120396 0.3048)
			(end -0.120396 0.2794)
			(stroke
				(width 0.1)
				(type default)
			)
			(layer "B.Fab")
		)
		(fp_line
			(start 0.12065 0.3048)
			(end 0.67945 0.3048)
			(stroke
				(width 0.1)
				(type default)
			)
			(layer "B.Fab")
		)
		(fp_line
			(start 0.67945 0.3048)
			(end 0.67945 -0.305054)
			(stroke
				(width 0.1)
				(type default)
			)
			(layer "B.Fab")
		)
		(fp_line
			(start -0.120396 0.2794)
			(end 0.12065 0.2794)
			(stroke
				(width 0.1)
				(type default)
			)
			(layer "B.Fab")
		)
		(fp_line
			(start 0.12065 0.2794)
			(end 0.12065 0.3048)
			(stroke
				(width 0.1)
				(type default)
			)
			(layer "B.Fab")
		)
		(fp_line
			(start -0.12065 -0.2794)
			(end -0.12065 -0.3048)
			(stroke
				(width 0.1)
				(type default)
			)
			(layer "B.Fab")
		)
		(fp_line
			(start 0.12065 -0.2794)
			(end -0.12065 -0.2794)
			(stroke
				(width 0.1)
				(type default)
			)
			(layer "B.Fab")
		)
		(fp_line
			(start -0.67945 -0.3048)
			(end -0.67945 0.3048)
			(stroke
				(width 0.1)
				(type default)
			)
			(layer "B.Fab")
		)
		(fp_line
			(start -0.12065 -0.3048)
			(end -0.67945 -0.3048)
			(stroke
				(width 0.1)
				(type default)
			)
			(layer "B.Fab")
		)
		(fp_line
			(start 0.12065 -0.305054)
			(end 0.12065 -0.2794)
			(stroke
				(width 0.1)
				(type default)
			)
			(layer "B.Fab")
		)
		(fp_line
			(start 0.67945 -0.305054)
			(end 0.12065 -0.305054)
			(stroke
				(width 0.1)
				(type default)
			)
			(layer "B.Fab")
		)
		(pad "1" smd circle
			(at 0.40005 0 90)
			(size 0 0)
			(layers "B.Cu" "B.Mask" "B.Paste")
			(net "P1V25_PEX3_VCC")
		)
		(pad "2" smd circle
			(at -0.40005 0 90)
			(size 0 0)
			(layers "B.Cu" "B.Mask" "B.Paste")
			(net "PWRGD_P1V25_PEX3")
		)
	)
	(footprint ""
		(layer "B.Cu")
		(at 170.524932 -286.399732 90)
		(property "Reference" "C3153"
			(at 0 0 90)
			(layer "B.SilkS")
			(hide yes)
			(effects
				(font
					(size 1.27 1.27)
				)
				(justify mirror)
			)
		)
		(property "Value" ""
			(at 0 0 90)
			(layer "B.Fab")
			(effects
				(font
					(size 1.27 1.27)
				)
				(justify mirror)
			)
		)
		(duplicate_pad_numbers_are_jumpers no)
		(fp_line
			(start 0.299974 -0.150114)
			(end -0.299974 -0.150114)
			(stroke
				(width 0.1)
				(type default)
			)
			(layer "B.Fab")
		)
		(fp_line
			(start -0.299974 -0.150114)
			(end -0.299974 0.150114)
			(stroke
				(width 0.1)
				(type default)
			)
			(layer "B.Fab")
		)
		(fp_line
			(start 0.299974 0.150114)
			(end 0.299974 -0.150114)
			(stroke
				(width 0.1)
				(type default)
			)
			(layer "B.Fab")
		)
		(fp_line
			(start -0.299974 0.150114)
			(end 0.299974 0.150114)
			(stroke
				(width 0.1)
				(type default)
			)
			(layer "B.Fab")
		)
		(pad "1" smd rect
			(at 0.2667 0 270)
			(size 0.3048 0.381)
			(layers "B.Cu" "B.Mask" "B.Paste")
			(net "P1V25_SERDES_VDDPLL_PEX1")
		)
		(pad "2" smd rect
			(at -0.2667 0 270)
			(size 0.3048 0.381)
			(layers "B.Cu" "B.Mask" "B.Paste")
			(net "GND")
		)
	)
	(footprint ""
		(layer "B.Cu")
		(at 287.574736 -293.99992 -90)
		(property "Reference" "C1646"
			(at 0 0 90)
			(layer "B.SilkS")
			(hide yes)
			(effects
				(font
					(size 1.27 1.27)
				)
				(justify mirror)
			)
		)
		(property "Value" ""
			(at 0 0 90)
			(layer "B.Fab")
			(effects
				(font
					(size 1.27 1.27)
				)
				(justify mirror)
			)
		)
		(duplicate_pad_numbers_are_jumpers no)
		(fp_line
			(start -0.299974 0.150114)
			(end 0.299974 0.150114)
			(stroke
				(width 0.1)
				(type default)
			)
			(layer "B.Fab")
		)
		(fp_line
			(start 0.299974 0.150114)
			(end 0.299974 -0.150114)
			(stroke
				(width 0.1)
				(type default)
			)
			(layer "B.Fab")
		)
		(fp_line
			(start -0.299974 -0.150114)
			(end -0.299974 0.150114)
			(stroke
				(width 0.1)
				(type default)
			)
			(layer "B.Fab")
		)
		(fp_line
			(start 0.299974 -0.150114)
			(end -0.299974 -0.150114)
			(stroke
				(width 0.1)
				(type default)
			)
			(layer "B.Fab")
		)
		(pad "1" smd rect
			(at 0.2667 0 90)
			(size 0.3048 0.381)
			(layers "B.Cu" "B.Mask" "B.Paste")
			(net "P0V8_PEX2")
		)
		(pad "2" smd rect
			(at -0.2667 0 90)
			(size 0.3048 0.381)
			(layers "B.Cu" "B.Mask" "B.Paste")
			(net "GND")
		)
	)
	(footprint ""
		(layer "B.Cu")
		(at 301.349918 -303.024794)
		(property "Reference" "C3342"
			(at 0 0 0)
			(layer "B.SilkS")
			(hide yes)
			(effects
				(font
					(size 1.27 1.27)
				)
				(justify mirror)
			)
		)
		(property "Value" ""
			(at 0 0 0)
			(layer "B.Fab")
			(effects
				(font
					(size 1.27 1.27)
				)
				(justify mirror)
			)
		)
		(duplicate_pad_numbers_are_jumpers no)
		(fp_line
			(start -0.299974 -0.150114)
			(end -0.299974 0.150114)
			(stroke
				(width 0.1)
				(type default)
			)
			(layer "B.Fab")
		)
		(fp_line
			(start -0.299974 0.150114)
			(end 0.299974 0.150114)
			(stroke
				(width 0.1)
				(type default)
			)
			(layer "B.Fab")
		)
		(fp_line
			(start 0.299974 -0.150114)
			(end -0.299974 -0.150114)
			(stroke
				(width 0.1)
				(type default)
			)
			(layer "B.Fab")
		)
		(fp_line
			(start 0.299974 0.150114)
			(end 0.299974 -0.150114)
			(stroke
				(width 0.1)
				(type default)
			)
			(layer "B.Fab")
		)
		(pad "1" smd rect
			(at 0.2667 0 180)
			(size 0.3048 0.381)
			(layers "B.Cu" "B.Mask" "B.Paste")
			(net "P1V8_PEX")
		)
		(pad "2" smd rect
			(at -0.2667 0 180)
			(size 0.3048 0.381)
			(layers "B.Cu" "B.Mask" "B.Paste")
			(net "GND")
		)
	)
	(footprint ""
		(layer "B.Cu")
		(at 350.65716 -316.868048)
		(property "Reference" "C4365"
			(at 0 0 0)
			(layer "B.SilkS")
			(hide yes)
			(effects
				(font
					(size 1.27 1.27)
				)
				(justify mirror)
			)
		)
		(property "Value" ""
			(at 0 0 0)
			(layer "B.Fab")
			(effects
				(font
					(size 1.27 1.27)
				)
				(justify mirror)
			)
		)
		(duplicate_pad_numbers_are_jumpers no)
		(fp_line
			(start -0.299974 -0.150114)
			(end -0.299974 0.150114)
			(stroke
				(width 0.1)
				(type default)
			)
			(layer "B.Fab")
		)
		(fp_line
			(start -0.299974 0.150114)
			(end 0.299974 0.150114)
			(stroke
				(width 0.1)
				(type default)
			)
			(layer "B.Fab")
		)
		(fp_line
			(start 0.299974 -0.150114)
			(end -0.299974 -0.150114)
			(stroke
				(width 0.1)
				(type default)
			)
			(layer "B.Fab")
		)
		(fp_line
			(start 0.299974 0.150114)
			(end 0.299974 -0.150114)
			(stroke
				(width 0.1)
				(type default)
			)
			(layer "B.Fab")
		)
		(pad "1" smd rect
			(at 0.2667 0 180)
			(size 0.3048 0.381)
			(layers "B.Cu" "B.Mask" "B.Paste")
			(net "P0V8_SERDES_VDDA_PEX3")
		)
		(pad "2" smd rect
			(at -0.2667 0 180)
			(size 0.3048 0.381)
			(layers "B.Cu" "B.Mask" "B.Paste")
			(net "GND")
		)
	)
	(footprint ""
		(layer "B.Cu")
		(at 61.549788 -290.199826 90)
		(property "Reference" "C1208"
			(at 0 0 90)
			(layer "B.SilkS")
			(hide yes)
			(effects
				(font
					(size 1.27 1.27)
				)
				(justify mirror)
			)
		)
		(property "Value" ""
			(at 0 0 90)
			(layer "B.Fab")
			(effects
				(font
					(size 1.27 1.27)
				)
				(justify mirror)
			)
		)
		(duplicate_pad_numbers_are_jumpers no)
		(fp_line
			(start 0.299974 -0.150114)
			(end -0.299974 -0.150114)
			(stroke
				(width 0.1)
				(type default)
			)
			(layer "B.Fab")
		)
		(fp_line
			(start -0.299974 -0.150114)
			(end -0.299974 0.150114)
			(stroke
				(width 0.1)
				(type default)
			)
			(layer "B.Fab")
		)
		(fp_line
			(start 0.299974 0.150114)
			(end 0.299974 -0.150114)
			(stroke
				(width 0.1)
				(type default)
			)
			(layer "B.Fab")
		)
		(fp_line
			(start -0.299974 0.150114)
			(end 0.299974 0.150114)
			(stroke
				(width 0.1)
				(type default)
			)
			(layer "B.Fab")
		)
		(pad "1" smd rect
			(at 0.2667 0 270)
			(size 0.3048 0.381)
			(layers "B.Cu" "B.Mask" "B.Paste")
			(net "P0V8_SERDES_VDDA_PEX0")
		)
		(pad "2" smd rect
			(at -0.2667 0 270)
			(size 0.3048 0.381)
			(layers "B.Cu" "B.Mask" "B.Paste")
			(net "GND")
		)
	)
	(footprint ""
		(layer "B.Cu")
		(at 279.974802 -290.941506 90)
		(property "Reference" "C3408"
			(at 0 0 90)
			(layer "B.SilkS")
			(hide yes)
			(effects
				(font
					(size 1.27 1.27)
				)
				(justify mirror)
			)
		)
		(property "Value" ""
			(at 0 0 90)
			(layer "B.Fab")
			(effects
				(font
					(size 1.27 1.27)
				)
				(justify mirror)
			)
		)
		(duplicate_pad_numbers_are_jumpers no)
		(fp_line
			(start 0.299974 -0.150114)
			(end -0.299974 -0.150114)
			(stroke
				(width 0.1)
				(type default)
			)
			(layer "B.Fab")
		)
		(fp_line
			(start -0.299974 -0.150114)
			(end -0.299974 0.150114)
			(stroke
				(width 0.1)
				(type default)
			)
			(layer "B.Fab")
		)
		(fp_line
			(start 0.299974 0.150114)
			(end 0.299974 -0.150114)
			(stroke
				(width 0.1)
				(type default)
			)
			(layer "B.Fab")
		)
		(fp_line
			(start -0.299974 0.150114)
			(end 0.299974 0.150114)
			(stroke
				(width 0.1)
				(type default)
			)
			(layer "B.Fab")
		)
		(pad "1" smd rect
			(at 0.2667 0 270)
			(size 0.3048 0.381)
			(layers "B.Cu" "B.Mask" "B.Paste")
			(net "PCEPLL7_VDDA18_PEX2")
		)
		(pad "2" smd rect
			(at -0.2667 0 270)
			(size 0.3048 0.381)
			(layers "B.Cu" "B.Mask" "B.Paste")
			(net "GND")
		)
	)
	(footprint ""
		(layer "B.Cu")
		(at 366.316768 -324.163944 -90)
		(property "Reference" "C4371"
			(at 0 0 90)
			(layer "B.SilkS")
			(hide yes)
			(effects
				(font
					(size 1.27 1.27)
				)
				(justify mirror)
			)
		)
		(property "Value" ""
			(at 0 0 90)
			(layer "B.Fab")
			(effects
				(font
					(size 1.27 1.27)
				)
				(justify mirror)
			)
		)
		(duplicate_pad_numbers_are_jumpers no)
		(fp_line
			(start -1.2954 0.5842)
			(end 1.2954 0.5842)
			(stroke
				(width 0.1524)
				(type default)
			)
			(layer "B.SilkS")
		)
		(fp_line
			(start 1.2954 0.5842)
			(end 1.2954 -0.5842)
			(stroke
				(width 0.1524)
				(type default)
			)
			(layer "B.SilkS")
		)
		(fp_line
			(start -1.2954 -0.5842)
			(end -1.2954 0.5842)
			(stroke
				(width 0.1524)
				(type default)
			)
			(layer "B.SilkS")
		)
		(fp_line
			(start 1.2954 -0.5842)
			(end -1.2954 -0.5842)
			(stroke
				(width 0.1524)
				(type default)
			)
			(layer "B.SilkS")
		)
		(fp_line
			(start -0.8636 0.4572)
			(end 0.8636 0.4572)
			(stroke
				(width 0.1)
				(type default)
			)
			(layer "B.Fab")
		)
		(fp_line
			(start 0.8636 0.4572)
			(end 0.8636 0.4064)
			(stroke
				(width 0.1)
				(type default)
			)
			(layer "B.Fab")
		)
		(fp_line
			(start -1.1938 0.4064)
			(end -0.8636 0.4064)
			(stroke
				(width 0.1)
				(type default)
			)
			(layer "B.Fab")
		)
		(fp_line
			(start -0.8636 0.4064)
			(end -0.8636 0.4572)
			(stroke
				(width 0.1)
				(type default)
			)
			(layer "B.Fab")
		)
		(fp_line
			(start 0.8636 0.4064)
			(end 1.1938 0.4064)
			(stroke
				(width 0.1)
				(type default)
			)
			(layer "B.Fab")
		)
		(fp_line
			(start 1.1938 0.4064)
			(end 1.1938 -0.4064)
			(stroke
				(width 0.1)
				(type default)
			)
			(layer "B.Fab")
		)
		(fp_line
			(start -1.1938 -0.4064)
			(end -1.1938 0.4064)
			(stroke
				(width 0.1)
				(type default)
			)
			(layer "B.Fab")
		)
		(fp_line
			(start -0.8636 -0.4064)
			(end -1.1938 -0.4064)
			(stroke
				(width 0.1)
				(type default)
			)
			(layer "B.Fab")
		)
		(fp_line
			(start 0.8636 -0.4064)
			(end 0.8636 -0.4572)
			(stroke
				(width 0.1)
				(type default)
			)
			(layer "B.Fab")
		)
		(fp_line
			(start 1.1938 -0.4064)
			(end 0.8636 -0.4064)
			(stroke
				(width 0.1)
				(type default)
			)
			(layer "B.Fab")
		)
		(fp_line
			(start -0.8636 -0.4572)
			(end -0.8636 -0.4064)
			(stroke
				(width 0.1)
				(type default)
			)
			(layer "B.Fab")
		)
		(fp_line
			(start 0.8636 -0.4572)
			(end -0.8636 -0.4572)
			(stroke
				(width 0.1)
				(type default)
			)
			(layer "B.Fab")
		)
		(pad "1" smd rect
			(at 0.7366 0 180)
			(size 0.7112 0.8128)
			(layers "B.Cu" "B.Mask" "B.Paste")
			(net "P0V8_SERDES_VDDA_PEX3_C5")
		)
		(pad "2" smd rect
			(at -0.7366 0 180)
			(size 0.7112 0.8128)
			(layers "B.Cu" "B.Mask" "B.Paste")
			(net "GND")
		)
	)
	(footprint ""
		(layer "B.Cu")
		(at 143.790162 -243.282978 90)
		(property "Reference" "R6571"
			(at 0 0 90)
			(layer "B.SilkS")
			(hide yes)
			(effects
				(font
					(size 1.27 1.27)
				)
				(justify mirror)
			)
		)
		(property "Value" ""
			(at 0 0 90)
			(layer "B.Fab")
			(effects
				(font
					(size 1.27 1.27)
				)
				(justify mirror)
			)
		)
		(duplicate_pad_numbers_are_jumpers no)
		(fp_line
			(start 0.7874 -0.4064)
			(end -0.7874 -0.4064)
			(stroke
				(width 0.1524)
				(type default)
			)
			(layer "B.SilkS")
		)
		(fp_line
			(start -0.7874 -0.4064)
			(end -0.7874 0.4064)
			(stroke
				(width 0.1524)
				(type default)
			)
			(layer "B.SilkS")
		)
		(fp_line
			(start 0.7874 0.4064)
			(end 0.7874 -0.4064)
			(stroke
				(width 0.1524)
				(type default)
			)
			(layer "B.SilkS")
		)
		(fp_line
			(start -0.7874 0.4064)
			(end 0.7874 0.4064)
			(stroke
				(width 0.1524)
				(type default)
			)
			(layer "B.SilkS")
		)
		(fp_line
			(start 0.67945 -0.305054)
			(end 0.12065 -0.305054)
			(stroke
				(width 0.1)
				(type default)
			)
			(layer "B.Fab")
		)
		(fp_line
			(start 0.12065 -0.305054)
			(end 0.12065 -0.2794)
			(stroke
				(width 0.1)
				(type default)
			)
			(layer "B.Fab")
		)
		(fp_line
			(start -0.12065 -0.3048)
			(end -0.67945 -0.3048)
			(stroke
				(width 0.1)
				(type default)
			)
			(layer "B.Fab")
		)
		(fp_line
			(start -0.67945 -0.3048)
			(end -0.67945 0.3048)
			(stroke
				(width 0.1)
				(type default)
			)
			(layer "B.Fab")
		)
		(fp_line
			(start 0.12065 -0.2794)
			(end -0.12065 -0.2794)
			(stroke
				(width 0.1)
				(type default)
			)
			(layer "B.Fab")
		)
		(fp_line
			(start -0.12065 -0.2794)
			(end -0.12065 -0.3048)
			(stroke
				(width 0.1)
				(type default)
			)
			(layer "B.Fab")
		)
		(fp_line
			(start 0.12065 0.2794)
			(end 0.12065 0.3048)
			(stroke
				(width 0.1)
				(type default)
			)
			(layer "B.Fab")
		)
		(fp_line
			(start -0.120396 0.2794)
			(end 0.12065 0.2794)
			(stroke
				(width 0.1)
				(type default)
			)
			(layer "B.Fab")
		)
		(fp_line
			(start 0.67945 0.3048)
			(end 0.67945 -0.305054)
			(stroke
				(width 0.1)
				(type default)
			)
			(layer "B.Fab")
		)
		(fp_line
			(start 0.12065 0.3048)
			(end 0.67945 0.3048)
			(stroke
				(width 0.1)
				(type default)
			)
			(layer "B.Fab")
		)
		(fp_line
			(start -0.120396 0.3048)
			(end -0.120396 0.2794)
			(stroke
				(width 0.1)
				(type default)
			)
			(layer "B.Fab")
		)
		(fp_line
			(start -0.67945 0.3048)
			(end -0.120396 0.3048)
			(stroke
				(width 0.1)
				(type default)
			)
			(layer "B.Fab")
		)
		(pad "1" smd circle
			(at 0.40005 0 270)
			(size 0 0)
			(layers "B.Cu" "B.Mask" "B.Paste")
			(net "P3V3_AUX")
		)
		(pad "2" smd circle
			(at -0.40005 0 270)
			(size 0 0)
			(layers "B.Cu" "B.Mask" "B.Paste")
			(net "PEX1_P1V8_PLL_EN")
		)
	)
	(footprint ""
		(layer "B.Cu")
		(at 237.609634 -348.475554 180)
		(property "Reference" "PR7144"
			(at 0 0 0)
			(layer "B.SilkS")
			(hide yes)
			(effects
				(font
					(size 1.27 1.27)
				)
				(justify mirror)
			)
		)
		(property "Value" ""
			(at 0 0 0)
			(layer "B.Fab")
			(effects
				(font
					(size 1.27 1.27)
				)
				(justify mirror)
			)
		)
		(duplicate_pad_numbers_are_jumpers no)
		(fp_line
			(start 0.7874 0.4064)
			(end 0.7874 -0.4064)
			(stroke
				(width 0.1524)
				(type default)
			)
			(layer "B.SilkS")
		)
		(fp_line
			(start 0.7874 -0.4064)
			(end -0.7874 -0.4064)
			(stroke
				(width 0.1524)
				(type default)
			)
			(layer "B.SilkS")
		)
		(fp_line
			(start -0.7874 0.4064)
			(end 0.7874 0.4064)
			(stroke
				(width 0.1524)
				(type default)
			)
			(layer "B.SilkS")
		)
		(fp_line
			(start -0.7874 -0.4064)
			(end -0.7874 0.4064)
			(stroke
				(width 0.1524)
				(type default)
			)
			(layer "B.SilkS")
		)
		(fp_line
			(start 0.67945 0.3048)
			(end 0.67945 -0.305054)
			(stroke
				(width 0.1)
				(type default)
			)
			(layer "B.Fab")
		)
		(fp_line
			(start 0.67945 -0.305054)
			(end 0.12065 -0.305054)
			(stroke
				(width 0.1)
				(type default)
			)
			(layer "B.Fab")
		)
		(fp_line
			(start 0.12065 0.3048)
			(end 0.67945 0.3048)
			(stroke
				(width 0.1)
				(type default)
			)
			(layer "B.Fab")
		)
		(fp_line
			(start 0.12065 0.2794)
			(end 0.12065 0.3048)
			(stroke
				(width 0.1)
				(type default)
			)
			(layer "B.Fab")
		)
		(fp_line
			(start 0.12065 -0.2794)
			(end -0.12065 -0.2794)
			(stroke
				(width 0.1)
				(type default)
			)
			(layer "B.Fab")
		)
		(fp_line
			(start 0.12065 -0.305054)
			(end 0.12065 -0.2794)
			(stroke
				(width 0.1)
				(type default)
			)
			(layer "B.Fab")
		)
		(fp_line
			(start -0.120396 0.3048)
			(end -0.120396 0.2794)
			(stroke
				(width 0.1)
				(type default)
			)
			(layer "B.Fab")
		)
		(fp_line
			(start -0.120396 0.2794)
			(end 0.12065 0.2794)
			(stroke
				(width 0.1)
				(type default)
			)
			(layer "B.Fab")
		)
		(fp_line
			(start -0.12065 -0.2794)
			(end -0.12065 -0.3048)
			(stroke
				(width 0.1)
				(type default)
			)
			(layer "B.Fab")
		)
		(fp_line
			(start -0.12065 -0.3048)
			(end -0.67945 -0.3048)
			(stroke
				(width 0.1)
				(type default)
			)
			(layer "B.Fab")
		)
		(fp_line
			(start -0.67945 0.3048)
			(end -0.120396 0.3048)
			(stroke
				(width 0.1)
				(type default)
			)
			(layer "B.Fab")
		)
		(fp_line
			(start -0.67945 -0.3048)
			(end -0.67945 0.3048)
			(stroke
				(width 0.1)
				(type default)
			)
			(layer "B.Fab")
		)
		(pad "1" smd circle
			(at 0.40005 0)
			(size 0 0)
			(layers "B.Cu" "B.Mask" "B.Paste")
			(net "P12V_HSC_ADC_P")
		)
		(pad "2" smd circle
			(at -0.40005 0)
			(size 0 0)
			(layers "B.Cu" "B.Mask" "B.Paste")
			(net "P12V_HSC_SENSE1_P")
		)
	)
	(footprint ""
		(layer "B.Cu")
		(at 404.625048 -293.99992 90)
		(property "Reference" "C1883"
			(at 0 0 90)
			(layer "B.SilkS")
			(hide yes)
			(effects
				(font
					(size 1.27 1.27)
				)
				(justify mirror)
			)
		)
		(property "Value" ""
			(at 0 0 90)
			(layer "B.Fab")
			(effects
				(font
					(size 1.27 1.27)
				)
				(justify mirror)
			)
		)
		(duplicate_pad_numbers_are_jumpers no)
		(fp_line
			(start 0.299974 -0.150114)
			(end -0.299974 -0.150114)
			(stroke
				(width 0.1)
				(type default)
			)
			(layer "B.Fab")
		)
		(fp_line
			(start -0.299974 -0.150114)
			(end -0.299974 0.150114)
			(stroke
				(width 0.1)
				(type default)
			)
			(layer "B.Fab")
		)
		(fp_line
			(start 0.299974 0.150114)
			(end 0.299974 -0.150114)
			(stroke
				(width 0.1)
				(type default)
			)
			(layer "B.Fab")
		)
		(fp_line
			(start -0.299974 0.150114)
			(end 0.299974 0.150114)
			(stroke
				(width 0.1)
				(type default)
			)
			(layer "B.Fab")
		)
		(pad "1" smd rect
			(at 0.2667 0 270)
			(size 0.3048 0.381)
			(layers "B.Cu" "B.Mask" "B.Paste")
			(net "P0V8_PEX3")
		)
		(pad "2" smd rect
			(at -0.2667 0 270)
			(size 0.3048 0.381)
			(layers "B.Cu" "B.Mask" "B.Paste")
			(net "GND")
		)
	)
	(footprint ""
		(layer "B.Cu")
		(at 132.8928 -282.173172 90)
		(property "Reference" "R6765"
			(at 0 0 90)
			(layer "B.SilkS")
			(hide yes)
			(effects
				(font
					(size 1.27 1.27)
				)
				(justify mirror)
			)
		)
		(property "Value" ""
			(at 0 0 90)
			(layer "B.Fab")
			(effects
				(font
					(size 1.27 1.27)
				)
				(justify mirror)
			)
		)
		(duplicate_pad_numbers_are_jumpers no)
		(fp_line
			(start 0.7874 -0.4064)
			(end -0.7874 -0.4064)
			(stroke
				(width 0.1524)
				(type default)
			)
			(layer "B.SilkS")
		)
		(fp_line
			(start -0.7874 -0.4064)
			(end -0.7874 0.4064)
			(stroke
				(width 0.1524)
				(type default)
			)
			(layer "B.SilkS")
		)
		(fp_line
			(start 0.7874 0.4064)
			(end 0.7874 -0.4064)
			(stroke
				(width 0.1524)
				(type default)
			)
			(layer "B.SilkS")
		)
		(fp_line
			(start -0.7874 0.4064)
			(end 0.7874 0.4064)
			(stroke
				(width 0.1524)
				(type default)
			)
			(layer "B.SilkS")
		)
		(fp_line
			(start 0.67945 -0.305054)
			(end 0.12065 -0.305054)
			(stroke
				(width 0.1)
				(type default)
			)
			(layer "B.Fab")
		)
		(fp_line
			(start 0.12065 -0.305054)
			(end 0.12065 -0.2794)
			(stroke
				(width 0.1)
				(type default)
			)
			(layer "B.Fab")
		)
		(fp_line
			(start -0.12065 -0.3048)
			(end -0.67945 -0.3048)
			(stroke
				(width 0.1)
				(type default)
			)
			(layer "B.Fab")
		)
		(fp_line
			(start -0.67945 -0.3048)
			(end -0.67945 0.3048)
			(stroke
				(width 0.1)
				(type default)
			)
			(layer "B.Fab")
		)
		(fp_line
			(start 0.12065 -0.2794)
			(end -0.12065 -0.2794)
			(stroke
				(width 0.1)
				(type default)
			)
			(layer "B.Fab")
		)
		(fp_line
			(start -0.12065 -0.2794)
			(end -0.12065 -0.3048)
			(stroke
				(width 0.1)
				(type default)
			)
			(layer "B.Fab")
		)
		(fp_line
			(start 0.12065 0.2794)
			(end 0.12065 0.3048)
			(stroke
				(width 0.1)
				(type default)
			)
			(layer "B.Fab")
		)
		(fp_line
			(start -0.120396 0.2794)
			(end 0.12065 0.2794)
			(stroke
				(width 0.1)
				(type default)
			)
			(layer "B.Fab")
		)
		(fp_line
			(start 0.67945 0.3048)
			(end 0.67945 -0.305054)
			(stroke
				(width 0.1)
				(type default)
			)
			(layer "B.Fab")
		)
		(fp_line
			(start 0.12065 0.3048)
			(end 0.67945 0.3048)
			(stroke
				(width 0.1)
				(type default)
			)
			(layer "B.Fab")
		)
		(fp_line
			(start -0.120396 0.3048)
			(end -0.120396 0.2794)
			(stroke
				(width 0.1)
				(type default)
			)
			(layer "B.Fab")
		)
		(fp_line
			(start -0.67945 0.3048)
			(end -0.120396 0.3048)
			(stroke
				(width 0.1)
				(type default)
			)
			(layer "B.Fab")
		)
		(pad "1" smd circle
			(at 0.40005 0 270)
			(size 0 0)
			(layers "B.Cu" "B.Mask" "B.Paste")
			(net "P0V8_PEX1_VCC2")
		)
		(pad "2" smd circle
			(at -0.40005 0 270)
			(size 0 0)
			(layers "B.Cu" "B.Mask" "B.Paste")
			(net "P0V8_PEX0_EN4")
		)
	)
	(footprint ""
		(layer "B.Cu")
		(at 356.524306 -244.139974)
		(property "Reference" "R5893"
			(at 0 0 0)
			(layer "B.SilkS")
			(hide yes)
			(effects
				(font
					(size 1.27 1.27)
				)
				(justify mirror)
			)
		)
		(property "Value" ""
			(at 0 0 0)
			(layer "B.Fab")
			(effects
				(font
					(size 1.27 1.27)
				)
				(justify mirror)
			)
		)
		(duplicate_pad_numbers_are_jumpers no)
		(fp_line
			(start -0.7874 -0.4064)
			(end -0.7874 0.4064)
			(stroke
				(width 0.1524)
				(type default)
			)
			(layer "B.SilkS")
		)
		(fp_line
			(start -0.7874 0.4064)
			(end 0.7874 0.4064)
			(stroke
				(width 0.1524)
				(type default)
			)
			(layer "B.SilkS")
		)
		(fp_line
			(start 0.7874 -0.4064)
			(end -0.7874 -0.4064)
			(stroke
				(width 0.1524)
				(type default)
			)
			(layer "B.SilkS")
		)
		(fp_line
			(start 0.7874 0.4064)
			(end 0.7874 -0.4064)
			(stroke
				(width 0.1524)
				(type default)
			)
			(layer "B.SilkS")
		)
		(fp_line
			(start -0.67945 -0.3048)
			(end -0.67945 0.3048)
			(stroke
				(width 0.1)
				(type default)
			)
			(layer "B.Fab")
		)
		(fp_line
			(start -0.67945 0.3048)
			(end -0.120396 0.3048)
			(stroke
				(width 0.1)
				(type default)
			)
			(layer "B.Fab")
		)
		(fp_line
			(start -0.12065 -0.3048)
			(end -0.67945 -0.3048)
			(stroke
				(width 0.1)
				(type default)
			)
			(layer "B.Fab")
		)
		(fp_line
			(start -0.12065 -0.2794)
			(end -0.12065 -0.3048)
			(stroke
				(width 0.1)
				(type default)
			)
			(layer "B.Fab")
		)
		(fp_line
			(start -0.120396 0.2794)
			(end 0.12065 0.2794)
			(stroke
				(width 0.1)
				(type default)
			)
			(layer "B.Fab")
		)
		(fp_line
			(start -0.120396 0.3048)
			(end -0.120396 0.2794)
			(stroke
				(width 0.1)
				(type default)
			)
			(layer "B.Fab")
		)
		(fp_line
			(start 0.12065 -0.305054)
			(end 0.12065 -0.2794)
			(stroke
				(width 0.1)
				(type default)
			)
			(layer "B.Fab")
		)
		(fp_line
			(start 0.12065 -0.2794)
			(end -0.12065 -0.2794)
			(stroke
				(width 0.1)
				(type default)
			)
			(layer "B.Fab")
		)
		(fp_line
			(start 0.12065 0.2794)
			(end 0.12065 0.3048)
			(stroke
				(width 0.1)
				(type default)
			)
			(layer "B.Fab")
		)
		(fp_line
			(start 0.12065 0.3048)
			(end 0.67945 0.3048)
			(stroke
				(width 0.1)
				(type default)
			)
			(layer "B.Fab")
		)
		(fp_line
			(start 0.67945 -0.305054)
			(end 0.12065 -0.305054)
			(stroke
				(width 0.1)
				(type default)
			)
			(layer "B.Fab")
		)
		(fp_line
			(start 0.67945 0.3048)
			(end 0.67945 -0.305054)
			(stroke
				(width 0.1)
				(type default)
			)
			(layer "B.Fab")
		)
		(pad "1" smd circle
			(at 0.40005 0 180)
			(size 0 0)
			(layers "B.Cu" "B.Mask" "B.Paste")
			(net "P3V3_AUX")
		)
		(pad "2" smd circle
			(at -0.40005 0 180)
			(size 0 0)
			(layers "B.Cu" "B.Mask" "B.Paste")
			(net "JP_FPGA_DEBUG_N")
		)
	)
	(footprint ""
		(layer "B.Cu")
		(at 357.9876 -361.6198 180)
		(property "Reference" "R6315"
			(at 0 0 0)
			(layer "B.SilkS")
			(hide yes)
			(effects
				(font
					(size 1.27 1.27)
				)
				(justify mirror)
			)
		)
		(property "Value" ""
			(at 0 0 0)
			(layer "B.Fab")
			(effects
				(font
					(size 1.27 1.27)
				)
				(justify mirror)
			)
		)
		(duplicate_pad_numbers_are_jumpers no)
		(fp_line
			(start 0.7874 0.4064)
			(end 0.7874 -0.4064)
			(stroke
				(width 0.1524)
				(type default)
			)
			(layer "B.SilkS")
		)
		(fp_line
			(start 0.7874 -0.4064)
			(end -0.7874 -0.4064)
			(stroke
				(width 0.1524)
				(type default)
			)
			(layer "B.SilkS")
		)
		(fp_line
			(start -0.7874 0.4064)
			(end 0.7874 0.4064)
			(stroke
				(width 0.1524)
				(type default)
			)
			(layer "B.SilkS")
		)
		(fp_line
			(start -0.7874 -0.4064)
			(end -0.7874 0.4064)
			(stroke
				(width 0.1524)
				(type default)
			)
			(layer "B.SilkS")
		)
		(fp_line
			(start 0.67945 0.3048)
			(end 0.67945 -0.305054)
			(stroke
				(width 0.1)
				(type default)
			)
			(layer "B.Fab")
		)
		(fp_line
			(start 0.67945 -0.305054)
			(end 0.12065 -0.305054)
			(stroke
				(width 0.1)
				(type default)
			)
			(layer "B.Fab")
		)
		(fp_line
			(start 0.12065 0.3048)
			(end 0.67945 0.3048)
			(stroke
				(width 0.1)
				(type default)
			)
			(layer "B.Fab")
		)
		(fp_line
			(start 0.12065 0.2794)
			(end 0.12065 0.3048)
			(stroke
				(width 0.1)
				(type default)
			)
			(layer "B.Fab")
		)
		(fp_line
			(start 0.12065 -0.2794)
			(end -0.12065 -0.2794)
			(stroke
				(width 0.1)
				(type default)
			)
			(layer "B.Fab")
		)
		(fp_line
			(start 0.12065 -0.305054)
			(end 0.12065 -0.2794)
			(stroke
				(width 0.1)
				(type default)
			)
			(layer "B.Fab")
		)
		(fp_line
			(start -0.120396 0.3048)
			(end -0.120396 0.2794)
			(stroke
				(width 0.1)
				(type default)
			)
			(layer "B.Fab")
		)
		(fp_line
			(start -0.120396 0.2794)
			(end 0.12065 0.2794)
			(stroke
				(width 0.1)
				(type default)
			)
			(layer "B.Fab")
		)
		(fp_line
			(start -0.12065 -0.2794)
			(end -0.12065 -0.3048)
			(stroke
				(width 0.1)
				(type default)
			)
			(layer "B.Fab")
		)
		(fp_line
			(start -0.12065 -0.3048)
			(end -0.67945 -0.3048)
			(stroke
				(width 0.1)
				(type default)
			)
			(layer "B.Fab")
		)
		(fp_line
			(start -0.67945 0.3048)
			(end -0.120396 0.3048)
			(stroke
				(width 0.1)
				(type default)
			)
			(layer "B.Fab")
		)
		(fp_line
			(start -0.67945 -0.3048)
			(end -0.67945 0.3048)
			(stroke
				(width 0.1)
				(type default)
			)
			(layer "B.Fab")
		)
		(pad "1" smd circle
			(at 0.40005 0)
			(size 0 0)
			(layers "B.Cu" "B.Mask" "B.Paste")
			(net "PWRGD_P12V_AUX_R")
		)
		(pad "2" smd circle
			(at -0.40005 0)
			(size 0 0)
			(layers "B.Cu" "B.Mask" "B.Paste")
			(net "SWB_HSC_PWRGD")
		)
	)
	(footprint ""
		(layer "B.Cu")
		(at 341.460328 -308.613556 90)
		(property "Reference" "C4317"
			(at 0 0 90)
			(layer "B.SilkS")
			(hide yes)
			(effects
				(font
					(size 1.27 1.27)
				)
				(justify mirror)
			)
		)
		(property "Value" ""
			(at 0 0 90)
			(layer "B.Fab")
			(effects
				(font
					(size 1.27 1.27)
				)
				(justify mirror)
			)
		)
		(duplicate_pad_numbers_are_jumpers no)
		(fp_line
			(start 1.2954 -0.5842)
			(end -1.2954 -0.5842)
			(stroke
				(width 0.1524)
				(type default)
			)
			(layer "B.SilkS")
		)
		(fp_line
			(start -1.2954 -0.5842)
			(end -1.2954 0.5842)
			(stroke
				(width 0.1524)
				(type default)
			)
			(layer "B.SilkS")
		)
		(fp_line
			(start 1.2954 0.5842)
			(end 1.2954 -0.5842)
			(stroke
				(width 0.1524)
				(type default)
			)
			(layer "B.SilkS")
		)
		(fp_line
			(start -1.2954 0.5842)
			(end 1.2954 0.5842)
			(stroke
				(width 0.1524)
				(type default)
			)
			(layer "B.SilkS")
		)
		(fp_line
			(start 0.8636 -0.4572)
			(end -0.8636 -0.4572)
			(stroke
				(width 0.1)
				(type default)
			)
			(layer "B.Fab")
		)
		(fp_line
			(start -0.8636 -0.4572)
			(end -0.8636 -0.4064)
			(stroke
				(width 0.1)
				(type default)
			)
			(layer "B.Fab")
		)
		(fp_line
			(start 1.1938 -0.4064)
			(end 0.8636 -0.4064)
			(stroke
				(width 0.1)
				(type default)
			)
			(layer "B.Fab")
		)
		(fp_line
			(start 0.8636 -0.4064)
			(end 0.8636 -0.4572)
			(stroke
				(width 0.1)
				(type default)
			)
			(layer "B.Fab")
		)
		(fp_line
			(start -0.8636 -0.4064)
			(end -1.1938 -0.4064)
			(stroke
				(width 0.1)
				(type default)
			)
			(layer "B.Fab")
		)
		(fp_line
			(start -1.1938 -0.4064)
			(end -1.1938 0.4064)
			(stroke
				(width 0.1)
				(type default)
			)
			(layer "B.Fab")
		)
		(fp_line
			(start 1.1938 0.4064)
			(end 1.1938 -0.4064)
			(stroke
				(width 0.1)
				(type default)
			)
			(layer "B.Fab")
		)
		(fp_line
			(start 0.8636 0.4064)
			(end 1.1938 0.4064)
			(stroke
				(width 0.1)
				(type default)
			)
			(layer "B.Fab")
		)
		(fp_line
			(start -0.8636 0.4064)
			(end -0.8636 0.4572)
			(stroke
				(width 0.1)
				(type default)
			)
			(layer "B.Fab")
		)
		(fp_line
			(start -1.1938 0.4064)
			(end -0.8636 0.4064)
			(stroke
				(width 0.1)
				(type default)
			)
			(layer "B.Fab")
		)
		(fp_line
			(start 0.8636 0.4572)
			(end 0.8636 0.4064)
			(stroke
				(width 0.1)
				(type default)
			)
			(layer "B.Fab")
		)
		(fp_line
			(start -0.8636 0.4572)
			(end 0.8636 0.4572)
			(stroke
				(width 0.1)
				(type default)
			)
			(layer "B.Fab")
		)
		(pad "1" smd rect
			(at 0.7366 0)
			(size 0.7112 0.8128)
			(layers "B.Cu" "B.Mask" "B.Paste")
			(net "P0V8_PEX2")
		)
		(pad "2" smd rect
			(at -0.7366 0)
			(size 0.7112 0.8128)
			(layers "B.Cu" "B.Mask" "B.Paste")
			(net "GND")
		)
	)
	(footprint ""
		(layer "B.Cu")
		(at 397.97482 -293.99992 -90)
		(property "Reference" "C1879"
			(at 0 0 90)
			(layer "B.SilkS")
			(hide yes)
			(effects
				(font
					(size 1.27 1.27)
				)
				(justify mirror)
			)
		)
		(property "Value" ""
			(at 0 0 90)
			(layer "B.Fab")
			(effects
				(font
					(size 1.27 1.27)
				)
				(justify mirror)
			)
		)
		(duplicate_pad_numbers_are_jumpers no)
		(fp_line
			(start -0.299974 0.150114)
			(end 0.299974 0.150114)
			(stroke
				(width 0.1)
				(type default)
			)
			(layer "B.Fab")
		)
		(fp_line
			(start 0.299974 0.150114)
			(end 0.299974 -0.150114)
			(stroke
				(width 0.1)
				(type default)
			)
			(layer "B.Fab")
		)
		(fp_line
			(start -0.299974 -0.150114)
			(end -0.299974 0.150114)
			(stroke
				(width 0.1)
				(type default)
			)
			(layer "B.Fab")
		)
		(fp_line
			(start 0.299974 -0.150114)
			(end -0.299974 -0.150114)
			(stroke
				(width 0.1)
				(type default)
			)
			(layer "B.Fab")
		)
		(pad "1" smd rect
			(at 0.2667 0 90)
			(size 0.3048 0.381)
			(layers "B.Cu" "B.Mask" "B.Paste")
			(net "P0V8_PEX3")
		)
		(pad "2" smd rect
			(at -0.2667 0 90)
			(size 0.3048 0.381)
			(layers "B.Cu" "B.Mask" "B.Paste")
			(net "GND")
		)
	)
	(footprint ""
		(layer "B.Cu")
		(at 334.227932 -275.813774)
		(property "Reference" "PC6618"
			(at 0 0 0)
			(layer "B.SilkS")
			(hide yes)
			(effects
				(font
					(size 1.27 1.27)
				)
				(justify mirror)
			)
		)
		(property "Value" ""
			(at 0 0 0)
			(layer "B.Fab")
			(effects
				(font
					(size 1.27 1.27)
				)
				(justify mirror)
			)
		)
		(duplicate_pad_numbers_are_jumpers no)
		(fp_line
			(start -1.524 -0.762)
			(end -1.524 0.762)
			(stroke
				(width 0.1524)
				(type default)
			)
			(layer "B.SilkS")
		)
		(fp_line
			(start -1.524 0.762)
			(end 1.524 0.762)
			(stroke
				(width 0.1524)
				(type default)
			)
			(layer "B.SilkS")
		)
		(fp_line
			(start 1.524 -0.762)
			(end -1.524 -0.762)
			(stroke
				(width 0.1524)
				(type default)
			)
			(layer "B.SilkS")
		)
		(fp_line
			(start 1.524 0.762)
			(end 1.524 -0.762)
			(stroke
				(width 0.1524)
				(type default)
			)
			(layer "B.SilkS")
		)
		(fp_line
			(start -1.1049 -0.724916)
			(end 1.1049 -0.724916)
			(stroke
				(width 0.1)
				(type default)
			)
			(layer "B.Fab")
		)
		(fp_line
			(start -1.1049 0.724916)
			(end -1.1049 -0.724916)
			(stroke
				(width 0.1)
				(type default)
			)
			(layer "B.Fab")
		)
		(fp_line
			(start 1.1049 -0.724916)
			(end 1.1049 0.724916)
			(stroke
				(width 0.1)
				(type default)
			)
			(layer "B.Fab")
		)
		(fp_line
			(start 1.1049 0.724916)
			(end -1.1049 0.724916)
			(stroke
				(width 0.1)
				(type default)
			)
			(layer "B.Fab")
		)
		(pad "1" smd rect
			(at 0.889 0)
			(size 1.016 1.27)
			(layers "B.Cu" "B.Mask" "B.Paste")
			(net "SW_P12V_P0V8_PEX2_FLT")
		)
		(pad "2" smd rect
			(at -0.889 0)
			(size 1.016 1.27)
			(layers "B.Cu" "B.Mask" "B.Paste")
			(net "GND")
		)
	)
	(footprint ""
		(layer "B.Cu")
		(at 57.749948 -301.599854 -90)
		(property "Reference" "C1231"
			(at 0 0 90)
			(layer "B.SilkS")
			(hide yes)
			(effects
				(font
					(size 1.27 1.27)
				)
				(justify mirror)
			)
		)
		(property "Value" ""
			(at 0 0 90)
			(layer "B.Fab")
			(effects
				(font
					(size 1.27 1.27)
				)
				(justify mirror)
			)
		)
		(duplicate_pad_numbers_are_jumpers no)
		(fp_line
			(start -0.299974 0.150114)
			(end 0.299974 0.150114)
			(stroke
				(width 0.1)
				(type default)
			)
			(layer "B.Fab")
		)
		(fp_line
			(start 0.299974 0.150114)
			(end 0.299974 -0.150114)
			(stroke
				(width 0.1)
				(type default)
			)
			(layer "B.Fab")
		)
		(fp_line
			(start -0.299974 -0.150114)
			(end -0.299974 0.150114)
			(stroke
				(width 0.1)
				(type default)
			)
			(layer "B.Fab")
		)
		(fp_line
			(start 0.299974 -0.150114)
			(end -0.299974 -0.150114)
			(stroke
				(width 0.1)
				(type default)
			)
			(layer "B.Fab")
		)
		(pad "1" smd rect
			(at 0.2667 0 90)
			(size 0.3048 0.381)
			(layers "B.Cu" "B.Mask" "B.Paste")
			(net "P0V8_SERDES_VDDA_PEX0")
		)
		(pad "2" smd rect
			(at -0.2667 0 90)
			(size 0.3048 0.381)
			(layers "B.Cu" "B.Mask" "B.Paste")
			(net "GND")
		)
	)
	(footprint ""
		(layer "B.Cu")
		(at 122.653552 -308.580028 90)
		(property "Reference" "C1415"
			(at 0 0 90)
			(layer "B.SilkS")
			(hide yes)
			(effects
				(font
					(size 1.27 1.27)
				)
				(justify mirror)
			)
		)
		(property "Value" ""
			(at 0 0 90)
			(layer "B.Fab")
			(effects
				(font
					(size 1.27 1.27)
				)
				(justify mirror)
			)
		)
		(duplicate_pad_numbers_are_jumpers no)
		(fp_line
			(start 1.2954 -0.5842)
			(end -1.2954 -0.5842)
			(stroke
				(width 0.1524)
				(type default)
			)
			(layer "B.SilkS")
		)
		(fp_line
			(start -1.2954 -0.5842)
			(end -1.2954 0.5842)
			(stroke
				(width 0.1524)
				(type default)
			)
			(layer "B.SilkS")
		)
		(fp_line
			(start 1.2954 0.5842)
			(end 1.2954 -0.5842)
			(stroke
				(width 0.1524)
				(type default)
			)
			(layer "B.SilkS")
		)
		(fp_line
			(start -1.2954 0.5842)
			(end 1.2954 0.5842)
			(stroke
				(width 0.1524)
				(type default)
			)
			(layer "B.SilkS")
		)
		(fp_line
			(start 0.8636 -0.4572)
			(end -0.8636 -0.4572)
			(stroke
				(width 0.1)
				(type default)
			)
			(layer "B.Fab")
		)
		(fp_line
			(start -0.8636 -0.4572)
			(end -0.8636 -0.4064)
			(stroke
				(width 0.1)
				(type default)
			)
			(layer "B.Fab")
		)
		(fp_line
			(start 1.1938 -0.4064)
			(end 0.8636 -0.4064)
			(stroke
				(width 0.1)
				(type default)
			)
			(layer "B.Fab")
		)
		(fp_line
			(start 0.8636 -0.4064)
			(end 0.8636 -0.4572)
			(stroke
				(width 0.1)
				(type default)
			)
			(layer "B.Fab")
		)
		(fp_line
			(start -0.8636 -0.4064)
			(end -1.1938 -0.4064)
			(stroke
				(width 0.1)
				(type default)
			)
			(layer "B.Fab")
		)
		(fp_line
			(start -1.1938 -0.4064)
			(end -1.1938 0.4064)
			(stroke
				(width 0.1)
				(type default)
			)
			(layer "B.Fab")
		)
		(fp_line
			(start 1.1938 0.4064)
			(end 1.1938 -0.4064)
			(stroke
				(width 0.1)
				(type default)
			)
			(layer "B.Fab")
		)
		(fp_line
			(start 0.8636 0.4064)
			(end 1.1938 0.4064)
			(stroke
				(width 0.1)
				(type default)
			)
			(layer "B.Fab")
		)
		(fp_line
			(start -0.8636 0.4064)
			(end -0.8636 0.4572)
			(stroke
				(width 0.1)
				(type default)
			)
			(layer "B.Fab")
		)
		(fp_line
			(start -1.1938 0.4064)
			(end -0.8636 0.4064)
			(stroke
				(width 0.1)
				(type default)
			)
			(layer "B.Fab")
		)
		(fp_line
			(start 0.8636 0.4572)
			(end 0.8636 0.4064)
			(stroke
				(width 0.1)
				(type default)
			)
			(layer "B.Fab")
		)
		(fp_line
			(start -0.8636 0.4572)
			(end 0.8636 0.4572)
			(stroke
				(width 0.1)
				(type default)
			)
			(layer "B.Fab")
		)
		(pad "1" smd rect
			(at 0.7366 0)
			(size 0.7112 0.8128)
			(layers "B.Cu" "B.Mask" "B.Paste")
			(net "P0V8_SERDES_VDDA_PEX1")
		)
		(pad "2" smd rect
			(at -0.7366 0)
			(size 0.7112 0.8128)
			(layers "B.Cu" "B.Mask" "B.Paste")
			(net "GND")
		)
	)
	(footprint ""
		(layer "B.Cu")
		(at 77.541882 -101.069648 180)
		(property "Reference" "R76"
			(at 0 0 0)
			(layer "B.SilkS")
			(hide yes)
			(effects
				(font
					(size 1.27 1.27)
				)
				(justify mirror)
			)
		)
		(property "Value" ""
			(at 0 0 0)
			(layer "B.Fab")
			(effects
				(font
					(size 1.27 1.27)
				)
				(justify mirror)
			)
		)
		(duplicate_pad_numbers_are_jumpers no)
		(fp_line
			(start 0.7874 0.4064)
			(end 0.7874 -0.4064)
			(stroke
				(width 0.1524)
				(type default)
			)
			(layer "B.SilkS")
		)
		(fp_line
			(start 0.7874 -0.4064)
			(end -0.7874 -0.4064)
			(stroke
				(width 0.1524)
				(type default)
			)
			(layer "B.SilkS")
		)
		(fp_line
			(start -0.7874 0.4064)
			(end 0.7874 0.4064)
			(stroke
				(width 0.1524)
				(type default)
			)
			(layer "B.SilkS")
		)
		(fp_line
			(start -0.7874 -0.4064)
			(end -0.7874 0.4064)
			(stroke
				(width 0.1524)
				(type default)
			)
			(layer "B.SilkS")
		)
		(fp_line
			(start 0.67945 0.3048)
			(end 0.67945 -0.305054)
			(stroke
				(width 0.1)
				(type default)
			)
			(layer "B.Fab")
		)
		(fp_line
			(start 0.67945 -0.305054)
			(end 0.12065 -0.305054)
			(stroke
				(width 0.1)
				(type default)
			)
			(layer "B.Fab")
		)
		(fp_line
			(start 0.12065 0.3048)
			(end 0.67945 0.3048)
			(stroke
				(width 0.1)
				(type default)
			)
			(layer "B.Fab")
		)
		(fp_line
			(start 0.12065 0.2794)
			(end 0.12065 0.3048)
			(stroke
				(width 0.1)
				(type default)
			)
			(layer "B.Fab")
		)
		(fp_line
			(start 0.12065 -0.2794)
			(end -0.12065 -0.2794)
			(stroke
				(width 0.1)
				(type default)
			)
			(layer "B.Fab")
		)
		(fp_line
			(start 0.12065 -0.305054)
			(end 0.12065 -0.2794)
			(stroke
				(width 0.1)
				(type default)
			)
			(layer "B.Fab")
		)
		(fp_line
			(start -0.120396 0.3048)
			(end -0.120396 0.2794)
			(stroke
				(width 0.1)
				(type default)
			)
			(layer "B.Fab")
		)
		(fp_line
			(start -0.120396 0.2794)
			(end 0.12065 0.2794)
			(stroke
				(width 0.1)
				(type default)
			)
			(layer "B.Fab")
		)
		(fp_line
			(start -0.12065 -0.2794)
			(end -0.12065 -0.3048)
			(stroke
				(width 0.1)
				(type default)
			)
			(layer "B.Fab")
		)
		(fp_line
			(start -0.12065 -0.3048)
			(end -0.67945 -0.3048)
			(stroke
				(width 0.1)
				(type default)
			)
			(layer "B.Fab")
		)
		(fp_line
			(start -0.67945 0.3048)
			(end -0.120396 0.3048)
			(stroke
				(width 0.1)
				(type default)
			)
			(layer "B.Fab")
		)
		(fp_line
			(start -0.67945 -0.3048)
			(end -0.67945 0.3048)
			(stroke
				(width 0.1)
				(type default)
			)
			(layer "B.Fab")
		)
		(pad "1" smd circle
			(at 0.40005 0)
			(size 0 0)
			(layers "B.Cu" "B.Mask" "B.Paste")
			(net "NIC1_SLOT_ID0")
		)
		(pad "2" smd circle
			(at -0.40005 0)
			(size 0 0)
			(layers "B.Cu" "B.Mask" "B.Paste")
			(net "P3V3_NIC1")
		)
	)
	(footprint ""
		(layer "B.Cu")
		(at 418.399976 -288.774886 180)
		(property "Reference" "C3526"
			(at 0 0 0)
			(layer "B.SilkS")
			(hide yes)
			(effects
				(font
					(size 1.27 1.27)
				)
				(justify mirror)
			)
		)
		(property "Value" ""
			(at 0 0 0)
			(layer "B.Fab")
			(effects
				(font
					(size 1.27 1.27)
				)
				(justify mirror)
			)
		)
		(duplicate_pad_numbers_are_jumpers no)
		(fp_line
			(start 0.299974 0.150114)
			(end 0.299974 -0.150114)
			(stroke
				(width 0.1)
				(type default)
			)
			(layer "B.Fab")
		)
		(fp_line
			(start 0.299974 -0.150114)
			(end -0.299974 -0.150114)
			(stroke
				(width 0.1)
				(type default)
			)
			(layer "B.Fab")
		)
		(fp_line
			(start -0.299974 0.150114)
			(end 0.299974 0.150114)
			(stroke
				(width 0.1)
				(type default)
			)
			(layer "B.Fab")
		)
		(fp_line
			(start -0.299974 -0.150114)
			(end -0.299974 0.150114)
			(stroke
				(width 0.1)
				(type default)
			)
			(layer "B.Fab")
		)
		(pad "1" smd rect
			(at 0.2667 0)
			(size 0.3048 0.381)
			(layers "B.Cu" "B.Mask" "B.Paste")
			(net "P1V8_PEX")
		)
		(pad "2" smd rect
			(at -0.2667 0)
			(size 0.3048 0.381)
			(layers "B.Cu" "B.Mask" "B.Paste")
			(net "GND")
		)
	)
	(footprint ""
		(layer "B.Cu")
		(at 104.359964 -326.990202 90)
		(property "Reference" "C2699"
			(at 0 0 90)
			(layer "B.SilkS")
			(hide yes)
			(effects
				(font
					(size 1.27 1.27)
				)
				(justify mirror)
			)
		)
		(property "Value" ""
			(at 0 0 90)
			(layer "B.Fab")
			(effects
				(font
					(size 1.27 1.27)
				)
				(justify mirror)
			)
		)
		(duplicate_pad_numbers_are_jumpers no)
		(fp_line
			(start 0.7874 -0.4064)
			(end -0.7874 -0.4064)
			(stroke
				(width 0.1524)
				(type default)
			)
			(layer "B.SilkS")
		)
		(fp_line
			(start -0.7874 -0.4064)
			(end -0.7874 0.4064)
			(stroke
				(width 0.1524)
				(type default)
			)
			(layer "B.SilkS")
		)
		(fp_line
			(start 0.7874 0.4064)
			(end 0.7874 -0.4064)
			(stroke
				(width 0.1524)
				(type default)
			)
			(layer "B.SilkS")
		)
		(fp_line
			(start -0.7874 0.4064)
			(end 0.7874 0.4064)
			(stroke
				(width 0.1524)
				(type default)
			)
			(layer "B.SilkS")
		)
		(fp_line
			(start 0.67945 -0.305054)
			(end 0.12065 -0.305054)
			(stroke
				(width 0.1)
				(type default)
			)
			(layer "B.Fab")
		)
		(fp_line
			(start 0.12065 -0.305054)
			(end 0.12065 -0.2794)
			(stroke
				(width 0.1)
				(type default)
			)
			(layer "B.Fab")
		)
		(fp_line
			(start -0.12065 -0.3048)
			(end -0.67945 -0.3048)
			(stroke
				(width 0.1)
				(type default)
			)
			(layer "B.Fab")
		)
		(fp_line
			(start -0.67945 -0.3048)
			(end -0.67945 0.3048)
			(stroke
				(width 0.1)
				(type default)
			)
			(layer "B.Fab")
		)
		(fp_line
			(start 0.12065 -0.2794)
			(end -0.12065 -0.2794)
			(stroke
				(width 0.1)
				(type default)
			)
			(layer "B.Fab")
		)
		(fp_line
			(start -0.12065 -0.2794)
			(end -0.12065 -0.3048)
			(stroke
				(width 0.1)
				(type default)
			)
			(layer "B.Fab")
		)
		(fp_line
			(start 0.12065 0.2794)
			(end 0.12065 0.3048)
			(stroke
				(width 0.1)
				(type default)
			)
			(layer "B.Fab")
		)
		(fp_line
			(start -0.120396 0.2794)
			(end 0.12065 0.2794)
			(stroke
				(width 0.1)
				(type default)
			)
			(layer "B.Fab")
		)
		(fp_line
			(start 0.67945 0.3048)
			(end 0.67945 -0.305054)
			(stroke
				(width 0.1)
				(type default)
			)
			(layer "B.Fab")
		)
		(fp_line
			(start 0.12065 0.3048)
			(end 0.67945 0.3048)
			(stroke
				(width 0.1)
				(type default)
			)
			(layer "B.Fab")
		)
		(fp_line
			(start -0.120396 0.3048)
			(end -0.120396 0.2794)
			(stroke
				(width 0.1)
				(type default)
			)
			(layer "B.Fab")
		)
		(fp_line
			(start -0.67945 0.3048)
			(end -0.120396 0.3048)
			(stroke
				(width 0.1)
				(type default)
			)
			(layer "B.Fab")
		)
		(pad "1" smd circle
			(at 0.40005 0 270)
			(size 0 0)
			(layers "B.Cu" "B.Mask" "B.Paste")
			(net "P3V3_CLK_BUFFER_9ZXL0451E_VZX3P3")
		)
		(pad "2" smd circle
			(at -0.40005 0 270)
			(size 0 0)
			(layers "B.Cu" "B.Mask" "B.Paste")
			(net "GND")
		)
	)
	(footprint ""
		(layer "B.Cu")
		(at 69.149976 -297.32478 180)
		(property "Reference" "C1161"
			(at 0 0 0)
			(layer "B.SilkS")
			(hide yes)
			(effects
				(font
					(size 1.27 1.27)
				)
				(justify mirror)
			)
		)
		(property "Value" ""
			(at 0 0 0)
			(layer "B.Fab")
			(effects
				(font
					(size 1.27 1.27)
				)
				(justify mirror)
			)
		)
		(duplicate_pad_numbers_are_jumpers no)
		(fp_line
			(start 0.299974 0.150114)
			(end 0.299974 -0.150114)
			(stroke
				(width 0.1)
				(type default)
			)
			(layer "B.Fab")
		)
		(fp_line
			(start 0.299974 -0.150114)
			(end -0.299974 -0.150114)
			(stroke
				(width 0.1)
				(type default)
			)
			(layer "B.Fab")
		)
		(fp_line
			(start -0.299974 0.150114)
			(end 0.299974 0.150114)
			(stroke
				(width 0.1)
				(type default)
			)
			(layer "B.Fab")
		)
		(fp_line
			(start -0.299974 -0.150114)
			(end -0.299974 0.150114)
			(stroke
				(width 0.1)
				(type default)
			)
			(layer "B.Fab")
		)
		(pad "1" smd rect
			(at 0.2667 0)
			(size 0.3048 0.381)
			(layers "B.Cu" "B.Mask" "B.Paste")
			(net "P0V8_SERDES_VDDA_PEX0")
		)
		(pad "2" smd rect
			(at -0.2667 0)
			(size 0.3048 0.381)
			(layers "B.Cu" "B.Mask" "B.Paste")
			(net "GND")
		)
	)
	(footprint ""
		(layer "B.Cu")
		(at 135.73887 -222.214186)
		(property "Reference" "R3464"
			(at 0 0 0)
			(layer "B.SilkS")
			(hide yes)
			(effects
				(font
					(size 1.27 1.27)
				)
				(justify mirror)
			)
		)
		(property "Value" ""
			(at 0 0 0)
			(layer "B.Fab")
			(effects
				(font
					(size 1.27 1.27)
				)
				(justify mirror)
			)
		)
		(duplicate_pad_numbers_are_jumpers no)
		(fp_line
			(start -0.7874 -0.4064)
			(end -0.7874 0.4064)
			(stroke
				(width 0.1524)
				(type default)
			)
			(layer "B.SilkS")
		)
		(fp_line
			(start -0.7874 0.4064)
			(end 0.7874 0.4064)
			(stroke
				(width 0.1524)
				(type default)
			)
			(layer "B.SilkS")
		)
		(fp_line
			(start 0.7874 -0.4064)
			(end -0.7874 -0.4064)
			(stroke
				(width 0.1524)
				(type default)
			)
			(layer "B.SilkS")
		)
		(fp_line
			(start 0.7874 0.4064)
			(end 0.7874 -0.4064)
			(stroke
				(width 0.1524)
				(type default)
			)
			(layer "B.SilkS")
		)
		(fp_line
			(start -0.67945 -0.3048)
			(end -0.67945 0.3048)
			(stroke
				(width 0.1)
				(type default)
			)
			(layer "B.Fab")
		)
		(fp_line
			(start -0.67945 0.3048)
			(end -0.120396 0.3048)
			(stroke
				(width 0.1)
				(type default)
			)
			(layer "B.Fab")
		)
		(fp_line
			(start -0.12065 -0.3048)
			(end -0.67945 -0.3048)
			(stroke
				(width 0.1)
				(type default)
			)
			(layer "B.Fab")
		)
		(fp_line
			(start -0.12065 -0.2794)
			(end -0.12065 -0.3048)
			(stroke
				(width 0.1)
				(type default)
			)
			(layer "B.Fab")
		)
		(fp_line
			(start -0.120396 0.2794)
			(end 0.12065 0.2794)
			(stroke
				(width 0.1)
				(type default)
			)
			(layer "B.Fab")
		)
		(fp_line
			(start -0.120396 0.3048)
			(end -0.120396 0.2794)
			(stroke
				(width 0.1)
				(type default)
			)
			(layer "B.Fab")
		)
		(fp_line
			(start 0.12065 -0.305054)
			(end 0.12065 -0.2794)
			(stroke
				(width 0.1)
				(type default)
			)
			(layer "B.Fab")
		)
		(fp_line
			(start 0.12065 -0.2794)
			(end -0.12065 -0.2794)
			(stroke
				(width 0.1)
				(type default)
			)
			(layer "B.Fab")
		)
		(fp_line
			(start 0.12065 0.2794)
			(end 0.12065 0.3048)
			(stroke
				(width 0.1)
				(type default)
			)
			(layer "B.Fab")
		)
		(fp_line
			(start 0.12065 0.3048)
			(end 0.67945 0.3048)
			(stroke
				(width 0.1)
				(type default)
			)
			(layer "B.Fab")
		)
		(fp_line
			(start 0.67945 -0.305054)
			(end 0.12065 -0.305054)
			(stroke
				(width 0.1)
				(type default)
			)
			(layer "B.Fab")
		)
		(fp_line
			(start 0.67945 0.3048)
			(end 0.67945 -0.305054)
			(stroke
				(width 0.1)
				(type default)
			)
			(layer "B.Fab")
		)
		(pad "1" smd circle
			(at 0.40005 0 180)
			(size 0 0)
			(layers "B.Cu" "B.Mask" "B.Paste")
			(net "SPI_PEX1_SDIO0_MUX")
		)
		(pad "2" smd circle
			(at -0.40005 0 180)
			(size 0 0)
			(layers "B.Cu" "B.Mask" "B.Paste")
			(net "SPI_PEX1_SDIO0_MUX_R")
		)
	)
	(footprint ""
		(layer "B.Cu")
		(at 140.894816 -203.552806 180)
		(property "Reference" "C2600"
			(at 0 0 0)
			(layer "B.SilkS")
			(hide yes)
			(effects
				(font
					(size 1.27 1.27)
				)
				(justify mirror)
			)
		)
		(property "Value" ""
			(at 0 0 0)
			(layer "B.Fab")
			(effects
				(font
					(size 1.27 1.27)
				)
				(justify mirror)
			)
		)
		(duplicate_pad_numbers_are_jumpers no)
		(fp_line
			(start 1.2954 0.5842)
			(end 1.2954 -0.5842)
			(stroke
				(width 0.1524)
				(type default)
			)
			(layer "B.SilkS")
		)
		(fp_line
			(start 1.2954 -0.5842)
			(end -1.2954 -0.5842)
			(stroke
				(width 0.1524)
				(type default)
			)
			(layer "B.SilkS")
		)
		(fp_line
			(start -1.2954 0.5842)
			(end 1.2954 0.5842)
			(stroke
				(width 0.1524)
				(type default)
			)
			(layer "B.SilkS")
		)
		(fp_line
			(start -1.2954 -0.5842)
			(end -1.2954 0.5842)
			(stroke
				(width 0.1524)
				(type default)
			)
			(layer "B.SilkS")
		)
		(fp_line
			(start 1.1938 0.4064)
			(end 1.1938 -0.4064)
			(stroke
				(width 0.1)
				(type default)
			)
			(layer "B.Fab")
		)
		(fp_line
			(start 1.1938 -0.4064)
			(end 0.8636 -0.4064)
			(stroke
				(width 0.1)
				(type default)
			)
			(layer "B.Fab")
		)
		(fp_line
			(start 0.8636 0.4572)
			(end 0.8636 0.4064)
			(stroke
				(width 0.1)
				(type default)
			)
			(layer "B.Fab")
		)
		(fp_line
			(start 0.8636 0.4064)
			(end 1.1938 0.4064)
			(stroke
				(width 0.1)
				(type default)
			)
			(layer "B.Fab")
		)
		(fp_line
			(start 0.8636 -0.4064)
			(end 0.8636 -0.4572)
			(stroke
				(width 0.1)
				(type default)
			)
			(layer "B.Fab")
		)
		(fp_line
			(start 0.8636 -0.4572)
			(end -0.8636 -0.4572)
			(stroke
				(width 0.1)
				(type default)
			)
			(layer "B.Fab")
		)
		(fp_line
			(start -0.8636 0.4572)
			(end 0.8636 0.4572)
			(stroke
				(width 0.1)
				(type default)
			)
			(layer "B.Fab")
		)
		(fp_line
			(start -0.8636 0.4064)
			(end -0.8636 0.4572)
			(stroke
				(width 0.1)
				(type default)
			)
			(layer "B.Fab")
		)
		(fp_line
			(start -0.8636 -0.4064)
			(end -1.1938 -0.4064)
			(stroke
				(width 0.1)
				(type default)
			)
			(layer "B.Fab")
		)
		(fp_line
			(start -0.8636 -0.4572)
			(end -0.8636 -0.4064)
			(stroke
				(width 0.1)
				(type default)
			)
			(layer "B.Fab")
		)
		(fp_line
			(start -1.1938 0.4064)
			(end -0.8636 0.4064)
			(stroke
				(width 0.1)
				(type default)
			)
			(layer "B.Fab")
		)
		(fp_line
			(start -1.1938 -0.4064)
			(end -1.1938 0.4064)
			(stroke
				(width 0.1)
				(type default)
			)
			(layer "B.Fab")
		)
		(pad "1" smd rect
			(at 0.7366 0 90)
			(size 0.7112 0.8128)
			(layers "B.Cu" "B.Mask" "B.Paste")
			(net "P3V3_CLI_VPLL")
		)
		(pad "2" smd rect
			(at -0.7366 0 90)
			(size 0.7112 0.8128)
			(layers "B.Cu" "B.Mask" "B.Paste")
			(net "GND")
		)
	)
	(footprint ""
		(layer "B.Cu")
		(at 300.012354 -236.736636 90)
		(property "Reference" "R1858"
			(at 0 0 90)
			(layer "B.SilkS")
			(hide yes)
			(effects
				(font
					(size 1.27 1.27)
				)
				(justify mirror)
			)
		)
		(property "Value" ""
			(at 0 0 90)
			(layer "B.Fab")
			(effects
				(font
					(size 1.27 1.27)
				)
				(justify mirror)
			)
		)
		(duplicate_pad_numbers_are_jumpers no)
		(fp_line
			(start 0.7874 -0.4064)
			(end -0.7874 -0.4064)
			(stroke
				(width 0.1524)
				(type default)
			)
			(layer "B.SilkS")
		)
		(fp_line
			(start -0.7874 -0.4064)
			(end -0.7874 0.4064)
			(stroke
				(width 0.1524)
				(type default)
			)
			(layer "B.SilkS")
		)
		(fp_line
			(start 0.7874 0.4064)
			(end 0.7874 -0.4064)
			(stroke
				(width 0.1524)
				(type default)
			)
			(layer "B.SilkS")
		)
		(fp_line
			(start -0.7874 0.4064)
			(end 0.7874 0.4064)
			(stroke
				(width 0.1524)
				(type default)
			)
			(layer "B.SilkS")
		)
		(fp_line
			(start 0.67945 -0.305054)
			(end 0.12065 -0.305054)
			(stroke
				(width 0.1)
				(type default)
			)
			(layer "B.Fab")
		)
		(fp_line
			(start 0.12065 -0.305054)
			(end 0.12065 -0.2794)
			(stroke
				(width 0.1)
				(type default)
			)
			(layer "B.Fab")
		)
		(fp_line
			(start -0.12065 -0.3048)
			(end -0.67945 -0.3048)
			(stroke
				(width 0.1)
				(type default)
			)
			(layer "B.Fab")
		)
		(fp_line
			(start -0.67945 -0.3048)
			(end -0.67945 0.3048)
			(stroke
				(width 0.1)
				(type default)
			)
			(layer "B.Fab")
		)
		(fp_line
			(start 0.12065 -0.2794)
			(end -0.12065 -0.2794)
			(stroke
				(width 0.1)
				(type default)
			)
			(layer "B.Fab")
		)
		(fp_line
			(start -0.12065 -0.2794)
			(end -0.12065 -0.3048)
			(stroke
				(width 0.1)
				(type default)
			)
			(layer "B.Fab")
		)
		(fp_line
			(start 0.12065 0.2794)
			(end 0.12065 0.3048)
			(stroke
				(width 0.1)
				(type default)
			)
			(layer "B.Fab")
		)
		(fp_line
			(start -0.120396 0.2794)
			(end 0.12065 0.2794)
			(stroke
				(width 0.1)
				(type default)
			)
			(layer "B.Fab")
		)
		(fp_line
			(start 0.67945 0.3048)
			(end 0.67945 -0.305054)
			(stroke
				(width 0.1)
				(type default)
			)
			(layer "B.Fab")
		)
		(fp_line
			(start 0.12065 0.3048)
			(end 0.67945 0.3048)
			(stroke
				(width 0.1)
				(type default)
			)
			(layer "B.Fab")
		)
		(fp_line
			(start -0.120396 0.3048)
			(end -0.120396 0.2794)
			(stroke
				(width 0.1)
				(type default)
			)
			(layer "B.Fab")
		)
		(fp_line
			(start -0.67945 0.3048)
			(end -0.120396 0.3048)
			(stroke
				(width 0.1)
				(type default)
			)
			(layer "B.Fab")
		)
		(pad "1" smd circle
			(at 0.40005 0 270)
			(size 0 0)
			(layers "B.Cu" "B.Mask" "B.Paste")
			(net "P3V3_AUX")
		)
		(pad "2" smd circle
			(at -0.40005 0 270)
			(size 0 0)
			(layers "B.Cu" "B.Mask" "B.Paste")
			(net "RST_GPU_PERST_0_N")
		)
	)
	(footprint ""
		(layer "B.Cu")
		(at 334.01 -207.772 90)
		(property "Reference" "R4118"
			(at 0 0 90)
			(layer "B.SilkS")
			(hide yes)
			(effects
				(font
					(size 1.27 1.27)
				)
				(justify mirror)
			)
		)
		(property "Value" ""
			(at 0 0 90)
			(layer "B.Fab")
			(effects
				(font
					(size 1.27 1.27)
				)
				(justify mirror)
			)
		)
		(duplicate_pad_numbers_are_jumpers no)
		(fp_line
			(start 0.7874 -0.4064)
			(end -0.7874 -0.4064)
			(stroke
				(width 0.1524)
				(type default)
			)
			(layer "B.SilkS")
		)
		(fp_line
			(start -0.7874 -0.4064)
			(end -0.7874 0.4064)
			(stroke
				(width 0.1524)
				(type default)
			)
			(layer "B.SilkS")
		)
		(fp_line
			(start 0.7874 0.4064)
			(end 0.7874 -0.4064)
			(stroke
				(width 0.1524)
				(type default)
			)
			(layer "B.SilkS")
		)
		(fp_line
			(start -0.7874 0.4064)
			(end 0.7874 0.4064)
			(stroke
				(width 0.1524)
				(type default)
			)
			(layer "B.SilkS")
		)
		(fp_line
			(start 0.67945 -0.305054)
			(end 0.12065 -0.305054)
			(stroke
				(width 0.1)
				(type default)
			)
			(layer "B.Fab")
		)
		(fp_line
			(start 0.12065 -0.305054)
			(end 0.12065 -0.2794)
			(stroke
				(width 0.1)
				(type default)
			)
			(layer "B.Fab")
		)
		(fp_line
			(start -0.12065 -0.3048)
			(end -0.67945 -0.3048)
			(stroke
				(width 0.1)
				(type default)
			)
			(layer "B.Fab")
		)
		(fp_line
			(start -0.67945 -0.3048)
			(end -0.67945 0.3048)
			(stroke
				(width 0.1)
				(type default)
			)
			(layer "B.Fab")
		)
		(fp_line
			(start 0.12065 -0.2794)
			(end -0.12065 -0.2794)
			(stroke
				(width 0.1)
				(type default)
			)
			(layer "B.Fab")
		)
		(fp_line
			(start -0.12065 -0.2794)
			(end -0.12065 -0.3048)
			(stroke
				(width 0.1)
				(type default)
			)
			(layer "B.Fab")
		)
		(fp_line
			(start 0.12065 0.2794)
			(end 0.12065 0.3048)
			(stroke
				(width 0.1)
				(type default)
			)
			(layer "B.Fab")
		)
		(fp_line
			(start -0.120396 0.2794)
			(end 0.12065 0.2794)
			(stroke
				(width 0.1)
				(type default)
			)
			(layer "B.Fab")
		)
		(fp_line
			(start 0.67945 0.3048)
			(end 0.67945 -0.305054)
			(stroke
				(width 0.1)
				(type default)
			)
			(layer "B.Fab")
		)
		(fp_line
			(start 0.12065 0.3048)
			(end 0.67945 0.3048)
			(stroke
				(width 0.1)
				(type default)
			)
			(layer "B.Fab")
		)
		(fp_line
			(start -0.120396 0.3048)
			(end -0.120396 0.2794)
			(stroke
				(width 0.1)
				(type default)
			)
			(layer "B.Fab")
		)
		(fp_line
			(start -0.67945 0.3048)
			(end -0.120396 0.3048)
			(stroke
				(width 0.1)
				(type default)
			)
			(layer "B.Fab")
		)
		(pad "1" smd circle
			(at 0.40005 0 270)
			(size 0 0)
			(layers "B.Cu" "B.Mask" "B.Paste")
			(net "SSD8_CLK_EN_N")
		)
		(pad "2" smd circle
			(at -0.40005 0 270)
			(size 0 0)
			(layers "B.Cu" "B.Mask" "B.Paste")
			(net "SSD8_CLK_EN_R_N")
		)
	)
	(footprint ""
		(layer "B.Cu")
		(at 3.079242 -270.585946)
		(property "Reference" "C4220"
			(at 0 0 0)
			(layer "B.SilkS")
			(hide yes)
			(effects
				(font
					(size 1.27 1.27)
				)
				(justify mirror)
			)
		)
		(property "Value" ""
			(at 0 0 0)
			(layer "B.Fab")
			(effects
				(font
					(size 1.27 1.27)
				)
				(justify mirror)
			)
		)
		(duplicate_pad_numbers_are_jumpers no)
		(fp_line
			(start -1.2954 -0.5842)
			(end -1.2954 0.5842)
			(stroke
				(width 0.1524)
				(type default)
			)
			(layer "B.SilkS")
		)
		(fp_line
			(start -1.2954 0.5842)
			(end 1.2954 0.5842)
			(stroke
				(width 0.1524)
				(type default)
			)
			(layer "B.SilkS")
		)
		(fp_line
			(start 1.2954 -0.5842)
			(end -1.2954 -0.5842)
			(stroke
				(width 0.1524)
				(type default)
			)
			(layer "B.SilkS")
		)
		(fp_line
			(start 1.2954 0.5842)
			(end 1.2954 -0.5842)
			(stroke
				(width 0.1524)
				(type default)
			)
			(layer "B.SilkS")
		)
		(fp_line
			(start -1.1938 -0.4064)
			(end -1.1938 0.4064)
			(stroke
				(width 0.1)
				(type default)
			)
			(layer "B.Fab")
		)
		(fp_line
			(start -1.1938 0.4064)
			(end -0.8636 0.4064)
			(stroke
				(width 0.1)
				(type default)
			)
			(layer "B.Fab")
		)
		(fp_line
			(start -0.8636 -0.4572)
			(end -0.8636 -0.4064)
			(stroke
				(width 0.1)
				(type default)
			)
			(layer "B.Fab")
		)
		(fp_line
			(start -0.8636 -0.4064)
			(end -1.1938 -0.4064)
			(stroke
				(width 0.1)
				(type default)
			)
			(layer "B.Fab")
		)
		(fp_line
			(start -0.8636 0.4064)
			(end -0.8636 0.4572)
			(stroke
				(width 0.1)
				(type default)
			)
			(layer "B.Fab")
		)
		(fp_line
			(start -0.8636 0.4572)
			(end 0.8636 0.4572)
			(stroke
				(width 0.1)
				(type default)
			)
			(layer "B.Fab")
		)
		(fp_line
			(start 0.8636 -0.4572)
			(end -0.8636 -0.4572)
			(stroke
				(width 0.1)
				(type default)
			)
			(layer "B.Fab")
		)
		(fp_line
			(start 0.8636 -0.4064)
			(end 0.8636 -0.4572)
			(stroke
				(width 0.1)
				(type default)
			)
			(layer "B.Fab")
		)
		(fp_line
			(start 0.8636 0.4064)
			(end 1.1938 0.4064)
			(stroke
				(width 0.1)
				(type default)
			)
			(layer "B.Fab")
		)
		(fp_line
			(start 0.8636 0.4572)
			(end 0.8636 0.4064)
			(stroke
				(width 0.1)
				(type default)
			)
			(layer "B.Fab")
		)
		(fp_line
			(start 1.1938 -0.4064)
			(end 0.8636 -0.4064)
			(stroke
				(width 0.1)
				(type default)
			)
			(layer "B.Fab")
		)
		(fp_line
			(start 1.1938 0.4064)
			(end 1.1938 -0.4064)
			(stroke
				(width 0.1)
				(type default)
			)
			(layer "B.Fab")
		)
		(pad "1" smd rect
			(at 0.7366 0 270)
			(size 0.7112 0.8128)
			(layers "B.Cu" "B.Mask" "B.Paste")
			(net "P1V25_PEX0")
		)
		(pad "2" smd rect
			(at -0.7366 0 270)
			(size 0.7112 0.8128)
			(layers "B.Cu" "B.Mask" "B.Paste")
			(net "GND")
		)
	)
	(footprint ""
		(layer "B.Cu")
		(at 363.332776 -152.71115 90)
		(property "Reference" "R764"
			(at 0 0 90)
			(layer "B.SilkS")
			(hide yes)
			(effects
				(font
					(size 1.27 1.27)
				)
				(justify mirror)
			)
		)
		(property "Value" ""
			(at 0 0 90)
			(layer "B.Fab")
			(effects
				(font
					(size 1.27 1.27)
				)
				(justify mirror)
			)
		)
		(duplicate_pad_numbers_are_jumpers no)
		(fp_line
			(start 0.7874 -0.4064)
			(end -0.7874 -0.4064)
			(stroke
				(width 0.1524)
				(type default)
			)
			(layer "B.SilkS")
		)
		(fp_line
			(start -0.7874 -0.4064)
			(end -0.7874 0.4064)
			(stroke
				(width 0.1524)
				(type default)
			)
			(layer "B.SilkS")
		)
		(fp_line
			(start 0.7874 0.4064)
			(end 0.7874 -0.4064)
			(stroke
				(width 0.1524)
				(type default)
			)
			(layer "B.SilkS")
		)
		(fp_line
			(start -0.7874 0.4064)
			(end 0.7874 0.4064)
			(stroke
				(width 0.1524)
				(type default)
			)
			(layer "B.SilkS")
		)
		(fp_line
			(start 0.67945 -0.305054)
			(end 0.12065 -0.305054)
			(stroke
				(width 0.1)
				(type default)
			)
			(layer "B.Fab")
		)
		(fp_line
			(start 0.12065 -0.305054)
			(end 0.12065 -0.2794)
			(stroke
				(width 0.1)
				(type default)
			)
			(layer "B.Fab")
		)
		(fp_line
			(start -0.12065 -0.3048)
			(end -0.67945 -0.3048)
			(stroke
				(width 0.1)
				(type default)
			)
			(layer "B.Fab")
		)
		(fp_line
			(start -0.67945 -0.3048)
			(end -0.67945 0.3048)
			(stroke
				(width 0.1)
				(type default)
			)
			(layer "B.Fab")
		)
		(fp_line
			(start 0.12065 -0.2794)
			(end -0.12065 -0.2794)
			(stroke
				(width 0.1)
				(type default)
			)
			(layer "B.Fab")
		)
		(fp_line
			(start -0.12065 -0.2794)
			(end -0.12065 -0.3048)
			(stroke
				(width 0.1)
				(type default)
			)
			(layer "B.Fab")
		)
		(fp_line
			(start 0.12065 0.2794)
			(end 0.12065 0.3048)
			(stroke
				(width 0.1)
				(type default)
			)
			(layer "B.Fab")
		)
		(fp_line
			(start -0.120396 0.2794)
			(end 0.12065 0.2794)
			(stroke
				(width 0.1)
				(type default)
			)
			(layer "B.Fab")
		)
		(fp_line
			(start 0.67945 0.3048)
			(end 0.67945 -0.305054)
			(stroke
				(width 0.1)
				(type default)
			)
			(layer "B.Fab")
		)
		(fp_line
			(start 0.12065 0.3048)
			(end 0.67945 0.3048)
			(stroke
				(width 0.1)
				(type default)
			)
			(layer "B.Fab")
		)
		(fp_line
			(start -0.120396 0.3048)
			(end -0.120396 0.2794)
			(stroke
				(width 0.1)
				(type default)
			)
			(layer "B.Fab")
		)
		(fp_line
			(start -0.67945 0.3048)
			(end -0.120396 0.3048)
			(stroke
				(width 0.1)
				(type default)
			)
			(layer "B.Fab")
		)
		(pad "1" smd circle
			(at 0.40005 0 270)
			(size 0 0)
			(layers "B.Cu" "B.Mask" "B.Paste")
			(net "SMB_BIC_I2C6_MUX_NIC_ADC_R_SCL")
		)
		(pad "2" smd circle
			(at -0.40005 0 270)
			(size 0 0)
			(layers "B.Cu" "B.Mask" "B.Paste")
			(net "SMB_NIC7_ADC_SCL")
		)
	)
	(footprint ""
		(layer "B.Cu")
		(at 99.35337 -334.083406 180)
		(property "Reference" "R1230"
			(at 0 0 0)
			(layer "B.SilkS")
			(hide yes)
			(effects
				(font
					(size 1.27 1.27)
				)
				(justify mirror)
			)
		)
		(property "Value" ""
			(at 0 0 0)
			(layer "B.Fab")
			(effects
				(font
					(size 1.27 1.27)
				)
				(justify mirror)
			)
		)
		(duplicate_pad_numbers_are_jumpers no)
		(fp_line
			(start 0.7874 0.4064)
			(end 0.7874 -0.4064)
			(stroke
				(width 0.1524)
				(type default)
			)
			(layer "B.SilkS")
		)
		(fp_line
			(start 0.7874 -0.4064)
			(end -0.7874 -0.4064)
			(stroke
				(width 0.1524)
				(type default)
			)
			(layer "B.SilkS")
		)
		(fp_line
			(start -0.7874 0.4064)
			(end 0.7874 0.4064)
			(stroke
				(width 0.1524)
				(type default)
			)
			(layer "B.SilkS")
		)
		(fp_line
			(start -0.7874 -0.4064)
			(end -0.7874 0.4064)
			(stroke
				(width 0.1524)
				(type default)
			)
			(layer "B.SilkS")
		)
		(fp_line
			(start 0.67945 0.3048)
			(end 0.67945 -0.305054)
			(stroke
				(width 0.1)
				(type default)
			)
			(layer "B.Fab")
		)
		(fp_line
			(start 0.67945 -0.305054)
			(end 0.12065 -0.305054)
			(stroke
				(width 0.1)
				(type default)
			)
			(layer "B.Fab")
		)
		(fp_line
			(start 0.12065 0.3048)
			(end 0.67945 0.3048)
			(stroke
				(width 0.1)
				(type default)
			)
			(layer "B.Fab")
		)
		(fp_line
			(start 0.12065 0.2794)
			(end 0.12065 0.3048)
			(stroke
				(width 0.1)
				(type default)
			)
			(layer "B.Fab")
		)
		(fp_line
			(start 0.12065 -0.2794)
			(end -0.12065 -0.2794)
			(stroke
				(width 0.1)
				(type default)
			)
			(layer "B.Fab")
		)
		(fp_line
			(start 0.12065 -0.305054)
			(end 0.12065 -0.2794)
			(stroke
				(width 0.1)
				(type default)
			)
			(layer "B.Fab")
		)
		(fp_line
			(start -0.120396 0.3048)
			(end -0.120396 0.2794)
			(stroke
				(width 0.1)
				(type default)
			)
			(layer "B.Fab")
		)
		(fp_line
			(start -0.120396 0.2794)
			(end 0.12065 0.2794)
			(stroke
				(width 0.1)
				(type default)
			)
			(layer "B.Fab")
		)
		(fp_line
			(start -0.12065 -0.2794)
			(end -0.12065 -0.3048)
			(stroke
				(width 0.1)
				(type default)
			)
			(layer "B.Fab")
		)
		(fp_line
			(start -0.12065 -0.3048)
			(end -0.67945 -0.3048)
			(stroke
				(width 0.1)
				(type default)
			)
			(layer "B.Fab")
		)
		(fp_line
			(start -0.67945 0.3048)
			(end -0.120396 0.3048)
			(stroke
				(width 0.1)
				(type default)
			)
			(layer "B.Fab")
		)
		(fp_line
			(start -0.67945 -0.3048)
			(end -0.67945 0.3048)
			(stroke
				(width 0.1)
				(type default)
			)
			(layer "B.Fab")
		)
		(pad "1" smd circle
			(at 0.40005 0)
			(size 0 0)
			(layers "B.Cu" "B.Mask" "B.Paste")
			(net "CLK_100M_DB800ZL_PEX2_S0_R_DN")
		)
		(pad "2" smd circle
			(at -0.40005 0)
			(size 0 0)
			(layers "B.Cu" "B.Mask" "B.Paste")
			(net "CLK_100M_DB800ZL_PEX2_S0_DN")
		)
	)
	(footprint ""
		(layer "B.Cu")
		(at 223.338644 -231.225598 -90)
		(property "Reference" "R1480"
			(at 0 0 90)
			(layer "B.SilkS")
			(hide yes)
			(effects
				(font
					(size 1.27 1.27)
				)
				(justify mirror)
			)
		)
		(property "Value" ""
			(at 0 0 90)
			(layer "B.Fab")
			(effects
				(font
					(size 1.27 1.27)
				)
				(justify mirror)
			)
		)
		(duplicate_pad_numbers_are_jumpers no)
		(fp_line
			(start -0.7874 0.4064)
			(end 0.7874 0.4064)
			(stroke
				(width 0.1524)
				(type default)
			)
			(layer "B.SilkS")
		)
		(fp_line
			(start 0.7874 0.4064)
			(end 0.7874 -0.4064)
			(stroke
				(width 0.1524)
				(type default)
			)
			(layer "B.SilkS")
		)
		(fp_line
			(start -0.7874 -0.4064)
			(end -0.7874 0.4064)
			(stroke
				(width 0.1524)
				(type default)
			)
			(layer "B.SilkS")
		)
		(fp_line
			(start 0.7874 -0.4064)
			(end -0.7874 -0.4064)
			(stroke
				(width 0.1524)
				(type default)
			)
			(layer "B.SilkS")
		)
		(fp_line
			(start -0.67945 0.3048)
			(end -0.120396 0.3048)
			(stroke
				(width 0.1)
				(type default)
			)
			(layer "B.Fab")
		)
		(fp_line
			(start -0.120396 0.3048)
			(end -0.120396 0.2794)
			(stroke
				(width 0.1)
				(type default)
			)
			(layer "B.Fab")
		)
		(fp_line
			(start 0.12065 0.3048)
			(end 0.67945 0.3048)
			(stroke
				(width 0.1)
				(type default)
			)
			(layer "B.Fab")
		)
		(fp_line
			(start 0.67945 0.3048)
			(end 0.67945 -0.305054)
			(stroke
				(width 0.1)
				(type default)
			)
			(layer "B.Fab")
		)
		(fp_line
			(start -0.120396 0.2794)
			(end 0.12065 0.2794)
			(stroke
				(width 0.1)
				(type default)
			)
			(layer "B.Fab")
		)
		(fp_line
			(start 0.12065 0.2794)
			(end 0.12065 0.3048)
			(stroke
				(width 0.1)
				(type default)
			)
			(layer "B.Fab")
		)
		(fp_line
			(start -0.12065 -0.2794)
			(end -0.12065 -0.3048)
			(stroke
				(width 0.1)
				(type default)
			)
			(layer "B.Fab")
		)
		(fp_line
			(start 0.12065 -0.2794)
			(end -0.12065 -0.2794)
			(stroke
				(width 0.1)
				(type default)
			)
			(layer "B.Fab")
		)
		(fp_line
			(start -0.67945 -0.3048)
			(end -0.67945 0.3048)
			(stroke
				(width 0.1)
				(type default)
			)
			(layer "B.Fab")
		)
		(fp_line
			(start -0.12065 -0.3048)
			(end -0.67945 -0.3048)
			(stroke
				(width 0.1)
				(type default)
			)
			(layer "B.Fab")
		)
		(fp_line
			(start 0.12065 -0.305054)
			(end 0.12065 -0.2794)
			(stroke
				(width 0.1)
				(type default)
			)
			(layer "B.Fab")
		)
		(fp_line
			(start 0.67945 -0.305054)
			(end 0.12065 -0.305054)
			(stroke
				(width 0.1)
				(type default)
			)
			(layer "B.Fab")
		)
		(pad "1" smd circle
			(at 0.40005 0 90)
			(size 0 0)
			(layers "B.Cu" "B.Mask" "B.Paste")
			(net "SMB_NIC1_SDA")
		)
		(pad "2" smd circle
			(at -0.40005 0 90)
			(size 0 0)
			(layers "B.Cu" "B.Mask" "B.Paste")
			(net "SMB_NIC1_R_SDA")
		)
	)
	(footprint ""
		(layer "B.Cu")
		(at 171.949872 -303.499774 -90)
		(property "Reference" "C3081"
			(at 0 0 90)
			(layer "B.SilkS")
			(hide yes)
			(effects
				(font
					(size 1.27 1.27)
				)
				(justify mirror)
			)
		)
		(property "Value" ""
			(at 0 0 90)
			(layer "B.Fab")
			(effects
				(font
					(size 1.27 1.27)
				)
				(justify mirror)
			)
		)
		(duplicate_pad_numbers_are_jumpers no)
		(fp_line
			(start -0.299974 0.150114)
			(end 0.299974 0.150114)
			(stroke
				(width 0.1)
				(type default)
			)
			(layer "B.Fab")
		)
		(fp_line
			(start 0.299974 0.150114)
			(end 0.299974 -0.150114)
			(stroke
				(width 0.1)
				(type default)
			)
			(layer "B.Fab")
		)
		(fp_line
			(start -0.299974 -0.150114)
			(end -0.299974 0.150114)
			(stroke
				(width 0.1)
				(type default)
			)
			(layer "B.Fab")
		)
		(fp_line
			(start 0.299974 -0.150114)
			(end -0.299974 -0.150114)
			(stroke
				(width 0.1)
				(type default)
			)
			(layer "B.Fab")
		)
		(pad "1" smd rect
			(at 0.2667 0 90)
			(size 0.3048 0.381)
			(layers "B.Cu" "B.Mask" "B.Paste")
			(net "P1V25_PEX1")
		)
		(pad "2" smd rect
			(at -0.2667 0 90)
			(size 0.3048 0.381)
			(layers "B.Cu" "B.Mask" "B.Paste")
			(net "GND")
		)
	)
	(footprint ""
		(layer "B.Cu")
		(at 337.439 -207.772 90)
		(property "Reference" "R4131"
			(at 0 0 90)
			(layer "B.SilkS")
			(hide yes)
			(effects
				(font
					(size 1.27 1.27)
				)
				(justify mirror)
			)
		)
		(property "Value" ""
			(at 0 0 90)
			(layer "B.Fab")
			(effects
				(font
					(size 1.27 1.27)
				)
				(justify mirror)
			)
		)
		(duplicate_pad_numbers_are_jumpers no)
		(fp_line
			(start 0.7874 -0.4064)
			(end -0.7874 -0.4064)
			(stroke
				(width 0.1524)
				(type default)
			)
			(layer "B.SilkS")
		)
		(fp_line
			(start -0.7874 -0.4064)
			(end -0.7874 0.4064)
			(stroke
				(width 0.1524)
				(type default)
			)
			(layer "B.SilkS")
		)
		(fp_line
			(start 0.7874 0.4064)
			(end 0.7874 -0.4064)
			(stroke
				(width 0.1524)
				(type default)
			)
			(layer "B.SilkS")
		)
		(fp_line
			(start -0.7874 0.4064)
			(end 0.7874 0.4064)
			(stroke
				(width 0.1524)
				(type default)
			)
			(layer "B.SilkS")
		)
		(fp_line
			(start 0.67945 -0.305054)
			(end 0.12065 -0.305054)
			(stroke
				(width 0.1)
				(type default)
			)
			(layer "B.Fab")
		)
		(fp_line
			(start 0.12065 -0.305054)
			(end 0.12065 -0.2794)
			(stroke
				(width 0.1)
				(type default)
			)
			(layer "B.Fab")
		)
		(fp_line
			(start -0.12065 -0.3048)
			(end -0.67945 -0.3048)
			(stroke
				(width 0.1)
				(type default)
			)
			(layer "B.Fab")
		)
		(fp_line
			(start -0.67945 -0.3048)
			(end -0.67945 0.3048)
			(stroke
				(width 0.1)
				(type default)
			)
			(layer "B.Fab")
		)
		(fp_line
			(start 0.12065 -0.2794)
			(end -0.12065 -0.2794)
			(stroke
				(width 0.1)
				(type default)
			)
			(layer "B.Fab")
		)
		(fp_line
			(start -0.12065 -0.2794)
			(end -0.12065 -0.3048)
			(stroke
				(width 0.1)
				(type default)
			)
			(layer "B.Fab")
		)
		(fp_line
			(start 0.12065 0.2794)
			(end 0.12065 0.3048)
			(stroke
				(width 0.1)
				(type default)
			)
			(layer "B.Fab")
		)
		(fp_line
			(start -0.120396 0.2794)
			(end 0.12065 0.2794)
			(stroke
				(width 0.1)
				(type default)
			)
			(layer "B.Fab")
		)
		(fp_line
			(start 0.67945 0.3048)
			(end 0.67945 -0.305054)
			(stroke
				(width 0.1)
				(type default)
			)
			(layer "B.Fab")
		)
		(fp_line
			(start 0.12065 0.3048)
			(end 0.67945 0.3048)
			(stroke
				(width 0.1)
				(type default)
			)
			(layer "B.Fab")
		)
		(fp_line
			(start -0.120396 0.3048)
			(end -0.120396 0.2794)
			(stroke
				(width 0.1)
				(type default)
			)
			(layer "B.Fab")
		)
		(fp_line
			(start -0.67945 0.3048)
			(end -0.120396 0.3048)
			(stroke
				(width 0.1)
				(type default)
			)
			(layer "B.Fab")
		)
		(pad "1" smd circle
			(at 0.40005 0 270)
			(size 0 0)
			(layers "B.Cu" "B.Mask" "B.Paste")
			(net "SSD12_PWR_EN")
		)
		(pad "2" smd circle
			(at -0.40005 0 270)
			(size 0 0)
			(layers "B.Cu" "B.Mask" "B.Paste")
			(net "SSD12_PWR_EN_R")
		)
	)
	(footprint ""
		(layer "B.Cu")
		(at 165.299898 -288.774886 180)
		(property "Reference" "C3185"
			(at 0 0 0)
			(layer "B.SilkS")
			(hide yes)
			(effects
				(font
					(size 1.27 1.27)
				)
				(justify mirror)
			)
		)
		(property "Value" ""
			(at 0 0 0)
			(layer "B.Fab")
			(effects
				(font
					(size 1.27 1.27)
				)
				(justify mirror)
			)
		)
		(duplicate_pad_numbers_are_jumpers no)
		(fp_line
			(start 0.299974 0.150114)
			(end 0.299974 -0.150114)
			(stroke
				(width 0.1)
				(type default)
			)
			(layer "B.Fab")
		)
		(fp_line
			(start 0.299974 -0.150114)
			(end -0.299974 -0.150114)
			(stroke
				(width 0.1)
				(type default)
			)
			(layer "B.Fab")
		)
		(fp_line
			(start -0.299974 0.150114)
			(end 0.299974 0.150114)
			(stroke
				(width 0.1)
				(type default)
			)
			(layer "B.Fab")
		)
		(fp_line
			(start -0.299974 -0.150114)
			(end -0.299974 0.150114)
			(stroke
				(width 0.1)
				(type default)
			)
			(layer "B.Fab")
		)
		(pad "1" smd rect
			(at 0.2667 0)
			(size 0.3048 0.381)
			(layers "B.Cu" "B.Mask" "B.Paste")
			(net "P1V8_VDDA_PEX1")
		)
		(pad "2" smd rect
			(at -0.2667 0)
			(size 0.3048 0.381)
			(layers "B.Cu" "B.Mask" "B.Paste")
			(net "GND")
		)
	)
	(footprint ""
		(layer "B.Cu")
		(at 58.699908 -292.099746 90)
		(property "Reference" "C1165"
			(at 0 0 90)
			(layer "B.SilkS")
			(hide yes)
			(effects
				(font
					(size 1.27 1.27)
				)
				(justify mirror)
			)
		)
		(property "Value" ""
			(at 0 0 90)
			(layer "B.Fab")
			(effects
				(font
					(size 1.27 1.27)
				)
				(justify mirror)
			)
		)
		(duplicate_pad_numbers_are_jumpers no)
		(fp_line
			(start 0.299974 -0.150114)
			(end -0.299974 -0.150114)
			(stroke
				(width 0.1)
				(type default)
			)
			(layer "B.Fab")
		)
		(fp_line
			(start -0.299974 -0.150114)
			(end -0.299974 0.150114)
			(stroke
				(width 0.1)
				(type default)
			)
			(layer "B.Fab")
		)
		(fp_line
			(start 0.299974 0.150114)
			(end 0.299974 -0.150114)
			(stroke
				(width 0.1)
				(type default)
			)
			(layer "B.Fab")
		)
		(fp_line
			(start -0.299974 0.150114)
			(end 0.299974 0.150114)
			(stroke
				(width 0.1)
				(type default)
			)
			(layer "B.Fab")
		)
		(pad "1" smd rect
			(at 0.2667 0 270)
			(size 0.3048 0.381)
			(layers "B.Cu" "B.Mask" "B.Paste")
			(net "P0V8_SERDES_VDDA_PEX0")
		)
		(pad "2" smd rect
			(at -0.2667 0 270)
			(size 0.3048 0.381)
			(layers "B.Cu" "B.Mask" "B.Paste")
			(net "GND")
		)
	)
	(footprint ""
		(layer "B.Cu")
		(at 127.748284 -284.796738 -90)
		(property "Reference" "PC110"
			(at 0 0 90)
			(layer "B.SilkS")
			(hide yes)
			(effects
				(font
					(size 1.27 1.27)
				)
				(justify mirror)
			)
		)
		(property "Value" ""
			(at 0 0 90)
			(layer "B.Fab")
			(effects
				(font
					(size 1.27 1.27)
				)
				(justify mirror)
			)
		)
		(duplicate_pad_numbers_are_jumpers no)
		(fp_line
			(start -1.524 0.762)
			(end 1.524 0.762)
			(stroke
				(width 0.1524)
				(type default)
			)
			(layer "B.SilkS")
		)
		(fp_line
			(start 1.524 0.762)
			(end 1.524 -0.762)
			(stroke
				(width 0.1524)
				(type default)
			)
			(layer "B.SilkS")
		)
		(fp_line
			(start -1.524 -0.762)
			(end -1.524 0.762)
			(stroke
				(width 0.1524)
				(type default)
			)
			(layer "B.SilkS")
		)
		(fp_line
			(start 1.524 -0.762)
			(end -1.524 -0.762)
			(stroke
				(width 0.1524)
				(type default)
			)
			(layer "B.SilkS")
		)
		(fp_line
			(start -1.1049 0.724916)
			(end -1.1049 -0.724916)
			(stroke
				(width 0.1)
				(type default)
			)
			(layer "B.Fab")
		)
		(fp_line
			(start 1.1049 0.724916)
			(end -1.1049 0.724916)
			(stroke
				(width 0.1)
				(type default)
			)
			(layer "B.Fab")
		)
		(fp_line
			(start -1.1049 -0.724916)
			(end 1.1049 -0.724916)
			(stroke
				(width 0.1)
				(type default)
			)
			(layer "B.Fab")
		)
		(fp_line
			(start 1.1049 -0.724916)
			(end 1.1049 0.724916)
			(stroke
				(width 0.1)
				(type default)
			)
			(layer "B.Fab")
		)
		(pad "1" smd rect
			(at 0.889 0 270)
			(size 1.016 1.27)
			(layers "B.Cu" "B.Mask" "B.Paste")
			(net "SW_P12V_P0V8_PEX1_FLT")
		)
		(pad "2" smd rect
			(at -0.889 0 270)
			(size 1.016 1.27)
			(layers "B.Cu" "B.Mask" "B.Paste")
			(net "GND")
		)
	)
	(footprint ""
		(layer "B.Cu")
		(at 139.36091 -214.964772 90)
		(property "Reference" "R989"
			(at 0 0 90)
			(layer "B.SilkS")
			(hide yes)
			(effects
				(font
					(size 1.27 1.27)
				)
				(justify mirror)
			)
		)
		(property "Value" ""
			(at 0 0 90)
			(layer "B.Fab")
			(effects
				(font
					(size 1.27 1.27)
				)
				(justify mirror)
			)
		)
		(duplicate_pad_numbers_are_jumpers no)
		(fp_line
			(start 0.7874 -0.4064)
			(end -0.7874 -0.4064)
			(stroke
				(width 0.1524)
				(type default)
			)
			(layer "B.SilkS")
		)
		(fp_line
			(start -0.7874 -0.4064)
			(end -0.7874 0.4064)
			(stroke
				(width 0.1524)
				(type default)
			)
			(layer "B.SilkS")
		)
		(fp_line
			(start 0.7874 0.4064)
			(end 0.7874 -0.4064)
			(stroke
				(width 0.1524)
				(type default)
			)
			(layer "B.SilkS")
		)
		(fp_line
			(start -0.7874 0.4064)
			(end 0.7874 0.4064)
			(stroke
				(width 0.1524)
				(type default)
			)
			(layer "B.SilkS")
		)
		(fp_line
			(start 0.67945 -0.305054)
			(end 0.12065 -0.305054)
			(stroke
				(width 0.1)
				(type default)
			)
			(layer "B.Fab")
		)
		(fp_line
			(start 0.12065 -0.305054)
			(end 0.12065 -0.2794)
			(stroke
				(width 0.1)
				(type default)
			)
			(layer "B.Fab")
		)
		(fp_line
			(start -0.12065 -0.3048)
			(end -0.67945 -0.3048)
			(stroke
				(width 0.1)
				(type default)
			)
			(layer "B.Fab")
		)
		(fp_line
			(start -0.67945 -0.3048)
			(end -0.67945 0.3048)
			(stroke
				(width 0.1)
				(type default)
			)
			(layer "B.Fab")
		)
		(fp_line
			(start 0.12065 -0.2794)
			(end -0.12065 -0.2794)
			(stroke
				(width 0.1)
				(type default)
			)
			(layer "B.Fab")
		)
		(fp_line
			(start -0.12065 -0.2794)
			(end -0.12065 -0.3048)
			(stroke
				(width 0.1)
				(type default)
			)
			(layer "B.Fab")
		)
		(fp_line
			(start 0.12065 0.2794)
			(end 0.12065 0.3048)
			(stroke
				(width 0.1)
				(type default)
			)
			(layer "B.Fab")
		)
		(fp_line
			(start -0.120396 0.2794)
			(end 0.12065 0.2794)
			(stroke
				(width 0.1)
				(type default)
			)
			(layer "B.Fab")
		)
		(fp_line
			(start 0.67945 0.3048)
			(end 0.67945 -0.305054)
			(stroke
				(width 0.1)
				(type default)
			)
			(layer "B.Fab")
		)
		(fp_line
			(start 0.12065 0.3048)
			(end 0.67945 0.3048)
			(stroke
				(width 0.1)
				(type default)
			)
			(layer "B.Fab")
		)
		(fp_line
			(start -0.120396 0.3048)
			(end -0.120396 0.2794)
			(stroke
				(width 0.1)
				(type default)
			)
			(layer "B.Fab")
		)
		(fp_line
			(start -0.67945 0.3048)
			(end -0.120396 0.3048)
			(stroke
				(width 0.1)
				(type default)
			)
			(layer "B.Fab")
		)
		(pad "1" smd circle
			(at 0.40005 0 270)
			(size 0 0)
			(layers "B.Cu" "B.Mask" "B.Paste")
			(net "UART_PEX3_CLI_BUF_RX")
		)
		(pad "2" smd circle
			(at -0.40005 0 270)
			(size 0 0)
			(layers "B.Cu" "B.Mask" "B.Paste")
			(net "P1V8_PEX")
		)
	)
	(footprint ""
		(layer "B.Cu")
		(at 404.149814 -290.199826 90)
		(property "Reference" "C1995"
			(at 0 0 90)
			(layer "B.SilkS")
			(hide yes)
			(effects
				(font
					(size 1.27 1.27)
				)
				(justify mirror)
			)
		)
		(property "Value" ""
			(at 0 0 90)
			(layer "B.Fab")
			(effects
				(font
					(size 1.27 1.27)
				)
				(justify mirror)
			)
		)
		(duplicate_pad_numbers_are_jumpers no)
		(fp_line
			(start 0.299974 -0.150114)
			(end -0.299974 -0.150114)
			(stroke
				(width 0.1)
				(type default)
			)
			(layer "B.Fab")
		)
		(fp_line
			(start -0.299974 -0.150114)
			(end -0.299974 0.150114)
			(stroke
				(width 0.1)
				(type default)
			)
			(layer "B.Fab")
		)
		(fp_line
			(start 0.299974 0.150114)
			(end 0.299974 -0.150114)
			(stroke
				(width 0.1)
				(type default)
			)
			(layer "B.Fab")
		)
		(fp_line
			(start -0.299974 0.150114)
			(end 0.299974 0.150114)
			(stroke
				(width 0.1)
				(type default)
			)
			(layer "B.Fab")
		)
		(pad "1" smd rect
			(at 0.2667 0 270)
			(size 0.3048 0.381)
			(layers "B.Cu" "B.Mask" "B.Paste")
			(net "P0V8_SERDES_VDDA_PEX3")
		)
		(pad "2" smd rect
			(at -0.2667 0 270)
			(size 0.3048 0.381)
			(layers "B.Cu" "B.Mask" "B.Paste")
			(net "GND")
		)
	)
	(footprint ""
		(layer "B.Cu")
		(at 353.819968 -284.796738 -90)
		(property "Reference" "PC191"
			(at 0 0 90)
			(layer "B.SilkS")
			(hide yes)
			(effects
				(font
					(size 1.27 1.27)
				)
				(justify mirror)
			)
		)
		(property "Value" ""
			(at 0 0 90)
			(layer "B.Fab")
			(effects
				(font
					(size 1.27 1.27)
				)
				(justify mirror)
			)
		)
		(duplicate_pad_numbers_are_jumpers no)
		(fp_line
			(start -1.524 0.762)
			(end 1.524 0.762)
			(stroke
				(width 0.1524)
				(type default)
			)
			(layer "B.SilkS")
		)
		(fp_line
			(start 1.524 0.762)
			(end 1.524 -0.762)
			(stroke
				(width 0.1524)
				(type default)
			)
			(layer "B.SilkS")
		)
		(fp_line
			(start -1.524 -0.762)
			(end -1.524 0.762)
			(stroke
				(width 0.1524)
				(type default)
			)
			(layer "B.SilkS")
		)
		(fp_line
			(start 1.524 -0.762)
			(end -1.524 -0.762)
			(stroke
				(width 0.1524)
				(type default)
			)
			(layer "B.SilkS")
		)
		(fp_line
			(start -1.1049 0.724916)
			(end -1.1049 -0.724916)
			(stroke
				(width 0.1)
				(type default)
			)
			(layer "B.Fab")
		)
		(fp_line
			(start 1.1049 0.724916)
			(end -1.1049 0.724916)
			(stroke
				(width 0.1)
				(type default)
			)
			(layer "B.Fab")
		)
		(fp_line
			(start -1.1049 -0.724916)
			(end 1.1049 -0.724916)
			(stroke
				(width 0.1)
				(type default)
			)
			(layer "B.Fab")
		)
		(fp_line
			(start 1.1049 -0.724916)
			(end 1.1049 0.724916)
			(stroke
				(width 0.1)
				(type default)
			)
			(layer "B.Fab")
		)
		(pad "1" smd rect
			(at 0.889 0 270)
			(size 1.016 1.27)
			(layers "B.Cu" "B.Mask" "B.Paste")
			(net "SW_P12V_P0V8_PEX3_FLT")
		)
		(pad "2" smd rect
			(at -0.889 0 270)
			(size 1.016 1.27)
			(layers "B.Cu" "B.Mask" "B.Paste")
			(net "GND")
		)
	)
	(footprint ""
		(layer "B.Cu")
		(at 377.988322 -248.203974 180)
		(property "Reference" "R970"
			(at 0 0 0)
			(layer "B.SilkS")
			(hide yes)
			(effects
				(font
					(size 1.27 1.27)
				)
				(justify mirror)
			)
		)
		(property "Value" ""
			(at 0 0 0)
			(layer "B.Fab")
			(effects
				(font
					(size 1.27 1.27)
				)
				(justify mirror)
			)
		)
		(duplicate_pad_numbers_are_jumpers no)
		(fp_line
			(start 0.7874 0.4064)
			(end 0.7874 -0.4064)
			(stroke
				(width 0.1524)
				(type default)
			)
			(layer "B.SilkS")
		)
		(fp_line
			(start 0.7874 -0.4064)
			(end -0.7874 -0.4064)
			(stroke
				(width 0.1524)
				(type default)
			)
			(layer "B.SilkS")
		)
		(fp_line
			(start -0.7874 0.4064)
			(end 0.7874 0.4064)
			(stroke
				(width 0.1524)
				(type default)
			)
			(layer "B.SilkS")
		)
		(fp_line
			(start -0.7874 -0.4064)
			(end -0.7874 0.4064)
			(stroke
				(width 0.1524)
				(type default)
			)
			(layer "B.SilkS")
		)
		(fp_line
			(start 0.67945 0.3048)
			(end 0.67945 -0.305054)
			(stroke
				(width 0.1)
				(type default)
			)
			(layer "B.Fab")
		)
		(fp_line
			(start 0.67945 -0.305054)
			(end 0.12065 -0.305054)
			(stroke
				(width 0.1)
				(type default)
			)
			(layer "B.Fab")
		)
		(fp_line
			(start 0.12065 0.3048)
			(end 0.67945 0.3048)
			(stroke
				(width 0.1)
				(type default)
			)
			(layer "B.Fab")
		)
		(fp_line
			(start 0.12065 0.2794)
			(end 0.12065 0.3048)
			(stroke
				(width 0.1)
				(type default)
			)
			(layer "B.Fab")
		)
		(fp_line
			(start 0.12065 -0.2794)
			(end -0.12065 -0.2794)
			(stroke
				(width 0.1)
				(type default)
			)
			(layer "B.Fab")
		)
		(fp_line
			(start 0.12065 -0.305054)
			(end 0.12065 -0.2794)
			(stroke
				(width 0.1)
				(type default)
			)
			(layer "B.Fab")
		)
		(fp_line
			(start -0.120396 0.3048)
			(end -0.120396 0.2794)
			(stroke
				(width 0.1)
				(type default)
			)
			(layer "B.Fab")
		)
		(fp_line
			(start -0.120396 0.2794)
			(end 0.12065 0.2794)
			(stroke
				(width 0.1)
				(type default)
			)
			(layer "B.Fab")
		)
		(fp_line
			(start -0.12065 -0.2794)
			(end -0.12065 -0.3048)
			(stroke
				(width 0.1)
				(type default)
			)
			(layer "B.Fab")
		)
		(fp_line
			(start -0.12065 -0.3048)
			(end -0.67945 -0.3048)
			(stroke
				(width 0.1)
				(type default)
			)
			(layer "B.Fab")
		)
		(fp_line
			(start -0.67945 0.3048)
			(end -0.120396 0.3048)
			(stroke
				(width 0.1)
				(type default)
			)
			(layer "B.Fab")
		)
		(fp_line
			(start -0.67945 -0.3048)
			(end -0.67945 0.3048)
			(stroke
				(width 0.1)
				(type default)
			)
			(layer "B.Fab")
		)
		(pad "1" smd circle
			(at 0.40005 0)
			(size 0 0)
			(layers "B.Cu" "B.Mask" "B.Paste")
			(net "UART_PEX3_SDB_BUF_R_TX")
		)
		(pad "2" smd circle
			(at -0.40005 0)
			(size 0 0)
			(layers "B.Cu" "B.Mask" "B.Paste")
			(net "UART_PEX3_SDB_BUF_TX")
		)
	)
	(footprint ""
		(layer "B.Cu")
		(at 344.493342 -221.98711 90)
		(property "Reference" "C2035"
			(at 0 0 90)
			(layer "B.SilkS")
			(hide yes)
			(effects
				(font
					(size 1.27 1.27)
				)
				(justify mirror)
			)
		)
		(property "Value" ""
			(at 0 0 90)
			(layer "B.Fab")
			(effects
				(font
					(size 1.27 1.27)
				)
				(justify mirror)
			)
		)
		(duplicate_pad_numbers_are_jumpers no)
		(fp_line
			(start 0.69215 -0.2921)
			(end -0.69215 -0.2921)
			(stroke
				(width 0.1524)
				(type default)
			)
			(layer "B.SilkS")
		)
		(fp_line
			(start -0.69215 -0.2921)
			(end -0.69215 0.2921)
			(stroke
				(width 0.1524)
				(type default)
			)
			(layer "B.SilkS")
		)
		(fp_line
			(start 0.69215 0.2921)
			(end 0.69215 -0.2921)
			(stroke
				(width 0.1524)
				(type default)
			)
			(layer "B.SilkS")
		)
		(fp_line
			(start -0.69215 0.2921)
			(end 0.69215 0.2921)
			(stroke
				(width 0.1524)
				(type default)
			)
			(layer "B.SilkS")
		)
		(fp_line
			(start 0.51435 -0.2794)
			(end -0.51435 -0.2794)
			(stroke
				(width 0.1)
				(type default)
			)
			(layer "B.Fab")
		)
		(fp_line
			(start -0.51435 -0.2794)
			(end -0.51435 0.2794)
			(stroke
				(width 0.1)
				(type default)
			)
			(layer "B.Fab")
		)
		(fp_line
			(start 0.51435 0.2794)
			(end 0.51435 -0.2794)
			(stroke
				(width 0.1)
				(type default)
			)
			(layer "B.Fab")
		)
		(fp_line
			(start -0.51435 0.2794)
			(end 0.51435 0.2794)
			(stroke
				(width 0.1)
				(type default)
			)
			(layer "B.Fab")
		)
		(pad "1" smd circle
			(at 0.40005 0 270)
			(size 0 0)
			(layers "B.Cu" "B.Mask" "B.Paste")
			(net "P3V3_FPGA_VCCIO0")
		)
		(pad "2" smd circle
			(at -0.40005 0 270)
			(size 0 0)
			(layers "B.Cu" "B.Mask" "B.Paste")
			(net "GND")
		)
		(zone
			(layer "B.Cu")
			(hatch none 0.5)
			(connect_pads
				(clearance 0)
			)
			(min_thickness 0.25)
			(keepout
				(tracks not_allowed)
				(vias allowed)
				(pads allowed)
				(copperpour not_allowed)
				(footprints allowed)
			)
			(placement
				(enabled no)
				(sheetname "")
			)
			(fill
				(thermal_gap 0.5)
				(thermal_bridge_width 0.5)
				(island_removal_mode 0)
			)
			(polygon
				(pts
					(xy 344.580972 -222.17761) (xy 344.639138 -222.08617) (xy 344.639138 -221.88678) (xy 344.580972 -221.79661)
					(xy 344.405712 -221.79661) (xy 344.347292 -221.88678) (xy 344.347292 -222.08617) (xy 344.405458 -222.17761)
				)
			)
		)
	)
	(footprint ""
		(layer "B.Cu")
		(at 169.574972 -305.399948 -90)
		(property "Reference" "C3151"
			(at 0 0 90)
			(layer "B.SilkS")
			(hide yes)
			(effects
				(font
					(size 1.27 1.27)
				)
				(justify mirror)
			)
		)
		(property "Value" ""
			(at 0 0 90)
			(layer "B.Fab")
			(effects
				(font
					(size 1.27 1.27)
				)
				(justify mirror)
			)
		)
		(duplicate_pad_numbers_are_jumpers no)
		(fp_line
			(start -0.299974 0.150114)
			(end 0.299974 0.150114)
			(stroke
				(width 0.1)
				(type default)
			)
			(layer "B.Fab")
		)
		(fp_line
			(start 0.299974 0.150114)
			(end 0.299974 -0.150114)
			(stroke
				(width 0.1)
				(type default)
			)
			(layer "B.Fab")
		)
		(fp_line
			(start -0.299974 -0.150114)
			(end -0.299974 0.150114)
			(stroke
				(width 0.1)
				(type default)
			)
			(layer "B.Fab")
		)
		(fp_line
			(start 0.299974 -0.150114)
			(end -0.299974 -0.150114)
			(stroke
				(width 0.1)
				(type default)
			)
			(layer "B.Fab")
		)
		(pad "1" smd rect
			(at 0.2667 0 90)
			(size 0.3048 0.381)
			(layers "B.Cu" "B.Mask" "B.Paste")
			(net "P1V25_SERDES_VDDPLL_PEX1")
		)
		(pad "2" smd rect
			(at -0.2667 0 90)
			(size 0.3048 0.381)
			(layers "B.Cu" "B.Mask" "B.Paste")
			(net "GND")
		)
	)
	(footprint ""
		(layer "B.Cu")
		(at 343.324942 -323.15531 -90)
		(property "Reference" "R6510"
			(at 0 0 90)
			(layer "B.SilkS")
			(hide yes)
			(effects
				(font
					(size 1.27 1.27)
				)
				(justify mirror)
			)
		)
		(property "Value" ""
			(at 0 0 90)
			(layer "B.Fab")
			(effects
				(font
					(size 1.27 1.27)
				)
				(justify mirror)
			)
		)
		(duplicate_pad_numbers_are_jumpers no)
		(fp_line
			(start -0.7874 0.4064)
			(end 0.7874 0.4064)
			(stroke
				(width 0.1524)
				(type default)
			)
			(layer "B.SilkS")
		)
		(fp_line
			(start 0.7874 0.4064)
			(end 0.7874 -0.4064)
			(stroke
				(width 0.1524)
				(type default)
			)
			(layer "B.SilkS")
		)
		(fp_line
			(start -0.7874 -0.4064)
			(end -0.7874 0.4064)
			(stroke
				(width 0.1524)
				(type default)
			)
			(layer "B.SilkS")
		)
		(fp_line
			(start 0.7874 -0.4064)
			(end -0.7874 -0.4064)
			(stroke
				(width 0.1524)
				(type default)
			)
			(layer "B.SilkS")
		)
		(fp_line
			(start -0.67945 0.3048)
			(end -0.120396 0.3048)
			(stroke
				(width 0.1)
				(type default)
			)
			(layer "B.Fab")
		)
		(fp_line
			(start -0.120396 0.3048)
			(end -0.120396 0.2794)
			(stroke
				(width 0.1)
				(type default)
			)
			(layer "B.Fab")
		)
		(fp_line
			(start 0.12065 0.3048)
			(end 0.67945 0.3048)
			(stroke
				(width 0.1)
				(type default)
			)
			(layer "B.Fab")
		)
		(fp_line
			(start 0.67945 0.3048)
			(end 0.67945 -0.305054)
			(stroke
				(width 0.1)
				(type default)
			)
			(layer "B.Fab")
		)
		(fp_line
			(start -0.120396 0.2794)
			(end 0.12065 0.2794)
			(stroke
				(width 0.1)
				(type default)
			)
			(layer "B.Fab")
		)
		(fp_line
			(start 0.12065 0.2794)
			(end 0.12065 0.3048)
			(stroke
				(width 0.1)
				(type default)
			)
			(layer "B.Fab")
		)
		(fp_line
			(start -0.12065 -0.2794)
			(end -0.12065 -0.3048)
			(stroke
				(width 0.1)
				(type default)
			)
			(layer "B.Fab")
		)
		(fp_line
			(start 0.12065 -0.2794)
			(end -0.12065 -0.2794)
			(stroke
				(width 0.1)
				(type default)
			)
			(layer "B.Fab")
		)
		(fp_line
			(start -0.67945 -0.3048)
			(end -0.67945 0.3048)
			(stroke
				(width 0.1)
				(type default)
			)
			(layer "B.Fab")
		)
		(fp_line
			(start -0.12065 -0.3048)
			(end -0.67945 -0.3048)
			(stroke
				(width 0.1)
				(type default)
			)
			(layer "B.Fab")
		)
		(fp_line
			(start 0.12065 -0.305054)
			(end 0.12065 -0.2794)
			(stroke
				(width 0.1)
				(type default)
			)
			(layer "B.Fab")
		)
		(fp_line
			(start 0.67945 -0.305054)
			(end 0.12065 -0.305054)
			(stroke
				(width 0.1)
				(type default)
			)
			(layer "B.Fab")
		)
		(pad "1" smd circle
			(at 0.40005 0 90)
			(size 0 0)
			(layers "B.Cu" "B.Mask" "B.Paste")
			(net "P0V8_SERDES_VDDA_PEX2")
		)
		(pad "2" smd circle
			(at -0.40005 0 90)
			(size 0 0)
			(layers "B.Cu" "B.Mask" "B.Paste")
			(net "P0V8_SERDES_VDDA_PEX2_C5")
		)
	)
	(footprint ""
		(layer "B.Cu")
		(at 344.784172 -277.644352 180)
		(property "Reference" "PC6615"
			(at 0 0 0)
			(layer "B.SilkS")
			(hide yes)
			(effects
				(font
					(size 1.27 1.27)
				)
				(justify mirror)
			)
		)
		(property "Value" ""
			(at 0 0 0)
			(layer "B.Fab")
			(effects
				(font
					(size 1.27 1.27)
				)
				(justify mirror)
			)
		)
		(duplicate_pad_numbers_are_jumpers no)
		(fp_line
			(start 1.524 0.762)
			(end 1.524 -0.762)
			(stroke
				(width 0.1524)
				(type default)
			)
			(layer "B.SilkS")
		)
		(fp_line
			(start 1.524 -0.762)
			(end -1.524 -0.762)
			(stroke
				(width 0.1524)
				(type default)
			)
			(layer "B.SilkS")
		)
		(fp_line
			(start -1.524 0.762)
			(end 1.524 0.762)
			(stroke
				(width 0.1524)
				(type default)
			)
			(layer "B.SilkS")
		)
		(fp_line
			(start -1.524 -0.762)
			(end -1.524 0.762)
			(stroke
				(width 0.1524)
				(type default)
			)
			(layer "B.SilkS")
		)
		(fp_line
			(start 1.1049 0.724916)
			(end -1.1049 0.724916)
			(stroke
				(width 0.1)
				(type default)
			)
			(layer "B.Fab")
		)
		(fp_line
			(start 1.1049 -0.724916)
			(end 1.1049 0.724916)
			(stroke
				(width 0.1)
				(type default)
			)
			(layer "B.Fab")
		)
		(fp_line
			(start -1.1049 0.724916)
			(end -1.1049 -0.724916)
			(stroke
				(width 0.1)
				(type default)
			)
			(layer "B.Fab")
		)
		(fp_line
			(start -1.1049 -0.724916)
			(end 1.1049 -0.724916)
			(stroke
				(width 0.1)
				(type default)
			)
			(layer "B.Fab")
		)
		(pad "1" smd rect
			(at 0.889 0 180)
			(size 1.016 1.27)
			(layers "B.Cu" "B.Mask" "B.Paste")
			(net "SW_P12V_P0V8_PEX2_FLT")
		)
		(pad "2" smd rect
			(at -0.889 0 180)
			(size 1.016 1.27)
			(layers "B.Cu" "B.Mask" "B.Paste")
			(net "GND")
		)
	)
	(footprint ""
		(layer "B.Cu")
		(at 449.83781 -279.694386)
		(property "Reference" "C4388"
			(at 0 0 0)
			(layer "B.SilkS")
			(hide yes)
			(effects
				(font
					(size 1.27 1.27)
				)
				(justify mirror)
			)
		)
		(property "Value" ""
			(at 0 0 0)
			(layer "B.Fab")
			(effects
				(font
					(size 1.27 1.27)
				)
				(justify mirror)
			)
		)
		(duplicate_pad_numbers_are_jumpers no)
		(fp_line
			(start -1.2954 -0.5842)
			(end -1.2954 0.5842)
			(stroke
				(width 0.1524)
				(type default)
			)
			(layer "B.SilkS")
		)
		(fp_line
			(start -1.2954 0.5842)
			(end 1.2954 0.5842)
			(stroke
				(width 0.1524)
				(type default)
			)
			(layer "B.SilkS")
		)
		(fp_line
			(start 1.2954 -0.5842)
			(end -1.2954 -0.5842)
			(stroke
				(width 0.1524)
				(type default)
			)
			(layer "B.SilkS")
		)
		(fp_line
			(start 1.2954 0.5842)
			(end 1.2954 -0.5842)
			(stroke
				(width 0.1524)
				(type default)
			)
			(layer "B.SilkS")
		)
		(fp_line
			(start -1.1938 -0.4064)
			(end -1.1938 0.4064)
			(stroke
				(width 0.1)
				(type default)
			)
			(layer "B.Fab")
		)
		(fp_line
			(start -1.1938 0.4064)
			(end -0.8636 0.4064)
			(stroke
				(width 0.1)
				(type default)
			)
			(layer "B.Fab")
		)
		(fp_line
			(start -0.8636 -0.4572)
			(end -0.8636 -0.4064)
			(stroke
				(width 0.1)
				(type default)
			)
			(layer "B.Fab")
		)
		(fp_line
			(start -0.8636 -0.4064)
			(end -1.1938 -0.4064)
			(stroke
				(width 0.1)
				(type default)
			)
			(layer "B.Fab")
		)
		(fp_line
			(start -0.8636 0.4064)
			(end -0.8636 0.4572)
			(stroke
				(width 0.1)
				(type default)
			)
			(layer "B.Fab")
		)
		(fp_line
			(start -0.8636 0.4572)
			(end 0.8636 0.4572)
			(stroke
				(width 0.1)
				(type default)
			)
			(layer "B.Fab")
		)
		(fp_line
			(start 0.8636 -0.4572)
			(end -0.8636 -0.4572)
			(stroke
				(width 0.1)
				(type default)
			)
			(layer "B.Fab")
		)
		(fp_line
			(start 0.8636 -0.4064)
			(end 0.8636 -0.4572)
			(stroke
				(width 0.1)
				(type default)
			)
			(layer "B.Fab")
		)
		(fp_line
			(start 0.8636 0.4064)
			(end 1.1938 0.4064)
			(stroke
				(width 0.1)
				(type default)
			)
			(layer "B.Fab")
		)
		(fp_line
			(start 0.8636 0.4572)
			(end 0.8636 0.4064)
			(stroke
				(width 0.1)
				(type default)
			)
			(layer "B.Fab")
		)
		(fp_line
			(start 1.1938 -0.4064)
			(end 0.8636 -0.4064)
			(stroke
				(width 0.1)
				(type default)
			)
			(layer "B.Fab")
		)
		(fp_line
			(start 1.1938 0.4064)
			(end 1.1938 -0.4064)
			(stroke
				(width 0.1)
				(type default)
			)
			(layer "B.Fab")
		)
		(pad "1" smd rect
			(at 0.7366 0 270)
			(size 0.7112 0.8128)
			(layers "B.Cu" "B.Mask" "B.Paste")
			(net "P1V25_PEX3")
		)
		(pad "2" smd rect
			(at -0.7366 0 270)
			(size 0.7112 0.8128)
			(layers "B.Cu" "B.Mask" "B.Paste")
			(net "GND")
		)
	)
	(footprint ""
		(layer "B.Cu")
		(at 361.913424 -308.613556 90)
		(property "Reference" "C4358"
			(at 0 0 90)
			(layer "B.SilkS")
			(hide yes)
			(effects
				(font
					(size 1.27 1.27)
				)
				(justify mirror)
			)
		)
		(property "Value" ""
			(at 0 0 90)
			(layer "B.Fab")
			(effects
				(font
					(size 1.27 1.27)
				)
				(justify mirror)
			)
		)
		(duplicate_pad_numbers_are_jumpers no)
		(fp_line
			(start 1.2954 -0.5842)
			(end -1.2954 -0.5842)
			(stroke
				(width 0.1524)
				(type default)
			)
			(layer "B.SilkS")
		)
		(fp_line
			(start -1.2954 -0.5842)
			(end -1.2954 0.5842)
			(stroke
				(width 0.1524)
				(type default)
			)
			(layer "B.SilkS")
		)
		(fp_line
			(start 1.2954 0.5842)
			(end 1.2954 -0.5842)
			(stroke
				(width 0.1524)
				(type default)
			)
			(layer "B.SilkS")
		)
		(fp_line
			(start -1.2954 0.5842)
			(end 1.2954 0.5842)
			(stroke
				(width 0.1524)
				(type default)
			)
			(layer "B.SilkS")
		)
		(fp_line
			(start 0.8636 -0.4572)
			(end -0.8636 -0.4572)
			(stroke
				(width 0.1)
				(type default)
			)
			(layer "B.Fab")
		)
		(fp_line
			(start -0.8636 -0.4572)
			(end -0.8636 -0.4064)
			(stroke
				(width 0.1)
				(type default)
			)
			(layer "B.Fab")
		)
		(fp_line
			(start 1.1938 -0.4064)
			(end 0.8636 -0.4064)
			(stroke
				(width 0.1)
				(type default)
			)
			(layer "B.Fab")
		)
		(fp_line
			(start 0.8636 -0.4064)
			(end 0.8636 -0.4572)
			(stroke
				(width 0.1)
				(type default)
			)
			(layer "B.Fab")
		)
		(fp_line
			(start -0.8636 -0.4064)
			(end -1.1938 -0.4064)
			(stroke
				(width 0.1)
				(type default)
			)
			(layer "B.Fab")
		)
		(fp_line
			(start -1.1938 -0.4064)
			(end -1.1938 0.4064)
			(stroke
				(width 0.1)
				(type default)
			)
			(layer "B.Fab")
		)
		(fp_line
			(start 1.1938 0.4064)
			(end 1.1938 -0.4064)
			(stroke
				(width 0.1)
				(type default)
			)
			(layer "B.Fab")
		)
		(fp_line
			(start 0.8636 0.4064)
			(end 1.1938 0.4064)
			(stroke
				(width 0.1)
				(type default)
			)
			(layer "B.Fab")
		)
		(fp_line
			(start -0.8636 0.4064)
			(end -0.8636 0.4572)
			(stroke
				(width 0.1)
				(type default)
			)
			(layer "B.Fab")
		)
		(fp_line
			(start -1.1938 0.4064)
			(end -0.8636 0.4064)
			(stroke
				(width 0.1)
				(type default)
			)
			(layer "B.Fab")
		)
		(fp_line
			(start 0.8636 0.4572)
			(end 0.8636 0.4064)
			(stroke
				(width 0.1)
				(type default)
			)
			(layer "B.Fab")
		)
		(fp_line
			(start -0.8636 0.4572)
			(end 0.8636 0.4572)
			(stroke
				(width 0.1)
				(type default)
			)
			(layer "B.Fab")
		)
		(pad "1" smd rect
			(at 0.7366 0)
			(size 0.7112 0.8128)
			(layers "B.Cu" "B.Mask" "B.Paste")
			(net "P0V8_PEX3")
		)
		(pad "2" smd rect
			(at -0.7366 0)
			(size 0.7112 0.8128)
			(layers "B.Cu" "B.Mask" "B.Paste")
			(net "GND")
		)
	)
	(footprint ""
		(layer "B.Cu")
		(at 159.88665 -459.44663)
		(property "Reference" "X78"
			(at 0.1778 -1.92913 0)
			(unlocked yes)
			(layer "B.SilkS")
			(effects
				(font
					(size 0.7874 0.5842)
					(thickness 0.1524)
				)
				(justify left mirror)
			)
		)
		(property "Value" ""
			(at 0 0 0)
			(layer "B.Fab")
			(effects
				(font
					(size 1.27 1.27)
				)
				(justify mirror)
			)
		)
		(property "Device Type" "TP_TDR_4P_FTS_MPKT4_H025P0200_IO_TP15_TP_TDR_4P_DIP"
			(at -1.30175 1.27 270)
			(unlocked yes)
			(layer "B.Fab")
			(hide yes)
			(effects
				(font
					(size 0.635 0.4064)
					(thickness 0.1524)
				)
				(justify mirror)
			)
		)
		(property "User Part Number" "TP15"
			(at -1.30175 1.27 270)
			(unlocked yes)
			(layer "Cmts.User")
			(hide yes)
			(effects
				(font
					(size 0.635 0.4064)
					(thickness 0.1524)
				)
				(justify mirror)
			)
		)
		(duplicate_pad_numbers_are_jumpers no)
		(fp_line
			(start -2.54 -1.27)
			(end 0 -1.27)
			(stroke
				(width 0.1524)
				(type default)
			)
			(layer "B.SilkS")
		)
		(fp_line
			(start -2.54 -1.1303)
			(end -2.54 -1.27)
			(stroke
				(width 0.1524)
				(type default)
			)
			(layer "B.SilkS")
		)
		(fp_line
			(start -2.54 1.4097)
			(end -2.54 1.1303)
			(stroke
				(width 0.1524)
				(type default)
			)
			(layer "B.SilkS")
		)
		(fp_line
			(start -2.54 3.81)
			(end -2.54 3.6703)
			(stroke
				(width 0.1524)
				(type default)
			)
			(layer "B.SilkS")
		)
		(fp_line
			(start 0 -1.27)
			(end 0 -0.635)
			(stroke
				(width 0.1524)
				(type default)
			)
			(layer "B.SilkS")
		)
		(fp_line
			(start 0 0.635)
			(end 0 1.905)
			(stroke
				(width 0.1524)
				(type default)
			)
			(layer "B.SilkS")
		)
		(fp_line
			(start 0 3.175)
			(end 0 3.81)
			(stroke
				(width 0.1524)
				(type default)
			)
			(layer "B.SilkS")
		)
		(fp_line
			(start 0 3.81)
			(end -2.54 3.81)
			(stroke
				(width 0.1524)
				(type default)
			)
			(layer "B.SilkS")
		)
		(fp_poly
			(pts
				(xy 0.761746 0) (xy 2.285746 -0.762) (xy 2.285746 0.762)
			)
			(stroke
				(width 0)
				(type default)
			)
			(fill yes)
			(layer "B.SilkS")
		)
		(fp_line
			(start -2.54 -1.27)
			(end 0 -1.27)
			(stroke
				(width 0.1)
				(type default)
			)
			(layer "B.Fab")
		)
		(fp_line
			(start -2.54 3.81)
			(end -2.54 -1.27)
			(stroke
				(width 0.1)
				(type default)
			)
			(layer "B.Fab")
		)
		(fp_line
			(start 0 -1.27)
			(end 0 3.81)
			(stroke
				(width 0.1)
				(type default)
			)
			(layer "B.Fab")
		)
		(fp_line
			(start 0 3.81)
			(end -2.54 3.81)
			(stroke
				(width 0.1)
				(type default)
			)
			(layer "B.Fab")
		)
		(fp_poly
			(pts
				(xy 0.761746 0) (xy 2.285746 -0.762) (xy 2.285746 0.762)
			)
			(stroke
				(width 0)
				(type default)
			)
			(fill yes)
			(layer "B.Fab")
		)
		(pad "1" thru_hole circle
			(at 0 0 180)
			(size 1.0033 1.0033)
			(drill 0.249936)
			(layers "*.Cu" "*.Mask")
			(remove_unused_layers no)
			(net "TDR_DIFF_100_IN6_DIP")
			(clearance 0.10795)
			(padstack
				(mode front_inner_back)
				(layer "Inner"
					(shape circle)
					(size 0.8001 0.8001)
					(clearance 0.1524)
				)
				(layer "B.Cu"
					(shape circle)
					(size 1.0033 1.0033)
					(thermal_gap 0.10795)
					(clearance 0.10795)
				)
			)
		)
		(pad "2" thru_hole circle
			(at -2.54 0 180)
			(size 1.9939 1.9939)
			(drill 0.249936)
			(layers "*.Cu" "*.Mask")
			(remove_unused_layers no)
			(net "COUPON_GND1")
			(clearance 0.10795)
			(padstack
				(mode front_inner_back)
				(layer "Inner"
					(shape circle)
					(size 0.8001 0.8001)
					(clearance 0.1524)
				)
				(layer "B.Cu"
					(shape circle)
					(size 1.9939 1.9939)
					(thermal_gap 0.10795)
					(clearance 0.10795)
				)
			)
		)
		(pad "3" thru_hole circle
			(at -2.54 2.54 180)
			(size 1.9939 1.9939)
			(drill 0.249936)
			(layers "*.Cu" "*.Mask")
			(remove_unused_layers no)
			(net "COUPON_GND1")
			(clearance 0.10795)
			(padstack
				(mode front_inner_back)
				(layer "Inner"
					(shape circle)
					(size 0.8001 0.8001)
					(clearance 0.1524)
				)
				(layer "B.Cu"
					(shape circle)
					(size 1.9939 1.9939)
					(thermal_gap 0.10795)
					(clearance 0.10795)
				)
			)
		)
		(pad "4" thru_hole circle
			(at 0 2.54 180)
			(size 1.0033 1.0033)
			(drill 0.249936)
			(layers "*.Cu" "*.Mask")
			(remove_unused_layers no)
			(net "TDR_DIFF_100_IN6_DIN")
			(clearance 0.10795)
			(padstack
				(mode front_inner_back)
				(layer "Inner"
					(shape circle)
					(size 0.8001 0.8001)
					(clearance 0.1524)
				)
				(layer "B.Cu"
					(shape circle)
					(size 1.0033 1.0033)
					(thermal_gap 0.10795)
					(clearance 0.10795)
				)
			)
		)
	)
	(footprint ""
		(layer "B.Cu")
		(at 56.007 -136.652 -90)
		(property "Reference" "R36"
			(at 0 0 90)
			(layer "B.SilkS")
			(hide yes)
			(effects
				(font
					(size 1.27 1.27)
				)
				(justify mirror)
			)
		)
		(property "Value" ""
			(at 0 0 90)
			(layer "B.Fab")
			(effects
				(font
					(size 1.27 1.27)
				)
				(justify mirror)
			)
		)
		(duplicate_pad_numbers_are_jumpers no)
		(fp_line
			(start -0.7874 0.4064)
			(end 0.7874 0.4064)
			(stroke
				(width 0.1524)
				(type default)
			)
			(layer "B.SilkS")
		)
		(fp_line
			(start 0.7874 0.4064)
			(end 0.7874 -0.4064)
			(stroke
				(width 0.1524)
				(type default)
			)
			(layer "B.SilkS")
		)
		(fp_line
			(start -0.7874 -0.4064)
			(end -0.7874 0.4064)
			(stroke
				(width 0.1524)
				(type default)
			)
			(layer "B.SilkS")
		)
		(fp_line
			(start 0.7874 -0.4064)
			(end -0.7874 -0.4064)
			(stroke
				(width 0.1524)
				(type default)
			)
			(layer "B.SilkS")
		)
		(fp_line
			(start -0.67945 0.3048)
			(end -0.120396 0.3048)
			(stroke
				(width 0.1)
				(type default)
			)
			(layer "B.Fab")
		)
		(fp_line
			(start -0.120396 0.3048)
			(end -0.120396 0.2794)
			(stroke
				(width 0.1)
				(type default)
			)
			(layer "B.Fab")
		)
		(fp_line
			(start 0.12065 0.3048)
			(end 0.67945 0.3048)
			(stroke
				(width 0.1)
				(type default)
			)
			(layer "B.Fab")
		)
		(fp_line
			(start 0.67945 0.3048)
			(end 0.67945 -0.305054)
			(stroke
				(width 0.1)
				(type default)
			)
			(layer "B.Fab")
		)
		(fp_line
			(start -0.120396 0.2794)
			(end 0.12065 0.2794)
			(stroke
				(width 0.1)
				(type default)
			)
			(layer "B.Fab")
		)
		(fp_line
			(start 0.12065 0.2794)
			(end 0.12065 0.3048)
			(stroke
				(width 0.1)
				(type default)
			)
			(layer "B.Fab")
		)
		(fp_line
			(start -0.12065 -0.2794)
			(end -0.12065 -0.3048)
			(stroke
				(width 0.1)
				(type default)
			)
			(layer "B.Fab")
		)
		(fp_line
			(start 0.12065 -0.2794)
			(end -0.12065 -0.2794)
			(stroke
				(width 0.1)
				(type default)
			)
			(layer "B.Fab")
		)
		(fp_line
			(start -0.67945 -0.3048)
			(end -0.67945 0.3048)
			(stroke
				(width 0.1)
				(type default)
			)
			(layer "B.Fab")
		)
		(fp_line
			(start -0.12065 -0.3048)
			(end -0.67945 -0.3048)
			(stroke
				(width 0.1)
				(type default)
			)
			(layer "B.Fab")
		)
		(fp_line
			(start 0.12065 -0.305054)
			(end 0.12065 -0.2794)
			(stroke
				(width 0.1)
				(type default)
			)
			(layer "B.Fab")
		)
		(fp_line
			(start 0.67945 -0.305054)
			(end 0.12065 -0.305054)
			(stroke
				(width 0.1)
				(type default)
			)
			(layer "B.Fab")
		)
		(pad "1" smd circle
			(at 0.40005 0 90)
			(size 0 0)
			(layers "B.Cu" "B.Mask" "B.Paste")
			(net "RST_SMB_NIC_MUX_R_N")
		)
		(pad "2" smd circle
			(at -0.40005 0 90)
			(size 0 0)
			(layers "B.Cu" "B.Mask" "B.Paste")
			(net "RST_SMB_NIC0_MUX_N")
		)
	)
	(footprint ""
		(layer "B.Cu")
		(at 49.24552 -296.37482)
		(property "Reference" "C1124"
			(at 0 0 0)
			(layer "B.SilkS")
			(hide yes)
			(effects
				(font
					(size 1.27 1.27)
				)
				(justify mirror)
			)
		)
		(property "Value" ""
			(at 0 0 0)
			(layer "B.Fab")
			(effects
				(font
					(size 1.27 1.27)
				)
				(justify mirror)
			)
		)
		(duplicate_pad_numbers_are_jumpers no)
		(fp_line
			(start -0.299974 -0.150114)
			(end -0.299974 0.150114)
			(stroke
				(width 0.1)
				(type default)
			)
			(layer "B.Fab")
		)
		(fp_line
			(start -0.299974 0.150114)
			(end 0.299974 0.150114)
			(stroke
				(width 0.1)
				(type default)
			)
			(layer "B.Fab")
		)
		(fp_line
			(start 0.299974 -0.150114)
			(end -0.299974 -0.150114)
			(stroke
				(width 0.1)
				(type default)
			)
			(layer "B.Fab")
		)
		(fp_line
			(start 0.299974 0.150114)
			(end 0.299974 -0.150114)
			(stroke
				(width 0.1)
				(type default)
			)
			(layer "B.Fab")
		)
		(pad "1" smd rect
			(at 0.2667 0 180)
			(size 0.3048 0.381)
			(layers "B.Cu" "B.Mask" "B.Paste")
			(net "P0V8_PEX0")
		)
		(pad "2" smd rect
			(at -0.2667 0 180)
			(size 0.3048 0.381)
			(layers "B.Cu" "B.Mask" "B.Paste")
			(net "GND")
		)
	)
	(footprint ""
		(layer "B.Cu")
		(at 57.749948 -288.299906 90)
		(property "Reference" "C2943"
			(at 0 0 90)
			(layer "B.SilkS")
			(hide yes)
			(effects
				(font
					(size 1.27 1.27)
				)
				(justify mirror)
			)
		)
		(property "Value" ""
			(at 0 0 90)
			(layer "B.Fab")
			(effects
				(font
					(size 1.27 1.27)
				)
				(justify mirror)
			)
		)
		(duplicate_pad_numbers_are_jumpers no)
		(fp_line
			(start 0.299974 -0.150114)
			(end -0.299974 -0.150114)
			(stroke
				(width 0.1)
				(type default)
			)
			(layer "B.Fab")
		)
		(fp_line
			(start -0.299974 -0.150114)
			(end -0.299974 0.150114)
			(stroke
				(width 0.1)
				(type default)
			)
			(layer "B.Fab")
		)
		(fp_line
			(start 0.299974 0.150114)
			(end 0.299974 -0.150114)
			(stroke
				(width 0.1)
				(type default)
			)
			(layer "B.Fab")
		)
		(fp_line
			(start -0.299974 0.150114)
			(end 0.299974 0.150114)
			(stroke
				(width 0.1)
				(type default)
			)
			(layer "B.Fab")
		)
		(pad "1" smd rect
			(at 0.2667 0 270)
			(size 0.3048 0.381)
			(layers "B.Cu" "B.Mask" "B.Paste")
			(net "P1V25_PEX0")
		)
		(pad "2" smd rect
			(at -0.2667 0 270)
			(size 0.3048 0.381)
			(layers "B.Cu" "B.Mask" "B.Paste")
			(net "GND")
		)
	)
	(footprint ""
		(layer "B.Cu")
		(at 24.496522 -226.535996 -90)
		(property "Reference" "R3439"
			(at 0 0 90)
			(layer "B.SilkS")
			(hide yes)
			(effects
				(font
					(size 1.27 1.27)
				)
				(justify mirror)
			)
		)
		(property "Value" ""
			(at 0 0 90)
			(layer "B.Fab")
			(effects
				(font
					(size 1.27 1.27)
				)
				(justify mirror)
			)
		)
		(duplicate_pad_numbers_are_jumpers no)
		(fp_line
			(start -0.7874 0.4064)
			(end 0.7874 0.4064)
			(stroke
				(width 0.1524)
				(type default)
			)
			(layer "B.SilkS")
		)
		(fp_line
			(start 0.7874 0.4064)
			(end 0.7874 -0.4064)
			(stroke
				(width 0.1524)
				(type default)
			)
			(layer "B.SilkS")
		)
		(fp_line
			(start -0.7874 -0.4064)
			(end -0.7874 0.4064)
			(stroke
				(width 0.1524)
				(type default)
			)
			(layer "B.SilkS")
		)
		(fp_line
			(start 0.7874 -0.4064)
			(end -0.7874 -0.4064)
			(stroke
				(width 0.1524)
				(type default)
			)
			(layer "B.SilkS")
		)
		(fp_line
			(start -0.67945 0.3048)
			(end -0.120396 0.3048)
			(stroke
				(width 0.1)
				(type default)
			)
			(layer "B.Fab")
		)
		(fp_line
			(start -0.120396 0.3048)
			(end -0.120396 0.2794)
			(stroke
				(width 0.1)
				(type default)
			)
			(layer "B.Fab")
		)
		(fp_line
			(start 0.12065 0.3048)
			(end 0.67945 0.3048)
			(stroke
				(width 0.1)
				(type default)
			)
			(layer "B.Fab")
		)
		(fp_line
			(start 0.67945 0.3048)
			(end 0.67945 -0.305054)
			(stroke
				(width 0.1)
				(type default)
			)
			(layer "B.Fab")
		)
		(fp_line
			(start -0.120396 0.2794)
			(end 0.12065 0.2794)
			(stroke
				(width 0.1)
				(type default)
			)
			(layer "B.Fab")
		)
		(fp_line
			(start 0.12065 0.2794)
			(end 0.12065 0.3048)
			(stroke
				(width 0.1)
				(type default)
			)
			(layer "B.Fab")
		)
		(fp_line
			(start -0.12065 -0.2794)
			(end -0.12065 -0.3048)
			(stroke
				(width 0.1)
				(type default)
			)
			(layer "B.Fab")
		)
		(fp_line
			(start 0.12065 -0.2794)
			(end -0.12065 -0.2794)
			(stroke
				(width 0.1)
				(type default)
			)
			(layer "B.Fab")
		)
		(fp_line
			(start -0.67945 -0.3048)
			(end -0.67945 0.3048)
			(stroke
				(width 0.1)
				(type default)
			)
			(layer "B.Fab")
		)
		(fp_line
			(start -0.12065 -0.3048)
			(end -0.67945 -0.3048)
			(stroke
				(width 0.1)
				(type default)
			)
			(layer "B.Fab")
		)
		(fp_line
			(start 0.12065 -0.305054)
			(end 0.12065 -0.2794)
			(stroke
				(width 0.1)
				(type default)
			)
			(layer "B.Fab")
		)
		(fp_line
			(start 0.67945 -0.305054)
			(end 0.12065 -0.305054)
			(stroke
				(width 0.1)
				(type default)
			)
			(layer "B.Fab")
		)
		(pad "1" smd circle
			(at 0.40005 0 90)
			(size 0 0)
			(layers "B.Cu" "B.Mask" "B.Paste")
			(net "P1V8_PEX")
		)
		(pad "2" smd circle
			(at -0.40005 0 90)
			(size 0 0)
			(layers "B.Cu" "B.Mask" "B.Paste")
			(net "SPI_PEX0_CS_MUX_R_N")
		)
	)
	(footprint ""
		(layer "B.Cu")
		(at 65.824862 -297.79976 90)
		(property "Reference" "C1125"
			(at 0 0 90)
			(layer "B.SilkS")
			(hide yes)
			(effects
				(font
					(size 1.27 1.27)
				)
				(justify mirror)
			)
		)
		(property "Value" ""
			(at 0 0 90)
			(layer "B.Fab")
			(effects
				(font
					(size 1.27 1.27)
				)
				(justify mirror)
			)
		)
		(duplicate_pad_numbers_are_jumpers no)
		(fp_line
			(start 0.299974 -0.150114)
			(end -0.299974 -0.150114)
			(stroke
				(width 0.1)
				(type default)
			)
			(layer "B.Fab")
		)
		(fp_line
			(start -0.299974 -0.150114)
			(end -0.299974 0.150114)
			(stroke
				(width 0.1)
				(type default)
			)
			(layer "B.Fab")
		)
		(fp_line
			(start 0.299974 0.150114)
			(end 0.299974 -0.150114)
			(stroke
				(width 0.1)
				(type default)
			)
			(layer "B.Fab")
		)
		(fp_line
			(start -0.299974 0.150114)
			(end 0.299974 0.150114)
			(stroke
				(width 0.1)
				(type default)
			)
			(layer "B.Fab")
		)
		(pad "1" smd rect
			(at 0.2667 0 270)
			(size 0.3048 0.381)
			(layers "B.Cu" "B.Mask" "B.Paste")
			(net "P0V8_PEX0")
		)
		(pad "2" smd rect
			(at -0.2667 0 270)
			(size 0.3048 0.381)
			(layers "B.Cu" "B.Mask" "B.Paste")
			(net "GND")
		)
	)
	(footprint ""
		(layer "B.Cu")
		(at 343.694004 -217.187018 -90)
		(property "Reference" "C2056"
			(at 0 0 90)
			(layer "B.SilkS")
			(hide yes)
			(effects
				(font
					(size 1.27 1.27)
				)
				(justify mirror)
			)
		)
		(property "Value" ""
			(at 0 0 90)
			(layer "B.Fab")
			(effects
				(font
					(size 1.27 1.27)
				)
				(justify mirror)
			)
		)
		(duplicate_pad_numbers_are_jumpers no)
		(fp_line
			(start -0.69215 0.2921)
			(end 0.69215 0.2921)
			(stroke
				(width 0.1524)
				(type default)
			)
			(layer "B.SilkS")
		)
		(fp_line
			(start 0.69215 0.2921)
			(end 0.69215 -0.2921)
			(stroke
				(width 0.1524)
				(type default)
			)
			(layer "B.SilkS")
		)
		(fp_line
			(start -0.69215 -0.2921)
			(end -0.69215 0.2921)
			(stroke
				(width 0.1524)
				(type default)
			)
			(layer "B.SilkS")
		)
		(fp_line
			(start 0.69215 -0.2921)
			(end -0.69215 -0.2921)
			(stroke
				(width 0.1524)
				(type default)
			)
			(layer "B.SilkS")
		)
		(fp_line
			(start -0.51435 0.2794)
			(end 0.51435 0.2794)
			(stroke
				(width 0.1)
				(type default)
			)
			(layer "B.Fab")
		)
		(fp_line
			(start 0.51435 0.2794)
			(end 0.51435 -0.2794)
			(stroke
				(width 0.1)
				(type default)
			)
			(layer "B.Fab")
		)
		(fp_line
			(start -0.51435 -0.2794)
			(end -0.51435 0.2794)
			(stroke
				(width 0.1)
				(type default)
			)
			(layer "B.Fab")
		)
		(fp_line
			(start 0.51435 -0.2794)
			(end -0.51435 -0.2794)
			(stroke
				(width 0.1)
				(type default)
			)
			(layer "B.Fab")
		)
		(pad "1" smd circle
			(at 0.40005 0 90)
			(size 0 0)
			(layers "B.Cu" "B.Mask" "B.Paste")
			(net "P3V3_FPGA_VCCIO2")
		)
		(pad "2" smd circle
			(at -0.40005 0 90)
			(size 0 0)
			(layers "B.Cu" "B.Mask" "B.Paste")
			(net "GND")
		)
		(zone
			(layer "B.Cu")
			(hatch none 0.5)
			(connect_pads
				(clearance 0)
			)
			(min_thickness 0.25)
			(keepout
				(tracks not_allowed)
				(vias allowed)
				(pads allowed)
				(copperpour not_allowed)
				(footprints allowed)
			)
			(placement
				(enabled no)
				(sheetname "")
			)
			(fill
				(thermal_gap 0.5)
				(thermal_bridge_width 0.5)
				(island_removal_mode 0)
			)
			(polygon
				(pts
					(xy 343.606374 -216.996518) (xy 343.548208 -217.087958) (xy 343.548208 -217.287348) (xy 343.606374 -217.377518)
					(xy 343.781634 -217.377518) (xy 343.840054 -217.287348) (xy 343.840054 -217.087958) (xy 343.781888 -216.996518)
				)
			)
		)
	)
	(footprint ""
		(layer "B.Cu")
		(at 130.15722 -319.420494 -90)
		(property "Reference" "R5787"
			(at 0 0 90)
			(layer "B.SilkS")
			(hide yes)
			(effects
				(font
					(size 1.27 1.27)
				)
				(justify mirror)
			)
		)
		(property "Value" ""
			(at 0 0 90)
			(layer "B.Fab")
			(effects
				(font
					(size 1.27 1.27)
				)
				(justify mirror)
			)
		)
		(duplicate_pad_numbers_are_jumpers no)
		(fp_line
			(start -2.576322 1.1303)
			(end 2.576322 1.1303)
			(stroke
				(width 0.1524)
				(type default)
			)
			(layer "B.SilkS")
		)
		(fp_line
			(start 2.576322 1.1303)
			(end 2.576322 -1.1303)
			(stroke
				(width 0.1524)
				(type default)
			)
			(layer "B.SilkS")
		)
		(fp_line
			(start -2.576322 -1.1303)
			(end -2.576322 1.1303)
			(stroke
				(width 0.1524)
				(type default)
			)
			(layer "B.SilkS")
		)
		(fp_line
			(start 2.576322 -1.1303)
			(end -2.576322 -1.1303)
			(stroke
				(width 0.1524)
				(type default)
			)
			(layer "B.SilkS")
		)
		(fp_line
			(start -1.649984 0.899922)
			(end -1.649984 -0.899922)
			(stroke
				(width 0.1)
				(type default)
			)
			(layer "B.Fab")
		)
		(fp_line
			(start 1.649984 0.899922)
			(end -1.649984 0.899922)
			(stroke
				(width 0.1)
				(type default)
			)
			(layer "B.Fab")
		)
		(fp_line
			(start -1.649984 -0.899922)
			(end 1.649984 -0.899922)
			(stroke
				(width 0.1)
				(type default)
			)
			(layer "B.Fab")
		)
		(fp_line
			(start 1.649984 -0.899922)
			(end 1.649984 0.899922)
			(stroke
				(width 0.1)
				(type default)
			)
			(layer "B.Fab")
		)
		(pad "1A" smd rect
			(at 1.700022 0 90)
			(size 1.4986 2.0066)
			(layers "B.Cu" "B.Mask" "B.Paste")
			(net "P0V8_PEX1")
		)
		(pad "1B" smd rect
			(at 1.077722 0 90)
			(size 0.254 0.508)
			(layers "B.Cu" "B.Mask" "B.Paste")
			(net "P0V8_PEX1")
		)
		(pad "2A" smd rect
			(at -1.700022 0 90)
			(size 1.4986 2.0066)
			(layers "B.Cu" "B.Mask" "B.Paste")
			(net "P0V8_SERDES_VDDA_PEX1")
		)
		(pad "2B" smd rect
			(at -1.077722 0 90)
			(size 0.254 0.508)
			(layers "B.Cu" "B.Mask" "B.Paste")
			(net "P0V8_SERDES_VDDA_PEX1")
		)
	)
	(footprint ""
		(layer "B.Cu")
		(at 397.85544 -151.9936)
		(property "Reference" "R324"
			(at 0 0 0)
			(layer "B.SilkS")
			(hide yes)
			(effects
				(font
					(size 1.27 1.27)
				)
				(justify mirror)
			)
		)
		(property "Value" ""
			(at 0 0 0)
			(layer "B.Fab")
			(effects
				(font
					(size 1.27 1.27)
				)
				(justify mirror)
			)
		)
		(duplicate_pad_numbers_are_jumpers no)
		(fp_line
			(start -0.7874 -0.4064)
			(end -0.7874 0.4064)
			(stroke
				(width 0.1524)
				(type default)
			)
			(layer "B.SilkS")
		)
		(fp_line
			(start -0.7874 0.4064)
			(end 0.7874 0.4064)
			(stroke
				(width 0.1524)
				(type default)
			)
			(layer "B.SilkS")
		)
		(fp_line
			(start 0.7874 -0.4064)
			(end -0.7874 -0.4064)
			(stroke
				(width 0.1524)
				(type default)
			)
			(layer "B.SilkS")
		)
		(fp_line
			(start 0.7874 0.4064)
			(end 0.7874 -0.4064)
			(stroke
				(width 0.1524)
				(type default)
			)
			(layer "B.SilkS")
		)
		(fp_line
			(start -0.67945 -0.3048)
			(end -0.67945 0.3048)
			(stroke
				(width 0.1)
				(type default)
			)
			(layer "B.Fab")
		)
		(fp_line
			(start -0.67945 0.3048)
			(end -0.120396 0.3048)
			(stroke
				(width 0.1)
				(type default)
			)
			(layer "B.Fab")
		)
		(fp_line
			(start -0.12065 -0.3048)
			(end -0.67945 -0.3048)
			(stroke
				(width 0.1)
				(type default)
			)
			(layer "B.Fab")
		)
		(fp_line
			(start -0.12065 -0.2794)
			(end -0.12065 -0.3048)
			(stroke
				(width 0.1)
				(type default)
			)
			(layer "B.Fab")
		)
		(fp_line
			(start -0.120396 0.2794)
			(end 0.12065 0.2794)
			(stroke
				(width 0.1)
				(type default)
			)
			(layer "B.Fab")
		)
		(fp_line
			(start -0.120396 0.3048)
			(end -0.120396 0.2794)
			(stroke
				(width 0.1)
				(type default)
			)
			(layer "B.Fab")
		)
		(fp_line
			(start 0.12065 -0.305054)
			(end 0.12065 -0.2794)
			(stroke
				(width 0.1)
				(type default)
			)
			(layer "B.Fab")
		)
		(fp_line
			(start 0.12065 -0.2794)
			(end -0.12065 -0.2794)
			(stroke
				(width 0.1)
				(type default)
			)
			(layer "B.Fab")
		)
		(fp_line
			(start 0.12065 0.2794)
			(end 0.12065 0.3048)
			(stroke
				(width 0.1)
				(type default)
			)
			(layer "B.Fab")
		)
		(fp_line
			(start 0.12065 0.3048)
			(end 0.67945 0.3048)
			(stroke
				(width 0.1)
				(type default)
			)
			(layer "B.Fab")
		)
		(fp_line
			(start 0.67945 -0.305054)
			(end 0.12065 -0.305054)
			(stroke
				(width 0.1)
				(type default)
			)
			(layer "B.Fab")
		)
		(fp_line
			(start 0.67945 0.3048)
			(end 0.67945 -0.305054)
			(stroke
				(width 0.1)
				(type default)
			)
			(layer "B.Fab")
		)
		(pad "1" smd circle
			(at 0.40005 0 180)
			(size 0 0)
			(layers "B.Cu" "B.Mask" "B.Paste")
			(net "NCSI_NIC6_TXD0")
		)
		(pad "2" smd circle
			(at -0.40005 0 180)
			(size 0 0)
			(layers "B.Cu" "B.Mask" "B.Paste")
			(net "GND")
		)
	)
	(footprint ""
		(layer "B.Cu")
		(at 338.893912 -226.787202 -90)
		(property "Reference" "C2029"
			(at 0 0 90)
			(layer "B.SilkS")
			(hide yes)
			(effects
				(font
					(size 1.27 1.27)
				)
				(justify mirror)
			)
		)
		(property "Value" ""
			(at 0 0 90)
			(layer "B.Fab")
			(effects
				(font
					(size 1.27 1.27)
				)
				(justify mirror)
			)
		)
		(duplicate_pad_numbers_are_jumpers no)
		(fp_line
			(start -0.69215 0.2921)
			(end 0.69215 0.2921)
			(stroke
				(width 0.1524)
				(type default)
			)
			(layer "B.SilkS")
		)
		(fp_line
			(start 0.69215 0.2921)
			(end 0.69215 -0.2921)
			(stroke
				(width 0.1524)
				(type default)
			)
			(layer "B.SilkS")
		)
		(fp_line
			(start -0.69215 -0.2921)
			(end -0.69215 0.2921)
			(stroke
				(width 0.1524)
				(type default)
			)
			(layer "B.SilkS")
		)
		(fp_line
			(start 0.69215 -0.2921)
			(end -0.69215 -0.2921)
			(stroke
				(width 0.1524)
				(type default)
			)
			(layer "B.SilkS")
		)
		(fp_line
			(start -0.51435 0.2794)
			(end 0.51435 0.2794)
			(stroke
				(width 0.1)
				(type default)
			)
			(layer "B.Fab")
		)
		(fp_line
			(start 0.51435 0.2794)
			(end 0.51435 -0.2794)
			(stroke
				(width 0.1)
				(type default)
			)
			(layer "B.Fab")
		)
		(fp_line
			(start -0.51435 -0.2794)
			(end -0.51435 0.2794)
			(stroke
				(width 0.1)
				(type default)
			)
			(layer "B.Fab")
		)
		(fp_line
			(start 0.51435 -0.2794)
			(end -0.51435 -0.2794)
			(stroke
				(width 0.1)
				(type default)
			)
			(layer "B.Fab")
		)
		(pad "1" smd circle
			(at 0.40005 0 90)
			(size 0 0)
			(layers "B.Cu" "B.Mask" "B.Paste")
			(net "P3V3_FPGA_VCCIO0")
		)
		(pad "2" smd circle
			(at -0.40005 0 90)
			(size 0 0)
			(layers "B.Cu" "B.Mask" "B.Paste")
			(net "GND")
		)
		(zone
			(layer "B.Cu")
			(hatch none 0.5)
			(connect_pads
				(clearance 0)
			)
			(min_thickness 0.25)
			(keepout
				(tracks not_allowed)
				(vias allowed)
				(pads allowed)
				(copperpour not_allowed)
				(footprints allowed)
			)
			(placement
				(enabled no)
				(sheetname "")
			)
			(fill
				(thermal_gap 0.5)
				(thermal_bridge_width 0.5)
				(island_removal_mode 0)
			)
			(polygon
				(pts
					(xy 338.806282 -226.596702) (xy 338.748116 -226.688142) (xy 338.748116 -226.887532) (xy 338.806282 -226.977702)
					(xy 338.981542 -226.977702) (xy 339.039962 -226.887532) (xy 339.039962 -226.688142) (xy 338.981796 -226.596702)
				)
			)
		)
	)
	(footprint ""
		(layer "B.Cu")
		(at 373.035322 -247.441974 180)
		(property "Reference" "U103"
			(at 0.169926 2.10058 0)
			(unlocked yes)
			(layer "B.SilkS")
			(effects
				(font
					(size 0.7874 0.5842)
					(thickness 0.1524)
				)
				(justify mirror)
			)
		)
		(property "Value" ""
			(at 0 0 0)
			(layer "B.Fab")
			(effects
				(font
					(size 1.27 1.27)
				)
				(justify mirror)
			)
		)
		(duplicate_pad_numbers_are_jumpers no)
		(fp_line
			(start 1.7272 1.1176)
			(end 1.7272 -1.1176)
			(stroke
				(width 0.1524)
				(type default)
			)
			(layer "B.SilkS")
		)
		(fp_line
			(start 0.254 -1.1176)
			(end 1.7272 -1.1176)
			(stroke
				(width 0.1524)
				(type default)
			)
			(layer "B.SilkS")
		)
		(fp_line
			(start 0 -0.7366)
			(end 0.254 -1.1176)
			(stroke
				(width 0.1524)
				(type default)
			)
			(layer "B.SilkS")
		)
		(fp_line
			(start -0.254 -1.1176)
			(end 0 -0.7366)
			(stroke
				(width 0.1524)
				(type default)
			)
			(layer "B.SilkS")
		)
		(fp_line
			(start -1.7272 1.1176)
			(end 1.7272 1.1176)
			(stroke
				(width 0.1524)
				(type default)
			)
			(layer "B.SilkS")
		)
		(fp_line
			(start -1.7272 -1.1176)
			(end -0.254 -1.1176)
			(stroke
				(width 0.1524)
				(type default)
			)
			(layer "B.SilkS")
		)
		(fp_line
			(start -1.7272 -1.1176)
			(end -1.7272 1.1176)
			(stroke
				(width 0.1524)
				(type default)
			)
			(layer "B.SilkS")
		)
		(fp_poly
			(pts
				(xy 1.9558 -0.649986) (xy 2.7178 -0.268986) (xy 2.7178 -1.030986)
			)
			(stroke
				(width 0)
				(type default)
			)
			(fill yes)
			(layer "B.SilkS")
		)
		(fp_line
			(start 1.5748 1.1176)
			(end -1.5748 1.1176)
			(stroke
				(width 0.1)
				(type default)
			)
			(layer "B.Fab")
		)
		(fp_line
			(start 1.5748 -1.1176)
			(end 1.5748 1.1176)
			(stroke
				(width 0.1)
				(type default)
			)
			(layer "B.Fab")
		)
		(fp_line
			(start -1.5748 1.1176)
			(end -1.5748 -1.1176)
			(stroke
				(width 0.1)
				(type default)
			)
			(layer "B.Fab")
		)
		(fp_line
			(start -1.5748 -1.1176)
			(end 1.5748 -1.1176)
			(stroke
				(width 0.1)
				(type default)
			)
			(layer "B.Fab")
		)
		(fp_poly
			(pts
				(xy 1.9558 -0.649986) (xy 2.7178 -0.268986) (xy 2.7178 -1.030986)
			)
			(stroke
				(width 0)
				(type default)
			)
			(fill yes)
			(layer "B.Fab")
		)
		(pad "1" smd rect
			(at 0.999998 -0.649986 90)
			(size 0.3556 1.1176)
			(layers "B.Cu" "B.Mask" "B.Paste")
			(net "UART_PEX2_SDB_R_TX")
		)
		(pad "2" smd rect
			(at 0.999998 0 90)
			(size 0.3556 1.1176)
			(layers "B.Cu" "B.Mask" "B.Paste")
			(net "GND")
		)
		(pad "3" smd rect
			(at 0.999998 0.649986 90)
			(size 0.3556 1.1176)
			(layers "B.Cu" "B.Mask" "B.Paste")
			(net "UART_PEX3_SDB_R_TX")
		)
		(pad "4" smd rect
			(at -0.999998 0.649986 90)
			(size 0.3556 1.1176)
			(layers "B.Cu" "B.Mask" "B.Paste")
			(net "UART_PEX3_SDB_BUF_R_TX")
		)
		(pad "5" smd rect
			(at -0.999998 0 90)
			(size 0.3556 1.1176)
			(layers "B.Cu" "B.Mask" "B.Paste")
			(net "P1V8_PEX")
		)
		(pad "6" smd rect
			(at -0.999998 -0.649986 90)
			(size 0.3556 1.1176)
			(layers "B.Cu" "B.Mask" "B.Paste")
			(net "UART_PEX2_SDB_BUF_R_TX")
		)
	)
	(footprint ""
		(layer "B.Cu")
		(at 232.959402 -447.691764)
		(property "Reference" "X80"
			(at 0.1778 -1.92913 0)
			(unlocked yes)
			(layer "B.SilkS")
			(effects
				(font
					(size 0.7874 0.5842)
					(thickness 0.1524)
				)
				(justify left mirror)
			)
		)
		(property "Value" ""
			(at 0 0 0)
			(layer "B.Fab")
			(effects
				(font
					(size 1.27 1.27)
				)
				(justify mirror)
			)
		)
		(property "Device Type" "TP_TDR_4P_FTS_MPKT4_H025P0200_IO_TP15_TP_TDR_4P_DIP"
			(at -1.30175 1.27 270)
			(unlocked yes)
			(layer "B.Fab")
			(hide yes)
			(effects
				(font
					(size 0.635 0.4064)
					(thickness 0.1524)
				)
				(justify mirror)
			)
		)
		(property "User Part Number" "TP15"
			(at -1.30175 1.27 270)
			(unlocked yes)
			(layer "Cmts.User")
			(hide yes)
			(effects
				(font
					(size 0.635 0.4064)
					(thickness 0.1524)
				)
				(justify mirror)
			)
		)
		(duplicate_pad_numbers_are_jumpers no)
		(fp_line
			(start -2.54 -1.27)
			(end 0 -1.27)
			(stroke
				(width 0.1524)
				(type default)
			)
			(layer "B.SilkS")
		)
		(fp_line
			(start -2.54 -1.1303)
			(end -2.54 -1.27)
			(stroke
				(width 0.1524)
				(type default)
			)
			(layer "B.SilkS")
		)
		(fp_line
			(start -2.54 1.4097)
			(end -2.54 1.1303)
			(stroke
				(width 0.1524)
				(type default)
			)
			(layer "B.SilkS")
		)
		(fp_line
			(start -2.54 3.81)
			(end -2.54 3.6703)
			(stroke
				(width 0.1524)
				(type default)
			)
			(layer "B.SilkS")
		)
		(fp_line
			(start 0 -1.27)
			(end 0 -0.635)
			(stroke
				(width 0.1524)
				(type default)
			)
			(layer "B.SilkS")
		)
		(fp_line
			(start 0 0.635)
			(end 0 1.905)
			(stroke
				(width 0.1524)
				(type default)
			)
			(layer "B.SilkS")
		)
		(fp_line
			(start 0 3.175)
			(end 0 3.81)
			(stroke
				(width 0.1524)
				(type default)
			)
			(layer "B.SilkS")
		)
		(fp_line
			(start 0 3.81)
			(end -2.54 3.81)
			(stroke
				(width 0.1524)
				(type default)
			)
			(layer "B.SilkS")
		)
		(fp_poly
			(pts
				(xy 0.761746 0) (xy 2.285746 -0.762) (xy 2.285746 0.762)
			)
			(stroke
				(width 0)
				(type default)
			)
			(fill yes)
			(layer "B.SilkS")
		)
		(fp_line
			(start -2.54 -1.27)
			(end 0 -1.27)
			(stroke
				(width 0.1)
				(type default)
			)
			(layer "B.Fab")
		)
		(fp_line
			(start -2.54 3.81)
			(end -2.54 -1.27)
			(stroke
				(width 0.1)
				(type default)
			)
			(layer "B.Fab")
		)
		(fp_line
			(start 0 -1.27)
			(end 0 3.81)
			(stroke
				(width 0.1)
				(type default)
			)
			(layer "B.Fab")
		)
		(fp_line
			(start 0 3.81)
			(end -2.54 3.81)
			(stroke
				(width 0.1)
				(type default)
			)
			(layer "B.Fab")
		)
		(fp_poly
			(pts
				(xy 0.761746 0) (xy 2.285746 -0.762) (xy 2.285746 0.762)
			)
			(stroke
				(width 0)
				(type default)
			)
			(fill yes)
			(layer "B.Fab")
		)
		(pad "1" thru_hole circle
			(at 0 0 180)
			(size 1.0033 1.0033)
			(drill 0.249936)
			(layers "*.Cu" "*.Mask")
			(remove_unused_layers no)
			(net "TDR_DIFF_100_BOT_DIP")
			(clearance 0.10795)
			(padstack
				(mode front_inner_back)
				(layer "Inner"
					(shape circle)
					(size 0.8001 0.8001)
					(clearance 0.1524)
				)
				(layer "B.Cu"
					(shape circle)
					(size 1.0033 1.0033)
					(thermal_gap 0.10795)
					(clearance 0.10795)
				)
			)
		)
		(pad "2" thru_hole circle
			(at -2.54 0 180)
			(size 1.9939 1.9939)
			(drill 0.249936)
			(layers "*.Cu" "*.Mask")
			(remove_unused_layers no)
			(net "COUPON_GND1")
			(clearance 0.10795)
			(padstack
				(mode front_inner_back)
				(layer "Inner"
					(shape circle)
					(size 0.8001 0.8001)
					(clearance 0.1524)
				)
				(layer "B.Cu"
					(shape circle)
					(size 1.9939 1.9939)
					(thermal_gap 0.10795)
					(clearance 0.10795)
				)
			)
		)
		(pad "3" thru_hole circle
			(at -2.54 2.54 180)
			(size 1.9939 1.9939)
			(drill 0.249936)
			(layers "*.Cu" "*.Mask")
			(remove_unused_layers no)
			(net "COUPON_GND1")
			(clearance 0.10795)
			(padstack
				(mode front_inner_back)
				(layer "Inner"
					(shape circle)
					(size 0.8001 0.8001)
					(clearance 0.1524)
				)
				(layer "B.Cu"
					(shape circle)
					(size 1.9939 1.9939)
					(thermal_gap 0.10795)
					(clearance 0.10795)
				)
			)
		)
		(pad "4" thru_hole circle
			(at 0 2.54 180)
			(size 1.0033 1.0033)
			(drill 0.249936)
			(layers "*.Cu" "*.Mask")
			(remove_unused_layers no)
			(net "TDR_DIFF_100_BOT_DIN")
			(clearance 0.10795)
			(padstack
				(mode front_inner_back)
				(layer "Inner"
					(shape circle)
					(size 0.8001 0.8001)
					(clearance 0.1524)
				)
				(layer "B.Cu"
					(shape circle)
					(size 1.0033 1.0033)
					(thermal_gap 0.10795)
					(clearance 0.10795)
				)
			)
		)
	)
	(footprint ""
		(layer "B.Cu")
		(at 284.249876 -303.499774 -90)
		(property "Reference" "C3252"
			(at 0 0 90)
			(layer "B.SilkS")
			(hide yes)
			(effects
				(font
					(size 1.27 1.27)
				)
				(justify mirror)
			)
		)
		(property "Value" ""
			(at 0 0 90)
			(layer "B.Fab")
			(effects
				(font
					(size 1.27 1.27)
				)
				(justify mirror)
			)
		)
		(duplicate_pad_numbers_are_jumpers no)
		(fp_line
			(start -0.299974 0.150114)
			(end 0.299974 0.150114)
			(stroke
				(width 0.1)
				(type default)
			)
			(layer "B.Fab")
		)
		(fp_line
			(start 0.299974 0.150114)
			(end 0.299974 -0.150114)
			(stroke
				(width 0.1)
				(type default)
			)
			(layer "B.Fab")
		)
		(fp_line
			(start -0.299974 -0.150114)
			(end -0.299974 0.150114)
			(stroke
				(width 0.1)
				(type default)
			)
			(layer "B.Fab")
		)
		(fp_line
			(start 0.299974 -0.150114)
			(end -0.299974 -0.150114)
			(stroke
				(width 0.1)
				(type default)
			)
			(layer "B.Fab")
		)
		(pad "1" smd rect
			(at 0.2667 0 90)
			(size 0.3048 0.381)
			(layers "B.Cu" "B.Mask" "B.Paste")
			(net "P1V25_PEX2")
		)
		(pad "2" smd rect
			(at -0.2667 0 90)
			(size 0.3048 0.381)
			(layers "B.Cu" "B.Mask" "B.Paste")
			(net "GND")
		)
	)
	(footprint ""
		(layer "B.Cu")
		(at 400.349974 -303.499774 -90)
		(property "Reference" "C3433"
			(at 0 0 90)
			(layer "B.SilkS")
			(hide yes)
			(effects
				(font
					(size 1.27 1.27)
				)
				(justify mirror)
			)
		)
		(property "Value" ""
			(at 0 0 90)
			(layer "B.Fab")
			(effects
				(font
					(size 1.27 1.27)
				)
				(justify mirror)
			)
		)
		(duplicate_pad_numbers_are_jumpers no)
		(fp_line
			(start -0.299974 0.150114)
			(end 0.299974 0.150114)
			(stroke
				(width 0.1)
				(type default)
			)
			(layer "B.Fab")
		)
		(fp_line
			(start 0.299974 0.150114)
			(end 0.299974 -0.150114)
			(stroke
				(width 0.1)
				(type default)
			)
			(layer "B.Fab")
		)
		(fp_line
			(start -0.299974 -0.150114)
			(end -0.299974 0.150114)
			(stroke
				(width 0.1)
				(type default)
			)
			(layer "B.Fab")
		)
		(fp_line
			(start 0.299974 -0.150114)
			(end -0.299974 -0.150114)
			(stroke
				(width 0.1)
				(type default)
			)
			(layer "B.Fab")
		)
		(pad "1" smd rect
			(at 0.2667 0 90)
			(size 0.3048 0.381)
			(layers "B.Cu" "B.Mask" "B.Paste")
			(net "P1V25_PEX3")
		)
		(pad "2" smd rect
			(at -0.2667 0 90)
			(size 0.3048 0.381)
			(layers "B.Cu" "B.Mask" "B.Paste")
			(net "GND")
		)
	)
	(footprint ""
		(layer "B.Cu")
		(at 399.445734 -296.37482)
		(property "Reference" "C1874"
			(at 0 0 0)
			(layer "B.SilkS")
			(hide yes)
			(effects
				(font
					(size 1.27 1.27)
				)
				(justify mirror)
			)
		)
		(property "Value" ""
			(at 0 0 0)
			(layer "B.Fab")
			(effects
				(font
					(size 1.27 1.27)
				)
				(justify mirror)
			)
		)
		(duplicate_pad_numbers_are_jumpers no)
		(fp_line
			(start -0.299974 -0.150114)
			(end -0.299974 0.150114)
			(stroke
				(width 0.1)
				(type default)
			)
			(layer "B.Fab")
		)
		(fp_line
			(start -0.299974 0.150114)
			(end 0.299974 0.150114)
			(stroke
				(width 0.1)
				(type default)
			)
			(layer "B.Fab")
		)
		(fp_line
			(start 0.299974 -0.150114)
			(end -0.299974 -0.150114)
			(stroke
				(width 0.1)
				(type default)
			)
			(layer "B.Fab")
		)
		(fp_line
			(start 0.299974 0.150114)
			(end 0.299974 -0.150114)
			(stroke
				(width 0.1)
				(type default)
			)
			(layer "B.Fab")
		)
		(pad "1" smd rect
			(at 0.2667 0 180)
			(size 0.3048 0.381)
			(layers "B.Cu" "B.Mask" "B.Paste")
			(net "P0V8_PEX3")
		)
		(pad "2" smd rect
			(at -0.2667 0 180)
			(size 0.3048 0.381)
			(layers "B.Cu" "B.Mask" "B.Paste")
			(net "GND")
		)
	)
	(footprint ""
		(layer "B.Cu")
		(at 172.106844 -136.652 -90)
		(property "Reference" "R138"
			(at 0 0 90)
			(layer "B.SilkS")
			(hide yes)
			(effects
				(font
					(size 1.27 1.27)
				)
				(justify mirror)
			)
		)
		(property "Value" ""
			(at 0 0 90)
			(layer "B.Fab")
			(effects
				(font
					(size 1.27 1.27)
				)
				(justify mirror)
			)
		)
		(duplicate_pad_numbers_are_jumpers no)
		(fp_line
			(start -0.7874 0.4064)
			(end 0.7874 0.4064)
			(stroke
				(width 0.1524)
				(type default)
			)
			(layer "B.SilkS")
		)
		(fp_line
			(start 0.7874 0.4064)
			(end 0.7874 -0.4064)
			(stroke
				(width 0.1524)
				(type default)
			)
			(layer "B.SilkS")
		)
		(fp_line
			(start -0.7874 -0.4064)
			(end -0.7874 0.4064)
			(stroke
				(width 0.1524)
				(type default)
			)
			(layer "B.SilkS")
		)
		(fp_line
			(start 0.7874 -0.4064)
			(end -0.7874 -0.4064)
			(stroke
				(width 0.1524)
				(type default)
			)
			(layer "B.SilkS")
		)
		(fp_line
			(start -0.67945 0.3048)
			(end -0.120396 0.3048)
			(stroke
				(width 0.1)
				(type default)
			)
			(layer "B.Fab")
		)
		(fp_line
			(start -0.120396 0.3048)
			(end -0.120396 0.2794)
			(stroke
				(width 0.1)
				(type default)
			)
			(layer "B.Fab")
		)
		(fp_line
			(start 0.12065 0.3048)
			(end 0.67945 0.3048)
			(stroke
				(width 0.1)
				(type default)
			)
			(layer "B.Fab")
		)
		(fp_line
			(start 0.67945 0.3048)
			(end 0.67945 -0.305054)
			(stroke
				(width 0.1)
				(type default)
			)
			(layer "B.Fab")
		)
		(fp_line
			(start -0.120396 0.2794)
			(end 0.12065 0.2794)
			(stroke
				(width 0.1)
				(type default)
			)
			(layer "B.Fab")
		)
		(fp_line
			(start 0.12065 0.2794)
			(end 0.12065 0.3048)
			(stroke
				(width 0.1)
				(type default)
			)
			(layer "B.Fab")
		)
		(fp_line
			(start -0.12065 -0.2794)
			(end -0.12065 -0.3048)
			(stroke
				(width 0.1)
				(type default)
			)
			(layer "B.Fab")
		)
		(fp_line
			(start 0.12065 -0.2794)
			(end -0.12065 -0.2794)
			(stroke
				(width 0.1)
				(type default)
			)
			(layer "B.Fab")
		)
		(fp_line
			(start -0.67945 -0.3048)
			(end -0.67945 0.3048)
			(stroke
				(width 0.1)
				(type default)
			)
			(layer "B.Fab")
		)
		(fp_line
			(start -0.12065 -0.3048)
			(end -0.67945 -0.3048)
			(stroke
				(width 0.1)
				(type default)
			)
			(layer "B.Fab")
		)
		(fp_line
			(start 0.12065 -0.305054)
			(end 0.12065 -0.2794)
			(stroke
				(width 0.1)
				(type default)
			)
			(layer "B.Fab")
		)
		(fp_line
			(start 0.67945 -0.305054)
			(end 0.12065 -0.305054)
			(stroke
				(width 0.1)
				(type default)
			)
			(layer "B.Fab")
		)
		(pad "1" smd circle
			(at 0.40005 0 90)
			(size 0 0)
			(layers "B.Cu" "B.Mask" "B.Paste")
			(net "RST_SMB_NIC_MUX_R_N")
		)
		(pad "2" smd circle
			(at -0.40005 0 90)
			(size 0 0)
			(layers "B.Cu" "B.Mask" "B.Paste")
			(net "RST_SMB_NIC2_MUX_N")
		)
	)
	(footprint ""
		(layer "B.Cu")
		(at 301.349918 -296.37482 180)
		(property "Reference" "C1676"
			(at 0 0 0)
			(layer "B.SilkS")
			(hide yes)
			(effects
				(font
					(size 1.27 1.27)
				)
				(justify mirror)
			)
		)
		(property "Value" ""
			(at 0 0 0)
			(layer "B.Fab")
			(effects
				(font
					(size 1.27 1.27)
				)
				(justify mirror)
			)
		)
		(duplicate_pad_numbers_are_jumpers no)
		(fp_line
			(start 0.299974 0.150114)
			(end 0.299974 -0.150114)
			(stroke
				(width 0.1)
				(type default)
			)
			(layer "B.Fab")
		)
		(fp_line
			(start 0.299974 -0.150114)
			(end -0.299974 -0.150114)
			(stroke
				(width 0.1)
				(type default)
			)
			(layer "B.Fab")
		)
		(fp_line
			(start -0.299974 0.150114)
			(end 0.299974 0.150114)
			(stroke
				(width 0.1)
				(type default)
			)
			(layer "B.Fab")
		)
		(fp_line
			(start -0.299974 -0.150114)
			(end -0.299974 0.150114)
			(stroke
				(width 0.1)
				(type default)
			)
			(layer "B.Fab")
		)
		(pad "1" smd rect
			(at 0.2667 0)
			(size 0.3048 0.381)
			(layers "B.Cu" "B.Mask" "B.Paste")
			(net "P0V8_SERDES_VDDA_PEX2")
		)
		(pad "2" smd rect
			(at -0.2667 0)
			(size 0.3048 0.381)
			(layers "B.Cu" "B.Mask" "B.Paste")
			(net "GND")
		)
	)
	(footprint ""
		(layer "B.Cu")
		(at 235.530644 -231.225598 -90)
		(property "Reference" "R4528"
			(at 0 0 90)
			(layer "B.SilkS")
			(hide yes)
			(effects
				(font
					(size 1.27 1.27)
				)
				(justify mirror)
			)
		)
		(property "Value" ""
			(at 0 0 90)
			(layer "B.Fab")
			(effects
				(font
					(size 1.27 1.27)
				)
				(justify mirror)
			)
		)
		(duplicate_pad_numbers_are_jumpers no)
		(fp_line
			(start -0.7874 0.4064)
			(end 0.7874 0.4064)
			(stroke
				(width 0.1524)
				(type default)
			)
			(layer "B.SilkS")
		)
		(fp_line
			(start 0.7874 0.4064)
			(end 0.7874 -0.4064)
			(stroke
				(width 0.1524)
				(type default)
			)
			(layer "B.SilkS")
		)
		(fp_line
			(start -0.7874 -0.4064)
			(end -0.7874 0.4064)
			(stroke
				(width 0.1524)
				(type default)
			)
			(layer "B.SilkS")
		)
		(fp_line
			(start 0.7874 -0.4064)
			(end -0.7874 -0.4064)
			(stroke
				(width 0.1524)
				(type default)
			)
			(layer "B.SilkS")
		)
		(fp_line
			(start -0.67945 0.3048)
			(end -0.120396 0.3048)
			(stroke
				(width 0.1)
				(type default)
			)
			(layer "B.Fab")
		)
		(fp_line
			(start -0.120396 0.3048)
			(end -0.120396 0.2794)
			(stroke
				(width 0.1)
				(type default)
			)
			(layer "B.Fab")
		)
		(fp_line
			(start 0.12065 0.3048)
			(end 0.67945 0.3048)
			(stroke
				(width 0.1)
				(type default)
			)
			(layer "B.Fab")
		)
		(fp_line
			(start 0.67945 0.3048)
			(end 0.67945 -0.305054)
			(stroke
				(width 0.1)
				(type default)
			)
			(layer "B.Fab")
		)
		(fp_line
			(start -0.120396 0.2794)
			(end 0.12065 0.2794)
			(stroke
				(width 0.1)
				(type default)
			)
			(layer "B.Fab")
		)
		(fp_line
			(start 0.12065 0.2794)
			(end 0.12065 0.3048)
			(stroke
				(width 0.1)
				(type default)
			)
			(layer "B.Fab")
		)
		(fp_line
			(start -0.12065 -0.2794)
			(end -0.12065 -0.3048)
			(stroke
				(width 0.1)
				(type default)
			)
			(layer "B.Fab")
		)
		(fp_line
			(start 0.12065 -0.2794)
			(end -0.12065 -0.2794)
			(stroke
				(width 0.1)
				(type default)
			)
			(layer "B.Fab")
		)
		(fp_line
			(start -0.67945 -0.3048)
			(end -0.67945 0.3048)
			(stroke
				(width 0.1)
				(type default)
			)
			(layer "B.Fab")
		)
		(fp_line
			(start -0.12065 -0.3048)
			(end -0.67945 -0.3048)
			(stroke
				(width 0.1)
				(type default)
			)
			(layer "B.Fab")
		)
		(fp_line
			(start 0.12065 -0.305054)
			(end 0.12065 -0.2794)
			(stroke
				(width 0.1)
				(type default)
			)
			(layer "B.Fab")
		)
		(fp_line
			(start 0.67945 -0.305054)
			(end 0.12065 -0.305054)
			(stroke
				(width 0.1)
				(type default)
			)
			(layer "B.Fab")
		)
		(pad "1" smd circle
			(at 0.40005 0 90)
			(size 0 0)
			(layers "B.Cu" "B.Mask" "B.Paste")
			(net "SSD14_PWRDIS_BIC")
		)
		(pad "2" smd circle
			(at -0.40005 0 90)
			(size 0 0)
			(layers "B.Cu" "B.Mask" "B.Paste")
			(net "SSD14_PWRDIS_BIC_R")
		)
	)
	(footprint ""
		(layer "B.Cu")
		(at 64.399922 -299.699934 -90)
		(property "Reference" "C1210"
			(at 0 0 90)
			(layer "B.SilkS")
			(hide yes)
			(effects
				(font
					(size 1.27 1.27)
				)
				(justify mirror)
			)
		)
		(property "Value" ""
			(at 0 0 90)
			(layer "B.Fab")
			(effects
				(font
					(size 1.27 1.27)
				)
				(justify mirror)
			)
		)
		(duplicate_pad_numbers_are_jumpers no)
		(fp_line
			(start -0.299974 0.150114)
			(end 0.299974 0.150114)
			(stroke
				(width 0.1)
				(type default)
			)
			(layer "B.Fab")
		)
		(fp_line
			(start 0.299974 0.150114)
			(end 0.299974 -0.150114)
			(stroke
				(width 0.1)
				(type default)
			)
			(layer "B.Fab")
		)
		(fp_line
			(start -0.299974 -0.150114)
			(end -0.299974 0.150114)
			(stroke
				(width 0.1)
				(type default)
			)
			(layer "B.Fab")
		)
		(fp_line
			(start 0.299974 -0.150114)
			(end -0.299974 -0.150114)
			(stroke
				(width 0.1)
				(type default)
			)
			(layer "B.Fab")
		)
		(pad "1" smd rect
			(at 0.2667 0 90)
			(size 0.3048 0.381)
			(layers "B.Cu" "B.Mask" "B.Paste")
			(net "P0V8_SERDES_VDDA_PEX0")
		)
		(pad "2" smd rect
			(at -0.2667 0 90)
			(size 0.3048 0.381)
			(layers "B.Cu" "B.Mask" "B.Paste")
			(net "GND")
		)
	)
	(footprint ""
		(layer "B.Cu")
		(at 130.016504 -325.30923 -90)
		(property "Reference" "C4273"
			(at 0 0 90)
			(layer "B.SilkS")
			(hide yes)
			(effects
				(font
					(size 1.27 1.27)
				)
				(justify mirror)
			)
		)
		(property "Value" ""
			(at 0 0 90)
			(layer "B.Fab")
			(effects
				(font
					(size 1.27 1.27)
				)
				(justify mirror)
			)
		)
		(duplicate_pad_numbers_are_jumpers no)
		(fp_line
			(start -1.2954 0.5842)
			(end 1.2954 0.5842)
			(stroke
				(width 0.1524)
				(type default)
			)
			(layer "B.SilkS")
		)
		(fp_line
			(start 1.2954 0.5842)
			(end 1.2954 -0.5842)
			(stroke
				(width 0.1524)
				(type default)
			)
			(layer "B.SilkS")
		)
		(fp_line
			(start -1.2954 -0.5842)
			(end -1.2954 0.5842)
			(stroke
				(width 0.1524)
				(type default)
			)
			(layer "B.SilkS")
		)
		(fp_line
			(start 1.2954 -0.5842)
			(end -1.2954 -0.5842)
			(stroke
				(width 0.1524)
				(type default)
			)
			(layer "B.SilkS")
		)
		(fp_line
			(start -0.8636 0.4572)
			(end 0.8636 0.4572)
			(stroke
				(width 0.1)
				(type default)
			)
			(layer "B.Fab")
		)
		(fp_line
			(start 0.8636 0.4572)
			(end 0.8636 0.4064)
			(stroke
				(width 0.1)
				(type default)
			)
			(layer "B.Fab")
		)
		(fp_line
			(start -1.1938 0.4064)
			(end -0.8636 0.4064)
			(stroke
				(width 0.1)
				(type default)
			)
			(layer "B.Fab")
		)
		(fp_line
			(start -0.8636 0.4064)
			(end -0.8636 0.4572)
			(stroke
				(width 0.1)
				(type default)
			)
			(layer "B.Fab")
		)
		(fp_line
			(start 0.8636 0.4064)
			(end 1.1938 0.4064)
			(stroke
				(width 0.1)
				(type default)
			)
			(layer "B.Fab")
		)
		(fp_line
			(start 1.1938 0.4064)
			(end 1.1938 -0.4064)
			(stroke
				(width 0.1)
				(type default)
			)
			(layer "B.Fab")
		)
		(fp_line
			(start -1.1938 -0.4064)
			(end -1.1938 0.4064)
			(stroke
				(width 0.1)
				(type default)
			)
			(layer "B.Fab")
		)
		(fp_line
			(start -0.8636 -0.4064)
			(end -1.1938 -0.4064)
			(stroke
				(width 0.1)
				(type default)
			)
			(layer "B.Fab")
		)
		(fp_line
			(start 0.8636 -0.4064)
			(end 0.8636 -0.4572)
			(stroke
				(width 0.1)
				(type default)
			)
			(layer "B.Fab")
		)
		(fp_line
			(start 1.1938 -0.4064)
			(end 0.8636 -0.4064)
			(stroke
				(width 0.1)
				(type default)
			)
			(layer "B.Fab")
		)
		(fp_line
			(start -0.8636 -0.4572)
			(end -0.8636 -0.4064)
			(stroke
				(width 0.1)
				(type default)
			)
			(layer "B.Fab")
		)
		(fp_line
			(start 0.8636 -0.4572)
			(end -0.8636 -0.4572)
			(stroke
				(width 0.1)
				(type default)
			)
			(layer "B.Fab")
		)
		(pad "1" smd rect
			(at 0.7366 0 180)
			(size 0.7112 0.8128)
			(layers "B.Cu" "B.Mask" "B.Paste")
			(net "P0V8_SERDES_VDDA_PEX1_C11")
		)
		(pad "2" smd rect
			(at -0.7366 0 180)
			(size 0.7112 0.8128)
			(layers "B.Cu" "B.Mask" "B.Paste")
			(net "GND")
		)
	)
	(footprint ""
		(layer "B.Cu")
		(at 231.889046 -148.047202)
		(property "Reference" "C2787"
			(at 0 0 0)
			(layer "B.SilkS")
			(hide yes)
			(effects
				(font
					(size 1.27 1.27)
				)
				(justify mirror)
			)
		)
		(property "Value" ""
			(at 0 0 0)
			(layer "B.Fab")
			(effects
				(font
					(size 1.27 1.27)
				)
				(justify mirror)
			)
		)
		(duplicate_pad_numbers_are_jumpers no)
		(fp_line
			(start -0.7874 -0.4064)
			(end -0.7874 0.4064)
			(stroke
				(width 0.1524)
				(type default)
			)
			(layer "B.SilkS")
		)
		(fp_line
			(start -0.7874 0.4064)
			(end 0.7874 0.4064)
			(stroke
				(width 0.1524)
				(type default)
			)
			(layer "B.SilkS")
		)
		(fp_line
			(start 0.7874 -0.4064)
			(end -0.7874 -0.4064)
			(stroke
				(width 0.1524)
				(type default)
			)
			(layer "B.SilkS")
		)
		(fp_line
			(start 0.7874 0.4064)
			(end 0.7874 -0.4064)
			(stroke
				(width 0.1524)
				(type default)
			)
			(layer "B.SilkS")
		)
		(fp_line
			(start -0.67945 -0.3048)
			(end -0.67945 0.3048)
			(stroke
				(width 0.1)
				(type default)
			)
			(layer "B.Fab")
		)
		(fp_line
			(start -0.67945 0.3048)
			(end -0.120396 0.3048)
			(stroke
				(width 0.1)
				(type default)
			)
			(layer "B.Fab")
		)
		(fp_line
			(start -0.12065 -0.3048)
			(end -0.67945 -0.3048)
			(stroke
				(width 0.1)
				(type default)
			)
			(layer "B.Fab")
		)
		(fp_line
			(start -0.12065 -0.2794)
			(end -0.12065 -0.3048)
			(stroke
				(width 0.1)
				(type default)
			)
			(layer "B.Fab")
		)
		(fp_line
			(start -0.120396 0.2794)
			(end 0.12065 0.2794)
			(stroke
				(width 0.1)
				(type default)
			)
			(layer "B.Fab")
		)
		(fp_line
			(start -0.120396 0.3048)
			(end -0.120396 0.2794)
			(stroke
				(width 0.1)
				(type default)
			)
			(layer "B.Fab")
		)
		(fp_line
			(start 0.12065 -0.305054)
			(end 0.12065 -0.2794)
			(stroke
				(width 0.1)
				(type default)
			)
			(layer "B.Fab")
		)
		(fp_line
			(start 0.12065 -0.2794)
			(end -0.12065 -0.2794)
			(stroke
				(width 0.1)
				(type default)
			)
			(layer "B.Fab")
		)
		(fp_line
			(start 0.12065 0.2794)
			(end 0.12065 0.3048)
			(stroke
				(width 0.1)
				(type default)
			)
			(layer "B.Fab")
		)
		(fp_line
			(start 0.12065 0.3048)
			(end 0.67945 0.3048)
			(stroke
				(width 0.1)
				(type default)
			)
			(layer "B.Fab")
		)
		(fp_line
			(start 0.67945 -0.305054)
			(end 0.12065 -0.305054)
			(stroke
				(width 0.1)
				(type default)
			)
			(layer "B.Fab")
		)
		(fp_line
			(start 0.67945 0.3048)
			(end 0.67945 -0.305054)
			(stroke
				(width 0.1)
				(type default)
			)
			(layer "B.Fab")
		)
		(pad "1" smd circle
			(at 0.40005 0 180)
			(size 0 0)
			(layers "B.Cu" "B.Mask" "B.Paste")
			(net "P3V3_CLK_GEN_VDD_CK440_PEX")
		)
		(pad "2" smd circle
			(at -0.40005 0 180)
			(size 0 0)
			(layers "B.Cu" "B.Mask" "B.Paste")
			(net "GND")
		)
	)
	(footprint ""
		(layer "B.Cu")
		(at 253.97968 -85.586316)
		(property "Reference" "C2650"
			(at 0 0 0)
			(layer "B.SilkS")
			(hide yes)
			(effects
				(font
					(size 1.27 1.27)
				)
				(justify mirror)
			)
		)
		(property "Value" ""
			(at 0 0 0)
			(layer "B.Fab")
			(effects
				(font
					(size 1.27 1.27)
				)
				(justify mirror)
			)
		)
		(duplicate_pad_numbers_are_jumpers no)
		(fp_line
			(start -1.2954 -0.5842)
			(end -1.2954 0.5842)
			(stroke
				(width 0.1524)
				(type default)
			)
			(layer "B.SilkS")
		)
		(fp_line
			(start -1.2954 0.5842)
			(end 1.2954 0.5842)
			(stroke
				(width 0.1524)
				(type default)
			)
			(layer "B.SilkS")
		)
		(fp_line
			(start 1.2954 -0.5842)
			(end -1.2954 -0.5842)
			(stroke
				(width 0.1524)
				(type default)
			)
			(layer "B.SilkS")
		)
		(fp_line
			(start 1.2954 0.5842)
			(end 1.2954 -0.5842)
			(stroke
				(width 0.1524)
				(type default)
			)
			(layer "B.SilkS")
		)
		(fp_line
			(start -1.1938 -0.4064)
			(end -1.1938 0.4064)
			(stroke
				(width 0.1)
				(type default)
			)
			(layer "B.Fab")
		)
		(fp_line
			(start -1.1938 0.4064)
			(end -0.8636 0.4064)
			(stroke
				(width 0.1)
				(type default)
			)
			(layer "B.Fab")
		)
		(fp_line
			(start -0.8636 -0.4572)
			(end -0.8636 -0.4064)
			(stroke
				(width 0.1)
				(type default)
			)
			(layer "B.Fab")
		)
		(fp_line
			(start -0.8636 -0.4064)
			(end -1.1938 -0.4064)
			(stroke
				(width 0.1)
				(type default)
			)
			(layer "B.Fab")
		)
		(fp_line
			(start -0.8636 0.4064)
			(end -0.8636 0.4572)
			(stroke
				(width 0.1)
				(type default)
			)
			(layer "B.Fab")
		)
		(fp_line
			(start -0.8636 0.4572)
			(end 0.8636 0.4572)
			(stroke
				(width 0.1)
				(type default)
			)
			(layer "B.Fab")
		)
		(fp_line
			(start 0.8636 -0.4572)
			(end -0.8636 -0.4572)
			(stroke
				(width 0.1)
				(type default)
			)
			(layer "B.Fab")
		)
		(fp_line
			(start 0.8636 -0.4064)
			(end 0.8636 -0.4572)
			(stroke
				(width 0.1)
				(type default)
			)
			(layer "B.Fab")
		)
		(fp_line
			(start 0.8636 0.4064)
			(end 1.1938 0.4064)
			(stroke
				(width 0.1)
				(type default)
			)
			(layer "B.Fab")
		)
		(fp_line
			(start 0.8636 0.4572)
			(end 0.8636 0.4064)
			(stroke
				(width 0.1)
				(type default)
			)
			(layer "B.Fab")
		)
		(fp_line
			(start 1.1938 -0.4064)
			(end 0.8636 -0.4064)
			(stroke
				(width 0.1)
				(type default)
			)
			(layer "B.Fab")
		)
		(fp_line
			(start 1.1938 0.4064)
			(end 1.1938 -0.4064)
			(stroke
				(width 0.1)
				(type default)
			)
			(layer "B.Fab")
		)
		(pad "1" smd rect
			(at 0.7366 0 270)
			(size 0.7112 0.8128)
			(layers "B.Cu" "B.Mask" "B.Paste")
			(net "P3V3_CLK_GEN_VDDPT_CK440")
		)
		(pad "2" smd rect
			(at -0.7366 0 270)
			(size 0.7112 0.8128)
			(layers "B.Cu" "B.Mask" "B.Paste")
			(net "GND")
		)
	)
	(footprint ""
		(layer "B.Cu")
		(at 297.549824 -301.599854 -90)
		(property "Reference" "C1679"
			(at 0 0 90)
			(layer "B.SilkS")
			(hide yes)
			(effects
				(font
					(size 1.27 1.27)
				)
				(justify mirror)
			)
		)
		(property "Value" ""
			(at 0 0 90)
			(layer "B.Fab")
			(effects
				(font
					(size 1.27 1.27)
				)
				(justify mirror)
			)
		)
		(duplicate_pad_numbers_are_jumpers no)
		(fp_line
			(start -0.299974 0.150114)
			(end 0.299974 0.150114)
			(stroke
				(width 0.1)
				(type default)
			)
			(layer "B.Fab")
		)
		(fp_line
			(start 0.299974 0.150114)
			(end 0.299974 -0.150114)
			(stroke
				(width 0.1)
				(type default)
			)
			(layer "B.Fab")
		)
		(fp_line
			(start -0.299974 -0.150114)
			(end -0.299974 0.150114)
			(stroke
				(width 0.1)
				(type default)
			)
			(layer "B.Fab")
		)
		(fp_line
			(start 0.299974 -0.150114)
			(end -0.299974 -0.150114)
			(stroke
				(width 0.1)
				(type default)
			)
			(layer "B.Fab")
		)
		(pad "1" smd rect
			(at 0.2667 0 90)
			(size 0.3048 0.381)
			(layers "B.Cu" "B.Mask" "B.Paste")
			(net "P0V8_SERDES_VDDA_PEX2")
		)
		(pad "2" smd rect
			(at -0.2667 0 90)
			(size 0.3048 0.381)
			(layers "B.Cu" "B.Mask" "B.Paste")
			(net "GND")
		)
	)
	(footprint ""
		(layer "B.Cu")
		(at 234.979972 -350.370394 180)
		(property "Reference" "PR7153"
			(at 0 0 0)
			(layer "B.SilkS")
			(hide yes)
			(effects
				(font
					(size 1.27 1.27)
				)
				(justify mirror)
			)
		)
		(property "Value" ""
			(at 0 0 0)
			(layer "B.Fab")
			(effects
				(font
					(size 1.27 1.27)
				)
				(justify mirror)
			)
		)
		(duplicate_pad_numbers_are_jumpers no)
		(fp_line
			(start 0.7874 0.4064)
			(end 0.7874 -0.4064)
			(stroke
				(width 0.1524)
				(type default)
			)
			(layer "B.SilkS")
		)
		(fp_line
			(start 0.7874 -0.4064)
			(end -0.7874 -0.4064)
			(stroke
				(width 0.1524)
				(type default)
			)
			(layer "B.SilkS")
		)
		(fp_line
			(start -0.7874 0.4064)
			(end 0.7874 0.4064)
			(stroke
				(width 0.1524)
				(type default)
			)
			(layer "B.SilkS")
		)
		(fp_line
			(start -0.7874 -0.4064)
			(end -0.7874 0.4064)
			(stroke
				(width 0.1524)
				(type default)
			)
			(layer "B.SilkS")
		)
		(fp_line
			(start 0.67945 0.3048)
			(end 0.67945 -0.305054)
			(stroke
				(width 0.1)
				(type default)
			)
			(layer "B.Fab")
		)
		(fp_line
			(start 0.67945 -0.305054)
			(end 0.12065 -0.305054)
			(stroke
				(width 0.1)
				(type default)
			)
			(layer "B.Fab")
		)
		(fp_line
			(start 0.12065 0.3048)
			(end 0.67945 0.3048)
			(stroke
				(width 0.1)
				(type default)
			)
			(layer "B.Fab")
		)
		(fp_line
			(start 0.12065 0.2794)
			(end 0.12065 0.3048)
			(stroke
				(width 0.1)
				(type default)
			)
			(layer "B.Fab")
		)
		(fp_line
			(start 0.12065 -0.2794)
			(end -0.12065 -0.2794)
			(stroke
				(width 0.1)
				(type default)
			)
			(layer "B.Fab")
		)
		(fp_line
			(start 0.12065 -0.305054)
			(end 0.12065 -0.2794)
			(stroke
				(width 0.1)
				(type default)
			)
			(layer "B.Fab")
		)
		(fp_line
			(start -0.120396 0.3048)
			(end -0.120396 0.2794)
			(stroke
				(width 0.1)
				(type default)
			)
			(layer "B.Fab")
		)
		(fp_line
			(start -0.120396 0.2794)
			(end 0.12065 0.2794)
			(stroke
				(width 0.1)
				(type default)
			)
			(layer "B.Fab")
		)
		(fp_line
			(start -0.12065 -0.2794)
			(end -0.12065 -0.3048)
			(stroke
				(width 0.1)
				(type default)
			)
			(layer "B.Fab")
		)
		(fp_line
			(start -0.12065 -0.3048)
			(end -0.67945 -0.3048)
			(stroke
				(width 0.1)
				(type default)
			)
			(layer "B.Fab")
		)
		(fp_line
			(start -0.67945 0.3048)
			(end -0.120396 0.3048)
			(stroke
				(width 0.1)
				(type default)
			)
			(layer "B.Fab")
		)
		(fp_line
			(start -0.67945 -0.3048)
			(end -0.67945 0.3048)
			(stroke
				(width 0.1)
				(type default)
			)
			(layer "B.Fab")
		)
		(pad "1" smd circle
			(at 0.40005 0)
			(size 0 0)
			(layers "B.Cu" "B.Mask" "B.Paste")
			(net "P12V_HSC_SENSE2_P")
		)
		(pad "2" smd circle
			(at -0.40005 0)
			(size 0 0)
			(layers "B.Cu" "B.Mask" "B.Paste")
			(net "P12V_HSC_SENSE2_R1_P")
		)
	)
	(footprint ""
		(layer "B.Cu")
		(at 74.026776 -299.2247 90)
		(property "Reference" "R1245"
			(at 0 0 90)
			(layer "B.SilkS")
			(hide yes)
			(effects
				(font
					(size 1.27 1.27)
				)
				(justify mirror)
			)
		)
		(property "Value" ""
			(at 0 0 90)
			(layer "B.Fab")
			(effects
				(font
					(size 1.27 1.27)
				)
				(justify mirror)
			)
		)
		(duplicate_pad_numbers_are_jumpers no)
		(fp_line
			(start 0.7874 -0.4064)
			(end -0.7874 -0.4064)
			(stroke
				(width 0.1524)
				(type default)
			)
			(layer "B.SilkS")
		)
		(fp_line
			(start -0.7874 -0.4064)
			(end -0.7874 0.4064)
			(stroke
				(width 0.1524)
				(type default)
			)
			(layer "B.SilkS")
		)
		(fp_line
			(start 0.7874 0.4064)
			(end 0.7874 -0.4064)
			(stroke
				(width 0.1524)
				(type default)
			)
			(layer "B.SilkS")
		)
		(fp_line
			(start -0.7874 0.4064)
			(end 0.7874 0.4064)
			(stroke
				(width 0.1524)
				(type default)
			)
			(layer "B.SilkS")
		)
		(fp_line
			(start 0.67945 -0.305054)
			(end 0.12065 -0.305054)
			(stroke
				(width 0.1)
				(type default)
			)
			(layer "B.Fab")
		)
		(fp_line
			(start 0.12065 -0.305054)
			(end 0.12065 -0.2794)
			(stroke
				(width 0.1)
				(type default)
			)
			(layer "B.Fab")
		)
		(fp_line
			(start -0.12065 -0.3048)
			(end -0.67945 -0.3048)
			(stroke
				(width 0.1)
				(type default)
			)
			(layer "B.Fab")
		)
		(fp_line
			(start -0.67945 -0.3048)
			(end -0.67945 0.3048)
			(stroke
				(width 0.1)
				(type default)
			)
			(layer "B.Fab")
		)
		(fp_line
			(start 0.12065 -0.2794)
			(end -0.12065 -0.2794)
			(stroke
				(width 0.1)
				(type default)
			)
			(layer "B.Fab")
		)
		(fp_line
			(start -0.12065 -0.2794)
			(end -0.12065 -0.3048)
			(stroke
				(width 0.1)
				(type default)
			)
			(layer "B.Fab")
		)
		(fp_line
			(start 0.12065 0.2794)
			(end 0.12065 0.3048)
			(stroke
				(width 0.1)
				(type default)
			)
			(layer "B.Fab")
		)
		(fp_line
			(start -0.120396 0.2794)
			(end 0.12065 0.2794)
			(stroke
				(width 0.1)
				(type default)
			)
			(layer "B.Fab")
		)
		(fp_line
			(start 0.67945 0.3048)
			(end 0.67945 -0.305054)
			(stroke
				(width 0.1)
				(type default)
			)
			(layer "B.Fab")
		)
		(fp_line
			(start 0.12065 0.3048)
			(end 0.67945 0.3048)
			(stroke
				(width 0.1)
				(type default)
			)
			(layer "B.Fab")
		)
		(fp_line
			(start -0.120396 0.3048)
			(end -0.120396 0.2794)
			(stroke
				(width 0.1)
				(type default)
			)
			(layer "B.Fab")
		)
		(fp_line
			(start -0.67945 0.3048)
			(end -0.120396 0.3048)
			(stroke
				(width 0.1)
				(type default)
			)
			(layer "B.Fab")
		)
		(pad "1" smd circle
			(at 0.40005 0 270)
			(size 0 0)
			(layers "B.Cu" "B.Mask" "B.Paste")
			(net "PEX0_ADCTEMP_VINP1")
		)
		(pad "2" smd circle
			(at -0.40005 0 270)
			(size 0 0)
			(layers "B.Cu" "B.Mask" "B.Paste")
			(net "GND")
		)
	)
	(footprint ""
		(layer "B.Cu")
		(at 181.4703 -296.37482)
		(property "Reference" "C1375"
			(at 0 0 0)
			(layer "B.SilkS")
			(hide yes)
			(effects
				(font
					(size 1.27 1.27)
				)
				(justify mirror)
			)
		)
		(property "Value" ""
			(at 0 0 0)
			(layer "B.Fab")
			(effects
				(font
					(size 1.27 1.27)
				)
				(justify mirror)
			)
		)
		(duplicate_pad_numbers_are_jumpers no)
		(fp_line
			(start -0.299974 -0.150114)
			(end -0.299974 0.150114)
			(stroke
				(width 0.1)
				(type default)
			)
			(layer "B.Fab")
		)
		(fp_line
			(start -0.299974 0.150114)
			(end 0.299974 0.150114)
			(stroke
				(width 0.1)
				(type default)
			)
			(layer "B.Fab")
		)
		(fp_line
			(start 0.299974 -0.150114)
			(end -0.299974 -0.150114)
			(stroke
				(width 0.1)
				(type default)
			)
			(layer "B.Fab")
		)
		(fp_line
			(start 0.299974 0.150114)
			(end 0.299974 -0.150114)
			(stroke
				(width 0.1)
				(type default)
			)
			(layer "B.Fab")
		)
		(pad "1" smd rect
			(at 0.2667 0 180)
			(size 0.3048 0.381)
			(layers "B.Cu" "B.Mask" "B.Paste")
			(net "P0V8_PEX1")
		)
		(pad "2" smd rect
			(at -0.2667 0 180)
			(size 0.3048 0.381)
			(layers "B.Cu" "B.Mask" "B.Paste")
			(net "GND")
		)
	)
	(footprint ""
		(layer "B.Cu")
		(at 121.437146 -325.186294 -90)
		(property "Reference" "C4270"
			(at 0 0 90)
			(layer "B.SilkS")
			(hide yes)
			(effects
				(font
					(size 1.27 1.27)
				)
				(justify mirror)
			)
		)
		(property "Value" ""
			(at 0 0 90)
			(layer "B.Fab")
			(effects
				(font
					(size 1.27 1.27)
				)
				(justify mirror)
			)
		)
		(duplicate_pad_numbers_are_jumpers no)
		(fp_line
			(start -1.2954 0.5842)
			(end 1.2954 0.5842)
			(stroke
				(width 0.1524)
				(type default)
			)
			(layer "B.SilkS")
		)
		(fp_line
			(start 1.2954 0.5842)
			(end 1.2954 -0.5842)
			(stroke
				(width 0.1524)
				(type default)
			)
			(layer "B.SilkS")
		)
		(fp_line
			(start -1.2954 -0.5842)
			(end -1.2954 0.5842)
			(stroke
				(width 0.1524)
				(type default)
			)
			(layer "B.SilkS")
		)
		(fp_line
			(start 1.2954 -0.5842)
			(end -1.2954 -0.5842)
			(stroke
				(width 0.1524)
				(type default)
			)
			(layer "B.SilkS")
		)
		(fp_line
			(start -0.8636 0.4572)
			(end 0.8636 0.4572)
			(stroke
				(width 0.1)
				(type default)
			)
			(layer "B.Fab")
		)
		(fp_line
			(start 0.8636 0.4572)
			(end 0.8636 0.4064)
			(stroke
				(width 0.1)
				(type default)
			)
			(layer "B.Fab")
		)
		(fp_line
			(start -1.1938 0.4064)
			(end -0.8636 0.4064)
			(stroke
				(width 0.1)
				(type default)
			)
			(layer "B.Fab")
		)
		(fp_line
			(start -0.8636 0.4064)
			(end -0.8636 0.4572)
			(stroke
				(width 0.1)
				(type default)
			)
			(layer "B.Fab")
		)
		(fp_line
			(start 0.8636 0.4064)
			(end 1.1938 0.4064)
			(stroke
				(width 0.1)
				(type default)
			)
			(layer "B.Fab")
		)
		(fp_line
			(start 1.1938 0.4064)
			(end 1.1938 -0.4064)
			(stroke
				(width 0.1)
				(type default)
			)
			(layer "B.Fab")
		)
		(fp_line
			(start -1.1938 -0.4064)
			(end -1.1938 0.4064)
			(stroke
				(width 0.1)
				(type default)
			)
			(layer "B.Fab")
		)
		(fp_line
			(start -0.8636 -0.4064)
			(end -1.1938 -0.4064)
			(stroke
				(width 0.1)
				(type default)
			)
			(layer "B.Fab")
		)
		(fp_line
			(start 0.8636 -0.4064)
			(end 0.8636 -0.4572)
			(stroke
				(width 0.1)
				(type default)
			)
			(layer "B.Fab")
		)
		(fp_line
			(start 1.1938 -0.4064)
			(end 0.8636 -0.4064)
			(stroke
				(width 0.1)
				(type default)
			)
			(layer "B.Fab")
		)
		(fp_line
			(start -0.8636 -0.4572)
			(end -0.8636 -0.4064)
			(stroke
				(width 0.1)
				(type default)
			)
			(layer "B.Fab")
		)
		(fp_line
			(start 0.8636 -0.4572)
			(end -0.8636 -0.4572)
			(stroke
				(width 0.1)
				(type default)
			)
			(layer "B.Fab")
		)
		(pad "1" smd rect
			(at 0.7366 0 180)
			(size 0.7112 0.8128)
			(layers "B.Cu" "B.Mask" "B.Paste")
			(net "P0V8_SERDES_VDDA_PEX1_C8")
		)
		(pad "2" smd rect
			(at -0.7366 0 180)
			(size 0.7112 0.8128)
			(layers "B.Cu" "B.Mask" "B.Paste")
			(net "GND")
		)
	)
	(footprint ""
		(layer "B.Cu")
		(at 40.05707 -291.72662 180)
		(property "Reference" "R3293"
			(at 0 0 0)
			(layer "B.SilkS")
			(hide yes)
			(effects
				(font
					(size 1.27 1.27)
				)
				(justify mirror)
			)
		)
		(property "Value" ""
			(at 0 0 0)
			(layer "B.Fab")
			(effects
				(font
					(size 1.27 1.27)
				)
				(justify mirror)
			)
		)
		(duplicate_pad_numbers_are_jumpers no)
		(fp_line
			(start 0.7874 0.4064)
			(end 0.7874 -0.4064)
			(stroke
				(width 0.1524)
				(type default)
			)
			(layer "B.SilkS")
		)
		(fp_line
			(start 0.7874 -0.4064)
			(end -0.7874 -0.4064)
			(stroke
				(width 0.1524)
				(type default)
			)
			(layer "B.SilkS")
		)
		(fp_line
			(start -0.7874 0.4064)
			(end 0.7874 0.4064)
			(stroke
				(width 0.1524)
				(type default)
			)
			(layer "B.SilkS")
		)
		(fp_line
			(start -0.7874 -0.4064)
			(end -0.7874 0.4064)
			(stroke
				(width 0.1524)
				(type default)
			)
			(layer "B.SilkS")
		)
		(fp_line
			(start 0.67945 0.3048)
			(end 0.67945 -0.305054)
			(stroke
				(width 0.1)
				(type default)
			)
			(layer "B.Fab")
		)
		(fp_line
			(start 0.67945 -0.305054)
			(end 0.12065 -0.305054)
			(stroke
				(width 0.1)
				(type default)
			)
			(layer "B.Fab")
		)
		(fp_line
			(start 0.12065 0.3048)
			(end 0.67945 0.3048)
			(stroke
				(width 0.1)
				(type default)
			)
			(layer "B.Fab")
		)
		(fp_line
			(start 0.12065 0.2794)
			(end 0.12065 0.3048)
			(stroke
				(width 0.1)
				(type default)
			)
			(layer "B.Fab")
		)
		(fp_line
			(start 0.12065 -0.2794)
			(end -0.12065 -0.2794)
			(stroke
				(width 0.1)
				(type default)
			)
			(layer "B.Fab")
		)
		(fp_line
			(start 0.12065 -0.305054)
			(end 0.12065 -0.2794)
			(stroke
				(width 0.1)
				(type default)
			)
			(layer "B.Fab")
		)
		(fp_line
			(start -0.120396 0.3048)
			(end -0.120396 0.2794)
			(stroke
				(width 0.1)
				(type default)
			)
			(layer "B.Fab")
		)
		(fp_line
			(start -0.120396 0.2794)
			(end 0.12065 0.2794)
			(stroke
				(width 0.1)
				(type default)
			)
			(layer "B.Fab")
		)
		(fp_line
			(start -0.12065 -0.2794)
			(end -0.12065 -0.3048)
			(stroke
				(width 0.1)
				(type default)
			)
			(layer "B.Fab")
		)
		(fp_line
			(start -0.12065 -0.3048)
			(end -0.67945 -0.3048)
			(stroke
				(width 0.1)
				(type default)
			)
			(layer "B.Fab")
		)
		(fp_line
			(start -0.67945 0.3048)
			(end -0.120396 0.3048)
			(stroke
				(width 0.1)
				(type default)
			)
			(layer "B.Fab")
		)
		(fp_line
			(start -0.67945 -0.3048)
			(end -0.67945 0.3048)
			(stroke
				(width 0.1)
				(type default)
			)
			(layer "B.Fab")
		)
		(pad "1" smd circle
			(at 0.40005 0)
			(size 0 0)
			(layers "B.Cu" "B.Mask" "B.Paste")
			(net "SPI_PEX0_CLK_R")
		)
		(pad "2" smd circle
			(at -0.40005 0)
			(size 0 0)
			(layers "B.Cu" "B.Mask" "B.Paste")
			(net "SPI_PEX0_CLK")
		)
	)
	(footprint ""
		(layer "B.Cu")
		(at 406.049988 -301.599854 -90)
		(property "Reference" "C1999"
			(at 0 0 90)
			(layer "B.SilkS")
			(hide yes)
			(effects
				(font
					(size 1.27 1.27)
				)
				(justify mirror)
			)
		)
		(property "Value" ""
			(at 0 0 90)
			(layer "B.Fab")
			(effects
				(font
					(size 1.27 1.27)
				)
				(justify mirror)
			)
		)
		(duplicate_pad_numbers_are_jumpers no)
		(fp_line
			(start -0.299974 0.150114)
			(end 0.299974 0.150114)
			(stroke
				(width 0.1)
				(type default)
			)
			(layer "B.Fab")
		)
		(fp_line
			(start 0.299974 0.150114)
			(end 0.299974 -0.150114)
			(stroke
				(width 0.1)
				(type default)
			)
			(layer "B.Fab")
		)
		(fp_line
			(start -0.299974 -0.150114)
			(end -0.299974 0.150114)
			(stroke
				(width 0.1)
				(type default)
			)
			(layer "B.Fab")
		)
		(fp_line
			(start 0.299974 -0.150114)
			(end -0.299974 -0.150114)
			(stroke
				(width 0.1)
				(type default)
			)
			(layer "B.Fab")
		)
		(pad "1" smd rect
			(at 0.2667 0 90)
			(size 0.3048 0.381)
			(layers "B.Cu" "B.Mask" "B.Paste")
			(net "P0V8_SERDES_VDDA_PEX3")
		)
		(pad "2" smd rect
			(at -0.2667 0 90)
			(size 0.3048 0.381)
			(layers "B.Cu" "B.Mask" "B.Paste")
			(net "GND")
		)
	)
	(footprint ""
		(layer "B.Cu")
		(at 405.100028 -288.299906 90)
		(property "Reference" "C3463"
			(at 0 0 90)
			(layer "B.SilkS")
			(hide yes)
			(effects
				(font
					(size 1.27 1.27)
				)
				(justify mirror)
			)
		)
		(property "Value" ""
			(at 0 0 90)
			(layer "B.Fab")
			(effects
				(font
					(size 1.27 1.27)
				)
				(justify mirror)
			)
		)
		(duplicate_pad_numbers_are_jumpers no)
		(fp_line
			(start 0.299974 -0.150114)
			(end -0.299974 -0.150114)
			(stroke
				(width 0.1)
				(type default)
			)
			(layer "B.Fab")
		)
		(fp_line
			(start -0.299974 -0.150114)
			(end -0.299974 0.150114)
			(stroke
				(width 0.1)
				(type default)
			)
			(layer "B.Fab")
		)
		(fp_line
			(start 0.299974 0.150114)
			(end 0.299974 -0.150114)
			(stroke
				(width 0.1)
				(type default)
			)
			(layer "B.Fab")
		)
		(fp_line
			(start -0.299974 0.150114)
			(end 0.299974 0.150114)
			(stroke
				(width 0.1)
				(type default)
			)
			(layer "B.Fab")
		)
		(pad "1" smd rect
			(at 0.2667 0 270)
			(size 0.3048 0.381)
			(layers "B.Cu" "B.Mask" "B.Paste")
			(net "P1V25_PEX3")
		)
		(pad "2" smd rect
			(at -0.2667 0 270)
			(size 0.3048 0.381)
			(layers "B.Cu" "B.Mask" "B.Paste")
			(net "GND")
		)
	)
	(footprint ""
		(layer "B.Cu")
		(at 348.435168 -282.16733 90)
		(property "Reference" "R6767"
			(at 0 0 90)
			(layer "B.SilkS")
			(hide yes)
			(effects
				(font
					(size 1.27 1.27)
				)
				(justify mirror)
			)
		)
		(property "Value" ""
			(at 0 0 90)
			(layer "B.Fab")
			(effects
				(font
					(size 1.27 1.27)
				)
				(justify mirror)
			)
		)
		(duplicate_pad_numbers_are_jumpers no)
		(fp_line
			(start 0.7874 -0.4064)
			(end -0.7874 -0.4064)
			(stroke
				(width 0.1524)
				(type default)
			)
			(layer "B.SilkS")
		)
		(fp_line
			(start -0.7874 -0.4064)
			(end -0.7874 0.4064)
			(stroke
				(width 0.1524)
				(type default)
			)
			(layer "B.SilkS")
		)
		(fp_line
			(start 0.7874 0.4064)
			(end 0.7874 -0.4064)
			(stroke
				(width 0.1524)
				(type default)
			)
			(layer "B.SilkS")
		)
		(fp_line
			(start -0.7874 0.4064)
			(end 0.7874 0.4064)
			(stroke
				(width 0.1524)
				(type default)
			)
			(layer "B.SilkS")
		)
		(fp_line
			(start 0.67945 -0.305054)
			(end 0.12065 -0.305054)
			(stroke
				(width 0.1)
				(type default)
			)
			(layer "B.Fab")
		)
		(fp_line
			(start 0.12065 -0.305054)
			(end 0.12065 -0.2794)
			(stroke
				(width 0.1)
				(type default)
			)
			(layer "B.Fab")
		)
		(fp_line
			(start -0.12065 -0.3048)
			(end -0.67945 -0.3048)
			(stroke
				(width 0.1)
				(type default)
			)
			(layer "B.Fab")
		)
		(fp_line
			(start -0.67945 -0.3048)
			(end -0.67945 0.3048)
			(stroke
				(width 0.1)
				(type default)
			)
			(layer "B.Fab")
		)
		(fp_line
			(start 0.12065 -0.2794)
			(end -0.12065 -0.2794)
			(stroke
				(width 0.1)
				(type default)
			)
			(layer "B.Fab")
		)
		(fp_line
			(start -0.12065 -0.2794)
			(end -0.12065 -0.3048)
			(stroke
				(width 0.1)
				(type default)
			)
			(layer "B.Fab")
		)
		(fp_line
			(start 0.12065 0.2794)
			(end 0.12065 0.3048)
			(stroke
				(width 0.1)
				(type default)
			)
			(layer "B.Fab")
		)
		(fp_line
			(start -0.120396 0.2794)
			(end 0.12065 0.2794)
			(stroke
				(width 0.1)
				(type default)
			)
			(layer "B.Fab")
		)
		(fp_line
			(start 0.67945 0.3048)
			(end 0.67945 -0.305054)
			(stroke
				(width 0.1)
				(type default)
			)
			(layer "B.Fab")
		)
		(fp_line
			(start 0.12065 0.3048)
			(end 0.67945 0.3048)
			(stroke
				(width 0.1)
				(type default)
			)
			(layer "B.Fab")
		)
		(fp_line
			(start -0.120396 0.3048)
			(end -0.120396 0.2794)
			(stroke
				(width 0.1)
				(type default)
			)
			(layer "B.Fab")
		)
		(fp_line
			(start -0.67945 0.3048)
			(end -0.120396 0.3048)
			(stroke
				(width 0.1)
				(type default)
			)
			(layer "B.Fab")
		)
		(pad "1" smd circle
			(at 0.40005 0 270)
			(size 0 0)
			(layers "B.Cu" "B.Mask" "B.Paste")
			(net "P0V8_PEX2_VCC2")
		)
		(pad "2" smd circle
			(at -0.40005 0 270)
			(size 0 0)
			(layers "B.Cu" "B.Mask" "B.Paste")
			(net "P0V8_PEX2_EN2")
		)
	)
	(footprint ""
		(layer "B.Cu")
		(at 277.5204 -386.334 180)
		(property "Reference" "PC6603"
			(at 0 0 0)
			(layer "B.SilkS")
			(hide yes)
			(effects
				(font
					(size 1.27 1.27)
				)
				(justify mirror)
			)
		)
		(property "Value" ""
			(at 0 0 0)
			(layer "B.Fab")
			(effects
				(font
					(size 1.27 1.27)
				)
				(justify mirror)
			)
		)
		(duplicate_pad_numbers_are_jumpers no)
		(fp_line
			(start 1.2954 0.5842)
			(end 1.2954 -0.5842)
			(stroke
				(width 0.1524)
				(type default)
			)
			(layer "B.SilkS")
		)
		(fp_line
			(start 1.2954 -0.5842)
			(end -1.2954 -0.5842)
			(stroke
				(width 0.1524)
				(type default)
			)
			(layer "B.SilkS")
		)
		(fp_line
			(start -1.2954 0.5842)
			(end 1.2954 0.5842)
			(stroke
				(width 0.1524)
				(type default)
			)
			(layer "B.SilkS")
		)
		(fp_line
			(start -1.2954 -0.5842)
			(end -1.2954 0.5842)
			(stroke
				(width 0.1524)
				(type default)
			)
			(layer "B.SilkS")
		)
		(fp_line
			(start 1.1938 0.4064)
			(end 1.1938 -0.4064)
			(stroke
				(width 0.1)
				(type default)
			)
			(layer "B.Fab")
		)
		(fp_line
			(start 1.1938 -0.4064)
			(end 0.8636 -0.4064)
			(stroke
				(width 0.1)
				(type default)
			)
			(layer "B.Fab")
		)
		(fp_line
			(start 0.8636 0.4572)
			(end 0.8636 0.4064)
			(stroke
				(width 0.1)
				(type default)
			)
			(layer "B.Fab")
		)
		(fp_line
			(start 0.8636 0.4064)
			(end 1.1938 0.4064)
			(stroke
				(width 0.1)
				(type default)
			)
			(layer "B.Fab")
		)
		(fp_line
			(start 0.8636 -0.4064)
			(end 0.8636 -0.4572)
			(stroke
				(width 0.1)
				(type default)
			)
			(layer "B.Fab")
		)
		(fp_line
			(start 0.8636 -0.4572)
			(end -0.8636 -0.4572)
			(stroke
				(width 0.1)
				(type default)
			)
			(layer "B.Fab")
		)
		(fp_line
			(start -0.8636 0.4572)
			(end 0.8636 0.4572)
			(stroke
				(width 0.1)
				(type default)
			)
			(layer "B.Fab")
		)
		(fp_line
			(start -0.8636 0.4064)
			(end -0.8636 0.4572)
			(stroke
				(width 0.1)
				(type default)
			)
			(layer "B.Fab")
		)
		(fp_line
			(start -0.8636 -0.4064)
			(end -1.1938 -0.4064)
			(stroke
				(width 0.1)
				(type default)
			)
			(layer "B.Fab")
		)
		(fp_line
			(start -0.8636 -0.4572)
			(end -0.8636 -0.4064)
			(stroke
				(width 0.1)
				(type default)
			)
			(layer "B.Fab")
		)
		(fp_line
			(start -1.1938 0.4064)
			(end -0.8636 0.4064)
			(stroke
				(width 0.1)
				(type default)
			)
			(layer "B.Fab")
		)
		(fp_line
			(start -1.1938 -0.4064)
			(end -1.1938 0.4064)
			(stroke
				(width 0.1)
				(type default)
			)
			(layer "B.Fab")
		)
		(pad "1" smd rect
			(at 0.7366 0 90)
			(size 0.7112 0.8128)
			(layers "B.Cu" "B.Mask" "B.Paste")
			(net "LTC4282_TEMP_D+")
		)
		(pad "2" smd rect
			(at -0.7366 0 90)
			(size 0.7112 0.8128)
			(layers "B.Cu" "B.Mask" "B.Paste")
			(net "LTC4282_TEMP_D-")
		)
	)
	(footprint ""
		(layer "B.Cu")
		(at 299.449744 -288.299906 90)
		(property "Reference" "C3284"
			(at 0 0 90)
			(layer "B.SilkS")
			(hide yes)
			(effects
				(font
					(size 1.27 1.27)
				)
				(justify mirror)
			)
		)
		(property "Value" ""
			(at 0 0 90)
			(layer "B.Fab")
			(effects
				(font
					(size 1.27 1.27)
				)
				(justify mirror)
			)
		)
		(duplicate_pad_numbers_are_jumpers no)
		(fp_line
			(start 0.299974 -0.150114)
			(end -0.299974 -0.150114)
			(stroke
				(width 0.1)
				(type default)
			)
			(layer "B.Fab")
		)
		(fp_line
			(start -0.299974 -0.150114)
			(end -0.299974 0.150114)
			(stroke
				(width 0.1)
				(type default)
			)
			(layer "B.Fab")
		)
		(fp_line
			(start 0.299974 0.150114)
			(end 0.299974 -0.150114)
			(stroke
				(width 0.1)
				(type default)
			)
			(layer "B.Fab")
		)
		(fp_line
			(start -0.299974 0.150114)
			(end 0.299974 0.150114)
			(stroke
				(width 0.1)
				(type default)
			)
			(layer "B.Fab")
		)
		(pad "1" smd rect
			(at 0.2667 0 270)
			(size 0.3048 0.381)
			(layers "B.Cu" "B.Mask" "B.Paste")
			(net "P1V25_PEX2")
		)
		(pad "2" smd rect
			(at -0.2667 0 270)
			(size 0.3048 0.381)
			(layers "B.Cu" "B.Mask" "B.Paste")
			(net "GND")
		)
	)
	(footprint ""
		(layer "B.Cu")
		(at 287.099756 -301.599854 -90)
		(property "Reference" "C1712"
			(at 0 0 90)
			(layer "B.SilkS")
			(hide yes)
			(effects
				(font
					(size 1.27 1.27)
				)
				(justify mirror)
			)
		)
		(property "Value" ""
			(at 0 0 90)
			(layer "B.Fab")
			(effects
				(font
					(size 1.27 1.27)
				)
				(justify mirror)
			)
		)
		(duplicate_pad_numbers_are_jumpers no)
		(fp_line
			(start -0.299974 0.150114)
			(end 0.299974 0.150114)
			(stroke
				(width 0.1)
				(type default)
			)
			(layer "B.Fab")
		)
		(fp_line
			(start 0.299974 0.150114)
			(end 0.299974 -0.150114)
			(stroke
				(width 0.1)
				(type default)
			)
			(layer "B.Fab")
		)
		(fp_line
			(start -0.299974 -0.150114)
			(end -0.299974 0.150114)
			(stroke
				(width 0.1)
				(type default)
			)
			(layer "B.Fab")
		)
		(fp_line
			(start 0.299974 -0.150114)
			(end -0.299974 -0.150114)
			(stroke
				(width 0.1)
				(type default)
			)
			(layer "B.Fab")
		)
		(pad "1" smd rect
			(at 0.2667 0 90)
			(size 0.3048 0.381)
			(layers "B.Cu" "B.Mask" "B.Paste")
			(net "P0V8_SERDES_VDDA_PEX2")
		)
		(pad "2" smd rect
			(at -0.2667 0 90)
			(size 0.3048 0.381)
			(layers "B.Cu" "B.Mask" "B.Paste")
			(net "GND")
		)
	)
	(footprint ""
		(layer "B.Cu")
		(at 285.199836 -299.699934 -90)
		(property "Reference" "C1689"
			(at 0 0 90)
			(layer "B.SilkS")
			(hide yes)
			(effects
				(font
					(size 1.27 1.27)
				)
				(justify mirror)
			)
		)
		(property "Value" ""
			(at 0 0 90)
			(layer "B.Fab")
			(effects
				(font
					(size 1.27 1.27)
				)
				(justify mirror)
			)
		)
		(duplicate_pad_numbers_are_jumpers no)
		(fp_line
			(start -0.299974 0.150114)
			(end 0.299974 0.150114)
			(stroke
				(width 0.1)
				(type default)
			)
			(layer "B.Fab")
		)
		(fp_line
			(start 0.299974 0.150114)
			(end 0.299974 -0.150114)
			(stroke
				(width 0.1)
				(type default)
			)
			(layer "B.Fab")
		)
		(fp_line
			(start -0.299974 -0.150114)
			(end -0.299974 0.150114)
			(stroke
				(width 0.1)
				(type default)
			)
			(layer "B.Fab")
		)
		(fp_line
			(start 0.299974 -0.150114)
			(end -0.299974 -0.150114)
			(stroke
				(width 0.1)
				(type default)
			)
			(layer "B.Fab")
		)
		(pad "1" smd rect
			(at 0.2667 0 90)
			(size 0.3048 0.381)
			(layers "B.Cu" "B.Mask" "B.Paste")
			(net "P0V8_SERDES_VDDA_PEX2")
		)
		(pad "2" smd rect
			(at -0.2667 0 90)
			(size 0.3048 0.381)
			(layers "B.Cu" "B.Mask" "B.Paste")
			(net "GND")
		)
	)
	(footprint ""
		(layer "B.Cu")
		(at 332.153514 -209.592418 -90)
		(property "Reference" "R5638"
			(at 0 0 90)
			(layer "B.SilkS")
			(hide yes)
			(effects
				(font
					(size 1.27 1.27)
				)
				(justify mirror)
			)
		)
		(property "Value" ""
			(at 0 0 90)
			(layer "B.Fab")
			(effects
				(font
					(size 1.27 1.27)
				)
				(justify mirror)
			)
		)
		(duplicate_pad_numbers_are_jumpers no)
		(fp_line
			(start -1.2954 0.5842)
			(end 1.2954 0.5842)
			(stroke
				(width 0.1524)
				(type default)
			)
			(layer "B.SilkS")
		)
		(fp_line
			(start 1.2954 0.5842)
			(end 1.2954 -0.5842)
			(stroke
				(width 0.1524)
				(type default)
			)
			(layer "B.SilkS")
		)
		(fp_line
			(start -1.2954 -0.5842)
			(end -1.2954 0.5842)
			(stroke
				(width 0.1524)
				(type default)
			)
			(layer "B.SilkS")
		)
		(fp_line
			(start 1.2954 -0.5842)
			(end -1.2954 -0.5842)
			(stroke
				(width 0.1524)
				(type default)
			)
			(layer "B.SilkS")
		)
		(fp_line
			(start -0.8636 0.4572)
			(end 0.8636 0.4572)
			(stroke
				(width 0.1)
				(type default)
			)
			(layer "B.Fab")
		)
		(fp_line
			(start 0.8636 0.4572)
			(end 0.8636 0.4318)
			(stroke
				(width 0.1)
				(type default)
			)
			(layer "B.Fab")
		)
		(fp_line
			(start 0.8636 0.4318)
			(end 0.8636 0.4064)
			(stroke
				(width 0.1)
				(type default)
			)
			(layer "B.Fab")
		)
		(fp_line
			(start -1.1938 0.4064)
			(end -0.8636 0.4064)
			(stroke
				(width 0.1)
				(type default)
			)
			(layer "B.Fab")
		)
		(fp_line
			(start -0.8636 0.4064)
			(end -0.8636 0.4572)
			(stroke
				(width 0.1)
				(type default)
			)
			(layer "B.Fab")
		)
		(fp_line
			(start 0.8636 0.4064)
			(end 1.1938 0.4064)
			(stroke
				(width 0.1)
				(type default)
			)
			(layer "B.Fab")
		)
		(fp_line
			(start 1.1938 0.4064)
			(end 1.1938 -0.406654)
			(stroke
				(width 0.1)
				(type default)
			)
			(layer "B.Fab")
		)
		(fp_line
			(start -1.1938 -0.406654)
			(end -1.1938 0.4064)
			(stroke
				(width 0.1)
				(type default)
			)
			(layer "B.Fab")
		)
		(fp_line
			(start -0.8636 -0.406654)
			(end -1.1938 -0.406654)
			(stroke
				(width 0.1)
				(type default)
			)
			(layer "B.Fab")
		)
		(fp_line
			(start 0.8636 -0.406654)
			(end 0.8636 -0.4572)
			(stroke
				(width 0.1)
				(type default)
			)
			(layer "B.Fab")
		)
		(fp_line
			(start 1.1938 -0.406654)
			(end 0.8636 -0.406654)
			(stroke
				(width 0.1)
				(type default)
			)
			(layer "B.Fab")
		)
		(fp_line
			(start -0.8636 -0.4572)
			(end -0.8636 -0.406654)
			(stroke
				(width 0.1)
				(type default)
			)
			(layer "B.Fab")
		)
		(fp_line
			(start 0.8636 -0.4572)
			(end -0.8636 -0.4572)
			(stroke
				(width 0.1)
				(type default)
			)
			(layer "B.Fab")
		)
		(pad "1" smd rect
			(at 0.7366 0 180)
			(size 0.7112 0.8128)
			(layers "B.Cu" "B.Mask" "B.Paste")
			(net "P3V3_AUX")
		)
		(pad "2" smd rect
			(at -0.7366 0 180)
			(size 0.7112 0.8128)
			(layers "B.Cu" "B.Mask" "B.Paste")
			(net "P3V3_FPGA_VCCIO2")
		)
	)
	(footprint ""
		(layer "B.Cu")
		(at 51.099974 -301.599854 -90)
		(property "Reference" "C1178"
			(at 0 0 90)
			(layer "B.SilkS")
			(hide yes)
			(effects
				(font
					(size 1.27 1.27)
				)
				(justify mirror)
			)
		)
		(property "Value" ""
			(at 0 0 90)
			(layer "B.Fab")
			(effects
				(font
					(size 1.27 1.27)
				)
				(justify mirror)
			)
		)
		(duplicate_pad_numbers_are_jumpers no)
		(fp_line
			(start -0.299974 0.150114)
			(end 0.299974 0.150114)
			(stroke
				(width 0.1)
				(type default)
			)
			(layer "B.Fab")
		)
		(fp_line
			(start 0.299974 0.150114)
			(end 0.299974 -0.150114)
			(stroke
				(width 0.1)
				(type default)
			)
			(layer "B.Fab")
		)
		(fp_line
			(start -0.299974 -0.150114)
			(end -0.299974 0.150114)
			(stroke
				(width 0.1)
				(type default)
			)
			(layer "B.Fab")
		)
		(fp_line
			(start 0.299974 -0.150114)
			(end -0.299974 -0.150114)
			(stroke
				(width 0.1)
				(type default)
			)
			(layer "B.Fab")
		)
		(pad "1" smd rect
			(at 0.2667 0 90)
			(size 0.3048 0.381)
			(layers "B.Cu" "B.Mask" "B.Paste")
			(net "P0V8_SERDES_VDDA_PEX0")
		)
		(pad "2" smd rect
			(at -0.2667 0 90)
			(size 0.3048 0.381)
			(layers "B.Cu" "B.Mask" "B.Paste")
			(net "GND")
		)
	)
	(footprint ""
		(layer "B.Cu")
		(at 301.536354 -236.736636 -90)
		(property "Reference" "R1869"
			(at 0 0 90)
			(layer "B.SilkS")
			(hide yes)
			(effects
				(font
					(size 1.27 1.27)
				)
				(justify mirror)
			)
		)
		(property "Value" ""
			(at 0 0 90)
			(layer "B.Fab")
			(effects
				(font
					(size 1.27 1.27)
				)
				(justify mirror)
			)
		)
		(duplicate_pad_numbers_are_jumpers no)
		(fp_line
			(start -0.7874 0.4064)
			(end 0.7874 0.4064)
			(stroke
				(width 0.1524)
				(type default)
			)
			(layer "B.SilkS")
		)
		(fp_line
			(start 0.7874 0.4064)
			(end 0.7874 -0.4064)
			(stroke
				(width 0.1524)
				(type default)
			)
			(layer "B.SilkS")
		)
		(fp_line
			(start -0.7874 -0.4064)
			(end -0.7874 0.4064)
			(stroke
				(width 0.1524)
				(type default)
			)
			(layer "B.SilkS")
		)
		(fp_line
			(start 0.7874 -0.4064)
			(end -0.7874 -0.4064)
			(stroke
				(width 0.1524)
				(type default)
			)
			(layer "B.SilkS")
		)
		(fp_line
			(start -0.67945 0.3048)
			(end -0.120396 0.3048)
			(stroke
				(width 0.1)
				(type default)
			)
			(layer "B.Fab")
		)
		(fp_line
			(start -0.120396 0.3048)
			(end -0.120396 0.2794)
			(stroke
				(width 0.1)
				(type default)
			)
			(layer "B.Fab")
		)
		(fp_line
			(start 0.12065 0.3048)
			(end 0.67945 0.3048)
			(stroke
				(width 0.1)
				(type default)
			)
			(layer "B.Fab")
		)
		(fp_line
			(start 0.67945 0.3048)
			(end 0.67945 -0.305054)
			(stroke
				(width 0.1)
				(type default)
			)
			(layer "B.Fab")
		)
		(fp_line
			(start -0.120396 0.2794)
			(end 0.12065 0.2794)
			(stroke
				(width 0.1)
				(type default)
			)
			(layer "B.Fab")
		)
		(fp_line
			(start 0.12065 0.2794)
			(end 0.12065 0.3048)
			(stroke
				(width 0.1)
				(type default)
			)
			(layer "B.Fab")
		)
		(fp_line
			(start -0.12065 -0.2794)
			(end -0.12065 -0.3048)
			(stroke
				(width 0.1)
				(type default)
			)
			(layer "B.Fab")
		)
		(fp_line
			(start 0.12065 -0.2794)
			(end -0.12065 -0.2794)
			(stroke
				(width 0.1)
				(type default)
			)
			(layer "B.Fab")
		)
		(fp_line
			(start -0.67945 -0.3048)
			(end -0.67945 0.3048)
			(stroke
				(width 0.1)
				(type default)
			)
			(layer "B.Fab")
		)
		(fp_line
			(start -0.12065 -0.3048)
			(end -0.67945 -0.3048)
			(stroke
				(width 0.1)
				(type default)
			)
			(layer "B.Fab")
		)
		(fp_line
			(start 0.12065 -0.305054)
			(end 0.12065 -0.2794)
			(stroke
				(width 0.1)
				(type default)
			)
			(layer "B.Fab")
		)
		(fp_line
			(start 0.67945 -0.305054)
			(end 0.12065 -0.305054)
			(stroke
				(width 0.1)
				(type default)
			)
			(layer "B.Fab")
		)
		(pad "1" smd circle
			(at 0.40005 0 90)
			(size 0 0)
			(layers "B.Cu" "B.Mask" "B.Paste")
			(net "RST_GPU_PERST_2_BUF_N")
		)
		(pad "2" smd circle
			(at -0.40005 0 90)
			(size 0 0)
			(layers "B.Cu" "B.Mask" "B.Paste")
			(net "RST_GPU_PERST_2_BUF_R_N")
		)
	)
	(footprint ""
		(layer "B.Cu")
		(at 157.699964 -288.774886 90)
		(property "Reference" "R6158"
			(at 0 0 90)
			(layer "B.SilkS")
			(hide yes)
			(effects
				(font
					(size 1.27 1.27)
				)
				(justify mirror)
			)
		)
		(property "Value" ""
			(at 0 0 90)
			(layer "B.Fab")
			(effects
				(font
					(size 1.27 1.27)
				)
				(justify mirror)
			)
		)
		(duplicate_pad_numbers_are_jumpers no)
		(fp_line
			(start 0.7874 -0.4064)
			(end -0.7874 -0.4064)
			(stroke
				(width 0.1524)
				(type default)
			)
			(layer "B.SilkS")
		)
		(fp_line
			(start -0.7874 -0.4064)
			(end -0.7874 0.4064)
			(stroke
				(width 0.1524)
				(type default)
			)
			(layer "B.SilkS")
		)
		(fp_line
			(start 0.7874 0.4064)
			(end 0.7874 -0.4064)
			(stroke
				(width 0.1524)
				(type default)
			)
			(layer "B.SilkS")
		)
		(fp_line
			(start -0.7874 0.4064)
			(end 0.7874 0.4064)
			(stroke
				(width 0.1524)
				(type default)
			)
			(layer "B.SilkS")
		)
		(fp_line
			(start 0.67945 -0.305054)
			(end 0.12065 -0.305054)
			(stroke
				(width 0.1)
				(type default)
			)
			(layer "B.Fab")
		)
		(fp_line
			(start 0.12065 -0.305054)
			(end 0.12065 -0.2794)
			(stroke
				(width 0.1)
				(type default)
			)
			(layer "B.Fab")
		)
		(fp_line
			(start -0.12065 -0.3048)
			(end -0.67945 -0.3048)
			(stroke
				(width 0.1)
				(type default)
			)
			(layer "B.Fab")
		)
		(fp_line
			(start -0.67945 -0.3048)
			(end -0.67945 0.3048)
			(stroke
				(width 0.1)
				(type default)
			)
			(layer "B.Fab")
		)
		(fp_line
			(start 0.12065 -0.2794)
			(end -0.12065 -0.2794)
			(stroke
				(width 0.1)
				(type default)
			)
			(layer "B.Fab")
		)
		(fp_line
			(start -0.12065 -0.2794)
			(end -0.12065 -0.3048)
			(stroke
				(width 0.1)
				(type default)
			)
			(layer "B.Fab")
		)
		(fp_line
			(start 0.12065 0.2794)
			(end 0.12065 0.3048)
			(stroke
				(width 0.1)
				(type default)
			)
			(layer "B.Fab")
		)
		(fp_line
			(start -0.120396 0.2794)
			(end 0.12065 0.2794)
			(stroke
				(width 0.1)
				(type default)
			)
			(layer "B.Fab")
		)
		(fp_line
			(start 0.67945 0.3048)
			(end 0.67945 -0.305054)
			(stroke
				(width 0.1)
				(type default)
			)
			(layer "B.Fab")
		)
		(fp_line
			(start 0.12065 0.3048)
			(end 0.67945 0.3048)
			(stroke
				(width 0.1)
				(type default)
			)
			(layer "B.Fab")
		)
		(fp_line
			(start -0.120396 0.3048)
			(end -0.120396 0.2794)
			(stroke
				(width 0.1)
				(type default)
			)
			(layer "B.Fab")
		)
		(fp_line
			(start -0.67945 0.3048)
			(end -0.120396 0.3048)
			(stroke
				(width 0.1)
				(type default)
			)
			(layer "B.Fab")
		)
		(pad "1" smd circle
			(at 0.40005 0 270)
			(size 0 0)
			(layers "B.Cu" "B.Mask" "B.Paste")
			(net "SPI_PEX1_CS_N")
		)
		(pad "2" smd circle
			(at -0.40005 0 270)
			(size 0 0)
			(layers "B.Cu" "B.Mask" "B.Paste")
			(net "P1V8_PEX")
		)
	)
	(footprint ""
		(layer "B.Cu")
		(at 135.941816 -204.060806 180)
		(property "Reference" "L7"
			(at 0 0 0)
			(layer "B.SilkS")
			(hide yes)
			(effects
				(font
					(size 1.27 1.27)
				)
				(justify mirror)
			)
		)
		(property "Value" ""
			(at 0 0 0)
			(layer "B.Fab")
			(effects
				(font
					(size 1.27 1.27)
				)
				(justify mirror)
			)
		)
		(duplicate_pad_numbers_are_jumpers no)
		(fp_line
			(start 1.27 0.5842)
			(end 1.27 -0.5842)
			(stroke
				(width 0.1524)
				(type default)
			)
			(layer "B.SilkS")
		)
		(fp_line
			(start 1.27 -0.5588)
			(end 1.27 -0.5842)
			(stroke
				(width 0.1524)
				(type default)
			)
			(layer "B.SilkS")
		)
		(fp_line
			(start 1.27 -0.5842)
			(end -1.27 -0.5842)
			(stroke
				(width 0.1524)
				(type default)
			)
			(layer "B.SilkS")
		)
		(fp_line
			(start -1.27 0.5842)
			(end 1.27 0.5842)
			(stroke
				(width 0.1524)
				(type default)
			)
			(layer "B.SilkS")
		)
		(fp_line
			(start -1.27 0.5842)
			(end -1.27 -0.5842)
			(stroke
				(width 0.1524)
				(type default)
			)
			(layer "B.SilkS")
		)
		(fp_line
			(start 1.194308 0.406654)
			(end 1.194308 -0.406654)
			(stroke
				(width 0.1)
				(type default)
			)
			(layer "B.Fab")
		)
		(fp_line
			(start 1.194308 -0.406654)
			(end 0.9144 -0.406654)
			(stroke
				(width 0.1)
				(type default)
			)
			(layer "B.Fab")
		)
		(fp_line
			(start 0.9144 0.508)
			(end 0.9144 0.406654)
			(stroke
				(width 0.1)
				(type default)
			)
			(layer "B.Fab")
		)
		(fp_line
			(start 0.9144 0.406654)
			(end 1.194308 0.406654)
			(stroke
				(width 0.1)
				(type default)
			)
			(layer "B.Fab")
		)
		(fp_line
			(start 0.9144 -0.406654)
			(end 0.9144 -0.508)
			(stroke
				(width 0.1)
				(type default)
			)
			(layer "B.Fab")
		)
		(fp_line
			(start 0.9144 -0.508)
			(end -0.9144 -0.508)
			(stroke
				(width 0.1)
				(type default)
			)
			(layer "B.Fab")
		)
		(fp_line
			(start -0.9144 0.508)
			(end 0.9144 0.508)
			(stroke
				(width 0.1)
				(type default)
			)
			(layer "B.Fab")
		)
		(fp_line
			(start -0.9144 0.4064)
			(end -0.9144 0.508)
			(stroke
				(width 0.1)
				(type default)
			)
			(layer "B.Fab")
		)
		(fp_line
			(start -0.9144 -0.406654)
			(end -1.1938 -0.406654)
			(stroke
				(width 0.1)
				(type default)
			)
			(layer "B.Fab")
		)
		(fp_line
			(start -0.9144 -0.508)
			(end -0.9144 -0.406654)
			(stroke
				(width 0.1)
				(type default)
			)
			(layer "B.Fab")
		)
		(fp_line
			(start -1.1938 0.4064)
			(end -0.9144 0.4064)
			(stroke
				(width 0.1)
				(type default)
			)
			(layer "B.Fab")
		)
		(fp_line
			(start -1.1938 -0.406654)
			(end -1.1938 0.4064)
			(stroke
				(width 0.1)
				(type default)
			)
			(layer "B.Fab")
		)
		(pad "1" smd rect
			(at 0.7366 0 90)
			(size 0.7112 0.8128)
			(layers "B.Cu" "B.Mask" "B.Paste")
			(net "P3V3_AUX")
		)
		(pad "2" smd rect
			(at -0.7366 0 90)
			(size 0.7112 0.8128)
			(layers "B.Cu" "B.Mask" "B.Paste")
			(net "P3V3_CLI_VPHY")
		)
	)
	(footprint ""
		(layer "B.Cu")
		(at 236.505496 -212.332824 90)
		(property "Reference" "R478"
			(at 0 0 90)
			(layer "B.SilkS")
			(hide yes)
			(effects
				(font
					(size 1.27 1.27)
				)
				(justify mirror)
			)
		)
		(property "Value" ""
			(at 0 0 90)
			(layer "B.Fab")
			(effects
				(font
					(size 1.27 1.27)
				)
				(justify mirror)
			)
		)
		(duplicate_pad_numbers_are_jumpers no)
		(fp_line
			(start 0.7874 -0.4064)
			(end -0.7874 -0.4064)
			(stroke
				(width 0.1524)
				(type default)
			)
			(layer "B.SilkS")
		)
		(fp_line
			(start -0.7874 -0.4064)
			(end -0.7874 0.4064)
			(stroke
				(width 0.1524)
				(type default)
			)
			(layer "B.SilkS")
		)
		(fp_line
			(start 0.7874 0.4064)
			(end 0.7874 -0.4064)
			(stroke
				(width 0.1524)
				(type default)
			)
			(layer "B.SilkS")
		)
		(fp_line
			(start -0.7874 0.4064)
			(end 0.7874 0.4064)
			(stroke
				(width 0.1524)
				(type default)
			)
			(layer "B.SilkS")
		)
		(fp_line
			(start 0.67945 -0.305054)
			(end 0.12065 -0.305054)
			(stroke
				(width 0.1)
				(type default)
			)
			(layer "B.Fab")
		)
		(fp_line
			(start 0.12065 -0.305054)
			(end 0.12065 -0.2794)
			(stroke
				(width 0.1)
				(type default)
			)
			(layer "B.Fab")
		)
		(fp_line
			(start -0.12065 -0.3048)
			(end -0.67945 -0.3048)
			(stroke
				(width 0.1)
				(type default)
			)
			(layer "B.Fab")
		)
		(fp_line
			(start -0.67945 -0.3048)
			(end -0.67945 0.3048)
			(stroke
				(width 0.1)
				(type default)
			)
			(layer "B.Fab")
		)
		(fp_line
			(start 0.12065 -0.2794)
			(end -0.12065 -0.2794)
			(stroke
				(width 0.1)
				(type default)
			)
			(layer "B.Fab")
		)
		(fp_line
			(start -0.12065 -0.2794)
			(end -0.12065 -0.3048)
			(stroke
				(width 0.1)
				(type default)
			)
			(layer "B.Fab")
		)
		(fp_line
			(start 0.12065 0.2794)
			(end 0.12065 0.3048)
			(stroke
				(width 0.1)
				(type default)
			)
			(layer "B.Fab")
		)
		(fp_line
			(start -0.120396 0.2794)
			(end 0.12065 0.2794)
			(stroke
				(width 0.1)
				(type default)
			)
			(layer "B.Fab")
		)
		(fp_line
			(start 0.67945 0.3048)
			(end 0.67945 -0.305054)
			(stroke
				(width 0.1)
				(type default)
			)
			(layer "B.Fab")
		)
		(fp_line
			(start 0.12065 0.3048)
			(end 0.67945 0.3048)
			(stroke
				(width 0.1)
				(type default)
			)
			(layer "B.Fab")
		)
		(fp_line
			(start -0.120396 0.3048)
			(end -0.120396 0.2794)
			(stroke
				(width 0.1)
				(type default)
			)
			(layer "B.Fab")
		)
		(fp_line
			(start -0.67945 0.3048)
			(end -0.120396 0.3048)
			(stroke
				(width 0.1)
				(type default)
			)
			(layer "B.Fab")
		)
		(pad "1" smd circle
			(at 0.40005 0 270)
			(size 0 0)
			(layers "B.Cu" "B.Mask" "B.Paste")
			(net "P1V2_AUX_SCALED")
		)
		(pad "2" smd circle
			(at -0.40005 0 270)
			(size 0 0)
			(layers "B.Cu" "B.Mask" "B.Paste")
			(net "GND")
		)
	)
	(footprint ""
		(layer "B.Cu")
		(at 105.287826 -319.420494 -90)
		(property "Reference" "R5785"
			(at 0 0 90)
			(layer "B.SilkS")
			(hide yes)
			(effects
				(font
					(size 1.27 1.27)
				)
				(justify mirror)
			)
		)
		(property "Value" ""
			(at 0 0 90)
			(layer "B.Fab")
			(effects
				(font
					(size 1.27 1.27)
				)
				(justify mirror)
			)
		)
		(duplicate_pad_numbers_are_jumpers no)
		(fp_line
			(start -2.576322 1.1303)
			(end 2.576322 1.1303)
			(stroke
				(width 0.1524)
				(type default)
			)
			(layer "B.SilkS")
		)
		(fp_line
			(start 2.576322 1.1303)
			(end 2.576322 -1.1303)
			(stroke
				(width 0.1524)
				(type default)
			)
			(layer "B.SilkS")
		)
		(fp_line
			(start -2.576322 -1.1303)
			(end -2.576322 1.1303)
			(stroke
				(width 0.1524)
				(type default)
			)
			(layer "B.SilkS")
		)
		(fp_line
			(start 2.576322 -1.1303)
			(end -2.576322 -1.1303)
			(stroke
				(width 0.1524)
				(type default)
			)
			(layer "B.SilkS")
		)
		(fp_line
			(start -1.649984 0.899922)
			(end -1.649984 -0.899922)
			(stroke
				(width 0.1)
				(type default)
			)
			(layer "B.Fab")
		)
		(fp_line
			(start 1.649984 0.899922)
			(end -1.649984 0.899922)
			(stroke
				(width 0.1)
				(type default)
			)
			(layer "B.Fab")
		)
		(fp_line
			(start -1.649984 -0.899922)
			(end 1.649984 -0.899922)
			(stroke
				(width 0.1)
				(type default)
			)
			(layer "B.Fab")
		)
		(fp_line
			(start 1.649984 -0.899922)
			(end 1.649984 0.899922)
			(stroke
				(width 0.1)
				(type default)
			)
			(layer "B.Fab")
		)
		(pad "1A" smd rect
			(at 1.700022 0 90)
			(size 1.4986 2.0066)
			(layers "B.Cu" "B.Mask" "B.Paste")
			(net "P0V8_PEX0")
		)
		(pad "1B" smd rect
			(at 1.077722 0 90)
			(size 0.254 0.508)
			(layers "B.Cu" "B.Mask" "B.Paste")
			(net "P0V8_PEX0")
		)
		(pad "2A" smd rect
			(at -1.700022 0 90)
			(size 1.4986 2.0066)
			(layers "B.Cu" "B.Mask" "B.Paste")
			(net "P0V8_SERDES_VDDA_PEX0")
		)
		(pad "2B" smd rect
			(at -1.077722 0 90)
			(size 0.254 0.508)
			(layers "B.Cu" "B.Mask" "B.Paste")
			(net "P0V8_SERDES_VDDA_PEX0")
		)
	)
	(footprint ""
		(layer "B.Cu")
		(at 56.799988 -290.199826 90)
		(property "Reference" "C1203"
			(at 0 0 90)
			(layer "B.SilkS")
			(hide yes)
			(effects
				(font
					(size 1.27 1.27)
				)
				(justify mirror)
			)
		)
		(property "Value" ""
			(at 0 0 90)
			(layer "B.Fab")
			(effects
				(font
					(size 1.27 1.27)
				)
				(justify mirror)
			)
		)
		(duplicate_pad_numbers_are_jumpers no)
		(fp_line
			(start 0.299974 -0.150114)
			(end -0.299974 -0.150114)
			(stroke
				(width 0.1)
				(type default)
			)
			(layer "B.Fab")
		)
		(fp_line
			(start -0.299974 -0.150114)
			(end -0.299974 0.150114)
			(stroke
				(width 0.1)
				(type default)
			)
			(layer "B.Fab")
		)
		(fp_line
			(start 0.299974 0.150114)
			(end 0.299974 -0.150114)
			(stroke
				(width 0.1)
				(type default)
			)
			(layer "B.Fab")
		)
		(fp_line
			(start -0.299974 0.150114)
			(end 0.299974 0.150114)
			(stroke
				(width 0.1)
				(type default)
			)
			(layer "B.Fab")
		)
		(pad "1" smd rect
			(at 0.2667 0 270)
			(size 0.3048 0.381)
			(layers "B.Cu" "B.Mask" "B.Paste")
			(net "P0V8_SERDES_VDDA_PEX0")
		)
		(pad "2" smd rect
			(at -0.2667 0 270)
			(size 0.3048 0.381)
			(layers "B.Cu" "B.Mask" "B.Paste")
			(net "GND")
		)
	)
	(footprint ""
		(layer "B.Cu")
		(at 213.730332 -223.382586 180)
		(property "Reference" "R4114"
			(at 0 0 0)
			(layer "B.SilkS")
			(hide yes)
			(effects
				(font
					(size 1.27 1.27)
				)
				(justify mirror)
			)
		)
		(property "Value" ""
			(at 0 0 0)
			(layer "B.Fab")
			(effects
				(font
					(size 1.27 1.27)
				)
				(justify mirror)
			)
		)
		(duplicate_pad_numbers_are_jumpers no)
		(fp_line
			(start 0.7874 0.4064)
			(end 0.7874 -0.4064)
			(stroke
				(width 0.1524)
				(type default)
			)
			(layer "B.SilkS")
		)
		(fp_line
			(start 0.7874 -0.4064)
			(end -0.7874 -0.4064)
			(stroke
				(width 0.1524)
				(type default)
			)
			(layer "B.SilkS")
		)
		(fp_line
			(start -0.7874 0.4064)
			(end 0.7874 0.4064)
			(stroke
				(width 0.1524)
				(type default)
			)
			(layer "B.SilkS")
		)
		(fp_line
			(start -0.7874 -0.4064)
			(end -0.7874 0.4064)
			(stroke
				(width 0.1524)
				(type default)
			)
			(layer "B.SilkS")
		)
		(fp_line
			(start 0.67945 0.3048)
			(end 0.67945 -0.305054)
			(stroke
				(width 0.1)
				(type default)
			)
			(layer "B.Fab")
		)
		(fp_line
			(start 0.67945 -0.305054)
			(end 0.12065 -0.305054)
			(stroke
				(width 0.1)
				(type default)
			)
			(layer "B.Fab")
		)
		(fp_line
			(start 0.12065 0.3048)
			(end 0.67945 0.3048)
			(stroke
				(width 0.1)
				(type default)
			)
			(layer "B.Fab")
		)
		(fp_line
			(start 0.12065 0.2794)
			(end 0.12065 0.3048)
			(stroke
				(width 0.1)
				(type default)
			)
			(layer "B.Fab")
		)
		(fp_line
			(start 0.12065 -0.2794)
			(end -0.12065 -0.2794)
			(stroke
				(width 0.1)
				(type default)
			)
			(layer "B.Fab")
		)
		(fp_line
			(start 0.12065 -0.305054)
			(end 0.12065 -0.2794)
			(stroke
				(width 0.1)
				(type default)
			)
			(layer "B.Fab")
		)
		(fp_line
			(start -0.120396 0.3048)
			(end -0.120396 0.2794)
			(stroke
				(width 0.1)
				(type default)
			)
			(layer "B.Fab")
		)
		(fp_line
			(start -0.120396 0.2794)
			(end 0.12065 0.2794)
			(stroke
				(width 0.1)
				(type default)
			)
			(layer "B.Fab")
		)
		(fp_line
			(start -0.12065 -0.2794)
			(end -0.12065 -0.3048)
			(stroke
				(width 0.1)
				(type default)
			)
			(layer "B.Fab")
		)
		(fp_line
			(start -0.12065 -0.3048)
			(end -0.67945 -0.3048)
			(stroke
				(width 0.1)
				(type default)
			)
			(layer "B.Fab")
		)
		(fp_line
			(start -0.67945 0.3048)
			(end -0.120396 0.3048)
			(stroke
				(width 0.1)
				(type default)
			)
			(layer "B.Fab")
		)
		(fp_line
			(start -0.67945 -0.3048)
			(end -0.67945 0.3048)
			(stroke
				(width 0.1)
				(type default)
			)
			(layer "B.Fab")
		)
		(pad "1" smd circle
			(at 0.40005 0)
			(size 0 0)
			(layers "B.Cu" "B.Mask" "B.Paste")
			(net "P3V3_AUX")
		)
		(pad "2" smd circle
			(at -0.40005 0)
			(size 0 0)
			(layers "B.Cu" "B.Mask" "B.Paste")
			(net "SMB_BIC_I2C6_SDA")
		)
	)
	(footprint ""
		(layer "B.Cu")
		(at 58.699908 -303.499774 -90)
		(property "Reference" "C2922"
			(at 0 0 90)
			(layer "B.SilkS")
			(hide yes)
			(effects
				(font
					(size 1.27 1.27)
				)
				(justify mirror)
			)
		)
		(property "Value" ""
			(at 0 0 90)
			(layer "B.Fab")
			(effects
				(font
					(size 1.27 1.27)
				)
				(justify mirror)
			)
		)
		(duplicate_pad_numbers_are_jumpers no)
		(fp_line
			(start -0.299974 0.150114)
			(end 0.299974 0.150114)
			(stroke
				(width 0.1)
				(type default)
			)
			(layer "B.Fab")
		)
		(fp_line
			(start 0.299974 0.150114)
			(end 0.299974 -0.150114)
			(stroke
				(width 0.1)
				(type default)
			)
			(layer "B.Fab")
		)
		(fp_line
			(start -0.299974 -0.150114)
			(end -0.299974 0.150114)
			(stroke
				(width 0.1)
				(type default)
			)
			(layer "B.Fab")
		)
		(fp_line
			(start 0.299974 -0.150114)
			(end -0.299974 -0.150114)
			(stroke
				(width 0.1)
				(type default)
			)
			(layer "B.Fab")
		)
		(pad "1" smd rect
			(at 0.2667 0 90)
			(size 0.3048 0.381)
			(layers "B.Cu" "B.Mask" "B.Paste")
			(net "P1V25_PEX0")
		)
		(pad "2" smd rect
			(at -0.2667 0 90)
			(size 0.3048 0.381)
			(layers "B.Cu" "B.Mask" "B.Paste")
			(net "GND")
		)
	)
	(footprint ""
		(layer "B.Cu")
		(at 417.450016 -296.37482 180)
		(property "Reference" "C1928"
			(at 0 0 0)
			(layer "B.SilkS")
			(hide yes)
			(effects
				(font
					(size 1.27 1.27)
				)
				(justify mirror)
			)
		)
		(property "Value" ""
			(at 0 0 0)
			(layer "B.Fab")
			(effects
				(font
					(size 1.27 1.27)
				)
				(justify mirror)
			)
		)
		(duplicate_pad_numbers_are_jumpers no)
		(fp_line
			(start 0.299974 0.150114)
			(end 0.299974 -0.150114)
			(stroke
				(width 0.1)
				(type default)
			)
			(layer "B.Fab")
		)
		(fp_line
			(start 0.299974 -0.150114)
			(end -0.299974 -0.150114)
			(stroke
				(width 0.1)
				(type default)
			)
			(layer "B.Fab")
		)
		(fp_line
			(start -0.299974 0.150114)
			(end 0.299974 0.150114)
			(stroke
				(width 0.1)
				(type default)
			)
			(layer "B.Fab")
		)
		(fp_line
			(start -0.299974 -0.150114)
			(end -0.299974 0.150114)
			(stroke
				(width 0.1)
				(type default)
			)
			(layer "B.Fab")
		)
		(pad "1" smd rect
			(at 0.2667 0)
			(size 0.3048 0.381)
			(layers "B.Cu" "B.Mask" "B.Paste")
			(net "P0V8_SERDES_VDDA_PEX3")
		)
		(pad "2" smd rect
			(at -0.2667 0)
			(size 0.3048 0.381)
			(layers "B.Cu" "B.Mask" "B.Paste")
			(net "GND")
		)
	)
	(footprint ""
		(layer "B.Cu")
		(at 267.087858 -366.778794 -90)
		(property "Reference" "PC6002"
			(at 0 0 90)
			(layer "B.SilkS")
			(hide yes)
			(effects
				(font
					(size 1.27 1.27)
				)
				(justify mirror)
			)
		)
		(property "Value" ""
			(at 0 0 90)
			(layer "B.Fab")
			(effects
				(font
					(size 1.27 1.27)
				)
				(justify mirror)
			)
		)
		(duplicate_pad_numbers_are_jumpers no)
		(fp_line
			(start -0.7874 0.4064)
			(end 0.7874 0.4064)
			(stroke
				(width 0.1524)
				(type default)
			)
			(layer "B.SilkS")
		)
		(fp_line
			(start 0.7874 0.4064)
			(end 0.7874 -0.4064)
			(stroke
				(width 0.1524)
				(type default)
			)
			(layer "B.SilkS")
		)
		(fp_line
			(start -0.7874 -0.4064)
			(end -0.7874 0.4064)
			(stroke
				(width 0.1524)
				(type default)
			)
			(layer "B.SilkS")
		)
		(fp_line
			(start 0.7874 -0.4064)
			(end -0.7874 -0.4064)
			(stroke
				(width 0.1524)
				(type default)
			)
			(layer "B.SilkS")
		)
		(fp_line
			(start -0.67945 0.3048)
			(end -0.120396 0.3048)
			(stroke
				(width 0.1)
				(type default)
			)
			(layer "B.Fab")
		)
		(fp_line
			(start -0.120396 0.3048)
			(end -0.120396 0.2794)
			(stroke
				(width 0.1)
				(type default)
			)
			(layer "B.Fab")
		)
		(fp_line
			(start 0.12065 0.3048)
			(end 0.67945 0.3048)
			(stroke
				(width 0.1)
				(type default)
			)
			(layer "B.Fab")
		)
		(fp_line
			(start 0.67945 0.3048)
			(end 0.67945 -0.305054)
			(stroke
				(width 0.1)
				(type default)
			)
			(layer "B.Fab")
		)
		(fp_line
			(start -0.120396 0.2794)
			(end 0.12065 0.2794)
			(stroke
				(width 0.1)
				(type default)
			)
			(layer "B.Fab")
		)
		(fp_line
			(start 0.12065 0.2794)
			(end 0.12065 0.3048)
			(stroke
				(width 0.1)
				(type default)
			)
			(layer "B.Fab")
		)
		(fp_line
			(start -0.12065 -0.2794)
			(end -0.12065 -0.3048)
			(stroke
				(width 0.1)
				(type default)
			)
			(layer "B.Fab")
		)
		(fp_line
			(start 0.12065 -0.2794)
			(end -0.12065 -0.2794)
			(stroke
				(width 0.1)
				(type default)
			)
			(layer "B.Fab")
		)
		(fp_line
			(start -0.67945 -0.3048)
			(end -0.67945 0.3048)
			(stroke
				(width 0.1)
				(type default)
			)
			(layer "B.Fab")
		)
		(fp_line
			(start -0.12065 -0.3048)
			(end -0.67945 -0.3048)
			(stroke
				(width 0.1)
				(type default)
			)
			(layer "B.Fab")
		)
		(fp_line
			(start 0.12065 -0.305054)
			(end 0.12065 -0.2794)
			(stroke
				(width 0.1)
				(type default)
			)
			(layer "B.Fab")
		)
		(fp_line
			(start 0.67945 -0.305054)
			(end 0.12065 -0.305054)
			(stroke
				(width 0.1)
				(type default)
			)
			(layer "B.Fab")
		)
		(pad "1" smd circle
			(at 0.40005 0 90)
			(size 0 0)
			(layers "B.Cu" "B.Mask" "B.Paste")
			(net "P12V_HSC_GATE_RC")
		)
		(pad "2" smd circle
			(at -0.40005 0 90)
			(size 0 0)
			(layers "B.Cu" "B.Mask" "B.Paste")
			(net "P12V_HSC_GATE2")
		)
	)
	(footprint ""
		(layer "B.Cu")
		(at 66.7766 -293.99992 90)
		(property "Reference" "C1166"
			(at 0 0 90)
			(layer "B.SilkS")
			(hide yes)
			(effects
				(font
					(size 1.27 1.27)
				)
				(justify mirror)
			)
		)
		(property "Value" ""
			(at 0 0 90)
			(layer "B.Fab")
			(effects
				(font
					(size 1.27 1.27)
				)
				(justify mirror)
			)
		)
		(duplicate_pad_numbers_are_jumpers no)
		(fp_line
			(start 0.299974 -0.150114)
			(end -0.299974 -0.150114)
			(stroke
				(width 0.1)
				(type default)
			)
			(layer "B.Fab")
		)
		(fp_line
			(start -0.299974 -0.150114)
			(end -0.299974 0.150114)
			(stroke
				(width 0.1)
				(type default)
			)
			(layer "B.Fab")
		)
		(fp_line
			(start 0.299974 0.150114)
			(end 0.299974 -0.150114)
			(stroke
				(width 0.1)
				(type default)
			)
			(layer "B.Fab")
		)
		(fp_line
			(start -0.299974 0.150114)
			(end 0.299974 0.150114)
			(stroke
				(width 0.1)
				(type default)
			)
			(layer "B.Fab")
		)
		(pad "1" smd rect
			(at 0.2667 0 270)
			(size 0.3048 0.381)
			(layers "B.Cu" "B.Mask" "B.Paste")
			(net "P0V8_SERDES_VDDA_PEX0")
		)
		(pad "2" smd rect
			(at -0.2667 0 270)
			(size 0.3048 0.381)
			(layers "B.Cu" "B.Mask" "B.Paste")
			(net "GND")
		)
	)
	(footprint ""
		(layer "B.Cu")
		(at 46.1264 -140.8176 180)
		(property "Reference" "C852"
			(at 0 0 0)
			(layer "B.SilkS")
			(hide yes)
			(effects
				(font
					(size 1.27 1.27)
				)
				(justify mirror)
			)
		)
		(property "Value" ""
			(at 0 0 0)
			(layer "B.Fab")
			(effects
				(font
					(size 1.27 1.27)
				)
				(justify mirror)
			)
		)
		(duplicate_pad_numbers_are_jumpers no)
		(fp_line
			(start 0.7874 0.4064)
			(end 0.7874 -0.4064)
			(stroke
				(width 0.1524)
				(type default)
			)
			(layer "B.SilkS")
		)
		(fp_line
			(start 0.7874 -0.4064)
			(end -0.7874 -0.4064)
			(stroke
				(width 0.1524)
				(type default)
			)
			(layer "B.SilkS")
		)
		(fp_line
			(start -0.7874 0.4064)
			(end 0.7874 0.4064)
			(stroke
				(width 0.1524)
				(type default)
			)
			(layer "B.SilkS")
		)
		(fp_line
			(start -0.7874 -0.4064)
			(end -0.7874 0.4064)
			(stroke
				(width 0.1524)
				(type default)
			)
			(layer "B.SilkS")
		)
		(fp_line
			(start 0.67945 0.3048)
			(end 0.67945 -0.305054)
			(stroke
				(width 0.1)
				(type default)
			)
			(layer "B.Fab")
		)
		(fp_line
			(start 0.67945 -0.305054)
			(end 0.12065 -0.305054)
			(stroke
				(width 0.1)
				(type default)
			)
			(layer "B.Fab")
		)
		(fp_line
			(start 0.12065 0.3048)
			(end 0.67945 0.3048)
			(stroke
				(width 0.1)
				(type default)
			)
			(layer "B.Fab")
		)
		(fp_line
			(start 0.12065 0.2794)
			(end 0.12065 0.3048)
			(stroke
				(width 0.1)
				(type default)
			)
			(layer "B.Fab")
		)
		(fp_line
			(start 0.12065 -0.2794)
			(end -0.12065 -0.2794)
			(stroke
				(width 0.1)
				(type default)
			)
			(layer "B.Fab")
		)
		(fp_line
			(start 0.12065 -0.305054)
			(end 0.12065 -0.2794)
			(stroke
				(width 0.1)
				(type default)
			)
			(layer "B.Fab")
		)
		(fp_line
			(start -0.120396 0.3048)
			(end -0.120396 0.2794)
			(stroke
				(width 0.1)
				(type default)
			)
			(layer "B.Fab")
		)
		(fp_line
			(start -0.120396 0.2794)
			(end 0.12065 0.2794)
			(stroke
				(width 0.1)
				(type default)
			)
			(layer "B.Fab")
		)
		(fp_line
			(start -0.12065 -0.2794)
			(end -0.12065 -0.3048)
			(stroke
				(width 0.1)
				(type default)
			)
			(layer "B.Fab")
		)
		(fp_line
			(start -0.12065 -0.3048)
			(end -0.67945 -0.3048)
			(stroke
				(width 0.1)
				(type default)
			)
			(layer "B.Fab")
		)
		(fp_line
			(start -0.67945 0.3048)
			(end -0.120396 0.3048)
			(stroke
				(width 0.1)
				(type default)
			)
			(layer "B.Fab")
		)
		(fp_line
			(start -0.67945 -0.3048)
			(end -0.67945 0.3048)
			(stroke
				(width 0.1)
				(type default)
			)
			(layer "B.Fab")
		)
		(pad "1" smd circle
			(at 0.40005 0)
			(size 0 0)
			(layers "B.Cu" "B.Mask" "B.Paste")
			(net "P3V3_NIC0")
		)
		(pad "2" smd circle
			(at -0.40005 0)
			(size 0 0)
			(layers "B.Cu" "B.Mask" "B.Paste")
			(net "GND")
		)
	)
	(footprint ""
		(layer "B.Cu")
		(at 375.58853 -237.572296 180)
		(property "Reference" "R913"
			(at 0 0 0)
			(layer "B.SilkS")
			(hide yes)
			(effects
				(font
					(size 1.27 1.27)
				)
				(justify mirror)
			)
		)
		(property "Value" ""
			(at 0 0 0)
			(layer "B.Fab")
			(effects
				(font
					(size 1.27 1.27)
				)
				(justify mirror)
			)
		)
		(duplicate_pad_numbers_are_jumpers no)
		(fp_line
			(start 0.7874 0.4064)
			(end 0.7874 -0.4064)
			(stroke
				(width 0.1524)
				(type default)
			)
			(layer "B.SilkS")
		)
		(fp_line
			(start 0.7874 -0.4064)
			(end -0.7874 -0.4064)
			(stroke
				(width 0.1524)
				(type default)
			)
			(layer "B.SilkS")
		)
		(fp_line
			(start -0.7874 0.4064)
			(end 0.7874 0.4064)
			(stroke
				(width 0.1524)
				(type default)
			)
			(layer "B.SilkS")
		)
		(fp_line
			(start -0.7874 -0.4064)
			(end -0.7874 0.4064)
			(stroke
				(width 0.1524)
				(type default)
			)
			(layer "B.SilkS")
		)
		(fp_line
			(start 0.67945 0.3048)
			(end 0.67945 -0.305054)
			(stroke
				(width 0.1)
				(type default)
			)
			(layer "B.Fab")
		)
		(fp_line
			(start 0.67945 -0.305054)
			(end 0.12065 -0.305054)
			(stroke
				(width 0.1)
				(type default)
			)
			(layer "B.Fab")
		)
		(fp_line
			(start 0.12065 0.3048)
			(end 0.67945 0.3048)
			(stroke
				(width 0.1)
				(type default)
			)
			(layer "B.Fab")
		)
		(fp_line
			(start 0.12065 0.2794)
			(end 0.12065 0.3048)
			(stroke
				(width 0.1)
				(type default)
			)
			(layer "B.Fab")
		)
		(fp_line
			(start 0.12065 -0.2794)
			(end -0.12065 -0.2794)
			(stroke
				(width 0.1)
				(type default)
			)
			(layer "B.Fab")
		)
		(fp_line
			(start 0.12065 -0.305054)
			(end 0.12065 -0.2794)
			(stroke
				(width 0.1)
				(type default)
			)
			(layer "B.Fab")
		)
		(fp_line
			(start -0.120396 0.3048)
			(end -0.120396 0.2794)
			(stroke
				(width 0.1)
				(type default)
			)
			(layer "B.Fab")
		)
		(fp_line
			(start -0.120396 0.2794)
			(end 0.12065 0.2794)
			(stroke
				(width 0.1)
				(type default)
			)
			(layer "B.Fab")
		)
		(fp_line
			(start -0.12065 -0.2794)
			(end -0.12065 -0.3048)
			(stroke
				(width 0.1)
				(type default)
			)
			(layer "B.Fab")
		)
		(fp_line
			(start -0.12065 -0.3048)
			(end -0.67945 -0.3048)
			(stroke
				(width 0.1)
				(type default)
			)
			(layer "B.Fab")
		)
		(fp_line
			(start -0.67945 0.3048)
			(end -0.120396 0.3048)
			(stroke
				(width 0.1)
				(type default)
			)
			(layer "B.Fab")
		)
		(fp_line
			(start -0.67945 -0.3048)
			(end -0.67945 0.3048)
			(stroke
				(width 0.1)
				(type default)
			)
			(layer "B.Fab")
		)
		(pad "1" smd circle
			(at 0.40005 0)
			(size 0 0)
			(layers "B.Cu" "B.Mask" "B.Paste")
			(net "FT4232_SDB_EEPROM_R_SCL")
		)
		(pad "2" smd circle
			(at -0.40005 0)
			(size 0 0)
			(layers "B.Cu" "B.Mask" "B.Paste")
			(net "FT4232_SDB_EEPROM_SCL")
		)
	)
	(footprint ""
		(layer "B.Cu")
		(at 344.297 -207.772 -90)
		(property "Reference" "R4147"
			(at 0 0 90)
			(layer "B.SilkS")
			(hide yes)
			(effects
				(font
					(size 1.27 1.27)
				)
				(justify mirror)
			)
		)
		(property "Value" ""
			(at 0 0 90)
			(layer "B.Fab")
			(effects
				(font
					(size 1.27 1.27)
				)
				(justify mirror)
			)
		)
		(duplicate_pad_numbers_are_jumpers no)
		(fp_line
			(start -0.7874 0.4064)
			(end 0.7874 0.4064)
			(stroke
				(width 0.1524)
				(type default)
			)
			(layer "B.SilkS")
		)
		(fp_line
			(start 0.7874 0.4064)
			(end 0.7874 -0.4064)
			(stroke
				(width 0.1524)
				(type default)
			)
			(layer "B.SilkS")
		)
		(fp_line
			(start -0.7874 -0.4064)
			(end -0.7874 0.4064)
			(stroke
				(width 0.1524)
				(type default)
			)
			(layer "B.SilkS")
		)
		(fp_line
			(start 0.7874 -0.4064)
			(end -0.7874 -0.4064)
			(stroke
				(width 0.1524)
				(type default)
			)
			(layer "B.SilkS")
		)
		(fp_line
			(start -0.67945 0.3048)
			(end -0.120396 0.3048)
			(stroke
				(width 0.1)
				(type default)
			)
			(layer "B.Fab")
		)
		(fp_line
			(start -0.120396 0.3048)
			(end -0.120396 0.2794)
			(stroke
				(width 0.1)
				(type default)
			)
			(layer "B.Fab")
		)
		(fp_line
			(start 0.12065 0.3048)
			(end 0.67945 0.3048)
			(stroke
				(width 0.1)
				(type default)
			)
			(layer "B.Fab")
		)
		(fp_line
			(start 0.67945 0.3048)
			(end 0.67945 -0.305054)
			(stroke
				(width 0.1)
				(type default)
			)
			(layer "B.Fab")
		)
		(fp_line
			(start -0.120396 0.2794)
			(end 0.12065 0.2794)
			(stroke
				(width 0.1)
				(type default)
			)
			(layer "B.Fab")
		)
		(fp_line
			(start 0.12065 0.2794)
			(end 0.12065 0.3048)
			(stroke
				(width 0.1)
				(type default)
			)
			(layer "B.Fab")
		)
		(fp_line
			(start -0.12065 -0.2794)
			(end -0.12065 -0.3048)
			(stroke
				(width 0.1)
				(type default)
			)
			(layer "B.Fab")
		)
		(fp_line
			(start 0.12065 -0.2794)
			(end -0.12065 -0.2794)
			(stroke
				(width 0.1)
				(type default)
			)
			(layer "B.Fab")
		)
		(fp_line
			(start -0.67945 -0.3048)
			(end -0.67945 0.3048)
			(stroke
				(width 0.1)
				(type default)
			)
			(layer "B.Fab")
		)
		(fp_line
			(start -0.12065 -0.3048)
			(end -0.67945 -0.3048)
			(stroke
				(width 0.1)
				(type default)
			)
			(layer "B.Fab")
		)
		(fp_line
			(start 0.12065 -0.305054)
			(end 0.12065 -0.2794)
			(stroke
				(width 0.1)
				(type default)
			)
			(layer "B.Fab")
		)
		(fp_line
			(start 0.67945 -0.305054)
			(end 0.12065 -0.305054)
			(stroke
				(width 0.1)
				(type default)
			)
			(layer "B.Fab")
		)
		(pad "1" smd circle
			(at 0.40005 0 90)
			(size 0 0)
			(layers "B.Cu" "B.Mask" "B.Paste")
			(net "PRSNT_SSD0_FPGA_R_N")
		)
		(pad "2" smd circle
			(at -0.40005 0 90)
			(size 0 0)
			(layers "B.Cu" "B.Mask" "B.Paste")
			(net "PRSNT_SSD0_FPGA_N")
		)
	)
	(footprint ""
		(layer "B.Cu")
		(at 343.449402 -308.613556 90)
		(property "Reference" "PR12"
			(at 0 0 90)
			(layer "B.SilkS")
			(hide yes)
			(effects
				(font
					(size 1.27 1.27)
				)
				(justify mirror)
			)
		)
		(property "Value" ""
			(at 0 0 90)
			(layer "B.Fab")
			(effects
				(font
					(size 1.27 1.27)
				)
				(justify mirror)
			)
		)
		(duplicate_pad_numbers_are_jumpers no)
		(fp_line
			(start 1.2954 -0.5842)
			(end -1.2954 -0.5842)
			(stroke
				(width 0.1524)
				(type default)
			)
			(layer "B.SilkS")
		)
		(fp_line
			(start -1.2954 -0.5842)
			(end -1.2954 0.5842)
			(stroke
				(width 0.1524)
				(type default)
			)
			(layer "B.SilkS")
		)
		(fp_line
			(start 1.2954 0.5842)
			(end 1.2954 -0.5842)
			(stroke
				(width 0.1524)
				(type default)
			)
			(layer "B.SilkS")
		)
		(fp_line
			(start -1.2954 0.5842)
			(end 1.2954 0.5842)
			(stroke
				(width 0.1524)
				(type default)
			)
			(layer "B.SilkS")
		)
		(fp_line
			(start 0.8636 -0.4572)
			(end -0.8636 -0.4572)
			(stroke
				(width 0.1)
				(type default)
			)
			(layer "B.Fab")
		)
		(fp_line
			(start -0.8636 -0.4572)
			(end -0.8636 -0.406654)
			(stroke
				(width 0.1)
				(type default)
			)
			(layer "B.Fab")
		)
		(fp_line
			(start 1.1938 -0.406654)
			(end 0.8636 -0.406654)
			(stroke
				(width 0.1)
				(type default)
			)
			(layer "B.Fab")
		)
		(fp_line
			(start 0.8636 -0.406654)
			(end 0.8636 -0.4572)
			(stroke
				(width 0.1)
				(type default)
			)
			(layer "B.Fab")
		)
		(fp_line
			(start -0.8636 -0.406654)
			(end -1.1938 -0.406654)
			(stroke
				(width 0.1)
				(type default)
			)
			(layer "B.Fab")
		)
		(fp_line
			(start -1.1938 -0.406654)
			(end -1.1938 0.4064)
			(stroke
				(width 0.1)
				(type default)
			)
			(layer "B.Fab")
		)
		(fp_line
			(start 1.1938 0.4064)
			(end 1.1938 -0.406654)
			(stroke
				(width 0.1)
				(type default)
			)
			(layer "B.Fab")
		)
		(fp_line
			(start 0.8636 0.4064)
			(end 1.1938 0.4064)
			(stroke
				(width 0.1)
				(type default)
			)
			(layer "B.Fab")
		)
		(fp_line
			(start -0.8636 0.4064)
			(end -0.8636 0.4572)
			(stroke
				(width 0.1)
				(type default)
			)
			(layer "B.Fab")
		)
		(fp_line
			(start -1.1938 0.4064)
			(end -0.8636 0.4064)
			(stroke
				(width 0.1)
				(type default)
			)
			(layer "B.Fab")
		)
		(fp_line
			(start 0.8636 0.4318)
			(end 0.8636 0.4064)
			(stroke
				(width 0.1)
				(type default)
			)
			(layer "B.Fab")
		)
		(fp_line
			(start 0.8636 0.4572)
			(end 0.8636 0.4318)
			(stroke
				(width 0.1)
				(type default)
			)
			(layer "B.Fab")
		)
		(fp_line
			(start -0.8636 0.4572)
			(end 0.8636 0.4572)
			(stroke
				(width 0.1)
				(type default)
			)
			(layer "B.Fab")
		)
		(pad "1" smd rect
			(at 0.7366 0)
			(size 0.7112 0.8128)
			(layers "B.Cu" "B.Mask" "B.Paste")
			(net "P0V8_PEX2")
		)
		(pad "2" smd rect
			(at -0.7366 0)
			(size 0.7112 0.8128)
			(layers "B.Cu" "B.Mask" "B.Paste")
			(net "GND")
		)
	)
	(footprint ""
		(layer "B.Cu")
		(at 402.249894 -299.699934 -90)
		(property "Reference" "C1972"
			(at 0 0 90)
			(layer "B.SilkS")
			(hide yes)
			(effects
				(font
					(size 1.27 1.27)
				)
				(justify mirror)
			)
		)
		(property "Value" ""
			(at 0 0 90)
			(layer "B.Fab")
			(effects
				(font
					(size 1.27 1.27)
				)
				(justify mirror)
			)
		)
		(duplicate_pad_numbers_are_jumpers no)
		(fp_line
			(start -0.299974 0.150114)
			(end 0.299974 0.150114)
			(stroke
				(width 0.1)
				(type default)
			)
			(layer "B.Fab")
		)
		(fp_line
			(start 0.299974 0.150114)
			(end 0.299974 -0.150114)
			(stroke
				(width 0.1)
				(type default)
			)
			(layer "B.Fab")
		)
		(fp_line
			(start -0.299974 -0.150114)
			(end -0.299974 0.150114)
			(stroke
				(width 0.1)
				(type default)
			)
			(layer "B.Fab")
		)
		(fp_line
			(start 0.299974 -0.150114)
			(end -0.299974 -0.150114)
			(stroke
				(width 0.1)
				(type default)
			)
			(layer "B.Fab")
		)
		(pad "1" smd rect
			(at 0.2667 0 90)
			(size 0.3048 0.381)
			(layers "B.Cu" "B.Mask" "B.Paste")
			(net "P0V8_SERDES_VDDA_PEX3")
		)
		(pad "2" smd rect
			(at -0.2667 0 90)
			(size 0.3048 0.381)
			(layers "B.Cu" "B.Mask" "B.Paste")
			(net "GND")
		)
	)
	(footprint ""
		(layer "B.Cu")
		(at 213.456774 -234.205526 -90)
		(property "Reference" "R6332"
			(at 0 0 90)
			(layer "B.SilkS")
			(hide yes)
			(effects
				(font
					(size 1.27 1.27)
				)
				(justify mirror)
			)
		)
		(property "Value" ""
			(at 0 0 90)
			(layer "B.Fab")
			(effects
				(font
					(size 1.27 1.27)
				)
				(justify mirror)
			)
		)
		(duplicate_pad_numbers_are_jumpers no)
		(fp_line
			(start -0.7874 0.4064)
			(end 0.7874 0.4064)
			(stroke
				(width 0.1524)
				(type default)
			)
			(layer "B.SilkS")
		)
		(fp_line
			(start 0.7874 0.4064)
			(end 0.7874 -0.4064)
			(stroke
				(width 0.1524)
				(type default)
			)
			(layer "B.SilkS")
		)
		(fp_line
			(start -0.7874 -0.4064)
			(end -0.7874 0.4064)
			(stroke
				(width 0.1524)
				(type default)
			)
			(layer "B.SilkS")
		)
		(fp_line
			(start 0.7874 -0.4064)
			(end -0.7874 -0.4064)
			(stroke
				(width 0.1524)
				(type default)
			)
			(layer "B.SilkS")
		)
		(fp_line
			(start -0.67945 0.3048)
			(end -0.120396 0.3048)
			(stroke
				(width 0.1)
				(type default)
			)
			(layer "B.Fab")
		)
		(fp_line
			(start -0.120396 0.3048)
			(end -0.120396 0.2794)
			(stroke
				(width 0.1)
				(type default)
			)
			(layer "B.Fab")
		)
		(fp_line
			(start 0.12065 0.3048)
			(end 0.67945 0.3048)
			(stroke
				(width 0.1)
				(type default)
			)
			(layer "B.Fab")
		)
		(fp_line
			(start 0.67945 0.3048)
			(end 0.67945 -0.305054)
			(stroke
				(width 0.1)
				(type default)
			)
			(layer "B.Fab")
		)
		(fp_line
			(start -0.120396 0.2794)
			(end 0.12065 0.2794)
			(stroke
				(width 0.1)
				(type default)
			)
			(layer "B.Fab")
		)
		(fp_line
			(start 0.12065 0.2794)
			(end 0.12065 0.3048)
			(stroke
				(width 0.1)
				(type default)
			)
			(layer "B.Fab")
		)
		(fp_line
			(start -0.12065 -0.2794)
			(end -0.12065 -0.3048)
			(stroke
				(width 0.1)
				(type default)
			)
			(layer "B.Fab")
		)
		(fp_line
			(start 0.12065 -0.2794)
			(end -0.12065 -0.2794)
			(stroke
				(width 0.1)
				(type default)
			)
			(layer "B.Fab")
		)
		(fp_line
			(start -0.67945 -0.3048)
			(end -0.67945 0.3048)
			(stroke
				(width 0.1)
				(type default)
			)
			(layer "B.Fab")
		)
		(fp_line
			(start -0.12065 -0.3048)
			(end -0.67945 -0.3048)
			(stroke
				(width 0.1)
				(type default)
			)
			(layer "B.Fab")
		)
		(fp_line
			(start 0.12065 -0.305054)
			(end 0.12065 -0.2794)
			(stroke
				(width 0.1)
				(type default)
			)
			(layer "B.Fab")
		)
		(fp_line
			(start 0.67945 -0.305054)
			(end 0.12065 -0.305054)
			(stroke
				(width 0.1)
				(type default)
			)
			(layer "B.Fab")
		)
		(pad "1" smd circle
			(at 0.40005 0 90)
			(size 0 0)
			(layers "B.Cu" "B.Mask" "B.Paste")
			(net "SMB_PEX3_SDA")
		)
		(pad "2" smd circle
			(at -0.40005 0 90)
			(size 0 0)
			(layers "B.Cu" "B.Mask" "B.Paste")
			(net "SMB_PEX3_MUX_SDA")
		)
	)
	(footprint ""
		(layer "B.Cu")
		(at 297.074844 -293.99992 90)
		(property "Reference" "C1640"
			(at 0 0 90)
			(layer "B.SilkS")
			(hide yes)
			(effects
				(font
					(size 1.27 1.27)
				)
				(justify mirror)
			)
		)
		(property "Value" ""
			(at 0 0 90)
			(layer "B.Fab")
			(effects
				(font
					(size 1.27 1.27)
				)
				(justify mirror)
			)
		)
		(duplicate_pad_numbers_are_jumpers no)
		(fp_line
			(start 0.299974 -0.150114)
			(end -0.299974 -0.150114)
			(stroke
				(width 0.1)
				(type default)
			)
			(layer "B.Fab")
		)
		(fp_line
			(start -0.299974 -0.150114)
			(end -0.299974 0.150114)
			(stroke
				(width 0.1)
				(type default)
			)
			(layer "B.Fab")
		)
		(fp_line
			(start 0.299974 0.150114)
			(end 0.299974 -0.150114)
			(stroke
				(width 0.1)
				(type default)
			)
			(layer "B.Fab")
		)
		(fp_line
			(start -0.299974 0.150114)
			(end 0.299974 0.150114)
			(stroke
				(width 0.1)
				(type default)
			)
			(layer "B.Fab")
		)
		(pad "1" smd rect
			(at 0.2667 0 270)
			(size 0.3048 0.381)
			(layers "B.Cu" "B.Mask" "B.Paste")
			(net "P0V8_PEX2")
		)
		(pad "2" smd rect
			(at -0.2667 0 270)
			(size 0.3048 0.381)
			(layers "B.Cu" "B.Mask" "B.Paste")
			(net "GND")
		)
	)
	(footprint ""
		(layer "B.Cu")
		(at 131.859274 -321.83451 -90)
		(property "Reference" "R6488"
			(at 0 0 90)
			(layer "B.SilkS")
			(hide yes)
			(effects
				(font
					(size 1.27 1.27)
				)
				(justify mirror)
			)
		)
		(property "Value" ""
			(at 0 0 90)
			(layer "B.Fab")
			(effects
				(font
					(size 1.27 1.27)
				)
				(justify mirror)
			)
		)
		(duplicate_pad_numbers_are_jumpers no)
		(fp_line
			(start -0.7874 0.4064)
			(end 0.7874 0.4064)
			(stroke
				(width 0.1524)
				(type default)
			)
			(layer "B.SilkS")
		)
		(fp_line
			(start 0.7874 0.4064)
			(end 0.7874 -0.4064)
			(stroke
				(width 0.1524)
				(type default)
			)
			(layer "B.SilkS")
		)
		(fp_line
			(start -0.7874 -0.4064)
			(end -0.7874 0.4064)
			(stroke
				(width 0.1524)
				(type default)
			)
			(layer "B.SilkS")
		)
		(fp_line
			(start 0.7874 -0.4064)
			(end -0.7874 -0.4064)
			(stroke
				(width 0.1524)
				(type default)
			)
			(layer "B.SilkS")
		)
		(fp_line
			(start -0.67945 0.3048)
			(end -0.120396 0.3048)
			(stroke
				(width 0.1)
				(type default)
			)
			(layer "B.Fab")
		)
		(fp_line
			(start -0.120396 0.3048)
			(end -0.120396 0.2794)
			(stroke
				(width 0.1)
				(type default)
			)
			(layer "B.Fab")
		)
		(fp_line
			(start 0.12065 0.3048)
			(end 0.67945 0.3048)
			(stroke
				(width 0.1)
				(type default)
			)
			(layer "B.Fab")
		)
		(fp_line
			(start 0.67945 0.3048)
			(end 0.67945 -0.305054)
			(stroke
				(width 0.1)
				(type default)
			)
			(layer "B.Fab")
		)
		(fp_line
			(start -0.120396 0.2794)
			(end 0.12065 0.2794)
			(stroke
				(width 0.1)
				(type default)
			)
			(layer "B.Fab")
		)
		(fp_line
			(start 0.12065 0.2794)
			(end 0.12065 0.3048)
			(stroke
				(width 0.1)
				(type default)
			)
			(layer "B.Fab")
		)
		(fp_line
			(start -0.12065 -0.2794)
			(end -0.12065 -0.3048)
			(stroke
				(width 0.1)
				(type default)
			)
			(layer "B.Fab")
		)
		(fp_line
			(start 0.12065 -0.2794)
			(end -0.12065 -0.2794)
			(stroke
				(width 0.1)
				(type default)
			)
			(layer "B.Fab")
		)
		(fp_line
			(start -0.67945 -0.3048)
			(end -0.67945 0.3048)
			(stroke
				(width 0.1)
				(type default)
			)
			(layer "B.Fab")
		)
		(fp_line
			(start -0.12065 -0.3048)
			(end -0.67945 -0.3048)
			(stroke
				(width 0.1)
				(type default)
			)
			(layer "B.Fab")
		)
		(fp_line
			(start 0.12065 -0.305054)
			(end 0.12065 -0.2794)
			(stroke
				(width 0.1)
				(type default)
			)
			(layer "B.Fab")
		)
		(fp_line
			(start 0.67945 -0.305054)
			(end 0.12065 -0.305054)
			(stroke
				(width 0.1)
				(type default)
			)
			(layer "B.Fab")
		)
		(pad "1" smd circle
			(at 0.40005 0 90)
			(size 0 0)
			(layers "B.Cu" "B.Mask" "B.Paste")
			(net "P0V8_SERDES_VDDA_PEX1")
		)
		(pad "2" smd circle
			(at -0.40005 0 90)
			(size 0 0)
			(layers "B.Cu" "B.Mask" "B.Paste")
			(net "P0V8_SERDES_VDDA_PEX1_C11")
		)
	)
	(footprint ""
		(layer "B.Cu")
		(at 449.810632 -277.073614)
		(property "Reference" "C4405"
			(at 0 0 0)
			(layer "B.SilkS")
			(hide yes)
			(effects
				(font
					(size 1.27 1.27)
				)
				(justify mirror)
			)
		)
		(property "Value" ""
			(at 0 0 0)
			(layer "B.Fab")
			(effects
				(font
					(size 1.27 1.27)
				)
				(justify mirror)
			)
		)
		(duplicate_pad_numbers_are_jumpers no)
		(fp_line
			(start -0.299974 -0.150114)
			(end -0.299974 0.150114)
			(stroke
				(width 0.1)
				(type default)
			)
			(layer "B.Fab")
		)
		(fp_line
			(start -0.299974 0.150114)
			(end 0.299974 0.150114)
			(stroke
				(width 0.1)
				(type default)
			)
			(layer "B.Fab")
		)
		(fp_line
			(start 0.299974 -0.150114)
			(end -0.299974 -0.150114)
			(stroke
				(width 0.1)
				(type default)
			)
			(layer "B.Fab")
		)
		(fp_line
			(start 0.299974 0.150114)
			(end 0.299974 -0.150114)
			(stroke
				(width 0.1)
				(type default)
			)
			(layer "B.Fab")
		)
		(pad "1" smd rect
			(at 0.2667 0 180)
			(size 0.3048 0.381)
			(layers "B.Cu" "B.Mask" "B.Paste")
			(net "P1V25_PEX3")
		)
		(pad "2" smd rect
			(at -0.2667 0 180)
			(size 0.3048 0.381)
			(layers "B.Cu" "B.Mask" "B.Paste")
			(net "GND")
		)
	)
	(footprint ""
		(layer "B.Cu")
		(at 361.407202 -275.81606 180)
		(property "Reference" "PC6619"
			(at 0 0 0)
			(layer "B.SilkS")
			(hide yes)
			(effects
				(font
					(size 1.27 1.27)
				)
				(justify mirror)
			)
		)
		(property "Value" ""
			(at 0 0 0)
			(layer "B.Fab")
			(effects
				(font
					(size 1.27 1.27)
				)
				(justify mirror)
			)
		)
		(duplicate_pad_numbers_are_jumpers no)
		(fp_line
			(start 1.524 0.762)
			(end 1.524 -0.762)
			(stroke
				(width 0.1524)
				(type default)
			)
			(layer "B.SilkS")
		)
		(fp_line
			(start 1.524 -0.762)
			(end -1.524 -0.762)
			(stroke
				(width 0.1524)
				(type default)
			)
			(layer "B.SilkS")
		)
		(fp_line
			(start -1.524 0.762)
			(end 1.524 0.762)
			(stroke
				(width 0.1524)
				(type default)
			)
			(layer "B.SilkS")
		)
		(fp_line
			(start -1.524 -0.762)
			(end -1.524 0.762)
			(stroke
				(width 0.1524)
				(type default)
			)
			(layer "B.SilkS")
		)
		(fp_line
			(start 1.1049 0.724916)
			(end -1.1049 0.724916)
			(stroke
				(width 0.1)
				(type default)
			)
			(layer "B.Fab")
		)
		(fp_line
			(start 1.1049 -0.724916)
			(end 1.1049 0.724916)
			(stroke
				(width 0.1)
				(type default)
			)
			(layer "B.Fab")
		)
		(fp_line
			(start -1.1049 0.724916)
			(end -1.1049 -0.724916)
			(stroke
				(width 0.1)
				(type default)
			)
			(layer "B.Fab")
		)
		(fp_line
			(start -1.1049 -0.724916)
			(end 1.1049 -0.724916)
			(stroke
				(width 0.1)
				(type default)
			)
			(layer "B.Fab")
		)
		(pad "1" smd rect
			(at 0.889 0 180)
			(size 1.016 1.27)
			(layers "B.Cu" "B.Mask" "B.Paste")
			(net "SW_P12V_P0V8_PEX3_FLT")
		)
		(pad "2" smd rect
			(at -0.889 0 180)
			(size 1.016 1.27)
			(layers "B.Cu" "B.Mask" "B.Paste")
			(net "GND")
		)
	)
	(footprint ""
		(layer "B.Cu")
		(at 134.735062 -321.851528 -90)
		(property "Reference" "R6479"
			(at 0 0 90)
			(layer "B.SilkS")
			(hide yes)
			(effects
				(font
					(size 1.27 1.27)
				)
				(justify mirror)
			)
		)
		(property "Value" ""
			(at 0 0 90)
			(layer "B.Fab")
			(effects
				(font
					(size 1.27 1.27)
				)
				(justify mirror)
			)
		)
		(duplicate_pad_numbers_are_jumpers no)
		(fp_line
			(start -0.7874 0.4064)
			(end 0.7874 0.4064)
			(stroke
				(width 0.1524)
				(type default)
			)
			(layer "B.SilkS")
		)
		(fp_line
			(start 0.7874 0.4064)
			(end 0.7874 -0.4064)
			(stroke
				(width 0.1524)
				(type default)
			)
			(layer "B.SilkS")
		)
		(fp_line
			(start -0.7874 -0.4064)
			(end -0.7874 0.4064)
			(stroke
				(width 0.1524)
				(type default)
			)
			(layer "B.SilkS")
		)
		(fp_line
			(start 0.7874 -0.4064)
			(end -0.7874 -0.4064)
			(stroke
				(width 0.1524)
				(type default)
			)
			(layer "B.SilkS")
		)
		(fp_line
			(start -0.67945 0.3048)
			(end -0.120396 0.3048)
			(stroke
				(width 0.1)
				(type default)
			)
			(layer "B.Fab")
		)
		(fp_line
			(start -0.120396 0.3048)
			(end -0.120396 0.2794)
			(stroke
				(width 0.1)
				(type default)
			)
			(layer "B.Fab")
		)
		(fp_line
			(start 0.12065 0.3048)
			(end 0.67945 0.3048)
			(stroke
				(width 0.1)
				(type default)
			)
			(layer "B.Fab")
		)
		(fp_line
			(start 0.67945 0.3048)
			(end 0.67945 -0.305054)
			(stroke
				(width 0.1)
				(type default)
			)
			(layer "B.Fab")
		)
		(fp_line
			(start -0.120396 0.2794)
			(end 0.12065 0.2794)
			(stroke
				(width 0.1)
				(type default)
			)
			(layer "B.Fab")
		)
		(fp_line
			(start 0.12065 0.2794)
			(end 0.12065 0.3048)
			(stroke
				(width 0.1)
				(type default)
			)
			(layer "B.Fab")
		)
		(fp_line
			(start -0.12065 -0.2794)
			(end -0.12065 -0.3048)
			(stroke
				(width 0.1)
				(type default)
			)
			(layer "B.Fab")
		)
		(fp_line
			(start 0.12065 -0.2794)
			(end -0.12065 -0.2794)
			(stroke
				(width 0.1)
				(type default)
			)
			(layer "B.Fab")
		)
		(fp_line
			(start -0.67945 -0.3048)
			(end -0.67945 0.3048)
			(stroke
				(width 0.1)
				(type default)
			)
			(layer "B.Fab")
		)
		(fp_line
			(start -0.12065 -0.3048)
			(end -0.67945 -0.3048)
			(stroke
				(width 0.1)
				(type default)
			)
			(layer "B.Fab")
		)
		(fp_line
			(start 0.12065 -0.305054)
			(end 0.12065 -0.2794)
			(stroke
				(width 0.1)
				(type default)
			)
			(layer "B.Fab")
		)
		(fp_line
			(start 0.67945 -0.305054)
			(end 0.12065 -0.305054)
			(stroke
				(width 0.1)
				(type default)
			)
			(layer "B.Fab")
		)
		(pad "1" smd circle
			(at 0.40005 0 90)
			(size 0 0)
			(layers "B.Cu" "B.Mask" "B.Paste")
			(net "P0V8_SERDES_VDDA_PEX1")
		)
		(pad "2" smd circle
			(at -0.40005 0 90)
			(size 0 0)
			(layers "B.Cu" "B.Mask" "B.Paste")
			(net "P0V8_SERDES_VDDA_PEX1_C4")
		)
	)
	(footprint ""
		(layer "B.Cu")
		(at 397.166084 -138.421618 180)
		(property "Reference" "R309"
			(at 0 0 0)
			(layer "B.SilkS")
			(hide yes)
			(effects
				(font
					(size 1.27 1.27)
				)
				(justify mirror)
			)
		)
		(property "Value" ""
			(at 0 0 0)
			(layer "B.Fab")
			(effects
				(font
					(size 1.27 1.27)
				)
				(justify mirror)
			)
		)
		(duplicate_pad_numbers_are_jumpers no)
		(fp_line
			(start 0.7874 0.4064)
			(end 0.7874 -0.4064)
			(stroke
				(width 0.1524)
				(type default)
			)
			(layer "B.SilkS")
		)
		(fp_line
			(start 0.7874 -0.4064)
			(end -0.7874 -0.4064)
			(stroke
				(width 0.1524)
				(type default)
			)
			(layer "B.SilkS")
		)
		(fp_line
			(start -0.7874 0.4064)
			(end 0.7874 0.4064)
			(stroke
				(width 0.1524)
				(type default)
			)
			(layer "B.SilkS")
		)
		(fp_line
			(start -0.7874 -0.4064)
			(end -0.7874 0.4064)
			(stroke
				(width 0.1524)
				(type default)
			)
			(layer "B.SilkS")
		)
		(fp_line
			(start 0.67945 0.3048)
			(end 0.67945 -0.305054)
			(stroke
				(width 0.1)
				(type default)
			)
			(layer "B.Fab")
		)
		(fp_line
			(start 0.67945 -0.305054)
			(end 0.12065 -0.305054)
			(stroke
				(width 0.1)
				(type default)
			)
			(layer "B.Fab")
		)
		(fp_line
			(start 0.12065 0.3048)
			(end 0.67945 0.3048)
			(stroke
				(width 0.1)
				(type default)
			)
			(layer "B.Fab")
		)
		(fp_line
			(start 0.12065 0.2794)
			(end 0.12065 0.3048)
			(stroke
				(width 0.1)
				(type default)
			)
			(layer "B.Fab")
		)
		(fp_line
			(start 0.12065 -0.2794)
			(end -0.12065 -0.2794)
			(stroke
				(width 0.1)
				(type default)
			)
			(layer "B.Fab")
		)
		(fp_line
			(start 0.12065 -0.305054)
			(end 0.12065 -0.2794)
			(stroke
				(width 0.1)
				(type default)
			)
			(layer "B.Fab")
		)
		(fp_line
			(start -0.120396 0.3048)
			(end -0.120396 0.2794)
			(stroke
				(width 0.1)
				(type default)
			)
			(layer "B.Fab")
		)
		(fp_line
			(start -0.120396 0.2794)
			(end 0.12065 0.2794)
			(stroke
				(width 0.1)
				(type default)
			)
			(layer "B.Fab")
		)
		(fp_line
			(start -0.12065 -0.2794)
			(end -0.12065 -0.3048)
			(stroke
				(width 0.1)
				(type default)
			)
			(layer "B.Fab")
		)
		(fp_line
			(start -0.12065 -0.3048)
			(end -0.67945 -0.3048)
			(stroke
				(width 0.1)
				(type default)
			)
			(layer "B.Fab")
		)
		(fp_line
			(start -0.67945 0.3048)
			(end -0.120396 0.3048)
			(stroke
				(width 0.1)
				(type default)
			)
			(layer "B.Fab")
		)
		(fp_line
			(start -0.67945 -0.3048)
			(end -0.67945 0.3048)
			(stroke
				(width 0.1)
				(type default)
			)
			(layer "B.Fab")
		)
		(pad "1" smd circle
			(at 0.40005 0)
			(size 0 0)
			(layers "B.Cu" "B.Mask" "B.Paste")
			(net "NIC6_AUX_PWR_EN_R")
		)
		(pad "2" smd circle
			(at -0.40005 0)
			(size 0 0)
			(layers "B.Cu" "B.Mask" "B.Paste")
			(net "NIC6_AUX_PWR_EN")
		)
	)
	(footprint ""
		(layer "B.Cu")
		(at 226.546664 -207.02016 -90)
		(property "Reference" "R5284"
			(at 0 0 90)
			(layer "B.SilkS")
			(hide yes)
			(effects
				(font
					(size 1.27 1.27)
				)
				(justify mirror)
			)
		)
		(property "Value" ""
			(at 0 0 90)
			(layer "B.Fab")
			(effects
				(font
					(size 1.27 1.27)
				)
				(justify mirror)
			)
		)
		(duplicate_pad_numbers_are_jumpers no)
		(fp_line
			(start -0.7874 0.4064)
			(end 0.7874 0.4064)
			(stroke
				(width 0.1524)
				(type default)
			)
			(layer "B.SilkS")
		)
		(fp_line
			(start 0.7874 0.4064)
			(end 0.7874 -0.4064)
			(stroke
				(width 0.1524)
				(type default)
			)
			(layer "B.SilkS")
		)
		(fp_line
			(start -0.7874 -0.4064)
			(end -0.7874 0.4064)
			(stroke
				(width 0.1524)
				(type default)
			)
			(layer "B.SilkS")
		)
		(fp_line
			(start 0.7874 -0.4064)
			(end -0.7874 -0.4064)
			(stroke
				(width 0.1524)
				(type default)
			)
			(layer "B.SilkS")
		)
		(fp_line
			(start -0.67945 0.3048)
			(end -0.120396 0.3048)
			(stroke
				(width 0.1)
				(type default)
			)
			(layer "B.Fab")
		)
		(fp_line
			(start -0.120396 0.3048)
			(end -0.120396 0.2794)
			(stroke
				(width 0.1)
				(type default)
			)
			(layer "B.Fab")
		)
		(fp_line
			(start 0.12065 0.3048)
			(end 0.67945 0.3048)
			(stroke
				(width 0.1)
				(type default)
			)
			(layer "B.Fab")
		)
		(fp_line
			(start 0.67945 0.3048)
			(end 0.67945 -0.305054)
			(stroke
				(width 0.1)
				(type default)
			)
			(layer "B.Fab")
		)
		(fp_line
			(start -0.120396 0.2794)
			(end 0.12065 0.2794)
			(stroke
				(width 0.1)
				(type default)
			)
			(layer "B.Fab")
		)
		(fp_line
			(start 0.12065 0.2794)
			(end 0.12065 0.3048)
			(stroke
				(width 0.1)
				(type default)
			)
			(layer "B.Fab")
		)
		(fp_line
			(start -0.12065 -0.2794)
			(end -0.12065 -0.3048)
			(stroke
				(width 0.1)
				(type default)
			)
			(layer "B.Fab")
		)
		(fp_line
			(start 0.12065 -0.2794)
			(end -0.12065 -0.2794)
			(stroke
				(width 0.1)
				(type default)
			)
			(layer "B.Fab")
		)
		(fp_line
			(start -0.67945 -0.3048)
			(end -0.67945 0.3048)
			(stroke
				(width 0.1)
				(type default)
			)
			(layer "B.Fab")
		)
		(fp_line
			(start -0.12065 -0.3048)
			(end -0.67945 -0.3048)
			(stroke
				(width 0.1)
				(type default)
			)
			(layer "B.Fab")
		)
		(fp_line
			(start 0.12065 -0.305054)
			(end 0.12065 -0.2794)
			(stroke
				(width 0.1)
				(type default)
			)
			(layer "B.Fab")
		)
		(fp_line
			(start 0.67945 -0.305054)
			(end 0.12065 -0.305054)
			(stroke
				(width 0.1)
				(type default)
			)
			(layer "B.Fab")
		)
		(pad "1" smd circle
			(at 0.40005 0 90)
			(size 0 0)
			(layers "B.Cu" "B.Mask" "B.Paste")
			(net "GND")
		)
		(pad "2" smd circle
			(at -0.40005 0 90)
			(size 0 0)
			(layers "B.Cu" "B.Mask" "B.Paste")
			(net "JTAG_BIC_TMS_R")
		)
	)
	(footprint ""
		(layer "B.Cu")
		(at 297.074844 -297.79976 -90)
		(property "Reference" "C1652"
			(at 0 0 90)
			(layer "B.SilkS")
			(hide yes)
			(effects
				(font
					(size 1.27 1.27)
				)
				(justify mirror)
			)
		)
		(property "Value" ""
			(at 0 0 90)
			(layer "B.Fab")
			(effects
				(font
					(size 1.27 1.27)
				)
				(justify mirror)
			)
		)
		(duplicate_pad_numbers_are_jumpers no)
		(fp_line
			(start -0.299974 0.150114)
			(end 0.299974 0.150114)
			(stroke
				(width 0.1)
				(type default)
			)
			(layer "B.Fab")
		)
		(fp_line
			(start 0.299974 0.150114)
			(end 0.299974 -0.150114)
			(stroke
				(width 0.1)
				(type default)
			)
			(layer "B.Fab")
		)
		(fp_line
			(start -0.299974 -0.150114)
			(end -0.299974 0.150114)
			(stroke
				(width 0.1)
				(type default)
			)
			(layer "B.Fab")
		)
		(fp_line
			(start 0.299974 -0.150114)
			(end -0.299974 -0.150114)
			(stroke
				(width 0.1)
				(type default)
			)
			(layer "B.Fab")
		)
		(pad "1" smd rect
			(at 0.2667 0 90)
			(size 0.3048 0.381)
			(layers "B.Cu" "B.Mask" "B.Paste")
			(net "P0V8_PEX2")
		)
		(pad "2" smd rect
			(at -0.2667 0 90)
			(size 0.3048 0.381)
			(layers "B.Cu" "B.Mask" "B.Paste")
			(net "GND")
		)
	)
	(footprint ""
		(layer "B.Cu")
		(at 297.549824 -288.299906 90)
		(property "Reference" "C3273"
			(at 0 0 90)
			(layer "B.SilkS")
			(hide yes)
			(effects
				(font
					(size 1.27 1.27)
				)
				(justify mirror)
			)
		)
		(property "Value" ""
			(at 0 0 90)
			(layer "B.Fab")
			(effects
				(font
					(size 1.27 1.27)
				)
				(justify mirror)
			)
		)
		(duplicate_pad_numbers_are_jumpers no)
		(fp_line
			(start 0.299974 -0.150114)
			(end -0.299974 -0.150114)
			(stroke
				(width 0.1)
				(type default)
			)
			(layer "B.Fab")
		)
		(fp_line
			(start -0.299974 -0.150114)
			(end -0.299974 0.150114)
			(stroke
				(width 0.1)
				(type default)
			)
			(layer "B.Fab")
		)
		(fp_line
			(start 0.299974 0.150114)
			(end 0.299974 -0.150114)
			(stroke
				(width 0.1)
				(type default)
			)
			(layer "B.Fab")
		)
		(fp_line
			(start -0.299974 0.150114)
			(end 0.299974 0.150114)
			(stroke
				(width 0.1)
				(type default)
			)
			(layer "B.Fab")
		)
		(pad "1" smd rect
			(at 0.2667 0 270)
			(size 0.3048 0.381)
			(layers "B.Cu" "B.Mask" "B.Paste")
			(net "P1V25_PEX2")
		)
		(pad "2" smd rect
			(at -0.2667 0 270)
			(size 0.3048 0.381)
			(layers "B.Cu" "B.Mask" "B.Paste")
			(net "GND")
		)
	)
	(footprint ""
		(layer "B.Cu")
		(at 40.649906 -288.774886 -90)
		(property "Reference" "R3292"
			(at 0 0 90)
			(layer "B.SilkS")
			(hide yes)
			(effects
				(font
					(size 1.27 1.27)
				)
				(justify mirror)
			)
		)
		(property "Value" ""
			(at 0 0 90)
			(layer "B.Fab")
			(effects
				(font
					(size 1.27 1.27)
				)
				(justify mirror)
			)
		)
		(duplicate_pad_numbers_are_jumpers no)
		(fp_line
			(start -0.7874 0.4064)
			(end 0.7874 0.4064)
			(stroke
				(width 0.1524)
				(type default)
			)
			(layer "B.SilkS")
		)
		(fp_line
			(start 0.7874 0.4064)
			(end 0.7874 -0.4064)
			(stroke
				(width 0.1524)
				(type default)
			)
			(layer "B.SilkS")
		)
		(fp_line
			(start -0.7874 -0.4064)
			(end -0.7874 0.4064)
			(stroke
				(width 0.1524)
				(type default)
			)
			(layer "B.SilkS")
		)
		(fp_line
			(start 0.7874 -0.4064)
			(end -0.7874 -0.4064)
			(stroke
				(width 0.1524)
				(type default)
			)
			(layer "B.SilkS")
		)
		(fp_line
			(start -0.67945 0.3048)
			(end -0.120396 0.3048)
			(stroke
				(width 0.1)
				(type default)
			)
			(layer "B.Fab")
		)
		(fp_line
			(start -0.120396 0.3048)
			(end -0.120396 0.2794)
			(stroke
				(width 0.1)
				(type default)
			)
			(layer "B.Fab")
		)
		(fp_line
			(start 0.12065 0.3048)
			(end 0.67945 0.3048)
			(stroke
				(width 0.1)
				(type default)
			)
			(layer "B.Fab")
		)
		(fp_line
			(start 0.67945 0.3048)
			(end 0.67945 -0.305054)
			(stroke
				(width 0.1)
				(type default)
			)
			(layer "B.Fab")
		)
		(fp_line
			(start -0.120396 0.2794)
			(end 0.12065 0.2794)
			(stroke
				(width 0.1)
				(type default)
			)
			(layer "B.Fab")
		)
		(fp_line
			(start 0.12065 0.2794)
			(end 0.12065 0.3048)
			(stroke
				(width 0.1)
				(type default)
			)
			(layer "B.Fab")
		)
		(fp_line
			(start -0.12065 -0.2794)
			(end -0.12065 -0.3048)
			(stroke
				(width 0.1)
				(type default)
			)
			(layer "B.Fab")
		)
		(fp_line
			(start 0.12065 -0.2794)
			(end -0.12065 -0.2794)
			(stroke
				(width 0.1)
				(type default)
			)
			(layer "B.Fab")
		)
		(fp_line
			(start -0.67945 -0.3048)
			(end -0.67945 0.3048)
			(stroke
				(width 0.1)
				(type default)
			)
			(layer "B.Fab")
		)
		(fp_line
			(start -0.12065 -0.3048)
			(end -0.67945 -0.3048)
			(stroke
				(width 0.1)
				(type default)
			)
			(layer "B.Fab")
		)
		(fp_line
			(start 0.12065 -0.305054)
			(end 0.12065 -0.2794)
			(stroke
				(width 0.1)
				(type default)
			)
			(layer "B.Fab")
		)
		(fp_line
			(start 0.67945 -0.305054)
			(end 0.12065 -0.305054)
			(stroke
				(width 0.1)
				(type default)
			)
			(layer "B.Fab")
		)
		(pad "1" smd circle
			(at 0.40005 0 90)
			(size 0 0)
			(layers "B.Cu" "B.Mask" "B.Paste")
			(net "SPI_PEX0_CS_R_N")
		)
		(pad "2" smd circle
			(at -0.40005 0 90)
			(size 0 0)
			(layers "B.Cu" "B.Mask" "B.Paste")
			(net "SPI_PEX0_CS_N")
		)
	)
	(footprint ""
		(layer "B.Cu")
		(at 287.099756 -288.299906 90)
		(property "Reference" "C3278"
			(at 0 0 90)
			(layer "B.SilkS")
			(hide yes)
			(effects
				(font
					(size 1.27 1.27)
				)
				(justify mirror)
			)
		)
		(property "Value" ""
			(at 0 0 90)
			(layer "B.Fab")
			(effects
				(font
					(size 1.27 1.27)
				)
				(justify mirror)
			)
		)
		(duplicate_pad_numbers_are_jumpers no)
		(fp_line
			(start 0.299974 -0.150114)
			(end -0.299974 -0.150114)
			(stroke
				(width 0.1)
				(type default)
			)
			(layer "B.Fab")
		)
		(fp_line
			(start -0.299974 -0.150114)
			(end -0.299974 0.150114)
			(stroke
				(width 0.1)
				(type default)
			)
			(layer "B.Fab")
		)
		(fp_line
			(start 0.299974 0.150114)
			(end 0.299974 -0.150114)
			(stroke
				(width 0.1)
				(type default)
			)
			(layer "B.Fab")
		)
		(fp_line
			(start -0.299974 0.150114)
			(end 0.299974 0.150114)
			(stroke
				(width 0.1)
				(type default)
			)
			(layer "B.Fab")
		)
		(pad "1" smd rect
			(at 0.2667 0 270)
			(size 0.3048 0.381)
			(layers "B.Cu" "B.Mask" "B.Paste")
			(net "P1V25_PEX2")
		)
		(pad "2" smd rect
			(at -0.2667 0 270)
			(size 0.3048 0.381)
			(layers "B.Cu" "B.Mask" "B.Paste")
			(net "GND")
		)
	)
	(footprint ""
		(layer "B.Cu")
		(at 237.562644 -231.225598 -90)
		(property "Reference" "R4527"
			(at 0 0 90)
			(layer "B.SilkS")
			(hide yes)
			(effects
				(font
					(size 1.27 1.27)
				)
				(justify mirror)
			)
		)
		(property "Value" ""
			(at 0 0 90)
			(layer "B.Fab")
			(effects
				(font
					(size 1.27 1.27)
				)
				(justify mirror)
			)
		)
		(duplicate_pad_numbers_are_jumpers no)
		(fp_line
			(start -0.7874 0.4064)
			(end 0.7874 0.4064)
			(stroke
				(width 0.1524)
				(type default)
			)
			(layer "B.SilkS")
		)
		(fp_line
			(start 0.7874 0.4064)
			(end 0.7874 -0.4064)
			(stroke
				(width 0.1524)
				(type default)
			)
			(layer "B.SilkS")
		)
		(fp_line
			(start -0.7874 -0.4064)
			(end -0.7874 0.4064)
			(stroke
				(width 0.1524)
				(type default)
			)
			(layer "B.SilkS")
		)
		(fp_line
			(start 0.7874 -0.4064)
			(end -0.7874 -0.4064)
			(stroke
				(width 0.1524)
				(type default)
			)
			(layer "B.SilkS")
		)
		(fp_line
			(start -0.67945 0.3048)
			(end -0.120396 0.3048)
			(stroke
				(width 0.1)
				(type default)
			)
			(layer "B.Fab")
		)
		(fp_line
			(start -0.120396 0.3048)
			(end -0.120396 0.2794)
			(stroke
				(width 0.1)
				(type default)
			)
			(layer "B.Fab")
		)
		(fp_line
			(start 0.12065 0.3048)
			(end 0.67945 0.3048)
			(stroke
				(width 0.1)
				(type default)
			)
			(layer "B.Fab")
		)
		(fp_line
			(start 0.67945 0.3048)
			(end 0.67945 -0.305054)
			(stroke
				(width 0.1)
				(type default)
			)
			(layer "B.Fab")
		)
		(fp_line
			(start -0.120396 0.2794)
			(end 0.12065 0.2794)
			(stroke
				(width 0.1)
				(type default)
			)
			(layer "B.Fab")
		)
		(fp_line
			(start 0.12065 0.2794)
			(end 0.12065 0.3048)
			(stroke
				(width 0.1)
				(type default)
			)
			(layer "B.Fab")
		)
		(fp_line
			(start -0.12065 -0.2794)
			(end -0.12065 -0.3048)
			(stroke
				(width 0.1)
				(type default)
			)
			(layer "B.Fab")
		)
		(fp_line
			(start 0.12065 -0.2794)
			(end -0.12065 -0.2794)
			(stroke
				(width 0.1)
				(type default)
			)
			(layer "B.Fab")
		)
		(fp_line
			(start -0.67945 -0.3048)
			(end -0.67945 0.3048)
			(stroke
				(width 0.1)
				(type default)
			)
			(layer "B.Fab")
		)
		(fp_line
			(start -0.12065 -0.3048)
			(end -0.67945 -0.3048)
			(stroke
				(width 0.1)
				(type default)
			)
			(layer "B.Fab")
		)
		(fp_line
			(start 0.12065 -0.305054)
			(end 0.12065 -0.2794)
			(stroke
				(width 0.1)
				(type default)
			)
			(layer "B.Fab")
		)
		(fp_line
			(start 0.67945 -0.305054)
			(end 0.12065 -0.305054)
			(stroke
				(width 0.1)
				(type default)
			)
			(layer "B.Fab")
		)
		(pad "1" smd circle
			(at 0.40005 0 90)
			(size 0 0)
			(layers "B.Cu" "B.Mask" "B.Paste")
			(net "SSD13_PWRDIS_BIC")
		)
		(pad "2" smd circle
			(at -0.40005 0 90)
			(size 0 0)
			(layers "B.Cu" "B.Mask" "B.Paste")
			(net "SSD13_PWRDIS_BIC_R")
		)
	)
	(footprint ""
		(layer "B.Cu")
		(at 108.146342 -321.810888 -90)
		(property "Reference" "R6458"
			(at 0 0 90)
			(layer "B.SilkS")
			(hide yes)
			(effects
				(font
					(size 1.27 1.27)
				)
				(justify mirror)
			)
		)
		(property "Value" ""
			(at 0 0 90)
			(layer "B.Fab")
			(effects
				(font
					(size 1.27 1.27)
				)
				(justify mirror)
			)
		)
		(duplicate_pad_numbers_are_jumpers no)
		(fp_line
			(start -0.7874 0.4064)
			(end 0.7874 0.4064)
			(stroke
				(width 0.1524)
				(type default)
			)
			(layer "B.SilkS")
		)
		(fp_line
			(start 0.7874 0.4064)
			(end 0.7874 -0.4064)
			(stroke
				(width 0.1524)
				(type default)
			)
			(layer "B.SilkS")
		)
		(fp_line
			(start -0.7874 -0.4064)
			(end -0.7874 0.4064)
			(stroke
				(width 0.1524)
				(type default)
			)
			(layer "B.SilkS")
		)
		(fp_line
			(start 0.7874 -0.4064)
			(end -0.7874 -0.4064)
			(stroke
				(width 0.1524)
				(type default)
			)
			(layer "B.SilkS")
		)
		(fp_line
			(start -0.67945 0.3048)
			(end -0.120396 0.3048)
			(stroke
				(width 0.1)
				(type default)
			)
			(layer "B.Fab")
		)
		(fp_line
			(start -0.120396 0.3048)
			(end -0.120396 0.2794)
			(stroke
				(width 0.1)
				(type default)
			)
			(layer "B.Fab")
		)
		(fp_line
			(start 0.12065 0.3048)
			(end 0.67945 0.3048)
			(stroke
				(width 0.1)
				(type default)
			)
			(layer "B.Fab")
		)
		(fp_line
			(start 0.67945 0.3048)
			(end 0.67945 -0.305054)
			(stroke
				(width 0.1)
				(type default)
			)
			(layer "B.Fab")
		)
		(fp_line
			(start -0.120396 0.2794)
			(end 0.12065 0.2794)
			(stroke
				(width 0.1)
				(type default)
			)
			(layer "B.Fab")
		)
		(fp_line
			(start 0.12065 0.2794)
			(end 0.12065 0.3048)
			(stroke
				(width 0.1)
				(type default)
			)
			(layer "B.Fab")
		)
		(fp_line
			(start -0.12065 -0.2794)
			(end -0.12065 -0.3048)
			(stroke
				(width 0.1)
				(type default)
			)
			(layer "B.Fab")
		)
		(fp_line
			(start 0.12065 -0.2794)
			(end -0.12065 -0.2794)
			(stroke
				(width 0.1)
				(type default)
			)
			(layer "B.Fab")
		)
		(fp_line
			(start -0.67945 -0.3048)
			(end -0.67945 0.3048)
			(stroke
				(width 0.1)
				(type default)
			)
			(layer "B.Fab")
		)
		(fp_line
			(start -0.12065 -0.3048)
			(end -0.67945 -0.3048)
			(stroke
				(width 0.1)
				(type default)
			)
			(layer "B.Fab")
		)
		(fp_line
			(start 0.12065 -0.305054)
			(end 0.12065 -0.2794)
			(stroke
				(width 0.1)
				(type default)
			)
			(layer "B.Fab")
		)
		(fp_line
			(start 0.67945 -0.305054)
			(end 0.12065 -0.305054)
			(stroke
				(width 0.1)
				(type default)
			)
			(layer "B.Fab")
		)
		(pad "1" smd circle
			(at 0.40005 0 90)
			(size 0 0)
			(layers "B.Cu" "B.Mask" "B.Paste")
			(net "P0V8_SERDES_VDDA_PEX0")
		)
		(pad "2" smd circle
			(at -0.40005 0 90)
			(size 0 0)
			(layers "B.Cu" "B.Mask" "B.Paste")
			(net "P0V8_SERDES_VDDA_PEX0_C9")
		)
	)
	(footprint ""
		(layer "B.Cu")
		(at 173.375066 -293.99992 -90)
		(property "Reference" "C1402"
			(at 0 0 90)
			(layer "B.SilkS")
			(hide yes)
			(effects
				(font
					(size 1.27 1.27)
				)
				(justify mirror)
			)
		)
		(property "Value" ""
			(at 0 0 90)
			(layer "B.Fab")
			(effects
				(font
					(size 1.27 1.27)
				)
				(justify mirror)
			)
		)
		(duplicate_pad_numbers_are_jumpers no)
		(fp_line
			(start -0.299974 0.150114)
			(end 0.299974 0.150114)
			(stroke
				(width 0.1)
				(type default)
			)
			(layer "B.Fab")
		)
		(fp_line
			(start 0.299974 0.150114)
			(end 0.299974 -0.150114)
			(stroke
				(width 0.1)
				(type default)
			)
			(layer "B.Fab")
		)
		(fp_line
			(start -0.299974 -0.150114)
			(end -0.299974 0.150114)
			(stroke
				(width 0.1)
				(type default)
			)
			(layer "B.Fab")
		)
		(fp_line
			(start 0.299974 -0.150114)
			(end -0.299974 -0.150114)
			(stroke
				(width 0.1)
				(type default)
			)
			(layer "B.Fab")
		)
		(pad "1" smd rect
			(at 0.2667 0 90)
			(size 0.3048 0.381)
			(layers "B.Cu" "B.Mask" "B.Paste")
			(net "P0V8_PEX1")
		)
		(pad "2" smd rect
			(at -0.2667 0 90)
			(size 0.3048 0.381)
			(layers "B.Cu" "B.Mask" "B.Paste")
			(net "GND")
		)
	)
	(footprint ""
		(layer "B.Cu")
		(at 397.49984 -288.774886 180)
		(property "Reference" "C3532"
			(at 0 0 0)
			(layer "B.SilkS")
			(hide yes)
			(effects
				(font
					(size 1.27 1.27)
				)
				(justify mirror)
			)
		)
		(property "Value" ""
			(at 0 0 0)
			(layer "B.Fab")
			(effects
				(font
					(size 1.27 1.27)
				)
				(justify mirror)
			)
		)
		(duplicate_pad_numbers_are_jumpers no)
		(fp_line
			(start 0.299974 0.150114)
			(end 0.299974 -0.150114)
			(stroke
				(width 0.1)
				(type default)
			)
			(layer "B.Fab")
		)
		(fp_line
			(start 0.299974 -0.150114)
			(end -0.299974 -0.150114)
			(stroke
				(width 0.1)
				(type default)
			)
			(layer "B.Fab")
		)
		(fp_line
			(start -0.299974 0.150114)
			(end 0.299974 0.150114)
			(stroke
				(width 0.1)
				(type default)
			)
			(layer "B.Fab")
		)
		(fp_line
			(start -0.299974 -0.150114)
			(end -0.299974 0.150114)
			(stroke
				(width 0.1)
				(type default)
			)
			(layer "B.Fab")
		)
		(pad "1" smd rect
			(at 0.2667 0)
			(size 0.3048 0.381)
			(layers "B.Cu" "B.Mask" "B.Paste")
			(net "P1V8_VDDA_PEX3")
		)
		(pad "2" smd rect
			(at -0.2667 0)
			(size 0.3048 0.381)
			(layers "B.Cu" "B.Mask" "B.Paste")
			(net "GND")
		)
	)
	(footprint ""
		(layer "B.Cu")
		(at 170.049952 -299.699934 -90)
		(property "Reference" "C1462"
			(at 0 0 90)
			(layer "B.SilkS")
			(hide yes)
			(effects
				(font
					(size 1.27 1.27)
				)
				(justify mirror)
			)
		)
		(property "Value" ""
			(at 0 0 90)
			(layer "B.Fab")
			(effects
				(font
					(size 1.27 1.27)
				)
				(justify mirror)
			)
		)
		(duplicate_pad_numbers_are_jumpers no)
		(fp_line
			(start -0.299974 0.150114)
			(end 0.299974 0.150114)
			(stroke
				(width 0.1)
				(type default)
			)
			(layer "B.Fab")
		)
		(fp_line
			(start 0.299974 0.150114)
			(end 0.299974 -0.150114)
			(stroke
				(width 0.1)
				(type default)
			)
			(layer "B.Fab")
		)
		(fp_line
			(start -0.299974 -0.150114)
			(end -0.299974 0.150114)
			(stroke
				(width 0.1)
				(type default)
			)
			(layer "B.Fab")
		)
		(fp_line
			(start 0.299974 -0.150114)
			(end -0.299974 -0.150114)
			(stroke
				(width 0.1)
				(type default)
			)
			(layer "B.Fab")
		)
		(pad "1" smd rect
			(at 0.2667 0 90)
			(size 0.3048 0.381)
			(layers "B.Cu" "B.Mask" "B.Paste")
			(net "P0V8_SERDES_VDDA_PEX1")
		)
		(pad "2" smd rect
			(at -0.2667 0 90)
			(size 0.3048 0.381)
			(layers "B.Cu" "B.Mask" "B.Paste")
			(net "GND")
		)
	)
	(footprint ""
		(layer "B.Cu")
		(at 239.470184 -222.292672 90)
		(property "Reference" "L148"
			(at 0 0 90)
			(layer "B.SilkS")
			(hide yes)
			(effects
				(font
					(size 1.27 1.27)
				)
				(justify mirror)
			)
		)
		(property "Value" ""
			(at 0 0 90)
			(layer "B.Fab")
			(effects
				(font
					(size 1.27 1.27)
				)
				(justify mirror)
			)
		)
		(duplicate_pad_numbers_are_jumpers no)
		(fp_line
			(start 1.27 -0.5842)
			(end -1.27 -0.5842)
			(stroke
				(width 0.1524)
				(type default)
			)
			(layer "B.SilkS")
		)
		(fp_line
			(start 1.27 -0.5588)
			(end 1.27 -0.5842)
			(stroke
				(width 0.1524)
				(type default)
			)
			(layer "B.SilkS")
		)
		(fp_line
			(start 1.27 0.5842)
			(end 1.27 -0.5842)
			(stroke
				(width 0.1524)
				(type default)
			)
			(layer "B.SilkS")
		)
		(fp_line
			(start -1.27 0.5842)
			(end -1.27 -0.5842)
			(stroke
				(width 0.1524)
				(type default)
			)
			(layer "B.SilkS")
		)
		(fp_line
			(start -1.27 0.5842)
			(end 1.27 0.5842)
			(stroke
				(width 0.1524)
				(type default)
			)
			(layer "B.SilkS")
		)
		(fp_line
			(start 0.9144 -0.508)
			(end -0.9144 -0.508)
			(stroke
				(width 0.1)
				(type default)
			)
			(layer "B.Fab")
		)
		(fp_line
			(start -0.9144 -0.508)
			(end -0.9144 -0.406654)
			(stroke
				(width 0.1)
				(type default)
			)
			(layer "B.Fab")
		)
		(fp_line
			(start 1.194308 -0.406654)
			(end 0.9144 -0.406654)
			(stroke
				(width 0.1)
				(type default)
			)
			(layer "B.Fab")
		)
		(fp_line
			(start 0.9144 -0.406654)
			(end 0.9144 -0.508)
			(stroke
				(width 0.1)
				(type default)
			)
			(layer "B.Fab")
		)
		(fp_line
			(start -0.9144 -0.406654)
			(end -1.1938 -0.406654)
			(stroke
				(width 0.1)
				(type default)
			)
			(layer "B.Fab")
		)
		(fp_line
			(start -1.1938 -0.406654)
			(end -1.1938 0.4064)
			(stroke
				(width 0.1)
				(type default)
			)
			(layer "B.Fab")
		)
		(fp_line
			(start -0.9144 0.4064)
			(end -0.9144 0.508)
			(stroke
				(width 0.1)
				(type default)
			)
			(layer "B.Fab")
		)
		(fp_line
			(start -1.1938 0.4064)
			(end -0.9144 0.4064)
			(stroke
				(width 0.1)
				(type default)
			)
			(layer "B.Fab")
		)
		(fp_line
			(start 1.194308 0.406654)
			(end 1.194308 -0.406654)
			(stroke
				(width 0.1)
				(type default)
			)
			(layer "B.Fab")
		)
		(fp_line
			(start 0.9144 0.406654)
			(end 1.194308 0.406654)
			(stroke
				(width 0.1)
				(type default)
			)
			(layer "B.Fab")
		)
		(fp_line
			(start 0.9144 0.508)
			(end 0.9144 0.406654)
			(stroke
				(width 0.1)
				(type default)
			)
			(layer "B.Fab")
		)
		(fp_line
			(start -0.9144 0.508)
			(end 0.9144 0.508)
			(stroke
				(width 0.1)
				(type default)
			)
			(layer "B.Fab")
		)
		(pad "1" smd rect
			(at 0.7366 0)
			(size 0.7112 0.8128)
			(layers "B.Cu" "B.Mask" "B.Paste")
			(net "P3V3_AUX")
		)
		(pad "2" smd rect
			(at -0.7366 0)
			(size 0.7112 0.8128)
			(layers "B.Cu" "B.Mask" "B.Paste")
			(net "P3V3_BIC_ADCAV33")
		)
	)
	(footprint ""
		(layer "B.Cu")
		(at 151.209248 -456.596496 180)
		(property "Reference" "X27"
			(at -4.300982 2.197862 90)
			(unlocked yes)
			(layer "B.SilkS")
			(effects
				(font
					(size 0.7874 0.5842)
					(thickness 0.1524)
				)
				(justify left mirror)
			)
		)
		(property "Value" ""
			(at 0 0 0)
			(layer "B.Fab")
			(effects
				(font
					(size 1.27 1.27)
				)
				(justify mirror)
			)
		)
		(property "Device Type" "TP_TDR_4P_FTS_MPKT4_H025P0200_IO_TP15_TP_TDR_4P_DIP"
			(at -1.30175 1.27 90)
			(unlocked yes)
			(layer "B.Fab")
			(hide yes)
			(effects
				(font
					(size 0.635 0.4064)
					(thickness 0.1524)
				)
				(justify mirror)
			)
		)
		(property "User Part Number" "TP15"
			(at -1.30175 1.27 90)
			(unlocked yes)
			(layer "Cmts.User")
			(hide yes)
			(effects
				(font
					(size 0.635 0.4064)
					(thickness 0.1524)
				)
				(justify mirror)
			)
		)
		(duplicate_pad_numbers_are_jumpers no)
		(fp_line
			(start 0 3.81)
			(end -2.54 3.81)
			(stroke
				(width 0.1524)
				(type default)
			)
			(layer "B.SilkS")
		)
		(fp_line
			(start 0 3.175)
			(end 0 3.81)
			(stroke
				(width 0.1524)
				(type default)
			)
			(layer "B.SilkS")
		)
		(fp_line
			(start 0 0.635)
			(end 0 1.905)
			(stroke
				(width 0.1524)
				(type default)
			)
			(layer "B.SilkS")
		)
		(fp_line
			(start 0 -1.27)
			(end 0 -0.635)
			(stroke
				(width 0.1524)
				(type default)
			)
			(layer "B.SilkS")
		)
		(fp_line
			(start -2.54 3.81)
			(end -2.54 3.6703)
			(stroke
				(width 0.1524)
				(type default)
			)
			(layer "B.SilkS")
		)
		(fp_line
			(start -2.54 1.4097)
			(end -2.54 1.1303)
			(stroke
				(width 0.1524)
				(type default)
			)
			(layer "B.SilkS")
		)
		(fp_line
			(start -2.54 -1.1303)
			(end -2.54 -1.27)
			(stroke
				(width 0.1524)
				(type default)
			)
			(layer "B.SilkS")
		)
		(fp_line
			(start -2.54 -1.27)
			(end 0 -1.27)
			(stroke
				(width 0.1524)
				(type default)
			)
			(layer "B.SilkS")
		)
		(fp_poly
			(pts
				(xy 0.761746 0) (xy 2.285746 -0.762) (xy 2.285746 0.762)
			)
			(stroke
				(width 0)
				(type default)
			)
			(fill yes)
			(layer "B.SilkS")
		)
		(fp_line
			(start 0 3.81)
			(end -2.54 3.81)
			(stroke
				(width 0.1)
				(type default)
			)
			(layer "B.Fab")
		)
		(fp_line
			(start 0 -1.27)
			(end 0 3.81)
			(stroke
				(width 0.1)
				(type default)
			)
			(layer "B.Fab")
		)
		(fp_line
			(start -2.54 3.81)
			(end -2.54 -1.27)
			(stroke
				(width 0.1)
				(type default)
			)
			(layer "B.Fab")
		)
		(fp_line
			(start -2.54 -1.27)
			(end 0 -1.27)
			(stroke
				(width 0.1)
				(type default)
			)
			(layer "B.Fab")
		)
		(fp_poly
			(pts
				(xy 0.761746 0) (xy 2.285746 -0.762) (xy 2.285746 0.762)
			)
			(stroke
				(width 0)
				(type default)
			)
			(fill yes)
			(layer "B.Fab")
		)
		(pad "1" thru_hole circle
			(at 0 0)
			(size 1.0033 1.0033)
			(drill 0.249936)
			(layers "*.Cu" "*.Mask")
			(remove_unused_layers no)
			(net "TDR_DIFF_85_IN4_DIN")
			(clearance 0.10795)
			(padstack
				(mode front_inner_back)
				(layer "Inner"
					(shape circle)
					(size 0.8001 0.8001)
					(clearance 0.1524)
				)
				(layer "B.Cu"
					(shape circle)
					(size 1.0033 1.0033)
					(thermal_gap 0.10795)
					(clearance 0.10795)
				)
			)
		)
		(pad "2" thru_hole circle
			(at -2.54 0)
			(size 1.9939 1.9939)
			(drill 0.249936)
			(layers "*.Cu" "*.Mask")
			(remove_unused_layers no)
			(net "COUPON_GND1")
			(clearance 0.10795)
			(padstack
				(mode front_inner_back)
				(layer "Inner"
					(shape circle)
					(size 0.8001 0.8001)
					(clearance 0.1524)
				)
				(layer "B.Cu"
					(shape circle)
					(size 1.9939 1.9939)
					(thermal_gap 0.10795)
					(clearance 0.10795)
				)
			)
		)
		(pad "3" thru_hole circle
			(at -2.54 2.54)
			(size 1.9939 1.9939)
			(drill 0.249936)
			(layers "*.Cu" "*.Mask")
			(remove_unused_layers no)
			(net "COUPON_GND1")
			(clearance 0.10795)
			(padstack
				(mode front_inner_back)
				(layer "Inner"
					(shape circle)
					(size 0.8001 0.8001)
					(clearance 0.1524)
				)
				(layer "B.Cu"
					(shape circle)
					(size 1.9939 1.9939)
					(thermal_gap 0.10795)
					(clearance 0.10795)
				)
			)
		)
		(pad "4" thru_hole circle
			(at 0 2.54)
			(size 1.0033 1.0033)
			(drill 0.249936)
			(layers "*.Cu" "*.Mask")
			(remove_unused_layers no)
			(net "TDR_DIFF_85_IN4_DIP")
			(clearance 0.10795)
			(padstack
				(mode front_inner_back)
				(layer "Inner"
					(shape circle)
					(size 0.8001 0.8001)
					(clearance 0.1524)
				)
				(layer "B.Cu"
					(shape circle)
					(size 1.0033 1.0033)
					(thermal_gap 0.10795)
					(clearance 0.10795)
				)
			)
		)
	)
	(footprint ""
		(layer "B.Cu")
		(at 403.164802 -140.931138 180)
		(property "Reference" "U38"
			(at -0.367792 1.820164 0)
			(unlocked yes)
			(layer "B.SilkS")
			(effects
				(font
					(size 0.7874 0.5842)
					(thickness 0.1524)
				)
				(justify mirror)
			)
		)
		(property "Value" ""
			(at 0 0 0)
			(layer "B.Fab")
			(effects
				(font
					(size 1.27 1.27)
				)
				(justify mirror)
			)
		)
		(duplicate_pad_numbers_are_jumpers no)
		(fp_line
			(start 1.3462 1.1938)
			(end -1.3462 1.1938)
			(stroke
				(width 0.1524)
				(type default)
			)
			(layer "B.SilkS")
		)
		(fp_line
			(start 1.3462 -1.1938)
			(end 1.3462 1.1684)
			(stroke
				(width 0.1524)
				(type default)
			)
			(layer "B.SilkS")
		)
		(fp_line
			(start -1.3462 1.1938)
			(end -1.3462 -1.1938)
			(stroke
				(width 0.1524)
				(type default)
			)
			(layer "B.SilkS")
		)
		(fp_line
			(start -1.3462 -1.1938)
			(end 1.3462 -1.1938)
			(stroke
				(width 0.1524)
				(type default)
			)
			(layer "B.SilkS")
		)
		(fp_poly
			(pts
				(xy 1.447038 -0.760476) (xy 2.052066 -0.457962) (xy 2.052066 -1.06299)
			)
			(stroke
				(width 0)
				(type default)
			)
			(fill yes)
			(layer "B.SilkS")
		)
		(fp_line
			(start 0.674878 1.124966)
			(end -0.674878 1.124966)
			(stroke
				(width 0.1)
				(type default)
			)
			(layer "B.Fab")
		)
		(fp_line
			(start 0.674878 -1.124966)
			(end 0.674878 1.124966)
			(stroke
				(width 0.1)
				(type default)
			)
			(layer "B.Fab")
		)
		(fp_line
			(start -0.674878 1.124966)
			(end -0.674878 -1.124966)
			(stroke
				(width 0.1)
				(type default)
			)
			(layer "B.Fab")
		)
		(fp_line
			(start -0.674878 -1.124966)
			(end 0.674878 -1.124966)
			(stroke
				(width 0.1)
				(type default)
			)
			(layer "B.Fab")
		)
		(fp_poly
			(pts
				(xy 1.447038 -0.760476) (xy 2.052066 -0.457962) (xy 2.052066 -1.06299)
			)
			(stroke
				(width 0)
				(type default)
			)
			(fill yes)
			(layer "B.Fab")
		)
		(pad "1" smd rect
			(at 0.899922 -0.750062)
			(size 0.6096 0.6096)
			(layers "B.Cu" "B.Mask" "B.Paste")
			(net "NIC6_AUX_PWR_EN_R")
		)
		(pad "2" smd rect
			(at 0.899922 0 270)
			(size 0.4064 0.6096)
			(layers "B.Cu" "B.Mask" "B.Paste")
			(net "RST_SMB_NIC6_MUX_N")
		)
		(pad "3" smd rect
			(at 0.899922 0.750062)
			(size 0.6096 0.6096)
			(layers "B.Cu" "B.Mask" "B.Paste")
			(net "GND")
		)
		(pad "4" smd rect
			(at -0.899922 0.750062)
			(size 0.6096 0.6096)
			(layers "B.Cu" "B.Mask" "B.Paste")
			(net "RST_SMB_NIC6_MUX_ISO_N")
		)
		(pad "5" smd rect
			(at -0.899922 -0.750062)
			(size 0.6096 0.6096)
			(layers "B.Cu" "B.Mask" "B.Paste")
			(net "P3V3_AUX")
		)
	)
	(footprint ""
		(layer "B.Cu")
		(at 206.112618 -232.58907)
		(property "Reference" "R6324"
			(at 0 0 0)
			(layer "B.SilkS")
			(hide yes)
			(effects
				(font
					(size 1.27 1.27)
				)
				(justify mirror)
			)
		)
		(property "Value" ""
			(at 0 0 0)
			(layer "B.Fab")
			(effects
				(font
					(size 1.27 1.27)
				)
				(justify mirror)
			)
		)
		(duplicate_pad_numbers_are_jumpers no)
		(fp_line
			(start -0.7874 -0.4064)
			(end -0.7874 0.4064)
			(stroke
				(width 0.1524)
				(type default)
			)
			(layer "B.SilkS")
		)
		(fp_line
			(start -0.7874 0.4064)
			(end 0.7874 0.4064)
			(stroke
				(width 0.1524)
				(type default)
			)
			(layer "B.SilkS")
		)
		(fp_line
			(start 0.7874 -0.4064)
			(end -0.7874 -0.4064)
			(stroke
				(width 0.1524)
				(type default)
			)
			(layer "B.SilkS")
		)
		(fp_line
			(start 0.7874 0.4064)
			(end 0.7874 -0.4064)
			(stroke
				(width 0.1524)
				(type default)
			)
			(layer "B.SilkS")
		)
		(fp_line
			(start -0.67945 -0.3048)
			(end -0.67945 0.3048)
			(stroke
				(width 0.1)
				(type default)
			)
			(layer "B.Fab")
		)
		(fp_line
			(start -0.67945 0.3048)
			(end -0.120396 0.3048)
			(stroke
				(width 0.1)
				(type default)
			)
			(layer "B.Fab")
		)
		(fp_line
			(start -0.12065 -0.3048)
			(end -0.67945 -0.3048)
			(stroke
				(width 0.1)
				(type default)
			)
			(layer "B.Fab")
		)
		(fp_line
			(start -0.12065 -0.2794)
			(end -0.12065 -0.3048)
			(stroke
				(width 0.1)
				(type default)
			)
			(layer "B.Fab")
		)
		(fp_line
			(start -0.120396 0.2794)
			(end 0.12065 0.2794)
			(stroke
				(width 0.1)
				(type default)
			)
			(layer "B.Fab")
		)
		(fp_line
			(start -0.120396 0.3048)
			(end -0.120396 0.2794)
			(stroke
				(width 0.1)
				(type default)
			)
			(layer "B.Fab")
		)
		(fp_line
			(start 0.12065 -0.305054)
			(end 0.12065 -0.2794)
			(stroke
				(width 0.1)
				(type default)
			)
			(layer "B.Fab")
		)
		(fp_line
			(start 0.12065 -0.2794)
			(end -0.12065 -0.2794)
			(stroke
				(width 0.1)
				(type default)
			)
			(layer "B.Fab")
		)
		(fp_line
			(start 0.12065 0.2794)
			(end 0.12065 0.3048)
			(stroke
				(width 0.1)
				(type default)
			)
			(layer "B.Fab")
		)
		(fp_line
			(start 0.12065 0.3048)
			(end 0.67945 0.3048)
			(stroke
				(width 0.1)
				(type default)
			)
			(layer "B.Fab")
		)
		(fp_line
			(start 0.67945 -0.305054)
			(end 0.12065 -0.305054)
			(stroke
				(width 0.1)
				(type default)
			)
			(layer "B.Fab")
		)
		(fp_line
			(start 0.67945 0.3048)
			(end 0.67945 -0.305054)
			(stroke
				(width 0.1)
				(type default)
			)
			(layer "B.Fab")
		)
		(pad "1" smd circle
			(at 0.40005 0 180)
			(size 0 0)
			(layers "B.Cu" "B.Mask" "B.Paste")
			(net "SMB_PEX1_SDA")
		)
		(pad "2" smd circle
			(at -0.40005 0 180)
			(size 0 0)
			(layers "B.Cu" "B.Mask" "B.Paste")
			(net "SMB_PEX1_MUX_SDA")
		)
	)
	(footprint ""
		(layer "B.Cu")
		(at 179.07508 -293.99992 90)
		(property "Reference" "C1385"
			(at 0 0 90)
			(layer "B.SilkS")
			(hide yes)
			(effects
				(font
					(size 1.27 1.27)
				)
				(justify mirror)
			)
		)
		(property "Value" ""
			(at 0 0 90)
			(layer "B.Fab")
			(effects
				(font
					(size 1.27 1.27)
				)
				(justify mirror)
			)
		)
		(duplicate_pad_numbers_are_jumpers no)
		(fp_line
			(start 0.299974 -0.150114)
			(end -0.299974 -0.150114)
			(stroke
				(width 0.1)
				(type default)
			)
			(layer "B.Fab")
		)
		(fp_line
			(start -0.299974 -0.150114)
			(end -0.299974 0.150114)
			(stroke
				(width 0.1)
				(type default)
			)
			(layer "B.Fab")
		)
		(fp_line
			(start 0.299974 0.150114)
			(end 0.299974 -0.150114)
			(stroke
				(width 0.1)
				(type default)
			)
			(layer "B.Fab")
		)
		(fp_line
			(start -0.299974 0.150114)
			(end 0.299974 0.150114)
			(stroke
				(width 0.1)
				(type default)
			)
			(layer "B.Fab")
		)
		(pad "1" smd rect
			(at 0.2667 0 270)
			(size 0.3048 0.381)
			(layers "B.Cu" "B.Mask" "B.Paste")
			(net "P0V8_PEX1")
		)
		(pad "2" smd rect
			(at -0.2667 0 270)
			(size 0.3048 0.381)
			(layers "B.Cu" "B.Mask" "B.Paste")
			(net "GND")
		)
	)
	(footprint ""
		(layer "B.Cu")
		(at 112.583976 -277.644352 180)
		(property "Reference" "PC6609"
			(at 0 0 0)
			(layer "B.SilkS")
			(hide yes)
			(effects
				(font
					(size 1.27 1.27)
				)
				(justify mirror)
			)
		)
		(property "Value" ""
			(at 0 0 0)
			(layer "B.Fab")
			(effects
				(font
					(size 1.27 1.27)
				)
				(justify mirror)
			)
		)
		(duplicate_pad_numbers_are_jumpers no)
		(fp_line
			(start 1.524 0.762)
			(end 1.524 -0.762)
			(stroke
				(width 0.1524)
				(type default)
			)
			(layer "B.SilkS")
		)
		(fp_line
			(start 1.524 -0.762)
			(end -1.524 -0.762)
			(stroke
				(width 0.1524)
				(type default)
			)
			(layer "B.SilkS")
		)
		(fp_line
			(start -1.524 0.762)
			(end 1.524 0.762)
			(stroke
				(width 0.1524)
				(type default)
			)
			(layer "B.SilkS")
		)
		(fp_line
			(start -1.524 -0.762)
			(end -1.524 0.762)
			(stroke
				(width 0.1524)
				(type default)
			)
			(layer "B.SilkS")
		)
		(fp_line
			(start 1.1049 0.724916)
			(end -1.1049 0.724916)
			(stroke
				(width 0.1)
				(type default)
			)
			(layer "B.Fab")
		)
		(fp_line
			(start 1.1049 -0.724916)
			(end 1.1049 0.724916)
			(stroke
				(width 0.1)
				(type default)
			)
			(layer "B.Fab")
		)
		(fp_line
			(start -1.1049 0.724916)
			(end -1.1049 -0.724916)
			(stroke
				(width 0.1)
				(type default)
			)
			(layer "B.Fab")
		)
		(fp_line
			(start -1.1049 -0.724916)
			(end 1.1049 -0.724916)
			(stroke
				(width 0.1)
				(type default)
			)
			(layer "B.Fab")
		)
		(pad "1" smd rect
			(at 0.889 0 180)
			(size 1.016 1.27)
			(layers "B.Cu" "B.Mask" "B.Paste")
			(net "SW_P12V_P0V8_PEX0_FLT")
		)
		(pad "2" smd rect
			(at -0.889 0 180)
			(size 1.016 1.27)
			(layers "B.Cu" "B.Mask" "B.Paste")
			(net "GND")
		)
	)
	(footprint ""
		(layer "B.Cu")
		(at 48.72482 -297.79976 -90)
		(property "Reference" "C1123"
			(at 0 0 90)
			(layer "B.SilkS")
			(hide yes)
			(effects
				(font
					(size 1.27 1.27)
				)
				(justify mirror)
			)
		)
		(property "Value" ""
			(at 0 0 90)
			(layer "B.Fab")
			(effects
				(font
					(size 1.27 1.27)
				)
				(justify mirror)
			)
		)
		(duplicate_pad_numbers_are_jumpers no)
		(fp_line
			(start -0.299974 0.150114)
			(end 0.299974 0.150114)
			(stroke
				(width 0.1)
				(type default)
			)
			(layer "B.Fab")
		)
		(fp_line
			(start 0.299974 0.150114)
			(end 0.299974 -0.150114)
			(stroke
				(width 0.1)
				(type default)
			)
			(layer "B.Fab")
		)
		(fp_line
			(start -0.299974 -0.150114)
			(end -0.299974 0.150114)
			(stroke
				(width 0.1)
				(type default)
			)
			(layer "B.Fab")
		)
		(fp_line
			(start 0.299974 -0.150114)
			(end -0.299974 -0.150114)
			(stroke
				(width 0.1)
				(type default)
			)
			(layer "B.Fab")
		)
		(pad "1" smd rect
			(at 0.2667 0 90)
			(size 0.3048 0.381)
			(layers "B.Cu" "B.Mask" "B.Paste")
			(net "P0V8_PEX0")
		)
		(pad "2" smd rect
			(at -0.2667 0 90)
			(size 0.3048 0.381)
			(layers "B.Cu" "B.Mask" "B.Paste")
			(net "GND")
		)
	)
	(footprint ""
		(layer "B.Cu")
		(at 119.347488 -303.141634)
		(property "Reference" "PR79"
			(at 0 0 0)
			(layer "B.SilkS")
			(hide yes)
			(effects
				(font
					(size 1.27 1.27)
				)
				(justify mirror)
			)
		)
		(property "Value" ""
			(at 0 0 0)
			(layer "B.Fab")
			(effects
				(font
					(size 1.27 1.27)
				)
				(justify mirror)
			)
		)
		(duplicate_pad_numbers_are_jumpers no)
		(fp_line
			(start -0.7874 -0.4064)
			(end -0.7874 0.4064)
			(stroke
				(width 0.1524)
				(type default)
			)
			(layer "B.SilkS")
		)
		(fp_line
			(start -0.7874 0.4064)
			(end 0.7874 0.4064)
			(stroke
				(width 0.1524)
				(type default)
			)
			(layer "B.SilkS")
		)
		(fp_line
			(start 0.7874 -0.4064)
			(end -0.7874 -0.4064)
			(stroke
				(width 0.1524)
				(type default)
			)
			(layer "B.SilkS")
		)
		(fp_line
			(start 0.7874 0.4064)
			(end 0.7874 -0.4064)
			(stroke
				(width 0.1524)
				(type default)
			)
			(layer "B.SilkS")
		)
		(fp_line
			(start -0.67945 -0.3048)
			(end -0.67945 0.3048)
			(stroke
				(width 0.1)
				(type default)
			)
			(layer "B.Fab")
		)
		(fp_line
			(start -0.67945 0.3048)
			(end -0.120396 0.3048)
			(stroke
				(width 0.1)
				(type default)
			)
			(layer "B.Fab")
		)
		(fp_line
			(start -0.12065 -0.3048)
			(end -0.67945 -0.3048)
			(stroke
				(width 0.1)
				(type default)
			)
			(layer "B.Fab")
		)
		(fp_line
			(start -0.12065 -0.2794)
			(end -0.12065 -0.3048)
			(stroke
				(width 0.1)
				(type default)
			)
			(layer "B.Fab")
		)
		(fp_line
			(start -0.120396 0.2794)
			(end 0.12065 0.2794)
			(stroke
				(width 0.1)
				(type default)
			)
			(layer "B.Fab")
		)
		(fp_line
			(start -0.120396 0.3048)
			(end -0.120396 0.2794)
			(stroke
				(width 0.1)
				(type default)
			)
			(layer "B.Fab")
		)
		(fp_line
			(start 0.12065 -0.305054)
			(end 0.12065 -0.2794)
			(stroke
				(width 0.1)
				(type default)
			)
			(layer "B.Fab")
		)
		(fp_line
			(start 0.12065 -0.2794)
			(end -0.12065 -0.2794)
			(stroke
				(width 0.1)
				(type default)
			)
			(layer "B.Fab")
		)
		(fp_line
			(start 0.12065 0.2794)
			(end 0.12065 0.3048)
			(stroke
				(width 0.1)
				(type default)
			)
			(layer "B.Fab")
		)
		(fp_line
			(start 0.12065 0.3048)
			(end 0.67945 0.3048)
			(stroke
				(width 0.1)
				(type default)
			)
			(layer "B.Fab")
		)
		(fp_line
			(start 0.67945 -0.305054)
			(end 0.12065 -0.305054)
			(stroke
				(width 0.1)
				(type default)
			)
			(layer "B.Fab")
		)
		(fp_line
			(start 0.67945 0.3048)
			(end 0.67945 -0.305054)
			(stroke
				(width 0.1)
				(type default)
			)
			(layer "B.Fab")
		)
		(pad "1" smd circle
			(at 0.40005 0 180)
			(size 0 0)
			(layers "B.Cu" "B.Mask" "B.Paste")
			(net "P0V8_PEX1")
		)
		(pad "2" smd circle
			(at -0.40005 0 180)
			(size 0 0)
			(layers "B.Cu" "B.Mask" "B.Paste")
			(net "SH_P0V8_PEX1_VSEN1_L")
		)
	)
	(footprint ""
		(layer "B.Cu")
		(at 51.099974 -288.299906 90)
		(property "Reference" "C2930"
			(at 0 0 90)
			(layer "B.SilkS")
			(hide yes)
			(effects
				(font
					(size 1.27 1.27)
				)
				(justify mirror)
			)
		)
		(property "Value" ""
			(at 0 0 90)
			(layer "B.Fab")
			(effects
				(font
					(size 1.27 1.27)
				)
				(justify mirror)
			)
		)
		(duplicate_pad_numbers_are_jumpers no)
		(fp_line
			(start 0.299974 -0.150114)
			(end -0.299974 -0.150114)
			(stroke
				(width 0.1)
				(type default)
			)
			(layer "B.Fab")
		)
		(fp_line
			(start -0.299974 -0.150114)
			(end -0.299974 0.150114)
			(stroke
				(width 0.1)
				(type default)
			)
			(layer "B.Fab")
		)
		(fp_line
			(start 0.299974 0.150114)
			(end 0.299974 -0.150114)
			(stroke
				(width 0.1)
				(type default)
			)
			(layer "B.Fab")
		)
		(fp_line
			(start -0.299974 0.150114)
			(end 0.299974 0.150114)
			(stroke
				(width 0.1)
				(type default)
			)
			(layer "B.Fab")
		)
		(pad "1" smd rect
			(at 0.2667 0 270)
			(size 0.3048 0.381)
			(layers "B.Cu" "B.Mask" "B.Paste")
			(net "P1V25_PEX0")
		)
		(pad "2" smd rect
			(at -0.2667 0 270)
			(size 0.3048 0.381)
			(layers "B.Cu" "B.Mask" "B.Paste")
			(net "GND")
		)
	)
	(footprint ""
		(layer "B.Cu")
		(at 294.22471 -297.79976 90)
		(property "Reference" "C1645"
			(at 0 0 90)
			(layer "B.SilkS")
			(hide yes)
			(effects
				(font
					(size 1.27 1.27)
				)
				(justify mirror)
			)
		)
		(property "Value" ""
			(at 0 0 90)
			(layer "B.Fab")
			(effects
				(font
					(size 1.27 1.27)
				)
				(justify mirror)
			)
		)
		(duplicate_pad_numbers_are_jumpers no)
		(fp_line
			(start 0.299974 -0.150114)
			(end -0.299974 -0.150114)
			(stroke
				(width 0.1)
				(type default)
			)
			(layer "B.Fab")
		)
		(fp_line
			(start -0.299974 -0.150114)
			(end -0.299974 0.150114)
			(stroke
				(width 0.1)
				(type default)
			)
			(layer "B.Fab")
		)
		(fp_line
			(start 0.299974 0.150114)
			(end 0.299974 -0.150114)
			(stroke
				(width 0.1)
				(type default)
			)
			(layer "B.Fab")
		)
		(fp_line
			(start -0.299974 0.150114)
			(end 0.299974 0.150114)
			(stroke
				(width 0.1)
				(type default)
			)
			(layer "B.Fab")
		)
		(pad "1" smd rect
			(at 0.2667 0 270)
			(size 0.3048 0.381)
			(layers "B.Cu" "B.Mask" "B.Paste")
			(net "P0V8_PEX2")
		)
		(pad "2" smd rect
			(at -0.2667 0 270)
			(size 0.3048 0.381)
			(layers "B.Cu" "B.Mask" "B.Paste")
			(net "GND")
		)
	)
	(footprint ""
		(layer "B.Cu")
		(at 350.757744 -321.14617 -90)
		(property "Reference" "R6536"
			(at 0 0 90)
			(layer "B.SilkS")
			(hide yes)
			(effects
				(font
					(size 1.27 1.27)
				)
				(justify mirror)
			)
		)
		(property "Value" ""
			(at 0 0 90)
			(layer "B.Fab")
			(effects
				(font
					(size 1.27 1.27)
				)
				(justify mirror)
			)
		)
		(duplicate_pad_numbers_are_jumpers no)
		(fp_line
			(start -0.7874 0.4064)
			(end 0.7874 0.4064)
			(stroke
				(width 0.1524)
				(type default)
			)
			(layer "B.SilkS")
		)
		(fp_line
			(start 0.7874 0.4064)
			(end 0.7874 -0.4064)
			(stroke
				(width 0.1524)
				(type default)
			)
			(layer "B.SilkS")
		)
		(fp_line
			(start -0.7874 -0.4064)
			(end -0.7874 0.4064)
			(stroke
				(width 0.1524)
				(type default)
			)
			(layer "B.SilkS")
		)
		(fp_line
			(start 0.7874 -0.4064)
			(end -0.7874 -0.4064)
			(stroke
				(width 0.1524)
				(type default)
			)
			(layer "B.SilkS")
		)
		(fp_line
			(start -0.67945 0.3048)
			(end -0.120396 0.3048)
			(stroke
				(width 0.1)
				(type default)
			)
			(layer "B.Fab")
		)
		(fp_line
			(start -0.120396 0.3048)
			(end -0.120396 0.2794)
			(stroke
				(width 0.1)
				(type default)
			)
			(layer "B.Fab")
		)
		(fp_line
			(start 0.12065 0.3048)
			(end 0.67945 0.3048)
			(stroke
				(width 0.1)
				(type default)
			)
			(layer "B.Fab")
		)
		(fp_line
			(start 0.67945 0.3048)
			(end 0.67945 -0.305054)
			(stroke
				(width 0.1)
				(type default)
			)
			(layer "B.Fab")
		)
		(fp_line
			(start -0.120396 0.2794)
			(end 0.12065 0.2794)
			(stroke
				(width 0.1)
				(type default)
			)
			(layer "B.Fab")
		)
		(fp_line
			(start 0.12065 0.2794)
			(end 0.12065 0.3048)
			(stroke
				(width 0.1)
				(type default)
			)
			(layer "B.Fab")
		)
		(fp_line
			(start -0.12065 -0.2794)
			(end -0.12065 -0.3048)
			(stroke
				(width 0.1)
				(type default)
			)
			(layer "B.Fab")
		)
		(fp_line
			(start 0.12065 -0.2794)
			(end -0.12065 -0.2794)
			(stroke
				(width 0.1)
				(type default)
			)
			(layer "B.Fab")
		)
		(fp_line
			(start -0.67945 -0.3048)
			(end -0.67945 0.3048)
			(stroke
				(width 0.1)
				(type default)
			)
			(layer "B.Fab")
		)
		(fp_line
			(start -0.12065 -0.3048)
			(end -0.67945 -0.3048)
			(stroke
				(width 0.1)
				(type default)
			)
			(layer "B.Fab")
		)
		(fp_line
			(start 0.12065 -0.305054)
			(end 0.12065 -0.2794)
			(stroke
				(width 0.1)
				(type default)
			)
			(layer "B.Fab")
		)
		(fp_line
			(start 0.67945 -0.305054)
			(end 0.12065 -0.305054)
			(stroke
				(width 0.1)
				(type default)
			)
			(layer "B.Fab")
		)
		(pad "1" smd circle
			(at 0.40005 0 90)
			(size 0 0)
			(layers "B.Cu" "B.Mask" "B.Paste")
			(net "P0V8_SERDES_VDDA_PEX3")
		)
		(pad "2" smd circle
			(at -0.40005 0 90)
			(size 0 0)
			(layers "B.Cu" "B.Mask" "B.Paste")
			(net "P0V8_SERDES_VDDA_PEX3_C1")
		)
	)
	(footprint ""
		(layer "B.Cu")
		(at 10.641838 -272.550636 180)
		(property "Reference" "C4223"
			(at 0 0 0)
			(layer "B.SilkS")
			(hide yes)
			(effects
				(font
					(size 1.27 1.27)
				)
				(justify mirror)
			)
		)
		(property "Value" ""
			(at 0 0 0)
			(layer "B.Fab")
			(effects
				(font
					(size 1.27 1.27)
				)
				(justify mirror)
			)
		)
		(duplicate_pad_numbers_are_jumpers no)
		(fp_line
			(start 0.299974 0.150114)
			(end 0.299974 -0.150114)
			(stroke
				(width 0.1)
				(type default)
			)
			(layer "B.Fab")
		)
		(fp_line
			(start 0.299974 -0.150114)
			(end -0.299974 -0.150114)
			(stroke
				(width 0.1)
				(type default)
			)
			(layer "B.Fab")
		)
		(fp_line
			(start -0.299974 0.150114)
			(end 0.299974 0.150114)
			(stroke
				(width 0.1)
				(type default)
			)
			(layer "B.Fab")
		)
		(fp_line
			(start -0.299974 -0.150114)
			(end -0.299974 0.150114)
			(stroke
				(width 0.1)
				(type default)
			)
			(layer "B.Fab")
		)
		(pad "1" smd rect
			(at 0.2667 0)
			(size 0.3048 0.381)
			(layers "B.Cu" "B.Mask" "B.Paste")
			(net "P1V25_PEX0")
		)
		(pad "2" smd rect
			(at -0.2667 0)
			(size 0.3048 0.381)
			(layers "B.Cu" "B.Mask" "B.Paste")
			(net "GND")
		)
	)
	(footprint ""
		(layer "B.Cu")
		(at 49.149 -301.0154 180)
		(property "Reference" "C1110"
			(at 0 0 0)
			(layer "B.SilkS")
			(hide yes)
			(effects
				(font
					(size 1.27 1.27)
				)
				(justify mirror)
			)
		)
		(property "Value" ""
			(at 0 0 0)
			(layer "B.Fab")
			(effects
				(font
					(size 1.27 1.27)
				)
				(justify mirror)
			)
		)
		(duplicate_pad_numbers_are_jumpers no)
		(fp_line
			(start 0.299974 0.150114)
			(end 0.299974 -0.150114)
			(stroke
				(width 0.1)
				(type default)
			)
			(layer "B.Fab")
		)
		(fp_line
			(start 0.299974 -0.150114)
			(end -0.299974 -0.150114)
			(stroke
				(width 0.1)
				(type default)
			)
			(layer "B.Fab")
		)
		(fp_line
			(start -0.299974 0.150114)
			(end 0.299974 0.150114)
			(stroke
				(width 0.1)
				(type default)
			)
			(layer "B.Fab")
		)
		(fp_line
			(start -0.299974 -0.150114)
			(end -0.299974 0.150114)
			(stroke
				(width 0.1)
				(type default)
			)
			(layer "B.Fab")
		)
		(pad "1" smd rect
			(at 0.2667 0)
			(size 0.3048 0.381)
			(layers "B.Cu" "B.Mask" "B.Paste")
			(net "P0V8_PEX0")
		)
		(pad "2" smd rect
			(at -0.2667 0)
			(size 0.3048 0.381)
			(layers "B.Cu" "B.Mask" "B.Paste")
			(net "GND")
		)
	)
	(footprint ""
		(layer "B.Cu")
		(at 348.493842 -220.387164 -90)
		(property "Reference" "C2040"
			(at 0 0 90)
			(layer "B.SilkS")
			(hide yes)
			(effects
				(font
					(size 1.27 1.27)
				)
				(justify mirror)
			)
		)
		(property "Value" ""
			(at 0 0 90)
			(layer "B.Fab")
			(effects
				(font
					(size 1.27 1.27)
				)
				(justify mirror)
			)
		)
		(duplicate_pad_numbers_are_jumpers no)
		(fp_line
			(start -0.69215 0.2921)
			(end 0.69215 0.2921)
			(stroke
				(width 0.1524)
				(type default)
			)
			(layer "B.SilkS")
		)
		(fp_line
			(start 0.69215 0.2921)
			(end 0.69215 -0.2921)
			(stroke
				(width 0.1524)
				(type default)
			)
			(layer "B.SilkS")
		)
		(fp_line
			(start -0.69215 -0.2921)
			(end -0.69215 0.2921)
			(stroke
				(width 0.1524)
				(type default)
			)
			(layer "B.SilkS")
		)
		(fp_line
			(start 0.69215 -0.2921)
			(end -0.69215 -0.2921)
			(stroke
				(width 0.1524)
				(type default)
			)
			(layer "B.SilkS")
		)
		(fp_line
			(start -0.51435 0.2794)
			(end 0.51435 0.2794)
			(stroke
				(width 0.1)
				(type default)
			)
			(layer "B.Fab")
		)
		(fp_line
			(start 0.51435 0.2794)
			(end 0.51435 -0.2794)
			(stroke
				(width 0.1)
				(type default)
			)
			(layer "B.Fab")
		)
		(fp_line
			(start -0.51435 -0.2794)
			(end -0.51435 0.2794)
			(stroke
				(width 0.1)
				(type default)
			)
			(layer "B.Fab")
		)
		(fp_line
			(start 0.51435 -0.2794)
			(end -0.51435 -0.2794)
			(stroke
				(width 0.1)
				(type default)
			)
			(layer "B.Fab")
		)
		(pad "1" smd circle
			(at 0.40005 0 90)
			(size 0 0)
			(layers "B.Cu" "B.Mask" "B.Paste")
			(net "P3V3_FPGA_VCCIO1")
		)
		(pad "2" smd circle
			(at -0.40005 0 90)
			(size 0 0)
			(layers "B.Cu" "B.Mask" "B.Paste")
			(net "GND")
		)
		(zone
			(layer "B.Cu")
			(hatch none 0.5)
			(connect_pads
				(clearance 0)
			)
			(min_thickness 0.25)
			(keepout
				(tracks not_allowed)
				(vias allowed)
				(pads allowed)
				(copperpour not_allowed)
				(footprints allowed)
			)
			(placement
				(enabled no)
				(sheetname "")
			)
			(fill
				(thermal_gap 0.5)
				(thermal_bridge_width 0.5)
				(island_removal_mode 0)
			)
			(polygon
				(pts
					(xy 348.406212 -220.196664) (xy 348.348046 -220.288104) (xy 348.348046 -220.487494) (xy 348.406212 -220.577664)
					(xy 348.581472 -220.577664) (xy 348.639892 -220.487494) (xy 348.639892 -220.288104) (xy 348.581726 -220.196664)
				)
			)
		)
	)
	(footprint ""
		(layer "B.Cu")
		(at 408.899868 -288.299906 90)
		(property "Reference" "C3448"
			(at 0 0 90)
			(layer "B.SilkS")
			(hide yes)
			(effects
				(font
					(size 1.27 1.27)
				)
				(justify mirror)
			)
		)
		(property "Value" ""
			(at 0 0 90)
			(layer "B.Fab")
			(effects
				(font
					(size 1.27 1.27)
				)
				(justify mirror)
			)
		)
		(duplicate_pad_numbers_are_jumpers no)
		(fp_line
			(start 0.299974 -0.150114)
			(end -0.299974 -0.150114)
			(stroke
				(width 0.1)
				(type default)
			)
			(layer "B.Fab")
		)
		(fp_line
			(start -0.299974 -0.150114)
			(end -0.299974 0.150114)
			(stroke
				(width 0.1)
				(type default)
			)
			(layer "B.Fab")
		)
		(fp_line
			(start 0.299974 0.150114)
			(end 0.299974 -0.150114)
			(stroke
				(width 0.1)
				(type default)
			)
			(layer "B.Fab")
		)
		(fp_line
			(start -0.299974 0.150114)
			(end 0.299974 0.150114)
			(stroke
				(width 0.1)
				(type default)
			)
			(layer "B.Fab")
		)
		(pad "1" smd rect
			(at 0.2667 0 270)
			(size 0.3048 0.381)
			(layers "B.Cu" "B.Mask" "B.Paste")
			(net "P1V25_PEX3")
		)
		(pad "2" smd rect
			(at -0.2667 0 270)
			(size 0.3048 0.381)
			(layers "B.Cu" "B.Mask" "B.Paste")
			(net "GND")
		)
	)
	(footprint ""
		(layer "B.Cu")
		(at 237.631986 -354.235258)
		(property "Reference" "PR7150"
			(at 0 0 0)
			(layer "B.SilkS")
			(hide yes)
			(effects
				(font
					(size 1.27 1.27)
				)
				(justify mirror)
			)
		)
		(property "Value" ""
			(at 0 0 0)
			(layer "B.Fab")
			(effects
				(font
					(size 1.27 1.27)
				)
				(justify mirror)
			)
		)
		(duplicate_pad_numbers_are_jumpers no)
		(fp_line
			(start -0.7874 -0.4064)
			(end -0.7874 0.4064)
			(stroke
				(width 0.1524)
				(type default)
			)
			(layer "B.SilkS")
		)
		(fp_line
			(start -0.7874 0.4064)
			(end 0.7874 0.4064)
			(stroke
				(width 0.1524)
				(type default)
			)
			(layer "B.SilkS")
		)
		(fp_line
			(start 0.7874 -0.4064)
			(end -0.7874 -0.4064)
			(stroke
				(width 0.1524)
				(type default)
			)
			(layer "B.SilkS")
		)
		(fp_line
			(start 0.7874 0.4064)
			(end 0.7874 -0.4064)
			(stroke
				(width 0.1524)
				(type default)
			)
			(layer "B.SilkS")
		)
		(fp_line
			(start -0.67945 -0.3048)
			(end -0.67945 0.3048)
			(stroke
				(width 0.1)
				(type default)
			)
			(layer "B.Fab")
		)
		(fp_line
			(start -0.67945 0.3048)
			(end -0.120396 0.3048)
			(stroke
				(width 0.1)
				(type default)
			)
			(layer "B.Fab")
		)
		(fp_line
			(start -0.12065 -0.3048)
			(end -0.67945 -0.3048)
			(stroke
				(width 0.1)
				(type default)
			)
			(layer "B.Fab")
		)
		(fp_line
			(start -0.12065 -0.2794)
			(end -0.12065 -0.3048)
			(stroke
				(width 0.1)
				(type default)
			)
			(layer "B.Fab")
		)
		(fp_line
			(start -0.120396 0.2794)
			(end 0.12065 0.2794)
			(stroke
				(width 0.1)
				(type default)
			)
			(layer "B.Fab")
		)
		(fp_line
			(start -0.120396 0.3048)
			(end -0.120396 0.2794)
			(stroke
				(width 0.1)
				(type default)
			)
			(layer "B.Fab")
		)
		(fp_line
			(start 0.12065 -0.305054)
			(end 0.12065 -0.2794)
			(stroke
				(width 0.1)
				(type default)
			)
			(layer "B.Fab")
		)
		(fp_line
			(start 0.12065 -0.2794)
			(end -0.12065 -0.2794)
			(stroke
				(width 0.1)
				(type default)
			)
			(layer "B.Fab")
		)
		(fp_line
			(start 0.12065 0.2794)
			(end 0.12065 0.3048)
			(stroke
				(width 0.1)
				(type default)
			)
			(layer "B.Fab")
		)
		(fp_line
			(start 0.12065 0.3048)
			(end 0.67945 0.3048)
			(stroke
				(width 0.1)
				(type default)
			)
			(layer "B.Fab")
		)
		(fp_line
			(start 0.67945 -0.305054)
			(end 0.12065 -0.305054)
			(stroke
				(width 0.1)
				(type default)
			)
			(layer "B.Fab")
		)
		(fp_line
			(start 0.67945 0.3048)
			(end 0.67945 -0.305054)
			(stroke
				(width 0.1)
				(type default)
			)
			(layer "B.Fab")
		)
		(pad "1" smd circle
			(at 0.40005 0 180)
			(size 0 0)
			(layers "B.Cu" "B.Mask" "B.Paste")
			(net "P12V_HSC_ADC_N")
		)
		(pad "2" smd circle
			(at -0.40005 0 180)
			(size 0 0)
			(layers "B.Cu" "B.Mask" "B.Paste")
			(net "P12V_HSC_SENSE2_R1_N")
		)
	)
	(footprint ""
		(layer "B.Cu")
		(at 282.364942 -301.599854 -90)
		(property "Reference" "C1681"
			(at 0 0 90)
			(layer "B.SilkS")
			(hide yes)
			(effects
				(font
					(size 1.27 1.27)
				)
				(justify mirror)
			)
		)
		(property "Value" ""
			(at 0 0 90)
			(layer "B.Fab")
			(effects
				(font
					(size 1.27 1.27)
				)
				(justify mirror)
			)
		)
		(duplicate_pad_numbers_are_jumpers no)
		(fp_line
			(start -0.299974 0.150114)
			(end 0.299974 0.150114)
			(stroke
				(width 0.1)
				(type default)
			)
			(layer "B.Fab")
		)
		(fp_line
			(start 0.299974 0.150114)
			(end 0.299974 -0.150114)
			(stroke
				(width 0.1)
				(type default)
			)
			(layer "B.Fab")
		)
		(fp_line
			(start -0.299974 -0.150114)
			(end -0.299974 0.150114)
			(stroke
				(width 0.1)
				(type default)
			)
			(layer "B.Fab")
		)
		(fp_line
			(start 0.299974 -0.150114)
			(end -0.299974 -0.150114)
			(stroke
				(width 0.1)
				(type default)
			)
			(layer "B.Fab")
		)
		(pad "1" smd rect
			(at 0.2667 0 90)
			(size 0.3048 0.381)
			(layers "B.Cu" "B.Mask" "B.Paste")
			(net "P0V8_SERDES_VDDA_PEX2")
		)
		(pad "2" smd rect
			(at -0.2667 0 90)
			(size 0.3048 0.381)
			(layers "B.Cu" "B.Mask" "B.Paste")
			(net "GND")
		)
	)
	(footprint ""
		(layer "B.Cu")
		(at 210.81873 -234.080304 -90)
		(property "Reference" "R6330"
			(at 0 0 90)
			(layer "B.SilkS")
			(hide yes)
			(effects
				(font
					(size 1.27 1.27)
				)
				(justify mirror)
			)
		)
		(property "Value" ""
			(at 0 0 90)
			(layer "B.Fab")
			(effects
				(font
					(size 1.27 1.27)
				)
				(justify mirror)
			)
		)
		(duplicate_pad_numbers_are_jumpers no)
		(fp_line
			(start -0.7874 0.4064)
			(end 0.7874 0.4064)
			(stroke
				(width 0.1524)
				(type default)
			)
			(layer "B.SilkS")
		)
		(fp_line
			(start 0.7874 0.4064)
			(end 0.7874 -0.4064)
			(stroke
				(width 0.1524)
				(type default)
			)
			(layer "B.SilkS")
		)
		(fp_line
			(start -0.7874 -0.4064)
			(end -0.7874 0.4064)
			(stroke
				(width 0.1524)
				(type default)
			)
			(layer "B.SilkS")
		)
		(fp_line
			(start 0.7874 -0.4064)
			(end -0.7874 -0.4064)
			(stroke
				(width 0.1524)
				(type default)
			)
			(layer "B.SilkS")
		)
		(fp_line
			(start -0.67945 0.3048)
			(end -0.120396 0.3048)
			(stroke
				(width 0.1)
				(type default)
			)
			(layer "B.Fab")
		)
		(fp_line
			(start -0.120396 0.3048)
			(end -0.120396 0.2794)
			(stroke
				(width 0.1)
				(type default)
			)
			(layer "B.Fab")
		)
		(fp_line
			(start 0.12065 0.3048)
			(end 0.67945 0.3048)
			(stroke
				(width 0.1)
				(type default)
			)
			(layer "B.Fab")
		)
		(fp_line
			(start 0.67945 0.3048)
			(end 0.67945 -0.305054)
			(stroke
				(width 0.1)
				(type default)
			)
			(layer "B.Fab")
		)
		(fp_line
			(start -0.120396 0.2794)
			(end 0.12065 0.2794)
			(stroke
				(width 0.1)
				(type default)
			)
			(layer "B.Fab")
		)
		(fp_line
			(start 0.12065 0.2794)
			(end 0.12065 0.3048)
			(stroke
				(width 0.1)
				(type default)
			)
			(layer "B.Fab")
		)
		(fp_line
			(start -0.12065 -0.2794)
			(end -0.12065 -0.3048)
			(stroke
				(width 0.1)
				(type default)
			)
			(layer "B.Fab")
		)
		(fp_line
			(start 0.12065 -0.2794)
			(end -0.12065 -0.2794)
			(stroke
				(width 0.1)
				(type default)
			)
			(layer "B.Fab")
		)
		(fp_line
			(start -0.67945 -0.3048)
			(end -0.67945 0.3048)
			(stroke
				(width 0.1)
				(type default)
			)
			(layer "B.Fab")
		)
		(fp_line
			(start -0.12065 -0.3048)
			(end -0.67945 -0.3048)
			(stroke
				(width 0.1)
				(type default)
			)
			(layer "B.Fab")
		)
		(fp_line
			(start 0.12065 -0.305054)
			(end 0.12065 -0.2794)
			(stroke
				(width 0.1)
				(type default)
			)
			(layer "B.Fab")
		)
		(fp_line
			(start 0.67945 -0.305054)
			(end 0.12065 -0.305054)
			(stroke
				(width 0.1)
				(type default)
			)
			(layer "B.Fab")
		)
		(pad "1" smd circle
			(at 0.40005 0 90)
			(size 0 0)
			(layers "B.Cu" "B.Mask" "B.Paste")
			(net "SMB_PEX2_SCL")
		)
		(pad "2" smd circle
			(at -0.40005 0 90)
			(size 0 0)
			(layers "B.Cu" "B.Mask" "B.Paste")
			(net "SMB_PEX2_MUX_SCL")
		)
	)
	(footprint ""
		(layer "B.Cu")
		(at 182.39994 -290.199826 90)
		(property "Reference" "C1438"
			(at 0 0 90)
			(layer "B.SilkS")
			(hide yes)
			(effects
				(font
					(size 1.27 1.27)
				)
				(justify mirror)
			)
		)
		(property "Value" ""
			(at 0 0 90)
			(layer "B.Fab")
			(effects
				(font
					(size 1.27 1.27)
				)
				(justify mirror)
			)
		)
		(duplicate_pad_numbers_are_jumpers no)
		(fp_line
			(start 0.299974 -0.150114)
			(end -0.299974 -0.150114)
			(stroke
				(width 0.1)
				(type default)
			)
			(layer "B.Fab")
		)
		(fp_line
			(start -0.299974 -0.150114)
			(end -0.299974 0.150114)
			(stroke
				(width 0.1)
				(type default)
			)
			(layer "B.Fab")
		)
		(fp_line
			(start 0.299974 0.150114)
			(end 0.299974 -0.150114)
			(stroke
				(width 0.1)
				(type default)
			)
			(layer "B.Fab")
		)
		(fp_line
			(start -0.299974 0.150114)
			(end 0.299974 0.150114)
			(stroke
				(width 0.1)
				(type default)
			)
			(layer "B.Fab")
		)
		(pad "1" smd rect
			(at 0.2667 0 270)
			(size 0.3048 0.381)
			(layers "B.Cu" "B.Mask" "B.Paste")
			(net "P0V8_SERDES_VDDA_PEX1")
		)
		(pad "2" smd rect
			(at -0.2667 0 270)
			(size 0.3048 0.381)
			(layers "B.Cu" "B.Mask" "B.Paste")
			(net "GND")
		)
	)
	(footprint ""
		(layer "B.Cu")
		(at 402.724874 -286.399732 90)
		(property "Reference" "C3501"
			(at 0 0 90)
			(layer "B.SilkS")
			(hide yes)
			(effects
				(font
					(size 1.27 1.27)
				)
				(justify mirror)
			)
		)
		(property "Value" ""
			(at 0 0 90)
			(layer "B.Fab")
			(effects
				(font
					(size 1.27 1.27)
				)
				(justify mirror)
			)
		)
		(duplicate_pad_numbers_are_jumpers no)
		(fp_line
			(start 0.299974 -0.150114)
			(end -0.299974 -0.150114)
			(stroke
				(width 0.1)
				(type default)
			)
			(layer "B.Fab")
		)
		(fp_line
			(start -0.299974 -0.150114)
			(end -0.299974 0.150114)
			(stroke
				(width 0.1)
				(type default)
			)
			(layer "B.Fab")
		)
		(fp_line
			(start 0.299974 0.150114)
			(end 0.299974 -0.150114)
			(stroke
				(width 0.1)
				(type default)
			)
			(layer "B.Fab")
		)
		(fp_line
			(start -0.299974 0.150114)
			(end 0.299974 0.150114)
			(stroke
				(width 0.1)
				(type default)
			)
			(layer "B.Fab")
		)
		(pad "1" smd rect
			(at 0.2667 0 270)
			(size 0.3048 0.381)
			(layers "B.Cu" "B.Mask" "B.Paste")
			(net "P1V25_SERDES_VDDPLL_PEX3")
		)
		(pad "2" smd rect
			(at -0.2667 0 270)
			(size 0.3048 0.381)
			(layers "B.Cu" "B.Mask" "B.Paste")
			(net "GND")
		)
	)
	(footprint ""
		(layer "B.Cu")
		(at 164.824918 -297.79976 -90)
		(property "Reference" "C1367"
			(at 0 0 90)
			(layer "B.SilkS")
			(hide yes)
			(effects
				(font
					(size 1.27 1.27)
				)
				(justify mirror)
			)
		)
		(property "Value" ""
			(at 0 0 90)
			(layer "B.Fab")
			(effects
				(font
					(size 1.27 1.27)
				)
				(justify mirror)
			)
		)
		(duplicate_pad_numbers_are_jumpers no)
		(fp_line
			(start -0.299974 0.150114)
			(end 0.299974 0.150114)
			(stroke
				(width 0.1)
				(type default)
			)
			(layer "B.Fab")
		)
		(fp_line
			(start 0.299974 0.150114)
			(end 0.299974 -0.150114)
			(stroke
				(width 0.1)
				(type default)
			)
			(layer "B.Fab")
		)
		(fp_line
			(start -0.299974 -0.150114)
			(end -0.299974 0.150114)
			(stroke
				(width 0.1)
				(type default)
			)
			(layer "B.Fab")
		)
		(fp_line
			(start 0.299974 -0.150114)
			(end -0.299974 -0.150114)
			(stroke
				(width 0.1)
				(type default)
			)
			(layer "B.Fab")
		)
		(pad "1" smd rect
			(at 0.2667 0 90)
			(size 0.3048 0.381)
			(layers "B.Cu" "B.Mask" "B.Paste")
			(net "P0V8_PEX1")
		)
		(pad "2" smd rect
			(at -0.2667 0 90)
			(size 0.3048 0.381)
			(layers "B.Cu" "B.Mask" "B.Paste")
			(net "GND")
		)
	)
	(footprint ""
		(layer "B.Cu")
		(at 233.412792 -90.50528 -90)
		(property "Reference" "C2619"
			(at 0 0 90)
			(layer "B.SilkS")
			(hide yes)
			(effects
				(font
					(size 1.27 1.27)
				)
				(justify mirror)
			)
		)
		(property "Value" ""
			(at 0 0 90)
			(layer "B.Fab")
			(effects
				(font
					(size 1.27 1.27)
				)
				(justify mirror)
			)
		)
		(duplicate_pad_numbers_are_jumpers no)
		(fp_line
			(start -0.7874 0.4064)
			(end 0.7874 0.4064)
			(stroke
				(width 0.1524)
				(type default)
			)
			(layer "B.SilkS")
		)
		(fp_line
			(start 0.7874 0.4064)
			(end 0.7874 -0.4064)
			(stroke
				(width 0.1524)
				(type default)
			)
			(layer "B.SilkS")
		)
		(fp_line
			(start -0.7874 -0.4064)
			(end -0.7874 0.4064)
			(stroke
				(width 0.1524)
				(type default)
			)
			(layer "B.SilkS")
		)
		(fp_line
			(start 0.7874 -0.4064)
			(end -0.7874 -0.4064)
			(stroke
				(width 0.1524)
				(type default)
			)
			(layer "B.SilkS")
		)
		(fp_line
			(start -0.67945 0.3048)
			(end -0.120396 0.3048)
			(stroke
				(width 0.1)
				(type default)
			)
			(layer "B.Fab")
		)
		(fp_line
			(start -0.120396 0.3048)
			(end -0.120396 0.2794)
			(stroke
				(width 0.1)
				(type default)
			)
			(layer "B.Fab")
		)
		(fp_line
			(start 0.12065 0.3048)
			(end 0.67945 0.3048)
			(stroke
				(width 0.1)
				(type default)
			)
			(layer "B.Fab")
		)
		(fp_line
			(start 0.67945 0.3048)
			(end 0.67945 -0.305054)
			(stroke
				(width 0.1)
				(type default)
			)
			(layer "B.Fab")
		)
		(fp_line
			(start -0.120396 0.2794)
			(end 0.12065 0.2794)
			(stroke
				(width 0.1)
				(type default)
			)
			(layer "B.Fab")
		)
		(fp_line
			(start 0.12065 0.2794)
			(end 0.12065 0.3048)
			(stroke
				(width 0.1)
				(type default)
			)
			(layer "B.Fab")
		)
		(fp_line
			(start -0.12065 -0.2794)
			(end -0.12065 -0.3048)
			(stroke
				(width 0.1)
				(type default)
			)
			(layer "B.Fab")
		)
		(fp_line
			(start 0.12065 -0.2794)
			(end -0.12065 -0.2794)
			(stroke
				(width 0.1)
				(type default)
			)
			(layer "B.Fab")
		)
		(fp_line
			(start -0.67945 -0.3048)
			(end -0.67945 0.3048)
			(stroke
				(width 0.1)
				(type default)
			)
			(layer "B.Fab")
		)
		(fp_line
			(start -0.12065 -0.3048)
			(end -0.67945 -0.3048)
			(stroke
				(width 0.1)
				(type default)
			)
			(layer "B.Fab")
		)
		(fp_line
			(start 0.12065 -0.305054)
			(end 0.12065 -0.2794)
			(stroke
				(width 0.1)
				(type default)
			)
			(layer "B.Fab")
		)
		(fp_line
			(start 0.67945 -0.305054)
			(end 0.12065 -0.305054)
			(stroke
				(width 0.1)
				(type default)
			)
			(layer "B.Fab")
		)
		(pad "1" smd circle
			(at 0.40005 0 90)
			(size 0 0)
			(layers "B.Cu" "B.Mask" "B.Paste")
			(net "P3V3_PEX_USB_HUB")
		)
		(pad "2" smd circle
			(at -0.40005 0 90)
			(size 0 0)
			(layers "B.Cu" "B.Mask" "B.Paste")
			(net "GND")
		)
	)
	(footprint ""
		(layer "B.Cu")
		(at 392.749786 -295.89984)
		(property "Reference" "C3527"
			(at 0 0 0)
			(layer "B.SilkS")
			(hide yes)
			(effects
				(font
					(size 1.27 1.27)
				)
				(justify mirror)
			)
		)
		(property "Value" ""
			(at 0 0 0)
			(layer "B.Fab")
			(effects
				(font
					(size 1.27 1.27)
				)
				(justify mirror)
			)
		)
		(duplicate_pad_numbers_are_jumpers no)
		(fp_line
			(start -0.299974 -0.150114)
			(end -0.299974 0.150114)
			(stroke
				(width 0.1)
				(type default)
			)
			(layer "B.Fab")
		)
		(fp_line
			(start -0.299974 0.150114)
			(end 0.299974 0.150114)
			(stroke
				(width 0.1)
				(type default)
			)
			(layer "B.Fab")
		)
		(fp_line
			(start 0.299974 -0.150114)
			(end -0.299974 -0.150114)
			(stroke
				(width 0.1)
				(type default)
			)
			(layer "B.Fab")
		)
		(fp_line
			(start 0.299974 0.150114)
			(end 0.299974 -0.150114)
			(stroke
				(width 0.1)
				(type default)
			)
			(layer "B.Fab")
		)
		(pad "1" smd rect
			(at 0.2667 0 180)
			(size 0.3048 0.381)
			(layers "B.Cu" "B.Mask" "B.Paste")
			(net "P1V8_PEX")
		)
		(pad "2" smd rect
			(at -0.2667 0 180)
			(size 0.3048 0.381)
			(layers "B.Cu" "B.Mask" "B.Paste")
			(net "GND")
		)
	)
	(footprint ""
		(layer "B.Cu")
		(at 111.276892 -333.855314)
		(property "Reference" "R1214"
			(at 0 0 0)
			(layer "B.SilkS")
			(hide yes)
			(effects
				(font
					(size 1.27 1.27)
				)
				(justify mirror)
			)
		)
		(property "Value" ""
			(at 0 0 0)
			(layer "B.Fab")
			(effects
				(font
					(size 1.27 1.27)
				)
				(justify mirror)
			)
		)
		(duplicate_pad_numbers_are_jumpers no)
		(fp_line
			(start -1.2954 -0.5842)
			(end -1.2954 0.5842)
			(stroke
				(width 0.1524)
				(type default)
			)
			(layer "B.SilkS")
		)
		(fp_line
			(start -1.2954 0.5842)
			(end 1.2954 0.5842)
			(stroke
				(width 0.1524)
				(type default)
			)
			(layer "B.SilkS")
		)
		(fp_line
			(start 1.2954 -0.5842)
			(end -1.2954 -0.5842)
			(stroke
				(width 0.1524)
				(type default)
			)
			(layer "B.SilkS")
		)
		(fp_line
			(start 1.2954 0.5842)
			(end 1.2954 -0.5842)
			(stroke
				(width 0.1524)
				(type default)
			)
			(layer "B.SilkS")
		)
		(fp_line
			(start -1.1938 -0.406654)
			(end -1.1938 0.4064)
			(stroke
				(width 0.1)
				(type default)
			)
			(layer "B.Fab")
		)
		(fp_line
			(start -1.1938 0.4064)
			(end -0.8636 0.4064)
			(stroke
				(width 0.1)
				(type default)
			)
			(layer "B.Fab")
		)
		(fp_line
			(start -0.8636 -0.4572)
			(end -0.8636 -0.406654)
			(stroke
				(width 0.1)
				(type default)
			)
			(layer "B.Fab")
		)
		(fp_line
			(start -0.8636 -0.406654)
			(end -1.1938 -0.406654)
			(stroke
				(width 0.1)
				(type default)
			)
			(layer "B.Fab")
		)
		(fp_line
			(start -0.8636 0.4064)
			(end -0.8636 0.4572)
			(stroke
				(width 0.1)
				(type default)
			)
			(layer "B.Fab")
		)
		(fp_line
			(start -0.8636 0.4572)
			(end 0.8636 0.4572)
			(stroke
				(width 0.1)
				(type default)
			)
			(layer "B.Fab")
		)
		(fp_line
			(start 0.8636 -0.4572)
			(end -0.8636 -0.4572)
			(stroke
				(width 0.1)
				(type default)
			)
			(layer "B.Fab")
		)
		(fp_line
			(start 0.8636 -0.406654)
			(end 0.8636 -0.4572)
			(stroke
				(width 0.1)
				(type default)
			)
			(layer "B.Fab")
		)
		(fp_line
			(start 0.8636 0.4064)
			(end 1.1938 0.4064)
			(stroke
				(width 0.1)
				(type default)
			)
			(layer "B.Fab")
		)
		(fp_line
			(start 0.8636 0.4318)
			(end 0.8636 0.4064)
			(stroke
				(width 0.1)
				(type default)
			)
			(layer "B.Fab")
		)
		(fp_line
			(start 0.8636 0.4572)
			(end 0.8636 0.4318)
			(stroke
				(width 0.1)
				(type default)
			)
			(layer "B.Fab")
		)
		(fp_line
			(start 1.1938 -0.406654)
			(end 0.8636 -0.406654)
			(stroke
				(width 0.1)
				(type default)
			)
			(layer "B.Fab")
		)
		(fp_line
			(start 1.1938 0.4064)
			(end 1.1938 -0.406654)
			(stroke
				(width 0.1)
				(type default)
			)
			(layer "B.Fab")
		)
		(pad "1" smd rect
			(at 0.7366 0 270)
			(size 0.7112 0.8128)
			(layers "B.Cu" "B.Mask" "B.Paste")
			(net "P3V3_CLK_BUFFER_9ZXL0451E_VZX3P3")
		)
		(pad "2" smd rect
			(at -0.7366 0 270)
			(size 0.7112 0.8128)
			(layers "B.Cu" "B.Mask" "B.Paste")
			(net "P3V3_CLK_BUFFER_9ZXL0451E_VZX3P3A")
		)
	)
	(footprint ""
		(layer "B.Cu")
		(at 134.144766 -308.668674 90)
		(property "Reference" "C4251"
			(at 0 0 90)
			(layer "B.SilkS")
			(hide yes)
			(effects
				(font
					(size 1.27 1.27)
				)
				(justify mirror)
			)
		)
		(property "Value" ""
			(at 0 0 90)
			(layer "B.Fab")
			(effects
				(font
					(size 1.27 1.27)
				)
				(justify mirror)
			)
		)
		(duplicate_pad_numbers_are_jumpers no)
		(fp_line
			(start 0.299974 -0.150114)
			(end -0.299974 -0.150114)
			(stroke
				(width 0.1)
				(type default)
			)
			(layer "B.Fab")
		)
		(fp_line
			(start -0.299974 -0.150114)
			(end -0.299974 0.150114)
			(stroke
				(width 0.1)
				(type default)
			)
			(layer "B.Fab")
		)
		(fp_line
			(start 0.299974 0.150114)
			(end 0.299974 -0.150114)
			(stroke
				(width 0.1)
				(type default)
			)
			(layer "B.Fab")
		)
		(fp_line
			(start -0.299974 0.150114)
			(end 0.299974 0.150114)
			(stroke
				(width 0.1)
				(type default)
			)
			(layer "B.Fab")
		)
		(pad "1" smd rect
			(at 0.2667 0 270)
			(size 0.3048 0.381)
			(layers "B.Cu" "B.Mask" "B.Paste")
			(net "P0V8_PEX1")
		)
		(pad "2" smd rect
			(at -0.2667 0 270)
			(size 0.3048 0.381)
			(layers "B.Cu" "B.Mask" "B.Paste")
			(net "GND")
		)
	)
	(footprint ""
		(layer "B.Cu")
		(at 78.345792 -438.897014 180)
		(property "Reference" "X63"
			(at 0.1778 -1.92913 180)
			(unlocked yes)
			(layer "B.SilkS")
			(effects
				(font
					(size 0.7874 0.5842)
					(thickness 0.1524)
				)
				(justify left mirror)
			)
		)
		(property "Value" ""
			(at 0 0 0)
			(layer "B.Fab")
			(effects
				(font
					(size 1.27 1.27)
				)
				(justify mirror)
			)
		)
		(property "Device Type" "TP_TDR_4P_FTS_MPKT4_H025P0200_IO_TP15_TP_TDR_4P_DIP"
			(at -1.30175 1.27 90)
			(unlocked yes)
			(layer "B.Fab")
			(hide yes)
			(effects
				(font
					(size 0.635 0.4064)
					(thickness 0.1524)
				)
				(justify mirror)
			)
		)
		(property "User Part Number" "TP15"
			(at -1.30175 1.27 90)
			(unlocked yes)
			(layer "Cmts.User")
			(hide yes)
			(effects
				(font
					(size 0.635 0.4064)
					(thickness 0.1524)
				)
				(justify mirror)
			)
		)
		(duplicate_pad_numbers_are_jumpers no)
		(fp_line
			(start 0 3.81)
			(end -2.54 3.81)
			(stroke
				(width 0.1524)
				(type default)
			)
			(layer "B.SilkS")
		)
		(fp_line
			(start 0 3.175)
			(end 0 3.81)
			(stroke
				(width 0.1524)
				(type default)
			)
			(layer "B.SilkS")
		)
		(fp_line
			(start 0 0.635)
			(end 0 1.905)
			(stroke
				(width 0.1524)
				(type default)
			)
			(layer "B.SilkS")
		)
		(fp_line
			(start 0 -1.27)
			(end 0 -0.635)
			(stroke
				(width 0.1524)
				(type default)
			)
			(layer "B.SilkS")
		)
		(fp_line
			(start -2.54 3.81)
			(end -2.54 3.6703)
			(stroke
				(width 0.1524)
				(type default)
			)
			(layer "B.SilkS")
		)
		(fp_line
			(start -2.54 1.4097)
			(end -2.54 1.1303)
			(stroke
				(width 0.1524)
				(type default)
			)
			(layer "B.SilkS")
		)
		(fp_line
			(start -2.54 -1.1303)
			(end -2.54 -1.27)
			(stroke
				(width 0.1524)
				(type default)
			)
			(layer "B.SilkS")
		)
		(fp_line
			(start -2.54 -1.27)
			(end 0 -1.27)
			(stroke
				(width 0.1524)
				(type default)
			)
			(layer "B.SilkS")
		)
		(fp_poly
			(pts
				(xy 0.761746 0) (xy 2.285746 -0.762) (xy 2.285746 0.762)
			)
			(stroke
				(width 0)
				(type default)
			)
			(fill yes)
			(layer "B.SilkS")
		)
		(fp_line
			(start 0 3.81)
			(end -2.54 3.81)
			(stroke
				(width 0.1)
				(type default)
			)
			(layer "B.Fab")
		)
		(fp_line
			(start 0 -1.27)
			(end 0 3.81)
			(stroke
				(width 0.1)
				(type default)
			)
			(layer "B.Fab")
		)
		(fp_line
			(start -2.54 3.81)
			(end -2.54 -1.27)
			(stroke
				(width 0.1)
				(type default)
			)
			(layer "B.Fab")
		)
		(fp_line
			(start -2.54 -1.27)
			(end 0 -1.27)
			(stroke
				(width 0.1)
				(type default)
			)
			(layer "B.Fab")
		)
		(fp_poly
			(pts
				(xy 0.761746 0) (xy 2.285746 -0.762) (xy 2.285746 0.762)
			)
			(stroke
				(width 0)
				(type default)
			)
			(fill yes)
			(layer "B.Fab")
		)
		(pad "1" thru_hole circle
			(at 0 0)
			(size 1.0033 1.0033)
			(drill 0.249936)
			(layers "*.Cu" "*.Mask")
			(remove_unused_layers no)
			(net "TDR_DIFF_85_IN5_DIN")
			(clearance 0.10795)
			(padstack
				(mode front_inner_back)
				(layer "Inner"
					(shape circle)
					(size 0.8001 0.8001)
					(clearance 0.1524)
				)
				(layer "B.Cu"
					(shape circle)
					(size 1.0033 1.0033)
					(thermal_gap 0.10795)
					(clearance 0.10795)
				)
			)
		)
		(pad "2" thru_hole circle
			(at -2.54 0)
			(size 1.9939 1.9939)
			(drill 0.249936)
			(layers "*.Cu" "*.Mask")
			(remove_unused_layers no)
			(net "COUPON_GND1")
			(clearance 0.10795)
			(padstack
				(mode front_inner_back)
				(layer "Inner"
					(shape circle)
					(size 0.8001 0.8001)
					(clearance 0.1524)
				)
				(layer "B.Cu"
					(shape circle)
					(size 1.9939 1.9939)
					(thermal_gap 0.10795)
					(clearance 0.10795)
				)
			)
		)
		(pad "3" thru_hole circle
			(at -2.54 2.54)
			(size 1.9939 1.9939)
			(drill 0.249936)
			(layers "*.Cu" "*.Mask")
			(remove_unused_layers no)
			(net "COUPON_GND1")
			(clearance 0.10795)
			(padstack
				(mode front_inner_back)
				(layer "Inner"
					(shape circle)
					(size 0.8001 0.8001)
					(clearance 0.1524)
				)
				(layer "B.Cu"
					(shape circle)
					(size 1.9939 1.9939)
					(thermal_gap 0.10795)
					(clearance 0.10795)
				)
			)
		)
		(pad "4" thru_hole circle
			(at 0 2.54)
			(size 1.0033 1.0033)
			(drill 0.249936)
			(layers "*.Cu" "*.Mask")
			(remove_unused_layers no)
			(net "TDR_DIFF_85_IN5_DIP")
			(clearance 0.10795)
			(padstack
				(mode front_inner_back)
				(layer "Inner"
					(shape circle)
					(size 0.8001 0.8001)
					(clearance 0.1524)
				)
				(layer "B.Cu"
					(shape circle)
					(size 1.0033 1.0033)
					(thermal_gap 0.10795)
					(clearance 0.10795)
				)
			)
		)
	)
	(footprint ""
		(layer "B.Cu")
		(at 159.984694 -447.48831)
		(property "Reference" "X76"
			(at 0.1778 -1.92913 0)
			(unlocked yes)
			(layer "B.SilkS")
			(effects
				(font
					(size 0.7874 0.5842)
					(thickness 0.1524)
				)
				(justify left mirror)
			)
		)
		(property "Value" ""
			(at 0 0 0)
			(layer "B.Fab")
			(effects
				(font
					(size 1.27 1.27)
				)
				(justify mirror)
			)
		)
		(property "Device Type" "TP_TDR_4P_FTS_MPKT4_H025P0200_IO_TP15_TP_TDR_4P_DIP"
			(at -1.30175 1.27 270)
			(unlocked yes)
			(layer "B.Fab")
			(hide yes)
			(effects
				(font
					(size 0.635 0.4064)
					(thickness 0.1524)
				)
				(justify mirror)
			)
		)
		(property "User Part Number" "TP15"
			(at -1.30175 1.27 270)
			(unlocked yes)
			(layer "Cmts.User")
			(hide yes)
			(effects
				(font
					(size 0.635 0.4064)
					(thickness 0.1524)
				)
				(justify mirror)
			)
		)
		(duplicate_pad_numbers_are_jumpers no)
		(fp_line
			(start -2.54 -1.27)
			(end 0 -1.27)
			(stroke
				(width 0.1524)
				(type default)
			)
			(layer "B.SilkS")
		)
		(fp_line
			(start -2.54 -1.1303)
			(end -2.54 -1.27)
			(stroke
				(width 0.1524)
				(type default)
			)
			(layer "B.SilkS")
		)
		(fp_line
			(start -2.54 1.4097)
			(end -2.54 1.1303)
			(stroke
				(width 0.1524)
				(type default)
			)
			(layer "B.SilkS")
		)
		(fp_line
			(start -2.54 3.81)
			(end -2.54 3.6703)
			(stroke
				(width 0.1524)
				(type default)
			)
			(layer "B.SilkS")
		)
		(fp_line
			(start 0 -1.27)
			(end 0 -0.635)
			(stroke
				(width 0.1524)
				(type default)
			)
			(layer "B.SilkS")
		)
		(fp_line
			(start 0 0.635)
			(end 0 1.905)
			(stroke
				(width 0.1524)
				(type default)
			)
			(layer "B.SilkS")
		)
		(fp_line
			(start 0 3.175)
			(end 0 3.81)
			(stroke
				(width 0.1524)
				(type default)
			)
			(layer "B.SilkS")
		)
		(fp_line
			(start 0 3.81)
			(end -2.54 3.81)
			(stroke
				(width 0.1524)
				(type default)
			)
			(layer "B.SilkS")
		)
		(fp_poly
			(pts
				(xy 0.761746 0) (xy 2.285746 -0.762) (xy 2.285746 0.762)
			)
			(stroke
				(width 0)
				(type default)
			)
			(fill yes)
			(layer "B.SilkS")
		)
		(fp_line
			(start -2.54 -1.27)
			(end 0 -1.27)
			(stroke
				(width 0.1)
				(type default)
			)
			(layer "B.Fab")
		)
		(fp_line
			(start -2.54 3.81)
			(end -2.54 -1.27)
			(stroke
				(width 0.1)
				(type default)
			)
			(layer "B.Fab")
		)
		(fp_line
			(start 0 -1.27)
			(end 0 3.81)
			(stroke
				(width 0.1)
				(type default)
			)
			(layer "B.Fab")
		)
		(fp_line
			(start 0 3.81)
			(end -2.54 3.81)
			(stroke
				(width 0.1)
				(type default)
			)
			(layer "B.Fab")
		)
		(fp_poly
			(pts
				(xy 0.761746 0) (xy 2.285746 -0.762) (xy 2.285746 0.762)
			)
			(stroke
				(width 0)
				(type default)
			)
			(fill yes)
			(layer "B.Fab")
		)
		(pad "1" thru_hole circle
			(at 0 0 180)
			(size 1.0033 1.0033)
			(drill 0.249936)
			(layers "*.Cu" "*.Mask")
			(remove_unused_layers no)
			(net "TDR_DIFF_100_IN5_DIP")
			(clearance 0.10795)
			(padstack
				(mode front_inner_back)
				(layer "Inner"
					(shape circle)
					(size 0.8001 0.8001)
					(clearance 0.1524)
				)
				(layer "B.Cu"
					(shape circle)
					(size 1.0033 1.0033)
					(thermal_gap 0.10795)
					(clearance 0.10795)
				)
			)
		)
		(pad "2" thru_hole circle
			(at -2.54 0 180)
			(size 1.9939 1.9939)
			(drill 0.249936)
			(layers "*.Cu" "*.Mask")
			(remove_unused_layers no)
			(net "COUPON_GND1")
			(clearance 0.10795)
			(padstack
				(mode front_inner_back)
				(layer "Inner"
					(shape circle)
					(size 0.8001 0.8001)
					(clearance 0.1524)
				)
				(layer "B.Cu"
					(shape circle)
					(size 1.9939 1.9939)
					(thermal_gap 0.10795)
					(clearance 0.10795)
				)
			)
		)
		(pad "3" thru_hole circle
			(at -2.54 2.54 180)
			(size 1.9939 1.9939)
			(drill 0.249936)
			(layers "*.Cu" "*.Mask")
			(remove_unused_layers no)
			(net "COUPON_GND1")
			(clearance 0.10795)
			(padstack
				(mode front_inner_back)
				(layer "Inner"
					(shape circle)
					(size 0.8001 0.8001)
					(clearance 0.1524)
				)
				(layer "B.Cu"
					(shape circle)
					(size 1.9939 1.9939)
					(thermal_gap 0.10795)
					(clearance 0.10795)
				)
			)
		)
		(pad "4" thru_hole circle
			(at 0 2.54 180)
			(size 1.0033 1.0033)
			(drill 0.249936)
			(layers "*.Cu" "*.Mask")
			(remove_unused_layers no)
			(net "TDR_DIFF_100_IN5_DIN")
			(clearance 0.10795)
			(padstack
				(mode front_inner_back)
				(layer "Inner"
					(shape circle)
					(size 0.8001 0.8001)
					(clearance 0.1524)
				)
				(layer "B.Cu"
					(shape circle)
					(size 1.0033 1.0033)
					(thermal_gap 0.10795)
					(clearance 0.10795)
				)
			)
		)
	)
	(footprint ""
		(layer "B.Cu")
		(at 148.209254 -206.387192 90)
		(property "Reference" "C2608"
			(at 0 0 90)
			(layer "B.SilkS")
			(hide yes)
			(effects
				(font
					(size 1.27 1.27)
				)
				(justify mirror)
			)
		)
		(property "Value" ""
			(at 0 0 90)
			(layer "B.Fab")
			(effects
				(font
					(size 1.27 1.27)
				)
				(justify mirror)
			)
		)
		(duplicate_pad_numbers_are_jumpers no)
		(fp_line
			(start 0.7874 -0.4064)
			(end -0.7874 -0.4064)
			(stroke
				(width 0.1524)
				(type default)
			)
			(layer "B.SilkS")
		)
		(fp_line
			(start -0.7874 -0.4064)
			(end -0.7874 0.4064)
			(stroke
				(width 0.1524)
				(type default)
			)
			(layer "B.SilkS")
		)
		(fp_line
			(start 0.7874 0.4064)
			(end 0.7874 -0.4064)
			(stroke
				(width 0.1524)
				(type default)
			)
			(layer "B.SilkS")
		)
		(fp_line
			(start -0.7874 0.4064)
			(end 0.7874 0.4064)
			(stroke
				(width 0.1524)
				(type default)
			)
			(layer "B.SilkS")
		)
		(fp_line
			(start 0.67945 -0.305054)
			(end 0.12065 -0.305054)
			(stroke
				(width 0.1)
				(type default)
			)
			(layer "B.Fab")
		)
		(fp_line
			(start 0.12065 -0.305054)
			(end 0.12065 -0.2794)
			(stroke
				(width 0.1)
				(type default)
			)
			(layer "B.Fab")
		)
		(fp_line
			(start -0.12065 -0.3048)
			(end -0.67945 -0.3048)
			(stroke
				(width 0.1)
				(type default)
			)
			(layer "B.Fab")
		)
		(fp_line
			(start -0.67945 -0.3048)
			(end -0.67945 0.3048)
			(stroke
				(width 0.1)
				(type default)
			)
			(layer "B.Fab")
		)
		(fp_line
			(start 0.12065 -0.2794)
			(end -0.12065 -0.2794)
			(stroke
				(width 0.1)
				(type default)
			)
			(layer "B.Fab")
		)
		(fp_line
			(start -0.12065 -0.2794)
			(end -0.12065 -0.3048)
			(stroke
				(width 0.1)
				(type default)
			)
			(layer "B.Fab")
		)
		(fp_line
			(start 0.12065 0.2794)
			(end 0.12065 0.3048)
			(stroke
				(width 0.1)
				(type default)
			)
			(layer "B.Fab")
		)
		(fp_line
			(start -0.120396 0.2794)
			(end 0.12065 0.2794)
			(stroke
				(width 0.1)
				(type default)
			)
			(layer "B.Fab")
		)
		(fp_line
			(start 0.67945 0.3048)
			(end 0.67945 -0.305054)
			(stroke
				(width 0.1)
				(type default)
			)
			(layer "B.Fab")
		)
		(fp_line
			(start 0.12065 0.3048)
			(end 0.67945 0.3048)
			(stroke
				(width 0.1)
				(type default)
			)
			(layer "B.Fab")
		)
		(fp_line
			(start -0.120396 0.3048)
			(end -0.120396 0.2794)
			(stroke
				(width 0.1)
				(type default)
			)
			(layer "B.Fab")
		)
		(fp_line
			(start -0.67945 0.3048)
			(end -0.120396 0.3048)
			(stroke
				(width 0.1)
				(type default)
			)
			(layer "B.Fab")
		)
		(pad "1" smd circle
			(at 0.40005 0 270)
			(size 0 0)
			(layers "B.Cu" "B.Mask" "B.Paste")
			(net "GND")
		)
		(pad "2" smd circle
			(at -0.40005 0 270)
			(size 0 0)
			(layers "B.Cu" "B.Mask" "B.Paste")
			(net "P3V3_AUX")
		)
	)
	(footprint ""
		(layer "B.Cu")
		(at 247.17502 -221.640908 90)
		(property "Reference" "R3484"
			(at 0 0 90)
			(layer "B.SilkS")
			(hide yes)
			(effects
				(font
					(size 1.27 1.27)
				)
				(justify mirror)
			)
		)
		(property "Value" ""
			(at 0 0 90)
			(layer "B.Fab")
			(effects
				(font
					(size 1.27 1.27)
				)
				(justify mirror)
			)
		)
		(duplicate_pad_numbers_are_jumpers no)
		(fp_line
			(start 0.7874 -0.4064)
			(end -0.7874 -0.4064)
			(stroke
				(width 0.1524)
				(type default)
			)
			(layer "B.SilkS")
		)
		(fp_line
			(start -0.7874 -0.4064)
			(end -0.7874 0.4064)
			(stroke
				(width 0.1524)
				(type default)
			)
			(layer "B.SilkS")
		)
		(fp_line
			(start 0.7874 0.4064)
			(end 0.7874 -0.4064)
			(stroke
				(width 0.1524)
				(type default)
			)
			(layer "B.SilkS")
		)
		(fp_line
			(start -0.7874 0.4064)
			(end 0.7874 0.4064)
			(stroke
				(width 0.1524)
				(type default)
			)
			(layer "B.SilkS")
		)
		(fp_line
			(start 0.67945 -0.305054)
			(end 0.12065 -0.305054)
			(stroke
				(width 0.1)
				(type default)
			)
			(layer "B.Fab")
		)
		(fp_line
			(start 0.12065 -0.305054)
			(end 0.12065 -0.2794)
			(stroke
				(width 0.1)
				(type default)
			)
			(layer "B.Fab")
		)
		(fp_line
			(start -0.12065 -0.3048)
			(end -0.67945 -0.3048)
			(stroke
				(width 0.1)
				(type default)
			)
			(layer "B.Fab")
		)
		(fp_line
			(start -0.67945 -0.3048)
			(end -0.67945 0.3048)
			(stroke
				(width 0.1)
				(type default)
			)
			(layer "B.Fab")
		)
		(fp_line
			(start 0.12065 -0.2794)
			(end -0.12065 -0.2794)
			(stroke
				(width 0.1)
				(type default)
			)
			(layer "B.Fab")
		)
		(fp_line
			(start -0.12065 -0.2794)
			(end -0.12065 -0.3048)
			(stroke
				(width 0.1)
				(type default)
			)
			(layer "B.Fab")
		)
		(fp_line
			(start 0.12065 0.2794)
			(end 0.12065 0.3048)
			(stroke
				(width 0.1)
				(type default)
			)
			(layer "B.Fab")
		)
		(fp_line
			(start -0.120396 0.2794)
			(end 0.12065 0.2794)
			(stroke
				(width 0.1)
				(type default)
			)
			(layer "B.Fab")
		)
		(fp_line
			(start 0.67945 0.3048)
			(end 0.67945 -0.305054)
			(stroke
				(width 0.1)
				(type default)
			)
			(layer "B.Fab")
		)
		(fp_line
			(start 0.12065 0.3048)
			(end 0.67945 0.3048)
			(stroke
				(width 0.1)
				(type default)
			)
			(layer "B.Fab")
		)
		(fp_line
			(start -0.120396 0.3048)
			(end -0.120396 0.2794)
			(stroke
				(width 0.1)
				(type default)
			)
			(layer "B.Fab")
		)
		(fp_line
			(start -0.67945 0.3048)
			(end -0.120396 0.3048)
			(stroke
				(width 0.1)
				(type default)
			)
			(layer "B.Fab")
		)
		(pad "1" smd circle
			(at 0.40005 0 270)
			(size 0 0)
			(layers "B.Cu" "B.Mask" "B.Paste")
			(net "SPI_PEX2_CLK_MUX")
		)
		(pad "2" smd circle
			(at -0.40005 0 270)
			(size 0 0)
			(layers "B.Cu" "B.Mask" "B.Paste")
			(net "SPI_PEX2_CLK_MUX_R")
		)
	)
	(footprint ""
		(layer "B.Cu")
		(at 287.574736 -286.399732 90)
		(property "Reference" "C3308"
			(at 0 0 90)
			(layer "B.SilkS")
			(hide yes)
			(effects
				(font
					(size 1.27 1.27)
				)
				(justify mirror)
			)
		)
		(property "Value" ""
			(at 0 0 90)
			(layer "B.Fab")
			(effects
				(font
					(size 1.27 1.27)
				)
				(justify mirror)
			)
		)
		(duplicate_pad_numbers_are_jumpers no)
		(fp_line
			(start 0.299974 -0.150114)
			(end -0.299974 -0.150114)
			(stroke
				(width 0.1)
				(type default)
			)
			(layer "B.Fab")
		)
		(fp_line
			(start -0.299974 -0.150114)
			(end -0.299974 0.150114)
			(stroke
				(width 0.1)
				(type default)
			)
			(layer "B.Fab")
		)
		(fp_line
			(start 0.299974 0.150114)
			(end 0.299974 -0.150114)
			(stroke
				(width 0.1)
				(type default)
			)
			(layer "B.Fab")
		)
		(fp_line
			(start -0.299974 0.150114)
			(end 0.299974 0.150114)
			(stroke
				(width 0.1)
				(type default)
			)
			(layer "B.Fab")
		)
		(pad "1" smd rect
			(at 0.2667 0 270)
			(size 0.3048 0.381)
			(layers "B.Cu" "B.Mask" "B.Paste")
			(net "P1V25_SERDES_VDDPLL_PEX2")
		)
		(pad "2" smd rect
			(at -0.2667 0 270)
			(size 0.3048 0.381)
			(layers "B.Cu" "B.Mask" "B.Paste")
			(net "GND")
		)
	)
	(footprint ""
		(layer "B.Cu")
		(at 213.935056 -215.272874)
		(property "Reference" "R6414"
			(at 0 0 0)
			(layer "B.SilkS")
			(hide yes)
			(effects
				(font
					(size 1.27 1.27)
				)
				(justify mirror)
			)
		)
		(property "Value" ""
			(at 0 0 0)
			(layer "B.Fab")
			(effects
				(font
					(size 1.27 1.27)
				)
				(justify mirror)
			)
		)
		(duplicate_pad_numbers_are_jumpers no)
		(fp_line
			(start -0.7874 -0.4064)
			(end -0.7874 0.4064)
			(stroke
				(width 0.1524)
				(type default)
			)
			(layer "B.SilkS")
		)
		(fp_line
			(start -0.7874 0.4064)
			(end 0.7874 0.4064)
			(stroke
				(width 0.1524)
				(type default)
			)
			(layer "B.SilkS")
		)
		(fp_line
			(start 0.7874 -0.4064)
			(end -0.7874 -0.4064)
			(stroke
				(width 0.1524)
				(type default)
			)
			(layer "B.SilkS")
		)
		(fp_line
			(start 0.7874 0.4064)
			(end 0.7874 -0.4064)
			(stroke
				(width 0.1524)
				(type default)
			)
			(layer "B.SilkS")
		)
		(fp_line
			(start -0.67945 -0.3048)
			(end -0.67945 0.3048)
			(stroke
				(width 0.1)
				(type default)
			)
			(layer "B.Fab")
		)
		(fp_line
			(start -0.67945 0.3048)
			(end -0.120396 0.3048)
			(stroke
				(width 0.1)
				(type default)
			)
			(layer "B.Fab")
		)
		(fp_line
			(start -0.12065 -0.3048)
			(end -0.67945 -0.3048)
			(stroke
				(width 0.1)
				(type default)
			)
			(layer "B.Fab")
		)
		(fp_line
			(start -0.12065 -0.2794)
			(end -0.12065 -0.3048)
			(stroke
				(width 0.1)
				(type default)
			)
			(layer "B.Fab")
		)
		(fp_line
			(start -0.120396 0.2794)
			(end 0.12065 0.2794)
			(stroke
				(width 0.1)
				(type default)
			)
			(layer "B.Fab")
		)
		(fp_line
			(start -0.120396 0.3048)
			(end -0.120396 0.2794)
			(stroke
				(width 0.1)
				(type default)
			)
			(layer "B.Fab")
		)
		(fp_line
			(start 0.12065 -0.305054)
			(end 0.12065 -0.2794)
			(stroke
				(width 0.1)
				(type default)
			)
			(layer "B.Fab")
		)
		(fp_line
			(start 0.12065 -0.2794)
			(end -0.12065 -0.2794)
			(stroke
				(width 0.1)
				(type default)
			)
			(layer "B.Fab")
		)
		(fp_line
			(start 0.12065 0.2794)
			(end 0.12065 0.3048)
			(stroke
				(width 0.1)
				(type default)
			)
			(layer "B.Fab")
		)
		(fp_line
			(start 0.12065 0.3048)
			(end 0.67945 0.3048)
			(stroke
				(width 0.1)
				(type default)
			)
			(layer "B.Fab")
		)
		(fp_line
			(start 0.67945 -0.305054)
			(end 0.12065 -0.305054)
			(stroke
				(width 0.1)
				(type default)
			)
			(layer "B.Fab")
		)
		(fp_line
			(start 0.67945 0.3048)
			(end 0.67945 -0.305054)
			(stroke
				(width 0.1)
				(type default)
			)
			(layer "B.Fab")
		)
		(pad "1" smd circle
			(at 0.40005 0 180)
			(size 0 0)
			(layers "B.Cu" "B.Mask" "B.Paste")
			(net "RST_BIC_I2C6_MUX_N")
		)
		(pad "2" smd circle
			(at -0.40005 0 180)
			(size 0 0)
			(layers "B.Cu" "B.Mask" "B.Paste")
			(net "P3V3_AUX")
		)
	)
	(footprint ""
		(layer "B.Cu")
		(at 342.011 -207.772 90)
		(property "Reference" "R4141"
			(at 0 0 90)
			(layer "B.SilkS")
			(hide yes)
			(effects
				(font
					(size 1.27 1.27)
				)
				(justify mirror)
			)
		)
		(property "Value" ""
			(at 0 0 90)
			(layer "B.Fab")
			(effects
				(font
					(size 1.27 1.27)
				)
				(justify mirror)
			)
		)
		(duplicate_pad_numbers_are_jumpers no)
		(fp_line
			(start 0.7874 -0.4064)
			(end -0.7874 -0.4064)
			(stroke
				(width 0.1524)
				(type default)
			)
			(layer "B.SilkS")
		)
		(fp_line
			(start -0.7874 -0.4064)
			(end -0.7874 0.4064)
			(stroke
				(width 0.1524)
				(type default)
			)
			(layer "B.SilkS")
		)
		(fp_line
			(start 0.7874 0.4064)
			(end 0.7874 -0.4064)
			(stroke
				(width 0.1524)
				(type default)
			)
			(layer "B.SilkS")
		)
		(fp_line
			(start -0.7874 0.4064)
			(end 0.7874 0.4064)
			(stroke
				(width 0.1524)
				(type default)
			)
			(layer "B.SilkS")
		)
		(fp_line
			(start 0.67945 -0.305054)
			(end 0.12065 -0.305054)
			(stroke
				(width 0.1)
				(type default)
			)
			(layer "B.Fab")
		)
		(fp_line
			(start 0.12065 -0.305054)
			(end 0.12065 -0.2794)
			(stroke
				(width 0.1)
				(type default)
			)
			(layer "B.Fab")
		)
		(fp_line
			(start -0.12065 -0.3048)
			(end -0.67945 -0.3048)
			(stroke
				(width 0.1)
				(type default)
			)
			(layer "B.Fab")
		)
		(fp_line
			(start -0.67945 -0.3048)
			(end -0.67945 0.3048)
			(stroke
				(width 0.1)
				(type default)
			)
			(layer "B.Fab")
		)
		(fp_line
			(start 0.12065 -0.2794)
			(end -0.12065 -0.2794)
			(stroke
				(width 0.1)
				(type default)
			)
			(layer "B.Fab")
		)
		(fp_line
			(start -0.12065 -0.2794)
			(end -0.12065 -0.3048)
			(stroke
				(width 0.1)
				(type default)
			)
			(layer "B.Fab")
		)
		(fp_line
			(start 0.12065 0.2794)
			(end 0.12065 0.3048)
			(stroke
				(width 0.1)
				(type default)
			)
			(layer "B.Fab")
		)
		(fp_line
			(start -0.120396 0.2794)
			(end 0.12065 0.2794)
			(stroke
				(width 0.1)
				(type default)
			)
			(layer "B.Fab")
		)
		(fp_line
			(start 0.67945 0.3048)
			(end 0.67945 -0.305054)
			(stroke
				(width 0.1)
				(type default)
			)
			(layer "B.Fab")
		)
		(fp_line
			(start 0.12065 0.3048)
			(end 0.67945 0.3048)
			(stroke
				(width 0.1)
				(type default)
			)
			(layer "B.Fab")
		)
		(fp_line
			(start -0.120396 0.3048)
			(end -0.120396 0.2794)
			(stroke
				(width 0.1)
				(type default)
			)
			(layer "B.Fab")
		)
		(fp_line
			(start -0.67945 0.3048)
			(end -0.120396 0.3048)
			(stroke
				(width 0.1)
				(type default)
			)
			(layer "B.Fab")
		)
		(pad "1" smd circle
			(at 0.40005 0 270)
			(size 0 0)
			(layers "B.Cu" "B.Mask" "B.Paste")
			(net "RST_SSD14_PERST_N")
		)
		(pad "2" smd circle
			(at -0.40005 0 270)
			(size 0 0)
			(layers "B.Cu" "B.Mask" "B.Paste")
			(net "RST_SSD14_PERST_R_N")
		)
	)
	(footprint ""
		(layer "B.Cu")
		(at 396.0749 -292.84168 90)
		(property "Reference" "C3568"
			(at 0 0 90)
			(layer "B.SilkS")
			(hide yes)
			(effects
				(font
					(size 1.27 1.27)
				)
				(justify mirror)
			)
		)
		(property "Value" ""
			(at 0 0 90)
			(layer "B.Fab")
			(effects
				(font
					(size 1.27 1.27)
				)
				(justify mirror)
			)
		)
		(duplicate_pad_numbers_are_jumpers no)
		(fp_line
			(start 0.299974 -0.150114)
			(end -0.299974 -0.150114)
			(stroke
				(width 0.1)
				(type default)
			)
			(layer "B.Fab")
		)
		(fp_line
			(start -0.299974 -0.150114)
			(end -0.299974 0.150114)
			(stroke
				(width 0.1)
				(type default)
			)
			(layer "B.Fab")
		)
		(fp_line
			(start 0.299974 0.150114)
			(end 0.299974 -0.150114)
			(stroke
				(width 0.1)
				(type default)
			)
			(layer "B.Fab")
		)
		(fp_line
			(start -0.299974 0.150114)
			(end 0.299974 0.150114)
			(stroke
				(width 0.1)
				(type default)
			)
			(layer "B.Fab")
		)
		(pad "1" smd rect
			(at 0.2667 0 270)
			(size 0.3048 0.381)
			(layers "B.Cu" "B.Mask" "B.Paste")
			(net "PCEPLL5_VDDA18_PEX3")
		)
		(pad "2" smd rect
			(at -0.2667 0 270)
			(size 0.3048 0.381)
			(layers "B.Cu" "B.Mask" "B.Paste")
			(net "GND")
		)
	)
	(footprint ""
		(layer "B.Cu")
		(at 162.226244 -140.8176 180)
		(property "Reference" "C884"
			(at 0 0 0)
			(layer "B.SilkS")
			(hide yes)
			(effects
				(font
					(size 1.27 1.27)
				)
				(justify mirror)
			)
		)
		(property "Value" ""
			(at 0 0 0)
			(layer "B.Fab")
			(effects
				(font
					(size 1.27 1.27)
				)
				(justify mirror)
			)
		)
		(duplicate_pad_numbers_are_jumpers no)
		(fp_line
			(start 0.7874 0.4064)
			(end 0.7874 -0.4064)
			(stroke
				(width 0.1524)
				(type default)
			)
			(layer "B.SilkS")
		)
		(fp_line
			(start 0.7874 -0.4064)
			(end -0.7874 -0.4064)
			(stroke
				(width 0.1524)
				(type default)
			)
			(layer "B.SilkS")
		)
		(fp_line
			(start -0.7874 0.4064)
			(end 0.7874 0.4064)
			(stroke
				(width 0.1524)
				(type default)
			)
			(layer "B.SilkS")
		)
		(fp_line
			(start -0.7874 -0.4064)
			(end -0.7874 0.4064)
			(stroke
				(width 0.1524)
				(type default)
			)
			(layer "B.SilkS")
		)
		(fp_line
			(start 0.67945 0.3048)
			(end 0.67945 -0.305054)
			(stroke
				(width 0.1)
				(type default)
			)
			(layer "B.Fab")
		)
		(fp_line
			(start 0.67945 -0.305054)
			(end 0.12065 -0.305054)
			(stroke
				(width 0.1)
				(type default)
			)
			(layer "B.Fab")
		)
		(fp_line
			(start 0.12065 0.3048)
			(end 0.67945 0.3048)
			(stroke
				(width 0.1)
				(type default)
			)
			(layer "B.Fab")
		)
		(fp_line
			(start 0.12065 0.2794)
			(end 0.12065 0.3048)
			(stroke
				(width 0.1)
				(type default)
			)
			(layer "B.Fab")
		)
		(fp_line
			(start 0.12065 -0.2794)
			(end -0.12065 -0.2794)
			(stroke
				(width 0.1)
				(type default)
			)
			(layer "B.Fab")
		)
		(fp_line
			(start 0.12065 -0.305054)
			(end 0.12065 -0.2794)
			(stroke
				(width 0.1)
				(type default)
			)
			(layer "B.Fab")
		)
		(fp_line
			(start -0.120396 0.3048)
			(end -0.120396 0.2794)
			(stroke
				(width 0.1)
				(type default)
			)
			(layer "B.Fab")
		)
		(fp_line
			(start -0.120396 0.2794)
			(end 0.12065 0.2794)
			(stroke
				(width 0.1)
				(type default)
			)
			(layer "B.Fab")
		)
		(fp_line
			(start -0.12065 -0.2794)
			(end -0.12065 -0.3048)
			(stroke
				(width 0.1)
				(type default)
			)
			(layer "B.Fab")
		)
		(fp_line
			(start -0.12065 -0.3048)
			(end -0.67945 -0.3048)
			(stroke
				(width 0.1)
				(type default)
			)
			(layer "B.Fab")
		)
		(fp_line
			(start -0.67945 0.3048)
			(end -0.120396 0.3048)
			(stroke
				(width 0.1)
				(type default)
			)
			(layer "B.Fab")
		)
		(fp_line
			(start -0.67945 -0.3048)
			(end -0.67945 0.3048)
			(stroke
				(width 0.1)
				(type default)
			)
			(layer "B.Fab")
		)
		(pad "1" smd circle
			(at 0.40005 0)
			(size 0 0)
			(layers "B.Cu" "B.Mask" "B.Paste")
			(net "P3V3_NIC2")
		)
		(pad "2" smd circle
			(at -0.40005 0)
			(size 0 0)
			(layers "B.Cu" "B.Mask" "B.Paste")
			(net "GND")
		)
	)
	(footprint ""
		(layer "B.Cu")
		(at 382.895602 -244.53596)
		(property "Reference" "C2567"
			(at 0 0 0)
			(layer "B.SilkS")
			(hide yes)
			(effects
				(font
					(size 1.27 1.27)
				)
				(justify mirror)
			)
		)
		(property "Value" ""
			(at 0 0 0)
			(layer "B.Fab")
			(effects
				(font
					(size 1.27 1.27)
				)
				(justify mirror)
			)
		)
		(duplicate_pad_numbers_are_jumpers no)
		(fp_line
			(start -0.7874 -0.4064)
			(end -0.7874 0.4064)
			(stroke
				(width 0.1524)
				(type default)
			)
			(layer "B.SilkS")
		)
		(fp_line
			(start -0.7874 0.4064)
			(end 0.7874 0.4064)
			(stroke
				(width 0.1524)
				(type default)
			)
			(layer "B.SilkS")
		)
		(fp_line
			(start 0.7874 -0.4064)
			(end -0.7874 -0.4064)
			(stroke
				(width 0.1524)
				(type default)
			)
			(layer "B.SilkS")
		)
		(fp_line
			(start 0.7874 0.4064)
			(end 0.7874 -0.4064)
			(stroke
				(width 0.1524)
				(type default)
			)
			(layer "B.SilkS")
		)
		(fp_line
			(start -0.67945 -0.3048)
			(end -0.67945 0.3048)
			(stroke
				(width 0.1)
				(type default)
			)
			(layer "B.Fab")
		)
		(fp_line
			(start -0.67945 0.3048)
			(end -0.120396 0.3048)
			(stroke
				(width 0.1)
				(type default)
			)
			(layer "B.Fab")
		)
		(fp_line
			(start -0.12065 -0.3048)
			(end -0.67945 -0.3048)
			(stroke
				(width 0.1)
				(type default)
			)
			(layer "B.Fab")
		)
		(fp_line
			(start -0.12065 -0.2794)
			(end -0.12065 -0.3048)
			(stroke
				(width 0.1)
				(type default)
			)
			(layer "B.Fab")
		)
		(fp_line
			(start -0.120396 0.2794)
			(end 0.12065 0.2794)
			(stroke
				(width 0.1)
				(type default)
			)
			(layer "B.Fab")
		)
		(fp_line
			(start -0.120396 0.3048)
			(end -0.120396 0.2794)
			(stroke
				(width 0.1)
				(type default)
			)
			(layer "B.Fab")
		)
		(fp_line
			(start 0.12065 -0.305054)
			(end 0.12065 -0.2794)
			(stroke
				(width 0.1)
				(type default)
			)
			(layer "B.Fab")
		)
		(fp_line
			(start 0.12065 -0.2794)
			(end -0.12065 -0.2794)
			(stroke
				(width 0.1)
				(type default)
			)
			(layer "B.Fab")
		)
		(fp_line
			(start 0.12065 0.2794)
			(end 0.12065 0.3048)
			(stroke
				(width 0.1)
				(type default)
			)
			(layer "B.Fab")
		)
		(fp_line
			(start 0.12065 0.3048)
			(end 0.67945 0.3048)
			(stroke
				(width 0.1)
				(type default)
			)
			(layer "B.Fab")
		)
		(fp_line
			(start 0.67945 -0.305054)
			(end 0.12065 -0.305054)
			(stroke
				(width 0.1)
				(type default)
			)
			(layer "B.Fab")
		)
		(fp_line
			(start 0.67945 0.3048)
			(end 0.67945 -0.305054)
			(stroke
				(width 0.1)
				(type default)
			)
			(layer "B.Fab")
		)
		(pad "1" smd circle
			(at 0.40005 0 180)
			(size 0 0)
			(layers "B.Cu" "B.Mask" "B.Paste")
			(net "P3V3_AUX")
		)
		(pad "2" smd circle
			(at -0.40005 0 180)
			(size 0 0)
			(layers "B.Cu" "B.Mask" "B.Paste")
			(net "GND")
		)
	)
	(footprint ""
		(layer "B.Cu")
		(at 155.800044 -288.774886 -90)
		(property "Reference" "R3453"
			(at 0 0 90)
			(layer "B.SilkS")
			(hide yes)
			(effects
				(font
					(size 1.27 1.27)
				)
				(justify mirror)
			)
		)
		(property "Value" ""
			(at 0 0 90)
			(layer "B.Fab")
			(effects
				(font
					(size 1.27 1.27)
				)
				(justify mirror)
			)
		)
		(duplicate_pad_numbers_are_jumpers no)
		(fp_line
			(start -0.7874 0.4064)
			(end 0.7874 0.4064)
			(stroke
				(width 0.1524)
				(type default)
			)
			(layer "B.SilkS")
		)
		(fp_line
			(start 0.7874 0.4064)
			(end 0.7874 -0.4064)
			(stroke
				(width 0.1524)
				(type default)
			)
			(layer "B.SilkS")
		)
		(fp_line
			(start -0.7874 -0.4064)
			(end -0.7874 0.4064)
			(stroke
				(width 0.1524)
				(type default)
			)
			(layer "B.SilkS")
		)
		(fp_line
			(start 0.7874 -0.4064)
			(end -0.7874 -0.4064)
			(stroke
				(width 0.1524)
				(type default)
			)
			(layer "B.SilkS")
		)
		(fp_line
			(start -0.67945 0.3048)
			(end -0.120396 0.3048)
			(stroke
				(width 0.1)
				(type default)
			)
			(layer "B.Fab")
		)
		(fp_line
			(start -0.120396 0.3048)
			(end -0.120396 0.2794)
			(stroke
				(width 0.1)
				(type default)
			)
			(layer "B.Fab")
		)
		(fp_line
			(start 0.12065 0.3048)
			(end 0.67945 0.3048)
			(stroke
				(width 0.1)
				(type default)
			)
			(layer "B.Fab")
		)
		(fp_line
			(start 0.67945 0.3048)
			(end 0.67945 -0.305054)
			(stroke
				(width 0.1)
				(type default)
			)
			(layer "B.Fab")
		)
		(fp_line
			(start -0.120396 0.2794)
			(end 0.12065 0.2794)
			(stroke
				(width 0.1)
				(type default)
			)
			(layer "B.Fab")
		)
		(fp_line
			(start 0.12065 0.2794)
			(end 0.12065 0.3048)
			(stroke
				(width 0.1)
				(type default)
			)
			(layer "B.Fab")
		)
		(fp_line
			(start -0.12065 -0.2794)
			(end -0.12065 -0.3048)
			(stroke
				(width 0.1)
				(type default)
			)
			(layer "B.Fab")
		)
		(fp_line
			(start 0.12065 -0.2794)
			(end -0.12065 -0.2794)
			(stroke
				(width 0.1)
				(type default)
			)
			(layer "B.Fab")
		)
		(fp_line
			(start -0.67945 -0.3048)
			(end -0.67945 0.3048)
			(stroke
				(width 0.1)
				(type default)
			)
			(layer "B.Fab")
		)
		(fp_line
			(start -0.12065 -0.3048)
			(end -0.67945 -0.3048)
			(stroke
				(width 0.1)
				(type default)
			)
			(layer "B.Fab")
		)
		(fp_line
			(start 0.12065 -0.305054)
			(end 0.12065 -0.2794)
			(stroke
				(width 0.1)
				(type default)
			)
			(layer "B.Fab")
		)
		(fp_line
			(start 0.67945 -0.305054)
			(end 0.12065 -0.305054)
			(stroke
				(width 0.1)
				(type default)
			)
			(layer "B.Fab")
		)
		(pad "1" smd circle
			(at 0.40005 0 90)
			(size 0 0)
			(layers "B.Cu" "B.Mask" "B.Paste")
			(net "SPI_PEX1_SDIO3_R")
		)
		(pad "2" smd circle
			(at -0.40005 0 90)
			(size 0 0)
			(layers "B.Cu" "B.Mask" "B.Paste")
			(net "SPI_PEX1_SDIO3")
		)
	)
	(footprint ""
		(layer "B.Cu")
		(at 451.298056 -266.996672)
		(property "Reference" "L131"
			(at 0 0 0)
			(layer "B.SilkS")
			(hide yes)
			(effects
				(font
					(size 1.27 1.27)
				)
				(justify mirror)
			)
		)
		(property "Value" ""
			(at 0 0 0)
			(layer "B.Fab")
			(effects
				(font
					(size 1.27 1.27)
				)
				(justify mirror)
			)
		)
		(duplicate_pad_numbers_are_jumpers no)
		(fp_line
			(start -2.248154 -4.9911)
			(end 2.248154 -4.9911)
			(stroke
				(width 0.1524)
				(type default)
			)
			(layer "B.SilkS")
		)
		(fp_line
			(start -2.248154 -1.89865)
			(end -2.248154 -4.9911)
			(stroke
				(width 0.1524)
				(type default)
			)
			(layer "B.SilkS")
		)
		(fp_line
			(start -2.248154 4.9911)
			(end -2.248154 2.293112)
			(stroke
				(width 0.1524)
				(type default)
			)
			(layer "B.SilkS")
		)
		(fp_line
			(start 2.248154 -4.9911)
			(end 2.248154 -1.89865)
			(stroke
				(width 0.1524)
				(type default)
			)
			(layer "B.SilkS")
		)
		(fp_line
			(start 2.248154 2.293112)
			(end 2.248154 4.9911)
			(stroke
				(width 0.1524)
				(type default)
			)
			(layer "B.SilkS")
		)
		(fp_line
			(start 2.248154 4.9911)
			(end -2.248154 4.9911)
			(stroke
				(width 0.1524)
				(type default)
			)
			(layer "B.SilkS")
		)
		(fp_line
			(start -1.700022 -0.899922)
			(end 1.700022 -0.899922)
			(stroke
				(width 0.1)
				(type default)
			)
			(layer "B.Fab")
		)
		(fp_line
			(start -1.700022 0.899922)
			(end -1.700022 -0.899922)
			(stroke
				(width 0.1)
				(type default)
			)
			(layer "B.Fab")
		)
		(fp_line
			(start 1.700022 -0.899922)
			(end 1.700022 0.899922)
			(stroke
				(width 0.1)
				(type default)
			)
			(layer "B.Fab")
		)
		(fp_line
			(start 1.700022 0.899922)
			(end -1.700022 0.899922)
			(stroke
				(width 0.1)
				(type default)
			)
			(layer "B.Fab")
		)
		(pad "1" smd rect
			(at 1.575054 0 180)
			(size 1.1684 9.8044)
			(layers "B.Cu" "B.Mask" "B.Paste")
			(net "P1V25_PEX3")
		)
		(pad "2" smd rect
			(at -1.575054 0 180)
			(size 1.1684 9.8044)
			(layers "B.Cu" "B.Mask" "B.Paste")
			(net "P1V25_SERDES_VDDPLL_PEX3")
		)
	)
	(footprint ""
		(layer "B.Cu")
		(at 379.349 -239.141 -90)
		(property "Reference" "C2565"
			(at 0 0 90)
			(layer "B.SilkS")
			(hide yes)
			(effects
				(font
					(size 1.27 1.27)
				)
				(justify mirror)
			)
		)
		(property "Value" ""
			(at 0 0 90)
			(layer "B.Fab")
			(effects
				(font
					(size 1.27 1.27)
				)
				(justify mirror)
			)
		)
		(duplicate_pad_numbers_are_jumpers no)
		(fp_line
			(start -0.7874 0.4064)
			(end 0.7874 0.4064)
			(stroke
				(width 0.1524)
				(type default)
			)
			(layer "B.SilkS")
		)
		(fp_line
			(start 0.7874 0.4064)
			(end 0.7874 -0.4064)
			(stroke
				(width 0.1524)
				(type default)
			)
			(layer "B.SilkS")
		)
		(fp_line
			(start -0.7874 -0.4064)
			(end -0.7874 0.4064)
			(stroke
				(width 0.1524)
				(type default)
			)
			(layer "B.SilkS")
		)
		(fp_line
			(start 0.7874 -0.4064)
			(end -0.7874 -0.4064)
			(stroke
				(width 0.1524)
				(type default)
			)
			(layer "B.SilkS")
		)
		(fp_line
			(start -0.67945 0.3048)
			(end -0.120396 0.3048)
			(stroke
				(width 0.1)
				(type default)
			)
			(layer "B.Fab")
		)
		(fp_line
			(start -0.120396 0.3048)
			(end -0.120396 0.2794)
			(stroke
				(width 0.1)
				(type default)
			)
			(layer "B.Fab")
		)
		(fp_line
			(start 0.12065 0.3048)
			(end 0.67945 0.3048)
			(stroke
				(width 0.1)
				(type default)
			)
			(layer "B.Fab")
		)
		(fp_line
			(start 0.67945 0.3048)
			(end 0.67945 -0.305054)
			(stroke
				(width 0.1)
				(type default)
			)
			(layer "B.Fab")
		)
		(fp_line
			(start -0.120396 0.2794)
			(end 0.12065 0.2794)
			(stroke
				(width 0.1)
				(type default)
			)
			(layer "B.Fab")
		)
		(fp_line
			(start 0.12065 0.2794)
			(end 0.12065 0.3048)
			(stroke
				(width 0.1)
				(type default)
			)
			(layer "B.Fab")
		)
		(fp_line
			(start -0.12065 -0.2794)
			(end -0.12065 -0.3048)
			(stroke
				(width 0.1)
				(type default)
			)
			(layer "B.Fab")
		)
		(fp_line
			(start 0.12065 -0.2794)
			(end -0.12065 -0.2794)
			(stroke
				(width 0.1)
				(type default)
			)
			(layer "B.Fab")
		)
		(fp_line
			(start -0.67945 -0.3048)
			(end -0.67945 0.3048)
			(stroke
				(width 0.1)
				(type default)
			)
			(layer "B.Fab")
		)
		(fp_line
			(start -0.12065 -0.3048)
			(end -0.67945 -0.3048)
			(stroke
				(width 0.1)
				(type default)
			)
			(layer "B.Fab")
		)
		(fp_line
			(start 0.12065 -0.305054)
			(end 0.12065 -0.2794)
			(stroke
				(width 0.1)
				(type default)
			)
			(layer "B.Fab")
		)
		(fp_line
			(start 0.67945 -0.305054)
			(end 0.12065 -0.305054)
			(stroke
				(width 0.1)
				(type default)
			)
			(layer "B.Fab")
		)
		(pad "1" smd circle
			(at 0.40005 0 90)
			(size 0 0)
			(layers "B.Cu" "B.Mask" "B.Paste")
			(net "P3V3_AUX")
		)
		(pad "2" smd circle
			(at -0.40005 0 90)
			(size 0 0)
			(layers "B.Cu" "B.Mask" "B.Paste")
			(net "GND")
		)
	)
	(footprint ""
		(layer "B.Cu")
		(at 225.370644 -231.225598 -90)
		(property "Reference" "R4556"
			(at 0 0 90)
			(layer "B.SilkS")
			(hide yes)
			(effects
				(font
					(size 1.27 1.27)
				)
				(justify mirror)
			)
		)
		(property "Value" ""
			(at 0 0 90)
			(layer "B.Fab")
			(effects
				(font
					(size 1.27 1.27)
				)
				(justify mirror)
			)
		)
		(duplicate_pad_numbers_are_jumpers no)
		(fp_line
			(start -0.7874 0.4064)
			(end 0.7874 0.4064)
			(stroke
				(width 0.1524)
				(type default)
			)
			(layer "B.SilkS")
		)
		(fp_line
			(start 0.7874 0.4064)
			(end 0.7874 -0.4064)
			(stroke
				(width 0.1524)
				(type default)
			)
			(layer "B.SilkS")
		)
		(fp_line
			(start -0.7874 -0.4064)
			(end -0.7874 0.4064)
			(stroke
				(width 0.1524)
				(type default)
			)
			(layer "B.SilkS")
		)
		(fp_line
			(start 0.7874 -0.4064)
			(end -0.7874 -0.4064)
			(stroke
				(width 0.1524)
				(type default)
			)
			(layer "B.SilkS")
		)
		(fp_line
			(start -0.67945 0.3048)
			(end -0.120396 0.3048)
			(stroke
				(width 0.1)
				(type default)
			)
			(layer "B.Fab")
		)
		(fp_line
			(start -0.120396 0.3048)
			(end -0.120396 0.2794)
			(stroke
				(width 0.1)
				(type default)
			)
			(layer "B.Fab")
		)
		(fp_line
			(start 0.12065 0.3048)
			(end 0.67945 0.3048)
			(stroke
				(width 0.1)
				(type default)
			)
			(layer "B.Fab")
		)
		(fp_line
			(start 0.67945 0.3048)
			(end 0.67945 -0.305054)
			(stroke
				(width 0.1)
				(type default)
			)
			(layer "B.Fab")
		)
		(fp_line
			(start -0.120396 0.2794)
			(end 0.12065 0.2794)
			(stroke
				(width 0.1)
				(type default)
			)
			(layer "B.Fab")
		)
		(fp_line
			(start 0.12065 0.2794)
			(end 0.12065 0.3048)
			(stroke
				(width 0.1)
				(type default)
			)
			(layer "B.Fab")
		)
		(fp_line
			(start -0.12065 -0.2794)
			(end -0.12065 -0.3048)
			(stroke
				(width 0.1)
				(type default)
			)
			(layer "B.Fab")
		)
		(fp_line
			(start 0.12065 -0.2794)
			(end -0.12065 -0.2794)
			(stroke
				(width 0.1)
				(type default)
			)
			(layer "B.Fab")
		)
		(fp_line
			(start -0.67945 -0.3048)
			(end -0.67945 0.3048)
			(stroke
				(width 0.1)
				(type default)
			)
			(layer "B.Fab")
		)
		(fp_line
			(start -0.12065 -0.3048)
			(end -0.67945 -0.3048)
			(stroke
				(width 0.1)
				(type default)
			)
			(layer "B.Fab")
		)
		(fp_line
			(start 0.12065 -0.305054)
			(end 0.12065 -0.2794)
			(stroke
				(width 0.1)
				(type default)
			)
			(layer "B.Fab")
		)
		(fp_line
			(start 0.67945 -0.305054)
			(end 0.12065 -0.305054)
			(stroke
				(width 0.1)
				(type default)
			)
			(layer "B.Fab")
		)
		(pad "1" smd circle
			(at 0.40005 0 90)
			(size 0 0)
			(layers "B.Cu" "B.Mask" "B.Paste")
			(net "BIC_FORCE_THROTTLE_N")
		)
		(pad "2" smd circle
			(at -0.40005 0 90)
			(size 0 0)
			(layers "B.Cu" "B.Mask" "B.Paste")
			(net "BIC_FORCE_THROTTLE_R_N")
		)
	)
	(footprint ""
		(layer "B.Cu")
		(at 212.09 -206.121 -90)
		(property "Reference" "R1513"
			(at 0 0 90)
			(layer "B.SilkS")
			(hide yes)
			(effects
				(font
					(size 1.27 1.27)
				)
				(justify mirror)
			)
		)
		(property "Value" ""
			(at 0 0 90)
			(layer "B.Fab")
			(effects
				(font
					(size 1.27 1.27)
				)
				(justify mirror)
			)
		)
		(duplicate_pad_numbers_are_jumpers no)
		(fp_line
			(start -0.7874 0.4064)
			(end 0.7874 0.4064)
			(stroke
				(width 0.1524)
				(type default)
			)
			(layer "B.SilkS")
		)
		(fp_line
			(start 0.7874 0.4064)
			(end 0.7874 -0.4064)
			(stroke
				(width 0.1524)
				(type default)
			)
			(layer "B.SilkS")
		)
		(fp_line
			(start -0.7874 -0.4064)
			(end -0.7874 0.4064)
			(stroke
				(width 0.1524)
				(type default)
			)
			(layer "B.SilkS")
		)
		(fp_line
			(start 0.7874 -0.4064)
			(end -0.7874 -0.4064)
			(stroke
				(width 0.1524)
				(type default)
			)
			(layer "B.SilkS")
		)
		(fp_line
			(start -0.67945 0.3048)
			(end -0.120396 0.3048)
			(stroke
				(width 0.1)
				(type default)
			)
			(layer "B.Fab")
		)
		(fp_line
			(start -0.120396 0.3048)
			(end -0.120396 0.2794)
			(stroke
				(width 0.1)
				(type default)
			)
			(layer "B.Fab")
		)
		(fp_line
			(start 0.12065 0.3048)
			(end 0.67945 0.3048)
			(stroke
				(width 0.1)
				(type default)
			)
			(layer "B.Fab")
		)
		(fp_line
			(start 0.67945 0.3048)
			(end 0.67945 -0.305054)
			(stroke
				(width 0.1)
				(type default)
			)
			(layer "B.Fab")
		)
		(fp_line
			(start -0.120396 0.2794)
			(end 0.12065 0.2794)
			(stroke
				(width 0.1)
				(type default)
			)
			(layer "B.Fab")
		)
		(fp_line
			(start 0.12065 0.2794)
			(end 0.12065 0.3048)
			(stroke
				(width 0.1)
				(type default)
			)
			(layer "B.Fab")
		)
		(fp_line
			(start -0.12065 -0.2794)
			(end -0.12065 -0.3048)
			(stroke
				(width 0.1)
				(type default)
			)
			(layer "B.Fab")
		)
		(fp_line
			(start 0.12065 -0.2794)
			(end -0.12065 -0.2794)
			(stroke
				(width 0.1)
				(type default)
			)
			(layer "B.Fab")
		)
		(fp_line
			(start -0.67945 -0.3048)
			(end -0.67945 0.3048)
			(stroke
				(width 0.1)
				(type default)
			)
			(layer "B.Fab")
		)
		(fp_line
			(start -0.12065 -0.3048)
			(end -0.67945 -0.3048)
			(stroke
				(width 0.1)
				(type default)
			)
			(layer "B.Fab")
		)
		(fp_line
			(start 0.12065 -0.305054)
			(end 0.12065 -0.2794)
			(stroke
				(width 0.1)
				(type default)
			)
			(layer "B.Fab")
		)
		(fp_line
			(start 0.67945 -0.305054)
			(end 0.12065 -0.305054)
			(stroke
				(width 0.1)
				(type default)
			)
			(layer "B.Fab")
		)
		(pad "1" smd circle
			(at 0.40005 0 90)
			(size 0 0)
			(layers "B.Cu" "B.Mask" "B.Paste")
			(net "SMB_NIC4_LS_R_SCL")
		)
		(pad "2" smd circle
			(at -0.40005 0 90)
			(size 0 0)
			(layers "B.Cu" "B.Mask" "B.Paste")
			(net "SMB_NIC4_R_SCL")
		)
	)
	(footprint ""
		(layer "B.Cu")
		(at 186.200034 -289.724846 180)
		(property "Reference" "C3177"
			(at 0 0 0)
			(layer "B.SilkS")
			(hide yes)
			(effects
				(font
					(size 1.27 1.27)
				)
				(justify mirror)
			)
		)
		(property "Value" ""
			(at 0 0 0)
			(layer "B.Fab")
			(effects
				(font
					(size 1.27 1.27)
				)
				(justify mirror)
			)
		)
		(duplicate_pad_numbers_are_jumpers no)
		(fp_line
			(start 0.299974 0.150114)
			(end 0.299974 -0.150114)
			(stroke
				(width 0.1)
				(type default)
			)
			(layer "B.Fab")
		)
		(fp_line
			(start 0.299974 -0.150114)
			(end -0.299974 -0.150114)
			(stroke
				(width 0.1)
				(type default)
			)
			(layer "B.Fab")
		)
		(fp_line
			(start -0.299974 0.150114)
			(end 0.299974 0.150114)
			(stroke
				(width 0.1)
				(type default)
			)
			(layer "B.Fab")
		)
		(fp_line
			(start -0.299974 -0.150114)
			(end -0.299974 0.150114)
			(stroke
				(width 0.1)
				(type default)
			)
			(layer "B.Fab")
		)
		(pad "1" smd rect
			(at 0.2667 0)
			(size 0.3048 0.381)
			(layers "B.Cu" "B.Mask" "B.Paste")
			(net "P1V8_PEX")
		)
		(pad "2" smd rect
			(at -0.2667 0)
			(size 0.3048 0.381)
			(layers "B.Cu" "B.Mask" "B.Paste")
			(net "GND")
		)
	)
	(footprint ""
		(layer "B.Cu")
		(at 165.299898 -300.174914)
		(property "Reference" "C1371"
			(at 0 0 0)
			(layer "B.SilkS")
			(hide yes)
			(effects
				(font
					(size 1.27 1.27)
				)
				(justify mirror)
			)
		)
		(property "Value" ""
			(at 0 0 0)
			(layer "B.Fab")
			(effects
				(font
					(size 1.27 1.27)
				)
				(justify mirror)
			)
		)
		(duplicate_pad_numbers_are_jumpers no)
		(fp_line
			(start -0.299974 -0.150114)
			(end -0.299974 0.150114)
			(stroke
				(width 0.1)
				(type default)
			)
			(layer "B.Fab")
		)
		(fp_line
			(start -0.299974 0.150114)
			(end 0.299974 0.150114)
			(stroke
				(width 0.1)
				(type default)
			)
			(layer "B.Fab")
		)
		(fp_line
			(start 0.299974 -0.150114)
			(end -0.299974 -0.150114)
			(stroke
				(width 0.1)
				(type default)
			)
			(layer "B.Fab")
		)
		(fp_line
			(start 0.299974 0.150114)
			(end 0.299974 -0.150114)
			(stroke
				(width 0.1)
				(type default)
			)
			(layer "B.Fab")
		)
		(pad "1" smd rect
			(at 0.2667 0 180)
			(size 0.3048 0.381)
			(layers "B.Cu" "B.Mask" "B.Paste")
			(net "P0V8_PEX1")
		)
		(pad "2" smd rect
			(at -0.2667 0 180)
			(size 0.3048 0.381)
			(layers "B.Cu" "B.Mask" "B.Paste")
			(net "GND")
		)
	)
	(footprint ""
		(layer "B.Cu")
		(at 15.736062 -389.078216 180)
		(property "Reference" "C4470"
			(at 0 0 0)
			(layer "B.SilkS")
			(hide yes)
			(effects
				(font
					(size 1.27 1.27)
				)
				(justify mirror)
			)
		)
		(property "Value" ""
			(at 0 0 0)
			(layer "B.Fab")
			(effects
				(font
					(size 1.27 1.27)
				)
				(justify mirror)
			)
		)
		(duplicate_pad_numbers_are_jumpers no)
		(fp_line
			(start 0.7874 0.4064)
			(end 0.7874 -0.4064)
			(stroke
				(width 0.1524)
				(type default)
			)
			(layer "B.SilkS")
		)
		(fp_line
			(start 0.7874 -0.4064)
			(end -0.7874 -0.4064)
			(stroke
				(width 0.1524)
				(type default)
			)
			(layer "B.SilkS")
		)
		(fp_line
			(start -0.7874 0.4064)
			(end 0.7874 0.4064)
			(stroke
				(width 0.1524)
				(type default)
			)
			(layer "B.SilkS")
		)
		(fp_line
			(start -0.7874 -0.4064)
			(end -0.7874 0.4064)
			(stroke
				(width 0.1524)
				(type default)
			)
			(layer "B.SilkS")
		)
		(fp_line
			(start 0.67945 0.3048)
			(end 0.67945 -0.305054)
			(stroke
				(width 0.1)
				(type default)
			)
			(layer "B.Fab")
		)
		(fp_line
			(start 0.67945 -0.305054)
			(end 0.12065 -0.305054)
			(stroke
				(width 0.1)
				(type default)
			)
			(layer "B.Fab")
		)
		(fp_line
			(start 0.12065 0.3048)
			(end 0.67945 0.3048)
			(stroke
				(width 0.1)
				(type default)
			)
			(layer "B.Fab")
		)
		(fp_line
			(start 0.12065 0.2794)
			(end 0.12065 0.3048)
			(stroke
				(width 0.1)
				(type default)
			)
			(layer "B.Fab")
		)
		(fp_line
			(start 0.12065 -0.2794)
			(end -0.12065 -0.2794)
			(stroke
				(width 0.1)
				(type default)
			)
			(layer "B.Fab")
		)
		(fp_line
			(start 0.12065 -0.305054)
			(end 0.12065 -0.2794)
			(stroke
				(width 0.1)
				(type default)
			)
			(layer "B.Fab")
		)
		(fp_line
			(start -0.120396 0.3048)
			(end -0.120396 0.2794)
			(stroke
				(width 0.1)
				(type default)
			)
			(layer "B.Fab")
		)
		(fp_line
			(start -0.120396 0.2794)
			(end 0.12065 0.2794)
			(stroke
				(width 0.1)
				(type default)
			)
			(layer "B.Fab")
		)
		(fp_line
			(start -0.12065 -0.2794)
			(end -0.12065 -0.3048)
			(stroke
				(width 0.1)
				(type default)
			)
			(layer "B.Fab")
		)
		(fp_line
			(start -0.12065 -0.3048)
			(end -0.67945 -0.3048)
			(stroke
				(width 0.1)
				(type default)
			)
			(layer "B.Fab")
		)
		(fp_line
			(start -0.67945 0.3048)
			(end -0.120396 0.3048)
			(stroke
				(width 0.1)
				(type default)
			)
			(layer "B.Fab")
		)
		(fp_line
			(start -0.67945 -0.3048)
			(end -0.67945 0.3048)
			(stroke
				(width 0.1)
				(type default)
			)
			(layer "B.Fab")
		)
		(pad "1" smd circle
			(at 0.40005 0)
			(size 0 0)
			(layers "B.Cu" "B.Mask" "B.Paste")
			(net "P1V2_USB_8042")
		)
		(pad "2" smd circle
			(at -0.40005 0)
			(size 0 0)
			(layers "B.Cu" "B.Mask" "B.Paste")
			(net "GND")
		)
	)
	(footprint ""
		(layer "B.Cu")
		(at 108.446062 -335.453736 180)
		(property "Reference" "C2703"
			(at 0 0 0)
			(layer "B.SilkS")
			(hide yes)
			(effects
				(font
					(size 1.27 1.27)
				)
				(justify mirror)
			)
		)
		(property "Value" ""
			(at 0 0 0)
			(layer "B.Fab")
			(effects
				(font
					(size 1.27 1.27)
				)
				(justify mirror)
			)
		)
		(duplicate_pad_numbers_are_jumpers no)
		(fp_line
			(start 0.7874 0.4064)
			(end 0.7874 -0.4064)
			(stroke
				(width 0.1524)
				(type default)
			)
			(layer "B.SilkS")
		)
		(fp_line
			(start 0.7874 -0.4064)
			(end -0.7874 -0.4064)
			(stroke
				(width 0.1524)
				(type default)
			)
			(layer "B.SilkS")
		)
		(fp_line
			(start -0.7874 0.4064)
			(end 0.7874 0.4064)
			(stroke
				(width 0.1524)
				(type default)
			)
			(layer "B.SilkS")
		)
		(fp_line
			(start -0.7874 -0.4064)
			(end -0.7874 0.4064)
			(stroke
				(width 0.1524)
				(type default)
			)
			(layer "B.SilkS")
		)
		(fp_line
			(start 0.67945 0.3048)
			(end 0.67945 -0.305054)
			(stroke
				(width 0.1)
				(type default)
			)
			(layer "B.Fab")
		)
		(fp_line
			(start 0.67945 -0.305054)
			(end 0.12065 -0.305054)
			(stroke
				(width 0.1)
				(type default)
			)
			(layer "B.Fab")
		)
		(fp_line
			(start 0.12065 0.3048)
			(end 0.67945 0.3048)
			(stroke
				(width 0.1)
				(type default)
			)
			(layer "B.Fab")
		)
		(fp_line
			(start 0.12065 0.2794)
			(end 0.12065 0.3048)
			(stroke
				(width 0.1)
				(type default)
			)
			(layer "B.Fab")
		)
		(fp_line
			(start 0.12065 -0.2794)
			(end -0.12065 -0.2794)
			(stroke
				(width 0.1)
				(type default)
			)
			(layer "B.Fab")
		)
		(fp_line
			(start 0.12065 -0.305054)
			(end 0.12065 -0.2794)
			(stroke
				(width 0.1)
				(type default)
			)
			(layer "B.Fab")
		)
		(fp_line
			(start -0.120396 0.3048)
			(end -0.120396 0.2794)
			(stroke
				(width 0.1)
				(type default)
			)
			(layer "B.Fab")
		)
		(fp_line
			(start -0.120396 0.2794)
			(end 0.12065 0.2794)
			(stroke
				(width 0.1)
				(type default)
			)
			(layer "B.Fab")
		)
		(fp_line
			(start -0.12065 -0.2794)
			(end -0.12065 -0.3048)
			(stroke
				(width 0.1)
				(type default)
			)
			(layer "B.Fab")
		)
		(fp_line
			(start -0.12065 -0.3048)
			(end -0.67945 -0.3048)
			(stroke
				(width 0.1)
				(type default)
			)
			(layer "B.Fab")
		)
		(fp_line
			(start -0.67945 0.3048)
			(end -0.120396 0.3048)
			(stroke
				(width 0.1)
				(type default)
			)
			(layer "B.Fab")
		)
		(fp_line
			(start -0.67945 -0.3048)
			(end -0.67945 0.3048)
			(stroke
				(width 0.1)
				(type default)
			)
			(layer "B.Fab")
		)
		(pad "1" smd circle
			(at 0.40005 0)
			(size 0 0)
			(layers "B.Cu" "B.Mask" "B.Paste")
			(net "P3V3_CLK_BUFFER_9ZXL0451E_VZX3P3A")
		)
		(pad "2" smd circle
			(at -0.40005 0)
			(size 0 0)
			(layers "B.Cu" "B.Mask" "B.Paste")
			(net "GND")
		)
	)
	(footprint ""
		(layer "B.Cu")
		(at 260.259322 -77.959458)
		(property "Reference" "R1046"
			(at 0 0 0)
			(layer "B.SilkS")
			(hide yes)
			(effects
				(font
					(size 1.27 1.27)
				)
				(justify mirror)
			)
		)
		(property "Value" ""
			(at 0 0 0)
			(layer "B.Fab")
			(effects
				(font
					(size 1.27 1.27)
				)
				(justify mirror)
			)
		)
		(duplicate_pad_numbers_are_jumpers no)
		(fp_line
			(start -1.2954 -0.5842)
			(end -1.2954 0.5842)
			(stroke
				(width 0.1524)
				(type default)
			)
			(layer "B.SilkS")
		)
		(fp_line
			(start -1.2954 0.5842)
			(end 1.2954 0.5842)
			(stroke
				(width 0.1524)
				(type default)
			)
			(layer "B.SilkS")
		)
		(fp_line
			(start 1.2954 -0.5842)
			(end -1.2954 -0.5842)
			(stroke
				(width 0.1524)
				(type default)
			)
			(layer "B.SilkS")
		)
		(fp_line
			(start 1.2954 0.5842)
			(end 1.2954 -0.5842)
			(stroke
				(width 0.1524)
				(type default)
			)
			(layer "B.SilkS")
		)
		(fp_line
			(start -1.1938 -0.406654)
			(end -1.1938 0.4064)
			(stroke
				(width 0.1)
				(type default)
			)
			(layer "B.Fab")
		)
		(fp_line
			(start -1.1938 0.4064)
			(end -0.8636 0.4064)
			(stroke
				(width 0.1)
				(type default)
			)
			(layer "B.Fab")
		)
		(fp_line
			(start -0.8636 -0.4572)
			(end -0.8636 -0.406654)
			(stroke
				(width 0.1)
				(type default)
			)
			(layer "B.Fab")
		)
		(fp_line
			(start -0.8636 -0.406654)
			(end -1.1938 -0.406654)
			(stroke
				(width 0.1)
				(type default)
			)
			(layer "B.Fab")
		)
		(fp_line
			(start -0.8636 0.4064)
			(end -0.8636 0.4572)
			(stroke
				(width 0.1)
				(type default)
			)
			(layer "B.Fab")
		)
		(fp_line
			(start -0.8636 0.4572)
			(end 0.8636 0.4572)
			(stroke
				(width 0.1)
				(type default)
			)
			(layer "B.Fab")
		)
		(fp_line
			(start 0.8636 -0.4572)
			(end -0.8636 -0.4572)
			(stroke
				(width 0.1)
				(type default)
			)
			(layer "B.Fab")
		)
		(fp_line
			(start 0.8636 -0.406654)
			(end 0.8636 -0.4572)
			(stroke
				(width 0.1)
				(type default)
			)
			(layer "B.Fab")
		)
		(fp_line
			(start 0.8636 0.4064)
			(end 1.1938 0.4064)
			(stroke
				(width 0.1)
				(type default)
			)
			(layer "B.Fab")
		)
		(fp_line
			(start 0.8636 0.4318)
			(end 0.8636 0.4064)
			(stroke
				(width 0.1)
				(type default)
			)
			(layer "B.Fab")
		)
		(fp_line
			(start 0.8636 0.4572)
			(end 0.8636 0.4318)
			(stroke
				(width 0.1)
				(type default)
			)
			(layer "B.Fab")
		)
		(fp_line
			(start 1.1938 -0.406654)
			(end 0.8636 -0.406654)
			(stroke
				(width 0.1)
				(type default)
			)
			(layer "B.Fab")
		)
		(fp_line
			(start 1.1938 0.4064)
			(end 1.1938 -0.406654)
			(stroke
				(width 0.1)
				(type default)
			)
			(layer "B.Fab")
		)
		(pad "1" smd rect
			(at 0.7366 0 270)
			(size 0.7112 0.8128)
			(layers "B.Cu" "B.Mask" "B.Paste")
			(net "P3V3_CLK_GEN_VDD_CK440")
		)
		(pad "2" smd rect
			(at -0.7366 0 270)
			(size 0.7112 0.8128)
			(layers "B.Cu" "B.Mask" "B.Paste")
			(net "P3V3_CLK_GEN_VDDA100M_CK440")
		)
	)
	(footprint ""
		(layer "B.Cu")
		(at 402.249894 -288.299906 90)
		(property "Reference" "C3451"
			(at 0 0 90)
			(layer "B.SilkS")
			(hide yes)
			(effects
				(font
					(size 1.27 1.27)
				)
				(justify mirror)
			)
		)
		(property "Value" ""
			(at 0 0 90)
			(layer "B.Fab")
			(effects
				(font
					(size 1.27 1.27)
				)
				(justify mirror)
			)
		)
		(duplicate_pad_numbers_are_jumpers no)
		(fp_line
			(start 0.299974 -0.150114)
			(end -0.299974 -0.150114)
			(stroke
				(width 0.1)
				(type default)
			)
			(layer "B.Fab")
		)
		(fp_line
			(start -0.299974 -0.150114)
			(end -0.299974 0.150114)
			(stroke
				(width 0.1)
				(type default)
			)
			(layer "B.Fab")
		)
		(fp_line
			(start 0.299974 0.150114)
			(end 0.299974 -0.150114)
			(stroke
				(width 0.1)
				(type default)
			)
			(layer "B.Fab")
		)
		(fp_line
			(start -0.299974 0.150114)
			(end 0.299974 0.150114)
			(stroke
				(width 0.1)
				(type default)
			)
			(layer "B.Fab")
		)
		(pad "1" smd rect
			(at 0.2667 0 270)
			(size 0.3048 0.381)
			(layers "B.Cu" "B.Mask" "B.Paste")
			(net "P1V25_PEX3")
		)
		(pad "2" smd rect
			(at -0.2667 0 270)
			(size 0.3048 0.381)
			(layers "B.Cu" "B.Mask" "B.Paste")
			(net "GND")
		)
	)
	(footprint ""
		(layer "B.Cu")
		(at 106.57078 -84.968842 180)
		(property "Reference" "C2666"
			(at 0 0 0)
			(layer "B.SilkS")
			(hide yes)
			(effects
				(font
					(size 1.27 1.27)
				)
				(justify mirror)
			)
		)
		(property "Value" ""
			(at 0 0 0)
			(layer "B.Fab")
			(effects
				(font
					(size 1.27 1.27)
				)
				(justify mirror)
			)
		)
		(duplicate_pad_numbers_are_jumpers no)
		(fp_line
			(start 0.7874 0.4064)
			(end 0.7874 -0.4064)
			(stroke
				(width 0.1524)
				(type default)
			)
			(layer "B.SilkS")
		)
		(fp_line
			(start 0.7874 -0.4064)
			(end -0.7874 -0.4064)
			(stroke
				(width 0.1524)
				(type default)
			)
			(layer "B.SilkS")
		)
		(fp_line
			(start -0.7874 0.4064)
			(end 0.7874 0.4064)
			(stroke
				(width 0.1524)
				(type default)
			)
			(layer "B.SilkS")
		)
		(fp_line
			(start -0.7874 -0.4064)
			(end -0.7874 0.4064)
			(stroke
				(width 0.1524)
				(type default)
			)
			(layer "B.SilkS")
		)
		(fp_line
			(start 0.67945 0.3048)
			(end 0.67945 -0.305054)
			(stroke
				(width 0.1)
				(type default)
			)
			(layer "B.Fab")
		)
		(fp_line
			(start 0.67945 -0.305054)
			(end 0.12065 -0.305054)
			(stroke
				(width 0.1)
				(type default)
			)
			(layer "B.Fab")
		)
		(fp_line
			(start 0.12065 0.3048)
			(end 0.67945 0.3048)
			(stroke
				(width 0.1)
				(type default)
			)
			(layer "B.Fab")
		)
		(fp_line
			(start 0.12065 0.2794)
			(end 0.12065 0.3048)
			(stroke
				(width 0.1)
				(type default)
			)
			(layer "B.Fab")
		)
		(fp_line
			(start 0.12065 -0.2794)
			(end -0.12065 -0.2794)
			(stroke
				(width 0.1)
				(type default)
			)
			(layer "B.Fab")
		)
		(fp_line
			(start 0.12065 -0.305054)
			(end 0.12065 -0.2794)
			(stroke
				(width 0.1)
				(type default)
			)
			(layer "B.Fab")
		)
		(fp_line
			(start -0.120396 0.3048)
			(end -0.120396 0.2794)
			(stroke
				(width 0.1)
				(type default)
			)
			(layer "B.Fab")
		)
		(fp_line
			(start -0.120396 0.2794)
			(end 0.12065 0.2794)
			(stroke
				(width 0.1)
				(type default)
			)
			(layer "B.Fab")
		)
		(fp_line
			(start -0.12065 -0.2794)
			(end -0.12065 -0.3048)
			(stroke
				(width 0.1)
				(type default)
			)
			(layer "B.Fab")
		)
		(fp_line
			(start -0.12065 -0.3048)
			(end -0.67945 -0.3048)
			(stroke
				(width 0.1)
				(type default)
			)
			(layer "B.Fab")
		)
		(fp_line
			(start -0.67945 0.3048)
			(end -0.120396 0.3048)
			(stroke
				(width 0.1)
				(type default)
			)
			(layer "B.Fab")
		)
		(fp_line
			(start -0.67945 -0.3048)
			(end -0.67945 0.3048)
			(stroke
				(width 0.1)
				(type default)
			)
			(layer "B.Fab")
		)
		(pad "1" smd circle
			(at 0.40005 0)
			(size 0 0)
			(layers "B.Cu" "B.Mask" "B.Paste")
			(net "P3V3_VDD_9ZXL0851_0_7")
		)
		(pad "2" smd circle
			(at -0.40005 0)
			(size 0 0)
			(layers "B.Cu" "B.Mask" "B.Paste")
			(net "GND")
		)
	)
	(footprint ""
		(layer "B.Cu")
		(at 340.494112 -218.787218 -90)
		(property "Reference" "C2064"
			(at 0 0 90)
			(layer "B.SilkS")
			(hide yes)
			(effects
				(font
					(size 1.27 1.27)
				)
				(justify mirror)
			)
		)
		(property "Value" ""
			(at 0 0 90)
			(layer "B.Fab")
			(effects
				(font
					(size 1.27 1.27)
				)
				(justify mirror)
			)
		)
		(duplicate_pad_numbers_are_jumpers no)
		(fp_line
			(start -0.69215 0.2921)
			(end 0.69215 0.2921)
			(stroke
				(width 0.1524)
				(type default)
			)
			(layer "B.SilkS")
		)
		(fp_line
			(start 0.69215 0.2921)
			(end 0.69215 -0.2921)
			(stroke
				(width 0.1524)
				(type default)
			)
			(layer "B.SilkS")
		)
		(fp_line
			(start -0.69215 -0.2921)
			(end -0.69215 0.2921)
			(stroke
				(width 0.1524)
				(type default)
			)
			(layer "B.SilkS")
		)
		(fp_line
			(start 0.69215 -0.2921)
			(end -0.69215 -0.2921)
			(stroke
				(width 0.1524)
				(type default)
			)
			(layer "B.SilkS")
		)
		(fp_line
			(start -0.51435 0.2794)
			(end 0.51435 0.2794)
			(stroke
				(width 0.1)
				(type default)
			)
			(layer "B.Fab")
		)
		(fp_line
			(start 0.51435 0.2794)
			(end 0.51435 -0.2794)
			(stroke
				(width 0.1)
				(type default)
			)
			(layer "B.Fab")
		)
		(fp_line
			(start -0.51435 -0.2794)
			(end -0.51435 0.2794)
			(stroke
				(width 0.1)
				(type default)
			)
			(layer "B.Fab")
		)
		(fp_line
			(start 0.51435 -0.2794)
			(end -0.51435 -0.2794)
			(stroke
				(width 0.1)
				(type default)
			)
			(layer "B.Fab")
		)
		(pad "1" smd circle
			(at 0.40005 0 90)
			(size 0 0)
			(layers "B.Cu" "B.Mask" "B.Paste")
			(net "P3V3_VCC_FPGA_CORE")
		)
		(pad "2" smd circle
			(at -0.40005 0 90)
			(size 0 0)
			(layers "B.Cu" "B.Mask" "B.Paste")
			(net "GND")
		)
		(zone
			(layer "B.Cu")
			(hatch none 0.5)
			(connect_pads
				(clearance 0)
			)
			(min_thickness 0.25)
			(keepout
				(tracks not_allowed)
				(vias allowed)
				(pads allowed)
				(copperpour not_allowed)
				(footprints allowed)
			)
			(placement
				(enabled no)
				(sheetname "")
			)
			(fill
				(thermal_gap 0.5)
				(thermal_bridge_width 0.5)
				(island_removal_mode 0)
			)
			(polygon
				(pts
					(xy 340.406482 -218.596718) (xy 340.348316 -218.688158) (xy 340.348316 -218.887548) (xy 340.406482 -218.977718)
					(xy 340.581742 -218.977718) (xy 340.640162 -218.887548) (xy 340.640162 -218.688158) (xy 340.581996 -218.596718)
				)
			)
		)
	)
	(footprint ""
		(layer "B.Cu")
		(at 130.906774 -174.596044 90)
		(property "Reference" "C2661"
			(at 0 0 90)
			(layer "B.SilkS")
			(hide yes)
			(effects
				(font
					(size 1.27 1.27)
				)
				(justify mirror)
			)
		)
		(property "Value" ""
			(at 0 0 90)
			(layer "B.Fab")
			(effects
				(font
					(size 1.27 1.27)
				)
				(justify mirror)
			)
		)
		(duplicate_pad_numbers_are_jumpers no)
		(fp_line
			(start 0.7874 -0.4064)
			(end -0.7874 -0.4064)
			(stroke
				(width 0.1524)
				(type default)
			)
			(layer "B.SilkS")
		)
		(fp_line
			(start -0.7874 -0.4064)
			(end -0.7874 0.4064)
			(stroke
				(width 0.1524)
				(type default)
			)
			(layer "B.SilkS")
		)
		(fp_line
			(start 0.7874 0.4064)
			(end 0.7874 -0.4064)
			(stroke
				(width 0.1524)
				(type default)
			)
			(layer "B.SilkS")
		)
		(fp_line
			(start -0.7874 0.4064)
			(end 0.7874 0.4064)
			(stroke
				(width 0.1524)
				(type default)
			)
			(layer "B.SilkS")
		)
		(fp_line
			(start 0.67945 -0.305054)
			(end 0.12065 -0.305054)
			(stroke
				(width 0.1)
				(type default)
			)
			(layer "B.Fab")
		)
		(fp_line
			(start 0.12065 -0.305054)
			(end 0.12065 -0.2794)
			(stroke
				(width 0.1)
				(type default)
			)
			(layer "B.Fab")
		)
		(fp_line
			(start -0.12065 -0.3048)
			(end -0.67945 -0.3048)
			(stroke
				(width 0.1)
				(type default)
			)
			(layer "B.Fab")
		)
		(fp_line
			(start -0.67945 -0.3048)
			(end -0.67945 0.3048)
			(stroke
				(width 0.1)
				(type default)
			)
			(layer "B.Fab")
		)
		(fp_line
			(start 0.12065 -0.2794)
			(end -0.12065 -0.2794)
			(stroke
				(width 0.1)
				(type default)
			)
			(layer "B.Fab")
		)
		(fp_line
			(start -0.12065 -0.2794)
			(end -0.12065 -0.3048)
			(stroke
				(width 0.1)
				(type default)
			)
			(layer "B.Fab")
		)
		(fp_line
			(start 0.12065 0.2794)
			(end 0.12065 0.3048)
			(stroke
				(width 0.1)
				(type default)
			)
			(layer "B.Fab")
		)
		(fp_line
			(start -0.120396 0.2794)
			(end 0.12065 0.2794)
			(stroke
				(width 0.1)
				(type default)
			)
			(layer "B.Fab")
		)
		(fp_line
			(start 0.67945 0.3048)
			(end 0.67945 -0.305054)
			(stroke
				(width 0.1)
				(type default)
			)
			(layer "B.Fab")
		)
		(fp_line
			(start 0.12065 0.3048)
			(end 0.67945 0.3048)
			(stroke
				(width 0.1)
				(type default)
			)
			(layer "B.Fab")
		)
		(fp_line
			(start -0.120396 0.3048)
			(end -0.120396 0.2794)
			(stroke
				(width 0.1)
				(type default)
			)
			(layer "B.Fab")
		)
		(fp_line
			(start -0.67945 0.3048)
			(end -0.120396 0.3048)
			(stroke
				(width 0.1)
				(type default)
			)
			(layer "B.Fab")
		)
		(pad "1" smd circle
			(at 0.40005 0 270)
			(size 0 0)
			(layers "B.Cu" "B.Mask" "B.Paste")
			(net "P3V3_DB2000QL_VDD")
		)
		(pad "2" smd circle
			(at -0.40005 0 270)
			(size 0 0)
			(layers "B.Cu" "B.Mask" "B.Paste")
			(net "GND")
		)
	)
	(footprint ""
		(layer "B.Cu")
		(at 213.813136 -221.350586)
		(property "Reference" "R4883"
			(at 0 0 0)
			(layer "B.SilkS")
			(hide yes)
			(effects
				(font
					(size 1.27 1.27)
				)
				(justify mirror)
			)
		)
		(property "Value" ""
			(at 0 0 0)
			(layer "B.Fab")
			(effects
				(font
					(size 1.27 1.27)
				)
				(justify mirror)
			)
		)
		(duplicate_pad_numbers_are_jumpers no)
		(fp_line
			(start -0.7874 -0.4064)
			(end -0.7874 0.4064)
			(stroke
				(width 0.1524)
				(type default)
			)
			(layer "B.SilkS")
		)
		(fp_line
			(start -0.7874 0.4064)
			(end 0.7874 0.4064)
			(stroke
				(width 0.1524)
				(type default)
			)
			(layer "B.SilkS")
		)
		(fp_line
			(start 0.7874 -0.4064)
			(end -0.7874 -0.4064)
			(stroke
				(width 0.1524)
				(type default)
			)
			(layer "B.SilkS")
		)
		(fp_line
			(start 0.7874 0.4064)
			(end 0.7874 -0.4064)
			(stroke
				(width 0.1524)
				(type default)
			)
			(layer "B.SilkS")
		)
		(fp_line
			(start -0.67945 -0.3048)
			(end -0.67945 0.3048)
			(stroke
				(width 0.1)
				(type default)
			)
			(layer "B.Fab")
		)
		(fp_line
			(start -0.67945 0.3048)
			(end -0.120396 0.3048)
			(stroke
				(width 0.1)
				(type default)
			)
			(layer "B.Fab")
		)
		(fp_line
			(start -0.12065 -0.3048)
			(end -0.67945 -0.3048)
			(stroke
				(width 0.1)
				(type default)
			)
			(layer "B.Fab")
		)
		(fp_line
			(start -0.12065 -0.2794)
			(end -0.12065 -0.3048)
			(stroke
				(width 0.1)
				(type default)
			)
			(layer "B.Fab")
		)
		(fp_line
			(start -0.120396 0.2794)
			(end 0.12065 0.2794)
			(stroke
				(width 0.1)
				(type default)
			)
			(layer "B.Fab")
		)
		(fp_line
			(start -0.120396 0.3048)
			(end -0.120396 0.2794)
			(stroke
				(width 0.1)
				(type default)
			)
			(layer "B.Fab")
		)
		(fp_line
			(start 0.12065 -0.305054)
			(end 0.12065 -0.2794)
			(stroke
				(width 0.1)
				(type default)
			)
			(layer "B.Fab")
		)
		(fp_line
			(start 0.12065 -0.2794)
			(end -0.12065 -0.2794)
			(stroke
				(width 0.1)
				(type default)
			)
			(layer "B.Fab")
		)
		(fp_line
			(start 0.12065 0.2794)
			(end 0.12065 0.3048)
			(stroke
				(width 0.1)
				(type default)
			)
			(layer "B.Fab")
		)
		(fp_line
			(start 0.12065 0.3048)
			(end 0.67945 0.3048)
			(stroke
				(width 0.1)
				(type default)
			)
			(layer "B.Fab")
		)
		(fp_line
			(start 0.67945 -0.305054)
			(end 0.12065 -0.305054)
			(stroke
				(width 0.1)
				(type default)
			)
			(layer "B.Fab")
		)
		(fp_line
			(start 0.67945 0.3048)
			(end 0.67945 -0.305054)
			(stroke
				(width 0.1)
				(type default)
			)
			(layer "B.Fab")
		)
		(pad "1" smd circle
			(at 0.40005 0 180)
			(size 0 0)
			(layers "B.Cu" "B.Mask" "B.Paste")
			(net "SMB_BIC_FPGA_R_SCL")
		)
		(pad "2" smd circle
			(at -0.40005 0 180)
			(size 0 0)
			(layers "B.Cu" "B.Mask" "B.Paste")
			(net "P3V3_AUX")
		)
	)
	(footprint ""
		(layer "B.Cu")
		(at 339.979 -233.553 -90)
		(property "Reference" "R3599"
			(at 0 0 90)
			(layer "B.SilkS")
			(hide yes)
			(effects
				(font
					(size 1.27 1.27)
				)
				(justify mirror)
			)
		)
		(property "Value" ""
			(at 0 0 90)
			(layer "B.Fab")
			(effects
				(font
					(size 1.27 1.27)
				)
				(justify mirror)
			)
		)
		(duplicate_pad_numbers_are_jumpers no)
		(fp_line
			(start -0.7874 0.4064)
			(end 0.7874 0.4064)
			(stroke
				(width 0.1524)
				(type default)
			)
			(layer "B.SilkS")
		)
		(fp_line
			(start 0.7874 0.4064)
			(end 0.7874 -0.4064)
			(stroke
				(width 0.1524)
				(type default)
			)
			(layer "B.SilkS")
		)
		(fp_line
			(start -0.7874 -0.4064)
			(end -0.7874 0.4064)
			(stroke
				(width 0.1524)
				(type default)
			)
			(layer "B.SilkS")
		)
		(fp_line
			(start 0.7874 -0.4064)
			(end -0.7874 -0.4064)
			(stroke
				(width 0.1524)
				(type default)
			)
			(layer "B.SilkS")
		)
		(fp_line
			(start -0.67945 0.3048)
			(end -0.120396 0.3048)
			(stroke
				(width 0.1)
				(type default)
			)
			(layer "B.Fab")
		)
		(fp_line
			(start -0.120396 0.3048)
			(end -0.120396 0.2794)
			(stroke
				(width 0.1)
				(type default)
			)
			(layer "B.Fab")
		)
		(fp_line
			(start 0.12065 0.3048)
			(end 0.67945 0.3048)
			(stroke
				(width 0.1)
				(type default)
			)
			(layer "B.Fab")
		)
		(fp_line
			(start 0.67945 0.3048)
			(end 0.67945 -0.305054)
			(stroke
				(width 0.1)
				(type default)
			)
			(layer "B.Fab")
		)
		(fp_line
			(start -0.120396 0.2794)
			(end 0.12065 0.2794)
			(stroke
				(width 0.1)
				(type default)
			)
			(layer "B.Fab")
		)
		(fp_line
			(start 0.12065 0.2794)
			(end 0.12065 0.3048)
			(stroke
				(width 0.1)
				(type default)
			)
			(layer "B.Fab")
		)
		(fp_line
			(start -0.12065 -0.2794)
			(end -0.12065 -0.3048)
			(stroke
				(width 0.1)
				(type default)
			)
			(layer "B.Fab")
		)
		(fp_line
			(start 0.12065 -0.2794)
			(end -0.12065 -0.2794)
			(stroke
				(width 0.1)
				(type default)
			)
			(layer "B.Fab")
		)
		(fp_line
			(start -0.67945 -0.3048)
			(end -0.67945 0.3048)
			(stroke
				(width 0.1)
				(type default)
			)
			(layer "B.Fab")
		)
		(fp_line
			(start -0.12065 -0.3048)
			(end -0.67945 -0.3048)
			(stroke
				(width 0.1)
				(type default)
			)
			(layer "B.Fab")
		)
		(fp_line
			(start 0.12065 -0.305054)
			(end 0.12065 -0.2794)
			(stroke
				(width 0.1)
				(type default)
			)
			(layer "B.Fab")
		)
		(fp_line
			(start 0.67945 -0.305054)
			(end 0.12065 -0.305054)
			(stroke
				(width 0.1)
				(type default)
			)
			(layer "B.Fab")
		)
		(pad "1" smd circle
			(at 0.40005 0 90)
			(size 0 0)
			(layers "B.Cu" "B.Mask" "B.Paste")
			(net "SSD1_CLK_EN_N")
		)
		(pad "2" smd circle
			(at -0.40005 0 90)
			(size 0 0)
			(layers "B.Cu" "B.Mask" "B.Paste")
			(net "SSD1_CLK_EN_R_N")
		)
	)
	(footprint ""
		(layer "B.Cu")
		(at 172.983906 -308.724808 -90)
		(property "Reference" "R1323"
			(at 0 0 90)
			(layer "B.SilkS")
			(hide yes)
			(effects
				(font
					(size 1.27 1.27)
				)
				(justify mirror)
			)
		)
		(property "Value" ""
			(at 0 0 90)
			(layer "B.Fab")
			(effects
				(font
					(size 1.27 1.27)
				)
				(justify mirror)
			)
		)
		(duplicate_pad_numbers_are_jumpers no)
		(fp_line
			(start -0.7874 0.4064)
			(end 0.7874 0.4064)
			(stroke
				(width 0.1524)
				(type default)
			)
			(layer "B.SilkS")
		)
		(fp_line
			(start 0.7874 0.4064)
			(end 0.7874 -0.4064)
			(stroke
				(width 0.1524)
				(type default)
			)
			(layer "B.SilkS")
		)
		(fp_line
			(start -0.7874 -0.4064)
			(end -0.7874 0.4064)
			(stroke
				(width 0.1524)
				(type default)
			)
			(layer "B.SilkS")
		)
		(fp_line
			(start 0.7874 -0.4064)
			(end -0.7874 -0.4064)
			(stroke
				(width 0.1524)
				(type default)
			)
			(layer "B.SilkS")
		)
		(fp_line
			(start -0.67945 0.3048)
			(end -0.120396 0.3048)
			(stroke
				(width 0.1)
				(type default)
			)
			(layer "B.Fab")
		)
		(fp_line
			(start -0.120396 0.3048)
			(end -0.120396 0.2794)
			(stroke
				(width 0.1)
				(type default)
			)
			(layer "B.Fab")
		)
		(fp_line
			(start 0.12065 0.3048)
			(end 0.67945 0.3048)
			(stroke
				(width 0.1)
				(type default)
			)
			(layer "B.Fab")
		)
		(fp_line
			(start 0.67945 0.3048)
			(end 0.67945 -0.305054)
			(stroke
				(width 0.1)
				(type default)
			)
			(layer "B.Fab")
		)
		(fp_line
			(start -0.120396 0.2794)
			(end 0.12065 0.2794)
			(stroke
				(width 0.1)
				(type default)
			)
			(layer "B.Fab")
		)
		(fp_line
			(start 0.12065 0.2794)
			(end 0.12065 0.3048)
			(stroke
				(width 0.1)
				(type default)
			)
			(layer "B.Fab")
		)
		(fp_line
			(start -0.12065 -0.2794)
			(end -0.12065 -0.3048)
			(stroke
				(width 0.1)
				(type default)
			)
			(layer "B.Fab")
		)
		(fp_line
			(start 0.12065 -0.2794)
			(end -0.12065 -0.2794)
			(stroke
				(width 0.1)
				(type default)
			)
			(layer "B.Fab")
		)
		(fp_line
			(start -0.67945 -0.3048)
			(end -0.67945 0.3048)
			(stroke
				(width 0.1)
				(type default)
			)
			(layer "B.Fab")
		)
		(fp_line
			(start -0.12065 -0.3048)
			(end -0.67945 -0.3048)
			(stroke
				(width 0.1)
				(type default)
			)
			(layer "B.Fab")
		)
		(fp_line
			(start 0.12065 -0.305054)
			(end 0.12065 -0.2794)
			(stroke
				(width 0.1)
				(type default)
			)
			(layer "B.Fab")
		)
		(fp_line
			(start 0.67945 -0.305054)
			(end 0.12065 -0.305054)
			(stroke
				(width 0.1)
				(type default)
			)
			(layer "B.Fab")
		)
		(pad "1" smd circle
			(at 0.40005 0 90)
			(size 0 0)
			(layers "B.Cu" "B.Mask" "B.Paste")
			(net "TP_PEX1_TRST_L")
		)
		(pad "2" smd circle
			(at -0.40005 0 90)
			(size 0 0)
			(layers "B.Cu" "B.Mask" "B.Paste")
			(net "GND")
		)
	)
	(footprint ""
		(layer "B.Cu")
		(at 101.823266 -356.061772 -90)
		(property "Reference" "R6371"
			(at 0 0 90)
			(layer "B.SilkS")
			(hide yes)
			(effects
				(font
					(size 1.27 1.27)
				)
				(justify mirror)
			)
		)
		(property "Value" ""
			(at 0 0 90)
			(layer "B.Fab")
			(effects
				(font
					(size 1.27 1.27)
				)
				(justify mirror)
			)
		)
		(duplicate_pad_numbers_are_jumpers no)
		(fp_line
			(start -0.7874 0.4064)
			(end 0.7874 0.4064)
			(stroke
				(width 0.1524)
				(type default)
			)
			(layer "B.SilkS")
		)
		(fp_line
			(start 0.7874 0.4064)
			(end 0.7874 -0.4064)
			(stroke
				(width 0.1524)
				(type default)
			)
			(layer "B.SilkS")
		)
		(fp_line
			(start -0.7874 -0.4064)
			(end -0.7874 0.4064)
			(stroke
				(width 0.1524)
				(type default)
			)
			(layer "B.SilkS")
		)
		(fp_line
			(start 0.7874 -0.4064)
			(end -0.7874 -0.4064)
			(stroke
				(width 0.1524)
				(type default)
			)
			(layer "B.SilkS")
		)
		(fp_line
			(start -0.67945 0.3048)
			(end -0.120396 0.3048)
			(stroke
				(width 0.1)
				(type default)
			)
			(layer "B.Fab")
		)
		(fp_line
			(start -0.120396 0.3048)
			(end -0.120396 0.2794)
			(stroke
				(width 0.1)
				(type default)
			)
			(layer "B.Fab")
		)
		(fp_line
			(start 0.12065 0.3048)
			(end 0.67945 0.3048)
			(stroke
				(width 0.1)
				(type default)
			)
			(layer "B.Fab")
		)
		(fp_line
			(start 0.67945 0.3048)
			(end 0.67945 -0.305054)
			(stroke
				(width 0.1)
				(type default)
			)
			(layer "B.Fab")
		)
		(fp_line
			(start -0.120396 0.2794)
			(end 0.12065 0.2794)
			(stroke
				(width 0.1)
				(type default)
			)
			(layer "B.Fab")
		)
		(fp_line
			(start 0.12065 0.2794)
			(end 0.12065 0.3048)
			(stroke
				(width 0.1)
				(type default)
			)
			(layer "B.Fab")
		)
		(fp_line
			(start -0.12065 -0.2794)
			(end -0.12065 -0.3048)
			(stroke
				(width 0.1)
				(type default)
			)
			(layer "B.Fab")
		)
		(fp_line
			(start 0.12065 -0.2794)
			(end -0.12065 -0.2794)
			(stroke
				(width 0.1)
				(type default)
			)
			(layer "B.Fab")
		)
		(fp_line
			(start -0.67945 -0.3048)
			(end -0.67945 0.3048)
			(stroke
				(width 0.1)
				(type default)
			)
			(layer "B.Fab")
		)
		(fp_line
			(start -0.12065 -0.3048)
			(end -0.67945 -0.3048)
			(stroke
				(width 0.1)
				(type default)
			)
			(layer "B.Fab")
		)
		(fp_line
			(start 0.12065 -0.305054)
			(end 0.12065 -0.2794)
			(stroke
				(width 0.1)
				(type default)
			)
			(layer "B.Fab")
		)
		(fp_line
			(start 0.67945 -0.305054)
			(end 0.12065 -0.305054)
			(stroke
				(width 0.1)
				(type default)
			)
			(layer "B.Fab")
		)
		(pad "1" smd circle
			(at 0.40005 0 90)
			(size 0 0)
			(layers "B.Cu" "B.Mask" "B.Paste")
			(net "PEX_S3_REF_CLK_BUFFER_EN_N")
		)
		(pad "2" smd circle
			(at -0.40005 0 90)
			(size 0 0)
			(layers "B.Cu" "B.Mask" "B.Paste")
			(net "GND")
		)
	)
	(footprint ""
		(layer "B.Cu")
		(at 109.543088 -351.796604)
		(property "Reference" "R6382"
			(at 0 0 0)
			(layer "B.SilkS")
			(hide yes)
			(effects
				(font
					(size 1.27 1.27)
				)
				(justify mirror)
			)
		)
		(property "Value" ""
			(at 0 0 0)
			(layer "B.Fab")
			(effects
				(font
					(size 1.27 1.27)
				)
				(justify mirror)
			)
		)
		(duplicate_pad_numbers_are_jumpers no)
		(fp_line
			(start -0.7874 -0.4064)
			(end -0.7874 0.4064)
			(stroke
				(width 0.1524)
				(type default)
			)
			(layer "B.SilkS")
		)
		(fp_line
			(start -0.7874 0.4064)
			(end 0.7874 0.4064)
			(stroke
				(width 0.1524)
				(type default)
			)
			(layer "B.SilkS")
		)
		(fp_line
			(start 0.7874 -0.4064)
			(end -0.7874 -0.4064)
			(stroke
				(width 0.1524)
				(type default)
			)
			(layer "B.SilkS")
		)
		(fp_line
			(start 0.7874 0.4064)
			(end 0.7874 -0.4064)
			(stroke
				(width 0.1524)
				(type default)
			)
			(layer "B.SilkS")
		)
		(fp_line
			(start -0.67945 -0.3048)
			(end -0.67945 0.3048)
			(stroke
				(width 0.1)
				(type default)
			)
			(layer "B.Fab")
		)
		(fp_line
			(start -0.67945 0.3048)
			(end -0.120396 0.3048)
			(stroke
				(width 0.1)
				(type default)
			)
			(layer "B.Fab")
		)
		(fp_line
			(start -0.12065 -0.3048)
			(end -0.67945 -0.3048)
			(stroke
				(width 0.1)
				(type default)
			)
			(layer "B.Fab")
		)
		(fp_line
			(start -0.12065 -0.2794)
			(end -0.12065 -0.3048)
			(stroke
				(width 0.1)
				(type default)
			)
			(layer "B.Fab")
		)
		(fp_line
			(start -0.120396 0.2794)
			(end 0.12065 0.2794)
			(stroke
				(width 0.1)
				(type default)
			)
			(layer "B.Fab")
		)
		(fp_line
			(start -0.120396 0.3048)
			(end -0.120396 0.2794)
			(stroke
				(width 0.1)
				(type default)
			)
			(layer "B.Fab")
		)
		(fp_line
			(start 0.12065 -0.305054)
			(end 0.12065 -0.2794)
			(stroke
				(width 0.1)
				(type default)
			)
			(layer "B.Fab")
		)
		(fp_line
			(start 0.12065 -0.2794)
			(end -0.12065 -0.2794)
			(stroke
				(width 0.1)
				(type default)
			)
			(layer "B.Fab")
		)
		(fp_line
			(start 0.12065 0.2794)
			(end 0.12065 0.3048)
			(stroke
				(width 0.1)
				(type default)
			)
			(layer "B.Fab")
		)
		(fp_line
			(start 0.12065 0.3048)
			(end 0.67945 0.3048)
			(stroke
				(width 0.1)
				(type default)
			)
			(layer "B.Fab")
		)
		(fp_line
			(start 0.67945 -0.305054)
			(end 0.12065 -0.305054)
			(stroke
				(width 0.1)
				(type default)
			)
			(layer "B.Fab")
		)
		(fp_line
			(start 0.67945 0.3048)
			(end 0.67945 -0.305054)
			(stroke
				(width 0.1)
				(type default)
			)
			(layer "B.Fab")
		)
		(pad "1" smd circle
			(at 0.40005 0 180)
			(size 0 0)
			(layers "B.Cu" "B.Mask" "B.Paste")
			(net "CLK_100M_DB800ZL_PEX3_S3_R_DN")
		)
		(pad "2" smd circle
			(at -0.40005 0 180)
			(size 0 0)
			(layers "B.Cu" "B.Mask" "B.Paste")
			(net "CLK_100M_DB800ZL_PEX3_S3_DN")
		)
	)
	(footprint ""
		(layer "B.Cu")
		(at 292.79977 -288.299906 90)
		(property "Reference" "C3269"
			(at 0 0 90)
			(layer "B.SilkS")
			(hide yes)
			(effects
				(font
					(size 1.27 1.27)
				)
				(justify mirror)
			)
		)
		(property "Value" ""
			(at 0 0 90)
			(layer "B.Fab")
			(effects
				(font
					(size 1.27 1.27)
				)
				(justify mirror)
			)
		)
		(duplicate_pad_numbers_are_jumpers no)
		(fp_line
			(start 0.299974 -0.150114)
			(end -0.299974 -0.150114)
			(stroke
				(width 0.1)
				(type default)
			)
			(layer "B.Fab")
		)
		(fp_line
			(start -0.299974 -0.150114)
			(end -0.299974 0.150114)
			(stroke
				(width 0.1)
				(type default)
			)
			(layer "B.Fab")
		)
		(fp_line
			(start 0.299974 0.150114)
			(end 0.299974 -0.150114)
			(stroke
				(width 0.1)
				(type default)
			)
			(layer "B.Fab")
		)
		(fp_line
			(start -0.299974 0.150114)
			(end 0.299974 0.150114)
			(stroke
				(width 0.1)
				(type default)
			)
			(layer "B.Fab")
		)
		(pad "1" smd rect
			(at 0.2667 0 270)
			(size 0.3048 0.381)
			(layers "B.Cu" "B.Mask" "B.Paste")
			(net "P1V25_PEX2")
		)
		(pad "2" smd rect
			(at -0.2667 0 270)
			(size 0.3048 0.381)
			(layers "B.Cu" "B.Mask" "B.Paste")
			(net "GND")
		)
	)
	(footprint ""
		(layer "B.Cu")
		(at 179.07508 -286.399732 90)
		(property "Reference" "C3138"
			(at 0 0 90)
			(layer "B.SilkS")
			(hide yes)
			(effects
				(font
					(size 1.27 1.27)
				)
				(justify mirror)
			)
		)
		(property "Value" ""
			(at 0 0 90)
			(layer "B.Fab")
			(effects
				(font
					(size 1.27 1.27)
				)
				(justify mirror)
			)
		)
		(duplicate_pad_numbers_are_jumpers no)
		(fp_line
			(start 0.299974 -0.150114)
			(end -0.299974 -0.150114)
			(stroke
				(width 0.1)
				(type default)
			)
			(layer "B.Fab")
		)
		(fp_line
			(start -0.299974 -0.150114)
			(end -0.299974 0.150114)
			(stroke
				(width 0.1)
				(type default)
			)
			(layer "B.Fab")
		)
		(fp_line
			(start 0.299974 0.150114)
			(end 0.299974 -0.150114)
			(stroke
				(width 0.1)
				(type default)
			)
			(layer "B.Fab")
		)
		(fp_line
			(start -0.299974 0.150114)
			(end 0.299974 0.150114)
			(stroke
				(width 0.1)
				(type default)
			)
			(layer "B.Fab")
		)
		(pad "1" smd rect
			(at 0.2667 0 270)
			(size 0.3048 0.381)
			(layers "B.Cu" "B.Mask" "B.Paste")
			(net "P1V25_SERDES_VDDPLL_PEX1")
		)
		(pad "2" smd rect
			(at -0.2667 0 270)
			(size 0.3048 0.381)
			(layers "B.Cu" "B.Mask" "B.Paste")
			(net "GND")
		)
	)
	(footprint ""
		(layer "B.Cu")
		(at 109.02315 -338.164424 180)
		(property "Reference" "C2701"
			(at 0 0 0)
			(layer "B.SilkS")
			(hide yes)
			(effects
				(font
					(size 1.27 1.27)
				)
				(justify mirror)
			)
		)
		(property "Value" ""
			(at 0 0 0)
			(layer "B.Fab")
			(effects
				(font
					(size 1.27 1.27)
				)
				(justify mirror)
			)
		)
		(duplicate_pad_numbers_are_jumpers no)
		(fp_line
			(start 1.524 0.762)
			(end 1.524 -0.762)
			(stroke
				(width 0.1524)
				(type default)
			)
			(layer "B.SilkS")
		)
		(fp_line
			(start 1.524 -0.762)
			(end -1.524 -0.762)
			(stroke
				(width 0.1524)
				(type default)
			)
			(layer "B.SilkS")
		)
		(fp_line
			(start -1.524 0.762)
			(end 1.524 0.762)
			(stroke
				(width 0.1524)
				(type default)
			)
			(layer "B.SilkS")
		)
		(fp_line
			(start -1.524 -0.762)
			(end -1.524 0.762)
			(stroke
				(width 0.1524)
				(type default)
			)
			(layer "B.SilkS")
		)
		(fp_line
			(start 1.1049 0.724916)
			(end -1.1049 0.724916)
			(stroke
				(width 0.1)
				(type default)
			)
			(layer "B.Fab")
		)
		(fp_line
			(start 1.1049 -0.724916)
			(end 1.1049 0.724916)
			(stroke
				(width 0.1)
				(type default)
			)
			(layer "B.Fab")
		)
		(fp_line
			(start -1.1049 0.724916)
			(end -1.1049 -0.724916)
			(stroke
				(width 0.1)
				(type default)
			)
			(layer "B.Fab")
		)
		(fp_line
			(start -1.1049 -0.724916)
			(end 1.1049 -0.724916)
			(stroke
				(width 0.1)
				(type default)
			)
			(layer "B.Fab")
		)
		(pad "1" smd rect
			(at 0.889 0 180)
			(size 1.016 1.27)
			(layers "B.Cu" "B.Mask" "B.Paste")
			(net "P3V3_CLK_BUFFER_9ZXL0451E_VZX3P3A")
		)
		(pad "2" smd rect
			(at -0.889 0 180)
			(size 1.016 1.27)
			(layers "B.Cu" "B.Mask" "B.Paste")
			(net "GND")
		)
	)
	(footprint ""
		(layer "B.Cu")
		(at 163.920424 -302.028606)
		(property "Reference" "C3163"
			(at 0 0 0)
			(layer "B.SilkS")
			(hide yes)
			(effects
				(font
					(size 1.27 1.27)
				)
				(justify mirror)
			)
		)
		(property "Value" ""
			(at 0 0 0)
			(layer "B.Fab")
			(effects
				(font
					(size 1.27 1.27)
				)
				(justify mirror)
			)
		)
		(duplicate_pad_numbers_are_jumpers no)
		(fp_line
			(start -1.2954 -0.5842)
			(end -1.2954 0.5842)
			(stroke
				(width 0.1524)
				(type default)
			)
			(layer "B.SilkS")
		)
		(fp_line
			(start -1.2954 0.5842)
			(end 1.2954 0.5842)
			(stroke
				(width 0.1524)
				(type default)
			)
			(layer "B.SilkS")
		)
		(fp_line
			(start 1.2954 -0.5842)
			(end -1.2954 -0.5842)
			(stroke
				(width 0.1524)
				(type default)
			)
			(layer "B.SilkS")
		)
		(fp_line
			(start 1.2954 0.5842)
			(end 1.2954 -0.5842)
			(stroke
				(width 0.1524)
				(type default)
			)
			(layer "B.SilkS")
		)
		(fp_line
			(start -1.1938 -0.4064)
			(end -1.1938 0.4064)
			(stroke
				(width 0.1)
				(type default)
			)
			(layer "B.Fab")
		)
		(fp_line
			(start -1.1938 0.4064)
			(end -0.8636 0.4064)
			(stroke
				(width 0.1)
				(type default)
			)
			(layer "B.Fab")
		)
		(fp_line
			(start -0.8636 -0.4572)
			(end -0.8636 -0.4064)
			(stroke
				(width 0.1)
				(type default)
			)
			(layer "B.Fab")
		)
		(fp_line
			(start -0.8636 -0.4064)
			(end -1.1938 -0.4064)
			(stroke
				(width 0.1)
				(type default)
			)
			(layer "B.Fab")
		)
		(fp_line
			(start -0.8636 0.4064)
			(end -0.8636 0.4572)
			(stroke
				(width 0.1)
				(type default)
			)
			(layer "B.Fab")
		)
		(fp_line
			(start -0.8636 0.4572)
			(end 0.8636 0.4572)
			(stroke
				(width 0.1)
				(type default)
			)
			(layer "B.Fab")
		)
		(fp_line
			(start 0.8636 -0.4572)
			(end -0.8636 -0.4572)
			(stroke
				(width 0.1)
				(type default)
			)
			(layer "B.Fab")
		)
		(fp_line
			(start 0.8636 -0.4064)
			(end 0.8636 -0.4572)
			(stroke
				(width 0.1)
				(type default)
			)
			(layer "B.Fab")
		)
		(fp_line
			(start 0.8636 0.4064)
			(end 1.1938 0.4064)
			(stroke
				(width 0.1)
				(type default)
			)
			(layer "B.Fab")
		)
		(fp_line
			(start 0.8636 0.4572)
			(end 0.8636 0.4064)
			(stroke
				(width 0.1)
				(type default)
			)
			(layer "B.Fab")
		)
		(fp_line
			(start 1.1938 -0.4064)
			(end 0.8636 -0.4064)
			(stroke
				(width 0.1)
				(type default)
			)
			(layer "B.Fab")
		)
		(fp_line
			(start 1.1938 0.4064)
			(end 1.1938 -0.4064)
			(stroke
				(width 0.1)
				(type default)
			)
			(layer "B.Fab")
		)
		(pad "1" smd rect
			(at 0.7366 0 270)
			(size 0.7112 0.8128)
			(layers "B.Cu" "B.Mask" "B.Paste")
			(net "P1V8_VDDA_PEX1")
		)
		(pad "2" smd rect
			(at -0.7366 0 270)
			(size 0.7112 0.8128)
			(layers "B.Cu" "B.Mask" "B.Paste")
			(net "GND")
		)
	)
	(footprint ""
		(layer "B.Cu")
		(at 61.101224 -305.399948 -90)
		(property "Reference" "C2978"
			(at 0 0 90)
			(layer "B.SilkS")
			(hide yes)
			(effects
				(font
					(size 1.27 1.27)
				)
				(justify mirror)
			)
		)
		(property "Value" ""
			(at 0 0 90)
			(layer "B.Fab")
			(effects
				(font
					(size 1.27 1.27)
				)
				(justify mirror)
			)
		)
		(duplicate_pad_numbers_are_jumpers no)
		(fp_line
			(start -0.299974 0.150114)
			(end 0.299974 0.150114)
			(stroke
				(width 0.1)
				(type default)
			)
			(layer "B.Fab")
		)
		(fp_line
			(start 0.299974 0.150114)
			(end 0.299974 -0.150114)
			(stroke
				(width 0.1)
				(type default)
			)
			(layer "B.Fab")
		)
		(fp_line
			(start -0.299974 -0.150114)
			(end -0.299974 0.150114)
			(stroke
				(width 0.1)
				(type default)
			)
			(layer "B.Fab")
		)
		(fp_line
			(start 0.299974 -0.150114)
			(end -0.299974 -0.150114)
			(stroke
				(width 0.1)
				(type default)
			)
			(layer "B.Fab")
		)
		(pad "1" smd rect
			(at 0.2667 0 90)
			(size 0.3048 0.381)
			(layers "B.Cu" "B.Mask" "B.Paste")
			(net "P1V25_SERDES_VDDPLL_PEX0")
		)
		(pad "2" smd rect
			(at -0.2667 0 90)
			(size 0.3048 0.381)
			(layers "B.Cu" "B.Mask" "B.Paste")
			(net "GND")
		)
	)
	(footprint ""
		(layer "B.Cu")
		(at 278.554942 -296.37482)
		(property "Reference" "C3376"
			(at 0 0 0)
			(layer "B.SilkS")
			(hide yes)
			(effects
				(font
					(size 1.27 1.27)
				)
				(justify mirror)
			)
		)
		(property "Value" ""
			(at 0 0 0)
			(layer "B.Fab")
			(effects
				(font
					(size 1.27 1.27)
				)
				(justify mirror)
			)
		)
		(duplicate_pad_numbers_are_jumpers no)
		(fp_line
			(start -0.299974 -0.150114)
			(end -0.299974 0.150114)
			(stroke
				(width 0.1)
				(type default)
			)
			(layer "B.Fab")
		)
		(fp_line
			(start -0.299974 0.150114)
			(end 0.299974 0.150114)
			(stroke
				(width 0.1)
				(type default)
			)
			(layer "B.Fab")
		)
		(fp_line
			(start 0.299974 -0.150114)
			(end -0.299974 -0.150114)
			(stroke
				(width 0.1)
				(type default)
			)
			(layer "B.Fab")
		)
		(fp_line
			(start 0.299974 0.150114)
			(end 0.299974 -0.150114)
			(stroke
				(width 0.1)
				(type default)
			)
			(layer "B.Fab")
		)
		(pad "1" smd rect
			(at 0.2667 0 180)
			(size 0.3048 0.381)
			(layers "B.Cu" "B.Mask" "B.Paste")
			(net "PCEPLL2_VDDA18_PEX2")
		)
		(pad "2" smd rect
			(at -0.2667 0 180)
			(size 0.3048 0.381)
			(layers "B.Cu" "B.Mask" "B.Paste")
			(net "GND")
		)
	)
	(footprint ""
		(layer "B.Cu")
		(at 383.667 -235.585 -90)
		(property "Reference" "R908"
			(at 0 0 90)
			(layer "B.SilkS")
			(hide yes)
			(effects
				(font
					(size 1.27 1.27)
				)
				(justify mirror)
			)
		)
		(property "Value" ""
			(at 0 0 90)
			(layer "B.Fab")
			(effects
				(font
					(size 1.27 1.27)
				)
				(justify mirror)
			)
		)
		(duplicate_pad_numbers_are_jumpers no)
		(fp_line
			(start -0.7874 0.4064)
			(end 0.7874 0.4064)
			(stroke
				(width 0.1524)
				(type default)
			)
			(layer "B.SilkS")
		)
		(fp_line
			(start 0.7874 0.4064)
			(end 0.7874 -0.4064)
			(stroke
				(width 0.1524)
				(type default)
			)
			(layer "B.SilkS")
		)
		(fp_line
			(start -0.7874 -0.4064)
			(end -0.7874 0.4064)
			(stroke
				(width 0.1524)
				(type default)
			)
			(layer "B.SilkS")
		)
		(fp_line
			(start 0.7874 -0.4064)
			(end -0.7874 -0.4064)
			(stroke
				(width 0.1524)
				(type default)
			)
			(layer "B.SilkS")
		)
		(fp_line
			(start -0.67945 0.3048)
			(end -0.120396 0.3048)
			(stroke
				(width 0.1)
				(type default)
			)
			(layer "B.Fab")
		)
		(fp_line
			(start -0.120396 0.3048)
			(end -0.120396 0.2794)
			(stroke
				(width 0.1)
				(type default)
			)
			(layer "B.Fab")
		)
		(fp_line
			(start 0.12065 0.3048)
			(end 0.67945 0.3048)
			(stroke
				(width 0.1)
				(type default)
			)
			(layer "B.Fab")
		)
		(fp_line
			(start 0.67945 0.3048)
			(end 0.67945 -0.305054)
			(stroke
				(width 0.1)
				(type default)
			)
			(layer "B.Fab")
		)
		(fp_line
			(start -0.120396 0.2794)
			(end 0.12065 0.2794)
			(stroke
				(width 0.1)
				(type default)
			)
			(layer "B.Fab")
		)
		(fp_line
			(start 0.12065 0.2794)
			(end 0.12065 0.3048)
			(stroke
				(width 0.1)
				(type default)
			)
			(layer "B.Fab")
		)
		(fp_line
			(start -0.12065 -0.2794)
			(end -0.12065 -0.3048)
			(stroke
				(width 0.1)
				(type default)
			)
			(layer "B.Fab")
		)
		(fp_line
			(start 0.12065 -0.2794)
			(end -0.12065 -0.2794)
			(stroke
				(width 0.1)
				(type default)
			)
			(layer "B.Fab")
		)
		(fp_line
			(start -0.67945 -0.3048)
			(end -0.67945 0.3048)
			(stroke
				(width 0.1)
				(type default)
			)
			(layer "B.Fab")
		)
		(fp_line
			(start -0.12065 -0.3048)
			(end -0.67945 -0.3048)
			(stroke
				(width 0.1)
				(type default)
			)
			(layer "B.Fab")
		)
		(fp_line
			(start 0.12065 -0.305054)
			(end 0.12065 -0.2794)
			(stroke
				(width 0.1)
				(type default)
			)
			(layer "B.Fab")
		)
		(fp_line
			(start 0.67945 -0.305054)
			(end 0.12065 -0.305054)
			(stroke
				(width 0.1)
				(type default)
			)
			(layer "B.Fab")
		)
		(pad "1" smd circle
			(at 0.40005 0 90)
			(size 0 0)
			(layers "B.Cu" "B.Mask" "B.Paste")
			(net "FT4232_SDB_REF")
		)
		(pad "2" smd circle
			(at -0.40005 0 90)
			(size 0 0)
			(layers "B.Cu" "B.Mask" "B.Paste")
			(net "GND")
		)
	)
	(footprint ""
		(layer "B.Cu")
		(at 292.32479 -286.399732 90)
		(property "Reference" "C3303"
			(at 0 0 90)
			(layer "B.SilkS")
			(hide yes)
			(effects
				(font
					(size 1.27 1.27)
				)
				(justify mirror)
			)
		)
		(property "Value" ""
			(at 0 0 90)
			(layer "B.Fab")
			(effects
				(font
					(size 1.27 1.27)
				)
				(justify mirror)
			)
		)
		(duplicate_pad_numbers_are_jumpers no)
		(fp_line
			(start 0.299974 -0.150114)
			(end -0.299974 -0.150114)
			(stroke
				(width 0.1)
				(type default)
			)
			(layer "B.Fab")
		)
		(fp_line
			(start -0.299974 -0.150114)
			(end -0.299974 0.150114)
			(stroke
				(width 0.1)
				(type default)
			)
			(layer "B.Fab")
		)
		(fp_line
			(start 0.299974 0.150114)
			(end 0.299974 -0.150114)
			(stroke
				(width 0.1)
				(type default)
			)
			(layer "B.Fab")
		)
		(fp_line
			(start -0.299974 0.150114)
			(end 0.299974 0.150114)
			(stroke
				(width 0.1)
				(type default)
			)
			(layer "B.Fab")
		)
		(pad "1" smd rect
			(at 0.2667 0 270)
			(size 0.3048 0.381)
			(layers "B.Cu" "B.Mask" "B.Paste")
			(net "P1V25_SERDES_VDDPLL_PEX2")
		)
		(pad "2" smd rect
			(at -0.2667 0 270)
			(size 0.3048 0.381)
			(layers "B.Cu" "B.Mask" "B.Paste")
			(net "GND")
		)
	)
	(footprint ""
		(layer "B.Cu")
		(at 252.0188 -354.1268 180)
		(property "Reference" "R6647"
			(at 0 0 0)
			(layer "B.SilkS")
			(hide yes)
			(effects
				(font
					(size 1.27 1.27)
				)
				(justify mirror)
			)
		)
		(property "Value" ""
			(at 0 0 0)
			(layer "B.Fab")
			(effects
				(font
					(size 1.27 1.27)
				)
				(justify mirror)
			)
		)
		(duplicate_pad_numbers_are_jumpers no)
		(fp_line
			(start 0.7874 0.4064)
			(end 0.7874 -0.4064)
			(stroke
				(width 0.1524)
				(type default)
			)
			(layer "B.SilkS")
		)
		(fp_line
			(start 0.7874 -0.4064)
			(end -0.7874 -0.4064)
			(stroke
				(width 0.1524)
				(type default)
			)
			(layer "B.SilkS")
		)
		(fp_line
			(start -0.7874 0.4064)
			(end 0.7874 0.4064)
			(stroke
				(width 0.1524)
				(type default)
			)
			(layer "B.SilkS")
		)
		(fp_line
			(start -0.7874 -0.4064)
			(end -0.7874 0.4064)
			(stroke
				(width 0.1524)
				(type default)
			)
			(layer "B.SilkS")
		)
		(fp_line
			(start 0.67945 0.3048)
			(end 0.67945 -0.305054)
			(stroke
				(width 0.1)
				(type default)
			)
			(layer "B.Fab")
		)
		(fp_line
			(start 0.67945 -0.305054)
			(end 0.12065 -0.305054)
			(stroke
				(width 0.1)
				(type default)
			)
			(layer "B.Fab")
		)
		(fp_line
			(start 0.12065 0.3048)
			(end 0.67945 0.3048)
			(stroke
				(width 0.1)
				(type default)
			)
			(layer "B.Fab")
		)
		(fp_line
			(start 0.12065 0.2794)
			(end 0.12065 0.3048)
			(stroke
				(width 0.1)
				(type default)
			)
			(layer "B.Fab")
		)
		(fp_line
			(start 0.12065 -0.2794)
			(end -0.12065 -0.2794)
			(stroke
				(width 0.1)
				(type default)
			)
			(layer "B.Fab")
		)
		(fp_line
			(start 0.12065 -0.305054)
			(end 0.12065 -0.2794)
			(stroke
				(width 0.1)
				(type default)
			)
			(layer "B.Fab")
		)
		(fp_line
			(start -0.120396 0.3048)
			(end -0.120396 0.2794)
			(stroke
				(width 0.1)
				(type default)
			)
			(layer "B.Fab")
		)
		(fp_line
			(start -0.120396 0.2794)
			(end 0.12065 0.2794)
			(stroke
				(width 0.1)
				(type default)
			)
			(layer "B.Fab")
		)
		(fp_line
			(start -0.12065 -0.2794)
			(end -0.12065 -0.3048)
			(stroke
				(width 0.1)
				(type default)
			)
			(layer "B.Fab")
		)
		(fp_line
			(start -0.12065 -0.3048)
			(end -0.67945 -0.3048)
			(stroke
				(width 0.1)
				(type default)
			)
			(layer "B.Fab")
		)
		(fp_line
			(start -0.67945 0.3048)
			(end -0.120396 0.3048)
			(stroke
				(width 0.1)
				(type default)
			)
			(layer "B.Fab")
		)
		(fp_line
			(start -0.67945 -0.3048)
			(end -0.67945 0.3048)
			(stroke
				(width 0.1)
				(type default)
			)
			(layer "B.Fab")
		)
		(pad "1" smd circle
			(at 0.40005 0)
			(size 0 0)
			(layers "B.Cu" "B.Mask" "B.Paste")
			(net "HSC_CSOUT")
		)
		(pad "2" smd circle
			(at -0.40005 0)
			(size 0 0)
			(layers "B.Cu" "B.Mask" "B.Paste")
			(net "HSC_D_OC_BUF_R_N")
		)
	)
	(footprint ""
		(layer "B.Cu")
		(at 342.093804 -218.787218 -90)
		(property "Reference" "C2066"
			(at 0 0 90)
			(layer "B.SilkS")
			(hide yes)
			(effects
				(font
					(size 1.27 1.27)
				)
				(justify mirror)
			)
		)
		(property "Value" ""
			(at 0 0 90)
			(layer "B.Fab")
			(effects
				(font
					(size 1.27 1.27)
				)
				(justify mirror)
			)
		)
		(duplicate_pad_numbers_are_jumpers no)
		(fp_line
			(start -0.69215 0.2921)
			(end 0.69215 0.2921)
			(stroke
				(width 0.1524)
				(type default)
			)
			(layer "B.SilkS")
		)
		(fp_line
			(start 0.69215 0.2921)
			(end 0.69215 -0.2921)
			(stroke
				(width 0.1524)
				(type default)
			)
			(layer "B.SilkS")
		)
		(fp_line
			(start -0.69215 -0.2921)
			(end -0.69215 0.2921)
			(stroke
				(width 0.1524)
				(type default)
			)
			(layer "B.SilkS")
		)
		(fp_line
			(start 0.69215 -0.2921)
			(end -0.69215 -0.2921)
			(stroke
				(width 0.1524)
				(type default)
			)
			(layer "B.SilkS")
		)
		(fp_line
			(start -0.51435 0.2794)
			(end 0.51435 0.2794)
			(stroke
				(width 0.1)
				(type default)
			)
			(layer "B.Fab")
		)
		(fp_line
			(start 0.51435 0.2794)
			(end 0.51435 -0.2794)
			(stroke
				(width 0.1)
				(type default)
			)
			(layer "B.Fab")
		)
		(fp_line
			(start -0.51435 -0.2794)
			(end -0.51435 0.2794)
			(stroke
				(width 0.1)
				(type default)
			)
			(layer "B.Fab")
		)
		(fp_line
			(start 0.51435 -0.2794)
			(end -0.51435 -0.2794)
			(stroke
				(width 0.1)
				(type default)
			)
			(layer "B.Fab")
		)
		(pad "1" smd circle
			(at 0.40005 0 90)
			(size 0 0)
			(layers "B.Cu" "B.Mask" "B.Paste")
			(net "P3V3_VCC_FPGA_CORE")
		)
		(pad "2" smd circle
			(at -0.40005 0 90)
			(size 0 0)
			(layers "B.Cu" "B.Mask" "B.Paste")
			(net "GND")
		)
		(zone
			(layer "B.Cu")
			(hatch none 0.5)
			(connect_pads
				(clearance 0)
			)
			(min_thickness 0.25)
			(keepout
				(tracks not_allowed)
				(vias allowed)
				(pads allowed)
				(copperpour not_allowed)
				(footprints allowed)
			)
			(placement
				(enabled no)
				(sheetname "")
			)
			(fill
				(thermal_gap 0.5)
				(thermal_bridge_width 0.5)
				(island_removal_mode 0)
			)
			(polygon
				(pts
					(xy 342.006174 -218.596718) (xy 341.948008 -218.688158) (xy 341.948008 -218.887548) (xy 342.006174 -218.977718)
					(xy 342.181434 -218.977718) (xy 342.239854 -218.887548) (xy 342.239854 -218.688158) (xy 342.181688 -218.596718)
				)
			)
		)
	)
	(footprint ""
		(layer "B.Cu")
		(at 350.153986 -260.39572 -90)
		(property "Reference" "PR139"
			(at 0 0 90)
			(layer "B.SilkS")
			(hide yes)
			(effects
				(font
					(size 1.27 1.27)
				)
				(justify mirror)
			)
		)
		(property "Value" ""
			(at 0 0 90)
			(layer "B.Fab")
			(effects
				(font
					(size 1.27 1.27)
				)
				(justify mirror)
			)
		)
		(duplicate_pad_numbers_are_jumpers no)
		(fp_line
			(start -0.7874 0.4064)
			(end 0.7874 0.4064)
			(stroke
				(width 0.1524)
				(type default)
			)
			(layer "B.SilkS")
		)
		(fp_line
			(start 0.7874 0.4064)
			(end 0.7874 -0.4064)
			(stroke
				(width 0.1524)
				(type default)
			)
			(layer "B.SilkS")
		)
		(fp_line
			(start -0.7874 -0.4064)
			(end -0.7874 0.4064)
			(stroke
				(width 0.1524)
				(type default)
			)
			(layer "B.SilkS")
		)
		(fp_line
			(start 0.7874 -0.4064)
			(end -0.7874 -0.4064)
			(stroke
				(width 0.1524)
				(type default)
			)
			(layer "B.SilkS")
		)
		(fp_line
			(start -0.67945 0.3048)
			(end -0.120396 0.3048)
			(stroke
				(width 0.1)
				(type default)
			)
			(layer "B.Fab")
		)
		(fp_line
			(start -0.120396 0.3048)
			(end -0.120396 0.2794)
			(stroke
				(width 0.1)
				(type default)
			)
			(layer "B.Fab")
		)
		(fp_line
			(start 0.12065 0.3048)
			(end 0.67945 0.3048)
			(stroke
				(width 0.1)
				(type default)
			)
			(layer "B.Fab")
		)
		(fp_line
			(start 0.67945 0.3048)
			(end 0.67945 -0.305054)
			(stroke
				(width 0.1)
				(type default)
			)
			(layer "B.Fab")
		)
		(fp_line
			(start -0.120396 0.2794)
			(end 0.12065 0.2794)
			(stroke
				(width 0.1)
				(type default)
			)
			(layer "B.Fab")
		)
		(fp_line
			(start 0.12065 0.2794)
			(end 0.12065 0.3048)
			(stroke
				(width 0.1)
				(type default)
			)
			(layer "B.Fab")
		)
		(fp_line
			(start -0.12065 -0.2794)
			(end -0.12065 -0.3048)
			(stroke
				(width 0.1)
				(type default)
			)
			(layer "B.Fab")
		)
		(fp_line
			(start 0.12065 -0.2794)
			(end -0.12065 -0.2794)
			(stroke
				(width 0.1)
				(type default)
			)
			(layer "B.Fab")
		)
		(fp_line
			(start -0.67945 -0.3048)
			(end -0.67945 0.3048)
			(stroke
				(width 0.1)
				(type default)
			)
			(layer "B.Fab")
		)
		(fp_line
			(start -0.12065 -0.3048)
			(end -0.67945 -0.3048)
			(stroke
				(width 0.1)
				(type default)
			)
			(layer "B.Fab")
		)
		(fp_line
			(start 0.12065 -0.305054)
			(end 0.12065 -0.2794)
			(stroke
				(width 0.1)
				(type default)
			)
			(layer "B.Fab")
		)
		(fp_line
			(start 0.67945 -0.305054)
			(end 0.12065 -0.305054)
			(stroke
				(width 0.1)
				(type default)
			)
			(layer "B.Fab")
		)
		(pad "1" smd circle
			(at 0.40005 0 90)
			(size 0 0)
			(layers "B.Cu" "B.Mask" "B.Paste")
			(net "P0V8_PEX3_TSEN_R")
		)
		(pad "2" smd circle
			(at -0.40005 0 90)
			(size 0 0)
			(layers "B.Cu" "B.Mask" "B.Paste")
			(net "P0V8_PEX3_TSEN")
		)
	)
	(footprint ""
		(layer "B.Cu")
		(at 236.234732 -290.501832)
		(property "Reference" "PC997"
			(at 0 0 0)
			(layer "B.SilkS")
			(hide yes)
			(effects
				(font
					(size 1.27 1.27)
				)
				(justify mirror)
			)
		)
		(property "Value" ""
			(at 0 0 0)
			(layer "B.Fab")
			(effects
				(font
					(size 1.27 1.27)
				)
				(justify mirror)
			)
		)
		(duplicate_pad_numbers_are_jumpers no)
		(fp_line
			(start -1.524 -0.762)
			(end -1.524 0.762)
			(stroke
				(width 0.1524)
				(type default)
			)
			(layer "B.SilkS")
		)
		(fp_line
			(start -1.524 0.762)
			(end 1.524 0.762)
			(stroke
				(width 0.1524)
				(type default)
			)
			(layer "B.SilkS")
		)
		(fp_line
			(start 1.524 -0.762)
			(end -1.524 -0.762)
			(stroke
				(width 0.1524)
				(type default)
			)
			(layer "B.SilkS")
		)
		(fp_line
			(start 1.524 0.762)
			(end 1.524 -0.762)
			(stroke
				(width 0.1524)
				(type default)
			)
			(layer "B.SilkS")
		)
		(fp_line
			(start -1.1049 -0.724916)
			(end 1.1049 -0.724916)
			(stroke
				(width 0.1)
				(type default)
			)
			(layer "B.Fab")
		)
		(fp_line
			(start -1.1049 0.724916)
			(end -1.1049 -0.724916)
			(stroke
				(width 0.1)
				(type default)
			)
			(layer "B.Fab")
		)
		(fp_line
			(start 1.1049 -0.724916)
			(end 1.1049 0.724916)
			(stroke
				(width 0.1)
				(type default)
			)
			(layer "B.Fab")
		)
		(fp_line
			(start 1.1049 0.724916)
			(end -1.1049 0.724916)
			(stroke
				(width 0.1)
				(type default)
			)
			(layer "B.Fab")
		)
		(pad "1" smd rect
			(at 0.889 0)
			(size 1.016 1.27)
			(layers "B.Cu" "B.Mask" "B.Paste")
			(net "P1V25_PEX2_R")
		)
		(pad "2" smd rect
			(at -0.889 0)
			(size 1.016 1.27)
			(layers "B.Cu" "B.Mask" "B.Paste")
			(net "GND")
		)
	)
	(footprint ""
		(layer "B.Cu")
		(at 345.29395 -217.187018 -90)
		(property "Reference" "C2045"
			(at 0 0 90)
			(layer "B.SilkS")
			(hide yes)
			(effects
				(font
					(size 1.27 1.27)
				)
				(justify mirror)
			)
		)
		(property "Value" ""
			(at 0 0 90)
			(layer "B.Fab")
			(effects
				(font
					(size 1.27 1.27)
				)
				(justify mirror)
			)
		)
		(duplicate_pad_numbers_are_jumpers no)
		(fp_line
			(start -0.69215 0.2921)
			(end 0.69215 0.2921)
			(stroke
				(width 0.1524)
				(type default)
			)
			(layer "B.SilkS")
		)
		(fp_line
			(start 0.69215 0.2921)
			(end 0.69215 -0.2921)
			(stroke
				(width 0.1524)
				(type default)
			)
			(layer "B.SilkS")
		)
		(fp_line
			(start -0.69215 -0.2921)
			(end -0.69215 0.2921)
			(stroke
				(width 0.1524)
				(type default)
			)
			(layer "B.SilkS")
		)
		(fp_line
			(start 0.69215 -0.2921)
			(end -0.69215 -0.2921)
			(stroke
				(width 0.1524)
				(type default)
			)
			(layer "B.SilkS")
		)
		(fp_line
			(start -0.51435 0.2794)
			(end 0.51435 0.2794)
			(stroke
				(width 0.1)
				(type default)
			)
			(layer "B.Fab")
		)
		(fp_line
			(start 0.51435 0.2794)
			(end 0.51435 -0.2794)
			(stroke
				(width 0.1)
				(type default)
			)
			(layer "B.Fab")
		)
		(fp_line
			(start -0.51435 -0.2794)
			(end -0.51435 0.2794)
			(stroke
				(width 0.1)
				(type default)
			)
			(layer "B.Fab")
		)
		(fp_line
			(start 0.51435 -0.2794)
			(end -0.51435 -0.2794)
			(stroke
				(width 0.1)
				(type default)
			)
			(layer "B.Fab")
		)
		(pad "1" smd circle
			(at 0.40005 0 90)
			(size 0 0)
			(layers "B.Cu" "B.Mask" "B.Paste")
			(net "P3V3_FPGA_VCCIO1")
		)
		(pad "2" smd circle
			(at -0.40005 0 90)
			(size 0 0)
			(layers "B.Cu" "B.Mask" "B.Paste")
			(net "GND")
		)
		(zone
			(layer "B.Cu")
			(hatch none 0.5)
			(connect_pads
				(clearance 0)
			)
			(min_thickness 0.25)
			(keepout
				(tracks not_allowed)
				(vias allowed)
				(pads allowed)
				(copperpour not_allowed)
				(footprints allowed)
			)
			(placement
				(enabled no)
				(sheetname "")
			)
			(fill
				(thermal_gap 0.5)
				(thermal_bridge_width 0.5)
				(island_removal_mode 0)
			)
			(polygon
				(pts
					(xy 345.20632 -216.996518) (xy 345.148154 -217.087958) (xy 345.148154 -217.287348) (xy 345.20632 -217.377518)
					(xy 345.38158 -217.377518) (xy 345.44 -217.287348) (xy 345.44 -217.087958) (xy 345.381834 -216.996518)
				)
			)
		)
	)
	(footprint ""
		(layer "B.Cu")
		(at 100.90023 -324.178422 180)
		(property "Reference" "PJ19"
			(at 0 0 0)
			(layer "B.SilkS")
			(hide yes)
			(effects
				(font
					(size 1.27 1.27)
				)
				(justify mirror)
			)
		)
		(property "Value" ""
			(at 0 0 0)
			(layer "B.Fab")
			(effects
				(font
					(size 1.27 1.27)
				)
				(justify mirror)
			)
		)
		(duplicate_pad_numbers_are_jumpers no)
		(pad "1" smd circle
			(at 0.40005 0 270)
			(size 0 0)
			(layers "B.Cu" "B.Mask" "B.Paste")
			(net "VSENSE_P0V8_PEX0_SKT_VRTN")
		)
		(pad "2" smd rect
			(at -0.40005 0 180)
			(size 0.4572 0.508)
			(layers "B.Cu" "B.Mask" "B.Paste")
			(net "SH_P0V8_PEX0_RGND0")
		)
		(zone
			(layer "B.Cu")
			(hatch none 0.5)
			(connect_pads
				(clearance 0)
			)
			(min_thickness 0.25)
			(keepout
				(tracks allowed)
				(vias not_allowed)
				(pads allowed)
				(copperpour not_allowed)
				(footprints allowed)
			)
			(placement
				(enabled no)
				(sheetname "")
			)
			(fill
				(thermal_gap 0.5)
				(thermal_bridge_width 0.5)
				(island_removal_mode 0)
			)
			(polygon
				(pts
					(xy 101.58603 -324.483222) (xy 101.58603 -323.873622) (xy 100.21443 -323.873622) (xy 100.21443 -324.483222)
				)
			)
		)
	)
	(footprint ""
		(layer "B.Cu")
		(at 425.841922 -98.021648 180)
		(property "Reference" "R370"
			(at 0 0 0)
			(layer "B.SilkS")
			(hide yes)
			(effects
				(font
					(size 1.27 1.27)
				)
				(justify mirror)
			)
		)
		(property "Value" ""
			(at 0 0 0)
			(layer "B.Fab")
			(effects
				(font
					(size 1.27 1.27)
				)
				(justify mirror)
			)
		)
		(duplicate_pad_numbers_are_jumpers no)
		(fp_line
			(start 0.7874 0.4064)
			(end 0.7874 -0.4064)
			(stroke
				(width 0.1524)
				(type default)
			)
			(layer "B.SilkS")
		)
		(fp_line
			(start 0.7874 -0.4064)
			(end -0.7874 -0.4064)
			(stroke
				(width 0.1524)
				(type default)
			)
			(layer "B.SilkS")
		)
		(fp_line
			(start -0.7874 0.4064)
			(end 0.7874 0.4064)
			(stroke
				(width 0.1524)
				(type default)
			)
			(layer "B.SilkS")
		)
		(fp_line
			(start -0.7874 -0.4064)
			(end -0.7874 0.4064)
			(stroke
				(width 0.1524)
				(type default)
			)
			(layer "B.SilkS")
		)
		(fp_line
			(start 0.67945 0.3048)
			(end 0.67945 -0.305054)
			(stroke
				(width 0.1)
				(type default)
			)
			(layer "B.Fab")
		)
		(fp_line
			(start 0.67945 -0.305054)
			(end 0.12065 -0.305054)
			(stroke
				(width 0.1)
				(type default)
			)
			(layer "B.Fab")
		)
		(fp_line
			(start 0.12065 0.3048)
			(end 0.67945 0.3048)
			(stroke
				(width 0.1)
				(type default)
			)
			(layer "B.Fab")
		)
		(fp_line
			(start 0.12065 0.2794)
			(end 0.12065 0.3048)
			(stroke
				(width 0.1)
				(type default)
			)
			(layer "B.Fab")
		)
		(fp_line
			(start 0.12065 -0.2794)
			(end -0.12065 -0.2794)
			(stroke
				(width 0.1)
				(type default)
			)
			(layer "B.Fab")
		)
		(fp_line
			(start 0.12065 -0.305054)
			(end 0.12065 -0.2794)
			(stroke
				(width 0.1)
				(type default)
			)
			(layer "B.Fab")
		)
		(fp_line
			(start -0.120396 0.3048)
			(end -0.120396 0.2794)
			(stroke
				(width 0.1)
				(type default)
			)
			(layer "B.Fab")
		)
		(fp_line
			(start -0.120396 0.2794)
			(end 0.12065 0.2794)
			(stroke
				(width 0.1)
				(type default)
			)
			(layer "B.Fab")
		)
		(fp_line
			(start -0.12065 -0.2794)
			(end -0.12065 -0.3048)
			(stroke
				(width 0.1)
				(type default)
			)
			(layer "B.Fab")
		)
		(fp_line
			(start -0.12065 -0.3048)
			(end -0.67945 -0.3048)
			(stroke
				(width 0.1)
				(type default)
			)
			(layer "B.Fab")
		)
		(fp_line
			(start -0.67945 0.3048)
			(end -0.120396 0.3048)
			(stroke
				(width 0.1)
				(type default)
			)
			(layer "B.Fab")
		)
		(fp_line
			(start -0.67945 -0.3048)
			(end -0.67945 0.3048)
			(stroke
				(width 0.1)
				(type default)
			)
			(layer "B.Fab")
		)
		(pad "1" smd circle
			(at 0.40005 0)
			(size 0 0)
			(layers "B.Cu" "B.Mask" "B.Paste")
			(net "NIC7_DATA_OUT")
		)
		(pad "2" smd circle
			(at -0.40005 0)
			(size 0 0)
			(layers "B.Cu" "B.Mask" "B.Paste")
			(net "GND")
		)
	)
	(footprint ""
		(layer "B.Cu")
		(at 101.589586 -344.563954 90)
		(property "Reference" "R6370"
			(at 0 0 90)
			(layer "B.SilkS")
			(hide yes)
			(effects
				(font
					(size 1.27 1.27)
				)
				(justify mirror)
			)
		)
		(property "Value" ""
			(at 0 0 90)
			(layer "B.Fab")
			(effects
				(font
					(size 1.27 1.27)
				)
				(justify mirror)
			)
		)
		(duplicate_pad_numbers_are_jumpers no)
		(fp_line
			(start 0.7874 -0.4064)
			(end -0.7874 -0.4064)
			(stroke
				(width 0.1524)
				(type default)
			)
			(layer "B.SilkS")
		)
		(fp_line
			(start -0.7874 -0.4064)
			(end -0.7874 0.4064)
			(stroke
				(width 0.1524)
				(type default)
			)
			(layer "B.SilkS")
		)
		(fp_line
			(start 0.7874 0.4064)
			(end 0.7874 -0.4064)
			(stroke
				(width 0.1524)
				(type default)
			)
			(layer "B.SilkS")
		)
		(fp_line
			(start -0.7874 0.4064)
			(end 0.7874 0.4064)
			(stroke
				(width 0.1524)
				(type default)
			)
			(layer "B.SilkS")
		)
		(fp_line
			(start 0.67945 -0.305054)
			(end 0.12065 -0.305054)
			(stroke
				(width 0.1)
				(type default)
			)
			(layer "B.Fab")
		)
		(fp_line
			(start 0.12065 -0.305054)
			(end 0.12065 -0.2794)
			(stroke
				(width 0.1)
				(type default)
			)
			(layer "B.Fab")
		)
		(fp_line
			(start -0.12065 -0.3048)
			(end -0.67945 -0.3048)
			(stroke
				(width 0.1)
				(type default)
			)
			(layer "B.Fab")
		)
		(fp_line
			(start -0.67945 -0.3048)
			(end -0.67945 0.3048)
			(stroke
				(width 0.1)
				(type default)
			)
			(layer "B.Fab")
		)
		(fp_line
			(start 0.12065 -0.2794)
			(end -0.12065 -0.2794)
			(stroke
				(width 0.1)
				(type default)
			)
			(layer "B.Fab")
		)
		(fp_line
			(start -0.12065 -0.2794)
			(end -0.12065 -0.3048)
			(stroke
				(width 0.1)
				(type default)
			)
			(layer "B.Fab")
		)
		(fp_line
			(start 0.12065 0.2794)
			(end 0.12065 0.3048)
			(stroke
				(width 0.1)
				(type default)
			)
			(layer "B.Fab")
		)
		(fp_line
			(start -0.120396 0.2794)
			(end 0.12065 0.2794)
			(stroke
				(width 0.1)
				(type default)
			)
			(layer "B.Fab")
		)
		(fp_line
			(start 0.67945 0.3048)
			(end 0.67945 -0.305054)
			(stroke
				(width 0.1)
				(type default)
			)
			(layer "B.Fab")
		)
		(fp_line
			(start 0.12065 0.3048)
			(end 0.67945 0.3048)
			(stroke
				(width 0.1)
				(type default)
			)
			(layer "B.Fab")
		)
		(fp_line
			(start -0.120396 0.3048)
			(end -0.120396 0.2794)
			(stroke
				(width 0.1)
				(type default)
			)
			(layer "B.Fab")
		)
		(fp_line
			(start -0.67945 0.3048)
			(end -0.120396 0.3048)
			(stroke
				(width 0.1)
				(type default)
			)
			(layer "B.Fab")
		)
		(pad "1" smd circle
			(at 0.40005 0 270)
			(size 0 0)
			(layers "B.Cu" "B.Mask" "B.Paste")
			(net "SMB_9ZXL0451E_S3_ADDR0")
		)
		(pad "2" smd circle
			(at -0.40005 0 270)
			(size 0 0)
			(layers "B.Cu" "B.Mask" "B.Paste")
			(net "P3V3")
		)
	)
	(footprint ""
		(layer "B.Cu")
		(at 222.999046 -143.094202 -90)
		(property "Reference" "R4187"
			(at 0 0 90)
			(layer "B.SilkS")
			(hide yes)
			(effects
				(font
					(size 1.27 1.27)
				)
				(justify mirror)
			)
		)
		(property "Value" ""
			(at 0 0 90)
			(layer "B.Fab")
			(effects
				(font
					(size 1.27 1.27)
				)
				(justify mirror)
			)
		)
		(duplicate_pad_numbers_are_jumpers no)
		(fp_line
			(start -1.2954 0.5842)
			(end 1.2954 0.5842)
			(stroke
				(width 0.1524)
				(type default)
			)
			(layer "B.SilkS")
		)
		(fp_line
			(start 1.2954 0.5842)
			(end 1.2954 -0.5842)
			(stroke
				(width 0.1524)
				(type default)
			)
			(layer "B.SilkS")
		)
		(fp_line
			(start -1.2954 -0.5842)
			(end -1.2954 0.5842)
			(stroke
				(width 0.1524)
				(type default)
			)
			(layer "B.SilkS")
		)
		(fp_line
			(start 1.2954 -0.5842)
			(end -1.2954 -0.5842)
			(stroke
				(width 0.1524)
				(type default)
			)
			(layer "B.SilkS")
		)
		(fp_line
			(start -0.8636 0.4572)
			(end 0.8636 0.4572)
			(stroke
				(width 0.1)
				(type default)
			)
			(layer "B.Fab")
		)
		(fp_line
			(start 0.8636 0.4572)
			(end 0.8636 0.4318)
			(stroke
				(width 0.1)
				(type default)
			)
			(layer "B.Fab")
		)
		(fp_line
			(start 0.8636 0.4318)
			(end 0.8636 0.4064)
			(stroke
				(width 0.1)
				(type default)
			)
			(layer "B.Fab")
		)
		(fp_line
			(start -1.1938 0.4064)
			(end -0.8636 0.4064)
			(stroke
				(width 0.1)
				(type default)
			)
			(layer "B.Fab")
		)
		(fp_line
			(start -0.8636 0.4064)
			(end -0.8636 0.4572)
			(stroke
				(width 0.1)
				(type default)
			)
			(layer "B.Fab")
		)
		(fp_line
			(start 0.8636 0.4064)
			(end 1.1938 0.4064)
			(stroke
				(width 0.1)
				(type default)
			)
			(layer "B.Fab")
		)
		(fp_line
			(start 1.1938 0.4064)
			(end 1.1938 -0.406654)
			(stroke
				(width 0.1)
				(type default)
			)
			(layer "B.Fab")
		)
		(fp_line
			(start -1.1938 -0.406654)
			(end -1.1938 0.4064)
			(stroke
				(width 0.1)
				(type default)
			)
			(layer "B.Fab")
		)
		(fp_line
			(start -0.8636 -0.406654)
			(end -1.1938 -0.406654)
			(stroke
				(width 0.1)
				(type default)
			)
			(layer "B.Fab")
		)
		(fp_line
			(start 0.8636 -0.406654)
			(end 0.8636 -0.4572)
			(stroke
				(width 0.1)
				(type default)
			)
			(layer "B.Fab")
		)
		(fp_line
			(start 1.1938 -0.406654)
			(end 0.8636 -0.406654)
			(stroke
				(width 0.1)
				(type default)
			)
			(layer "B.Fab")
		)
		(fp_line
			(start -0.8636 -0.4572)
			(end -0.8636 -0.406654)
			(stroke
				(width 0.1)
				(type default)
			)
			(layer "B.Fab")
		)
		(fp_line
			(start 0.8636 -0.4572)
			(end -0.8636 -0.4572)
			(stroke
				(width 0.1)
				(type default)
			)
			(layer "B.Fab")
		)
		(pad "1" smd rect
			(at 0.7366 0 180)
			(size 0.7112 0.8128)
			(layers "B.Cu" "B.Mask" "B.Paste")
			(net "P3V3_CLK_GEN_VDDXTAL_CK440_PEX")
		)
		(pad "2" smd rect
			(at -0.7366 0 180)
			(size 0.7112 0.8128)
			(layers "B.Cu" "B.Mask" "B.Paste")
			(net "P3V3_CLK_GEN_VDDA25M_CK440_PEX")
		)
	)
	(footprint ""
		(layer "B.Cu")
		(at 177.423826 -192.270634 180)
		(property "Reference" "R1032"
			(at 0 0 0)
			(layer "B.SilkS")
			(hide yes)
			(effects
				(font
					(size 1.27 1.27)
				)
				(justify mirror)
			)
		)
		(property "Value" ""
			(at 0 0 0)
			(layer "B.Fab")
			(effects
				(font
					(size 1.27 1.27)
				)
				(justify mirror)
			)
		)
		(duplicate_pad_numbers_are_jumpers no)
		(fp_line
			(start 0.7874 0.4064)
			(end 0.7874 -0.4064)
			(stroke
				(width 0.1524)
				(type default)
			)
			(layer "B.SilkS")
		)
		(fp_line
			(start 0.7874 -0.4064)
			(end -0.7874 -0.4064)
			(stroke
				(width 0.1524)
				(type default)
			)
			(layer "B.SilkS")
		)
		(fp_line
			(start -0.7874 0.4064)
			(end 0.7874 0.4064)
			(stroke
				(width 0.1524)
				(type default)
			)
			(layer "B.SilkS")
		)
		(fp_line
			(start -0.7874 -0.4064)
			(end -0.7874 0.4064)
			(stroke
				(width 0.1524)
				(type default)
			)
			(layer "B.SilkS")
		)
		(fp_line
			(start 0.67945 0.3048)
			(end 0.67945 -0.305054)
			(stroke
				(width 0.1)
				(type default)
			)
			(layer "B.Fab")
		)
		(fp_line
			(start 0.67945 -0.305054)
			(end 0.12065 -0.305054)
			(stroke
				(width 0.1)
				(type default)
			)
			(layer "B.Fab")
		)
		(fp_line
			(start 0.12065 0.3048)
			(end 0.67945 0.3048)
			(stroke
				(width 0.1)
				(type default)
			)
			(layer "B.Fab")
		)
		(fp_line
			(start 0.12065 0.2794)
			(end 0.12065 0.3048)
			(stroke
				(width 0.1)
				(type default)
			)
			(layer "B.Fab")
		)
		(fp_line
			(start 0.12065 -0.2794)
			(end -0.12065 -0.2794)
			(stroke
				(width 0.1)
				(type default)
			)
			(layer "B.Fab")
		)
		(fp_line
			(start 0.12065 -0.305054)
			(end 0.12065 -0.2794)
			(stroke
				(width 0.1)
				(type default)
			)
			(layer "B.Fab")
		)
		(fp_line
			(start -0.120396 0.3048)
			(end -0.120396 0.2794)
			(stroke
				(width 0.1)
				(type default)
			)
			(layer "B.Fab")
		)
		(fp_line
			(start -0.120396 0.2794)
			(end 0.12065 0.2794)
			(stroke
				(width 0.1)
				(type default)
			)
			(layer "B.Fab")
		)
		(fp_line
			(start -0.12065 -0.2794)
			(end -0.12065 -0.3048)
			(stroke
				(width 0.1)
				(type default)
			)
			(layer "B.Fab")
		)
		(fp_line
			(start -0.12065 -0.3048)
			(end -0.67945 -0.3048)
			(stroke
				(width 0.1)
				(type default)
			)
			(layer "B.Fab")
		)
		(fp_line
			(start -0.67945 0.3048)
			(end -0.120396 0.3048)
			(stroke
				(width 0.1)
				(type default)
			)
			(layer "B.Fab")
		)
		(fp_line
			(start -0.67945 -0.3048)
			(end -0.67945 0.3048)
			(stroke
				(width 0.1)
				(type default)
			)
			(layer "B.Fab")
		)
		(pad "1" smd circle
			(at 0.40005 0)
			(size 0 0)
			(layers "B.Cu" "B.Mask" "B.Paste")
			(net "SPI_BIC1_MISO_LS01_DIR4")
		)
		(pad "2" smd circle
			(at -0.40005 0)
			(size 0 0)
			(layers "B.Cu" "B.Mask" "B.Paste")
			(net "P1V8_PEX")
		)
	)
	(footprint ""
		(layer "B.Cu")
		(at 180.975 -305.399948 -90)
		(property "Reference" "C3128"
			(at 0 0 90)
			(layer "B.SilkS")
			(hide yes)
			(effects
				(font
					(size 1.27 1.27)
				)
				(justify mirror)
			)
		)
		(property "Value" ""
			(at 0 0 90)
			(layer "B.Fab")
			(effects
				(font
					(size 1.27 1.27)
				)
				(justify mirror)
			)
		)
		(duplicate_pad_numbers_are_jumpers no)
		(fp_line
			(start -0.299974 0.150114)
			(end 0.299974 0.150114)
			(stroke
				(width 0.1)
				(type default)
			)
			(layer "B.Fab")
		)
		(fp_line
			(start 0.299974 0.150114)
			(end 0.299974 -0.150114)
			(stroke
				(width 0.1)
				(type default)
			)
			(layer "B.Fab")
		)
		(fp_line
			(start -0.299974 -0.150114)
			(end -0.299974 0.150114)
			(stroke
				(width 0.1)
				(type default)
			)
			(layer "B.Fab")
		)
		(fp_line
			(start 0.299974 -0.150114)
			(end -0.299974 -0.150114)
			(stroke
				(width 0.1)
				(type default)
			)
			(layer "B.Fab")
		)
		(pad "1" smd rect
			(at 0.2667 0 90)
			(size 0.3048 0.381)
			(layers "B.Cu" "B.Mask" "B.Paste")
			(net "P1V25_SERDES_VDDPLL_PEX1")
		)
		(pad "2" smd rect
			(at -0.2667 0 90)
			(size 0.3048 0.381)
			(layers "B.Cu" "B.Mask" "B.Paste")
			(net "GND")
		)
	)
	(footprint ""
		(layer "B.Cu")
		(at 327.414128 -219.80144 90)
		(property "Reference" "R4903"
			(at 0 0 90)
			(layer "B.SilkS")
			(hide yes)
			(effects
				(font
					(size 1.27 1.27)
				)
				(justify mirror)
			)
		)
		(property "Value" ""
			(at 0 0 90)
			(layer "B.Fab")
			(effects
				(font
					(size 1.27 1.27)
				)
				(justify mirror)
			)
		)
		(duplicate_pad_numbers_are_jumpers no)
		(fp_line
			(start 0.7874 -0.4064)
			(end -0.7874 -0.4064)
			(stroke
				(width 0.1524)
				(type default)
			)
			(layer "B.SilkS")
		)
		(fp_line
			(start -0.7874 -0.4064)
			(end -0.7874 0.4064)
			(stroke
				(width 0.1524)
				(type default)
			)
			(layer "B.SilkS")
		)
		(fp_line
			(start 0.7874 0.4064)
			(end 0.7874 -0.4064)
			(stroke
				(width 0.1524)
				(type default)
			)
			(layer "B.SilkS")
		)
		(fp_line
			(start -0.7874 0.4064)
			(end 0.7874 0.4064)
			(stroke
				(width 0.1524)
				(type default)
			)
			(layer "B.SilkS")
		)
		(fp_line
			(start 0.67945 -0.305054)
			(end 0.12065 -0.305054)
			(stroke
				(width 0.1)
				(type default)
			)
			(layer "B.Fab")
		)
		(fp_line
			(start 0.12065 -0.305054)
			(end 0.12065 -0.2794)
			(stroke
				(width 0.1)
				(type default)
			)
			(layer "B.Fab")
		)
		(fp_line
			(start -0.12065 -0.3048)
			(end -0.67945 -0.3048)
			(stroke
				(width 0.1)
				(type default)
			)
			(layer "B.Fab")
		)
		(fp_line
			(start -0.67945 -0.3048)
			(end -0.67945 0.3048)
			(stroke
				(width 0.1)
				(type default)
			)
			(layer "B.Fab")
		)
		(fp_line
			(start 0.12065 -0.2794)
			(end -0.12065 -0.2794)
			(stroke
				(width 0.1)
				(type default)
			)
			(layer "B.Fab")
		)
		(fp_line
			(start -0.12065 -0.2794)
			(end -0.12065 -0.3048)
			(stroke
				(width 0.1)
				(type default)
			)
			(layer "B.Fab")
		)
		(fp_line
			(start 0.12065 0.2794)
			(end 0.12065 0.3048)
			(stroke
				(width 0.1)
				(type default)
			)
			(layer "B.Fab")
		)
		(fp_line
			(start -0.120396 0.2794)
			(end 0.12065 0.2794)
			(stroke
				(width 0.1)
				(type default)
			)
			(layer "B.Fab")
		)
		(fp_line
			(start 0.67945 0.3048)
			(end 0.67945 -0.305054)
			(stroke
				(width 0.1)
				(type default)
			)
			(layer "B.Fab")
		)
		(fp_line
			(start 0.12065 0.3048)
			(end 0.67945 0.3048)
			(stroke
				(width 0.1)
				(type default)
			)
			(layer "B.Fab")
		)
		(fp_line
			(start -0.120396 0.3048)
			(end -0.120396 0.2794)
			(stroke
				(width 0.1)
				(type default)
			)
			(layer "B.Fab")
		)
		(fp_line
			(start -0.67945 0.3048)
			(end -0.120396 0.3048)
			(stroke
				(width 0.1)
				(type default)
			)
			(layer "B.Fab")
		)
		(pad "1" smd circle
			(at 0.40005 0 270)
			(size 0 0)
			(layers "B.Cu" "B.Mask" "B.Paste")
			(net "JTAG_FPGA_TMS")
		)
		(pad "2" smd circle
			(at -0.40005 0 270)
			(size 0 0)
			(layers "B.Cu" "B.Mask" "B.Paste")
			(net "P3V3_AUX")
		)
	)
	(footprint ""
		(layer "B.Cu")
		(at 113.693956 -137.56132 90)
		(property "Reference" "PC35"
			(at 0 0 90)
			(layer "B.SilkS")
			(hide yes)
			(effects
				(font
					(size 1.27 1.27)
				)
				(justify mirror)
			)
		)
		(property "Value" ""
			(at 0 0 90)
			(layer "B.Fab")
			(effects
				(font
					(size 1.27 1.27)
				)
				(justify mirror)
			)
		)
		(duplicate_pad_numbers_are_jumpers no)
		(fp_line
			(start 1.524 -0.762)
			(end -1.524 -0.762)
			(stroke
				(width 0.1524)
				(type default)
			)
			(layer "B.SilkS")
		)
		(fp_line
			(start -1.524 -0.762)
			(end -1.524 0.762)
			(stroke
				(width 0.1524)
				(type default)
			)
			(layer "B.SilkS")
		)
		(fp_line
			(start 1.524 0.762)
			(end 1.524 -0.762)
			(stroke
				(width 0.1524)
				(type default)
			)
			(layer "B.SilkS")
		)
		(fp_line
			(start -1.524 0.762)
			(end 1.524 0.762)
			(stroke
				(width 0.1524)
				(type default)
			)
			(layer "B.SilkS")
		)
		(fp_line
			(start 1.1049 -0.724916)
			(end 1.1049 0.724916)
			(stroke
				(width 0.1)
				(type default)
			)
			(layer "B.Fab")
		)
		(fp_line
			(start -1.1049 -0.724916)
			(end 1.1049 -0.724916)
			(stroke
				(width 0.1)
				(type default)
			)
			(layer "B.Fab")
		)
		(fp_line
			(start 1.1049 0.724916)
			(end -1.1049 0.724916)
			(stroke
				(width 0.1)
				(type default)
			)
			(layer "B.Fab")
		)
		(fp_line
			(start -1.1049 0.724916)
			(end -1.1049 -0.724916)
			(stroke
				(width 0.1)
				(type default)
			)
			(layer "B.Fab")
		)
		(pad "1" smd rect
			(at 0.889 0 90)
			(size 1.016 1.27)
			(layers "B.Cu" "B.Mask" "B.Paste")
			(net "P3V3_AUX")
		)
		(pad "2" smd rect
			(at -0.889 0 90)
			(size 1.016 1.27)
			(layers "B.Cu" "B.Mask" "B.Paste")
			(net "GND")
		)
	)
	(footprint ""
		(layer "B.Cu")
		(at 63.375286 -109.481366 180)
		(property "Reference" "R83"
			(at 0 0 0)
			(layer "B.SilkS")
			(hide yes)
			(effects
				(font
					(size 1.27 1.27)
				)
				(justify mirror)
			)
		)
		(property "Value" ""
			(at 0 0 0)
			(layer "B.Fab")
			(effects
				(font
					(size 1.27 1.27)
				)
				(justify mirror)
			)
		)
		(duplicate_pad_numbers_are_jumpers no)
		(fp_line
			(start 0.7874 0.4064)
			(end 0.7874 -0.4064)
			(stroke
				(width 0.1524)
				(type default)
			)
			(layer "B.SilkS")
		)
		(fp_line
			(start 0.7874 -0.4064)
			(end -0.7874 -0.4064)
			(stroke
				(width 0.1524)
				(type default)
			)
			(layer "B.SilkS")
		)
		(fp_line
			(start -0.7874 0.4064)
			(end 0.7874 0.4064)
			(stroke
				(width 0.1524)
				(type default)
			)
			(layer "B.SilkS")
		)
		(fp_line
			(start -0.7874 -0.4064)
			(end -0.7874 0.4064)
			(stroke
				(width 0.1524)
				(type default)
			)
			(layer "B.SilkS")
		)
		(fp_line
			(start 0.67945 0.3048)
			(end 0.67945 -0.305054)
			(stroke
				(width 0.1)
				(type default)
			)
			(layer "B.Fab")
		)
		(fp_line
			(start 0.67945 -0.305054)
			(end 0.12065 -0.305054)
			(stroke
				(width 0.1)
				(type default)
			)
			(layer "B.Fab")
		)
		(fp_line
			(start 0.12065 0.3048)
			(end 0.67945 0.3048)
			(stroke
				(width 0.1)
				(type default)
			)
			(layer "B.Fab")
		)
		(fp_line
			(start 0.12065 0.2794)
			(end 0.12065 0.3048)
			(stroke
				(width 0.1)
				(type default)
			)
			(layer "B.Fab")
		)
		(fp_line
			(start 0.12065 -0.2794)
			(end -0.12065 -0.2794)
			(stroke
				(width 0.1)
				(type default)
			)
			(layer "B.Fab")
		)
		(fp_line
			(start 0.12065 -0.305054)
			(end 0.12065 -0.2794)
			(stroke
				(width 0.1)
				(type default)
			)
			(layer "B.Fab")
		)
		(fp_line
			(start -0.120396 0.3048)
			(end -0.120396 0.2794)
			(stroke
				(width 0.1)
				(type default)
			)
			(layer "B.Fab")
		)
		(fp_line
			(start -0.120396 0.2794)
			(end 0.12065 0.2794)
			(stroke
				(width 0.1)
				(type default)
			)
			(layer "B.Fab")
		)
		(fp_line
			(start -0.12065 -0.2794)
			(end -0.12065 -0.3048)
			(stroke
				(width 0.1)
				(type default)
			)
			(layer "B.Fab")
		)
		(fp_line
			(start -0.12065 -0.3048)
			(end -0.67945 -0.3048)
			(stroke
				(width 0.1)
				(type default)
			)
			(layer "B.Fab")
		)
		(fp_line
			(start -0.67945 0.3048)
			(end -0.120396 0.3048)
			(stroke
				(width 0.1)
				(type default)
			)
			(layer "B.Fab")
		)
		(fp_line
			(start -0.67945 -0.3048)
			(end -0.67945 0.3048)
			(stroke
				(width 0.1)
				(type default)
			)
			(layer "B.Fab")
		)
		(pad "1" smd circle
			(at 0.40005 0)
			(size 0 0)
			(layers "B.Cu" "B.Mask" "B.Paste")
			(net "NIC1_BIF1_N")
		)
		(pad "2" smd circle
			(at -0.40005 0)
			(size 0 0)
			(layers "B.Cu" "B.Mask" "B.Paste")
			(net "GND")
		)
	)
	(footprint ""
		(layer "B.Cu")
		(at 353.66833 -219.158566 180)
		(property "Reference" "C2044"
			(at 0 0 0)
			(layer "B.SilkS")
			(hide yes)
			(effects
				(font
					(size 1.27 1.27)
				)
				(justify mirror)
			)
		)
		(property "Value" ""
			(at 0 0 0)
			(layer "B.Fab")
			(effects
				(font
					(size 1.27 1.27)
				)
				(justify mirror)
			)
		)
		(duplicate_pad_numbers_are_jumpers no)
		(fp_line
			(start 0.69215 0.2921)
			(end 0.69215 -0.2921)
			(stroke
				(width 0.1524)
				(type default)
			)
			(layer "B.SilkS")
		)
		(fp_line
			(start 0.69215 -0.2921)
			(end -0.69215 -0.2921)
			(stroke
				(width 0.1524)
				(type default)
			)
			(layer "B.SilkS")
		)
		(fp_line
			(start -0.69215 0.2921)
			(end 0.69215 0.2921)
			(stroke
				(width 0.1524)
				(type default)
			)
			(layer "B.SilkS")
		)
		(fp_line
			(start -0.69215 -0.2921)
			(end -0.69215 0.2921)
			(stroke
				(width 0.1524)
				(type default)
			)
			(layer "B.SilkS")
		)
		(fp_line
			(start 0.51435 0.2794)
			(end 0.51435 -0.2794)
			(stroke
				(width 0.1)
				(type default)
			)
			(layer "B.Fab")
		)
		(fp_line
			(start 0.51435 -0.2794)
			(end -0.51435 -0.2794)
			(stroke
				(width 0.1)
				(type default)
			)
			(layer "B.Fab")
		)
		(fp_line
			(start -0.51435 0.2794)
			(end 0.51435 0.2794)
			(stroke
				(width 0.1)
				(type default)
			)
			(layer "B.Fab")
		)
		(fp_line
			(start -0.51435 -0.2794)
			(end -0.51435 0.2794)
			(stroke
				(width 0.1)
				(type default)
			)
			(layer "B.Fab")
		)
		(pad "1" smd circle
			(at 0.40005 0)
			(size 0 0)
			(layers "B.Cu" "B.Mask" "B.Paste")
			(net "P3V3_FPGA_VCCIO1")
		)
		(pad "2" smd circle
			(at -0.40005 0)
			(size 0 0)
			(layers "B.Cu" "B.Mask" "B.Paste")
			(net "GND")
		)
		(zone
			(layer "B.Cu")
			(hatch none 0.5)
			(connect_pads
				(clearance 0)
			)
			(min_thickness 0.25)
			(keepout
				(tracks not_allowed)
				(vias allowed)
				(pads allowed)
				(copperpour not_allowed)
				(footprints allowed)
			)
			(placement
				(enabled no)
				(sheetname "")
			)
			(fill
				(thermal_gap 0.5)
				(thermal_bridge_width 0.5)
				(island_removal_mode 0)
			)
			(polygon
				(pts
					(xy 353.47783 -219.246196) (xy 353.56927 -219.304362) (xy 353.76866 -219.304362) (xy 353.85883 -219.246196)
					(xy 353.85883 -219.070936) (xy 353.76866 -219.012516) (xy 353.56927 -219.012516) (xy 353.47783 -219.070682)
				)
			)
		)
	)
	(footprint ""
		(layer "B.Cu")
		(at 130.893058 -228.981)
		(property "Reference" "R3466"
			(at 0 0 0)
			(layer "B.SilkS")
			(hide yes)
			(effects
				(font
					(size 1.27 1.27)
				)
				(justify mirror)
			)
		)
		(property "Value" ""
			(at 0 0 0)
			(layer "B.Fab")
			(effects
				(font
					(size 1.27 1.27)
				)
				(justify mirror)
			)
		)
		(duplicate_pad_numbers_are_jumpers no)
		(fp_line
			(start -0.7874 -0.4064)
			(end -0.7874 0.4064)
			(stroke
				(width 0.1524)
				(type default)
			)
			(layer "B.SilkS")
		)
		(fp_line
			(start -0.7874 0.4064)
			(end 0.7874 0.4064)
			(stroke
				(width 0.1524)
				(type default)
			)
			(layer "B.SilkS")
		)
		(fp_line
			(start 0.7874 -0.4064)
			(end -0.7874 -0.4064)
			(stroke
				(width 0.1524)
				(type default)
			)
			(layer "B.SilkS")
		)
		(fp_line
			(start 0.7874 0.4064)
			(end 0.7874 -0.4064)
			(stroke
				(width 0.1524)
				(type default)
			)
			(layer "B.SilkS")
		)
		(fp_line
			(start -0.67945 -0.3048)
			(end -0.67945 0.3048)
			(stroke
				(width 0.1)
				(type default)
			)
			(layer "B.Fab")
		)
		(fp_line
			(start -0.67945 0.3048)
			(end -0.120396 0.3048)
			(stroke
				(width 0.1)
				(type default)
			)
			(layer "B.Fab")
		)
		(fp_line
			(start -0.12065 -0.3048)
			(end -0.67945 -0.3048)
			(stroke
				(width 0.1)
				(type default)
			)
			(layer "B.Fab")
		)
		(fp_line
			(start -0.12065 -0.2794)
			(end -0.12065 -0.3048)
			(stroke
				(width 0.1)
				(type default)
			)
			(layer "B.Fab")
		)
		(fp_line
			(start -0.120396 0.2794)
			(end 0.12065 0.2794)
			(stroke
				(width 0.1)
				(type default)
			)
			(layer "B.Fab")
		)
		(fp_line
			(start -0.120396 0.3048)
			(end -0.120396 0.2794)
			(stroke
				(width 0.1)
				(type default)
			)
			(layer "B.Fab")
		)
		(fp_line
			(start 0.12065 -0.305054)
			(end 0.12065 -0.2794)
			(stroke
				(width 0.1)
				(type default)
			)
			(layer "B.Fab")
		)
		(fp_line
			(start 0.12065 -0.2794)
			(end -0.12065 -0.2794)
			(stroke
				(width 0.1)
				(type default)
			)
			(layer "B.Fab")
		)
		(fp_line
			(start 0.12065 0.2794)
			(end 0.12065 0.3048)
			(stroke
				(width 0.1)
				(type default)
			)
			(layer "B.Fab")
		)
		(fp_line
			(start 0.12065 0.3048)
			(end 0.67945 0.3048)
			(stroke
				(width 0.1)
				(type default)
			)
			(layer "B.Fab")
		)
		(fp_line
			(start 0.67945 -0.305054)
			(end 0.12065 -0.305054)
			(stroke
				(width 0.1)
				(type default)
			)
			(layer "B.Fab")
		)
		(fp_line
			(start 0.67945 0.3048)
			(end 0.67945 -0.305054)
			(stroke
				(width 0.1)
				(type default)
			)
			(layer "B.Fab")
		)
		(pad "1" smd circle
			(at 0.40005 0 180)
			(size 0 0)
			(layers "B.Cu" "B.Mask" "B.Paste")
			(net "P1V8_PEX")
		)
		(pad "2" smd circle
			(at -0.40005 0 180)
			(size 0 0)
			(layers "B.Cu" "B.Mask" "B.Paste")
			(net "SPI_PEX1_SDIO2_R1")
		)
	)
	(footprint ""
		(layer "B.Cu")
		(at 282.843986 -138.421618 180)
		(property "Reference" "R228"
			(at 0 0 0)
			(layer "B.SilkS")
			(hide yes)
			(effects
				(font
					(size 1.27 1.27)
				)
				(justify mirror)
			)
		)
		(property "Value" ""
			(at 0 0 0)
			(layer "B.Fab")
			(effects
				(font
					(size 1.27 1.27)
				)
				(justify mirror)
			)
		)
		(duplicate_pad_numbers_are_jumpers no)
		(fp_line
			(start 0.7874 0.4064)
			(end 0.7874 -0.4064)
			(stroke
				(width 0.1524)
				(type default)
			)
			(layer "B.SilkS")
		)
		(fp_line
			(start 0.7874 -0.4064)
			(end -0.7874 -0.4064)
			(stroke
				(width 0.1524)
				(type default)
			)
			(layer "B.SilkS")
		)
		(fp_line
			(start -0.7874 0.4064)
			(end 0.7874 0.4064)
			(stroke
				(width 0.1524)
				(type default)
			)
			(layer "B.SilkS")
		)
		(fp_line
			(start -0.7874 -0.4064)
			(end -0.7874 0.4064)
			(stroke
				(width 0.1524)
				(type default)
			)
			(layer "B.SilkS")
		)
		(fp_line
			(start 0.67945 0.3048)
			(end 0.67945 -0.305054)
			(stroke
				(width 0.1)
				(type default)
			)
			(layer "B.Fab")
		)
		(fp_line
			(start 0.67945 -0.305054)
			(end 0.12065 -0.305054)
			(stroke
				(width 0.1)
				(type default)
			)
			(layer "B.Fab")
		)
		(fp_line
			(start 0.12065 0.3048)
			(end 0.67945 0.3048)
			(stroke
				(width 0.1)
				(type default)
			)
			(layer "B.Fab")
		)
		(fp_line
			(start 0.12065 0.2794)
			(end 0.12065 0.3048)
			(stroke
				(width 0.1)
				(type default)
			)
			(layer "B.Fab")
		)
		(fp_line
			(start 0.12065 -0.2794)
			(end -0.12065 -0.2794)
			(stroke
				(width 0.1)
				(type default)
			)
			(layer "B.Fab")
		)
		(fp_line
			(start 0.12065 -0.305054)
			(end 0.12065 -0.2794)
			(stroke
				(width 0.1)
				(type default)
			)
			(layer "B.Fab")
		)
		(fp_line
			(start -0.120396 0.3048)
			(end -0.120396 0.2794)
			(stroke
				(width 0.1)
				(type default)
			)
			(layer "B.Fab")
		)
		(fp_line
			(start -0.120396 0.2794)
			(end 0.12065 0.2794)
			(stroke
				(width 0.1)
				(type default)
			)
			(layer "B.Fab")
		)
		(fp_line
			(start -0.12065 -0.2794)
			(end -0.12065 -0.3048)
			(stroke
				(width 0.1)
				(type default)
			)
			(layer "B.Fab")
		)
		(fp_line
			(start -0.12065 -0.3048)
			(end -0.67945 -0.3048)
			(stroke
				(width 0.1)
				(type default)
			)
			(layer "B.Fab")
		)
		(fp_line
			(start -0.67945 0.3048)
			(end -0.120396 0.3048)
			(stroke
				(width 0.1)
				(type default)
			)
			(layer "B.Fab")
		)
		(fp_line
			(start -0.67945 -0.3048)
			(end -0.67945 0.3048)
			(stroke
				(width 0.1)
				(type default)
			)
			(layer "B.Fab")
		)
		(pad "1" smd circle
			(at 0.40005 0)
			(size 0 0)
			(layers "B.Cu" "B.Mask" "B.Paste")
			(net "NIC4_AUX_PWR_EN")
		)
		(pad "2" smd circle
			(at -0.40005 0)
			(size 0 0)
			(layers "B.Cu" "B.Mask" "B.Paste")
			(net "GND")
		)
	)
	(footprint ""
		(layer "B.Cu")
		(at 210.228942 -259.311648 90)
		(property "Reference" "R6348"
			(at 0 0 90)
			(layer "B.SilkS")
			(hide yes)
			(effects
				(font
					(size 1.27 1.27)
				)
				(justify mirror)
			)
		)
		(property "Value" ""
			(at 0 0 90)
			(layer "B.Fab")
			(effects
				(font
					(size 1.27 1.27)
				)
				(justify mirror)
			)
		)
		(duplicate_pad_numbers_are_jumpers no)
		(fp_line
			(start 0.7874 -0.4064)
			(end -0.7874 -0.4064)
			(stroke
				(width 0.1524)
				(type default)
			)
			(layer "B.SilkS")
		)
		(fp_line
			(start -0.7874 -0.4064)
			(end -0.7874 0.4064)
			(stroke
				(width 0.1524)
				(type default)
			)
			(layer "B.SilkS")
		)
		(fp_line
			(start 0.7874 0.4064)
			(end 0.7874 -0.4064)
			(stroke
				(width 0.1524)
				(type default)
			)
			(layer "B.SilkS")
		)
		(fp_line
			(start -0.7874 0.4064)
			(end 0.7874 0.4064)
			(stroke
				(width 0.1524)
				(type default)
			)
			(layer "B.SilkS")
		)
		(fp_line
			(start 0.67945 -0.305054)
			(end 0.12065 -0.305054)
			(stroke
				(width 0.1)
				(type default)
			)
			(layer "B.Fab")
		)
		(fp_line
			(start 0.12065 -0.305054)
			(end 0.12065 -0.2794)
			(stroke
				(width 0.1)
				(type default)
			)
			(layer "B.Fab")
		)
		(fp_line
			(start -0.12065 -0.3048)
			(end -0.67945 -0.3048)
			(stroke
				(width 0.1)
				(type default)
			)
			(layer "B.Fab")
		)
		(fp_line
			(start -0.67945 -0.3048)
			(end -0.67945 0.3048)
			(stroke
				(width 0.1)
				(type default)
			)
			(layer "B.Fab")
		)
		(fp_line
			(start 0.12065 -0.2794)
			(end -0.12065 -0.2794)
			(stroke
				(width 0.1)
				(type default)
			)
			(layer "B.Fab")
		)
		(fp_line
			(start -0.12065 -0.2794)
			(end -0.12065 -0.3048)
			(stroke
				(width 0.1)
				(type default)
			)
			(layer "B.Fab")
		)
		(fp_line
			(start 0.12065 0.2794)
			(end 0.12065 0.3048)
			(stroke
				(width 0.1)
				(type default)
			)
			(layer "B.Fab")
		)
		(fp_line
			(start -0.120396 0.2794)
			(end 0.12065 0.2794)
			(stroke
				(width 0.1)
				(type default)
			)
			(layer "B.Fab")
		)
		(fp_line
			(start 0.67945 0.3048)
			(end 0.67945 -0.305054)
			(stroke
				(width 0.1)
				(type default)
			)
			(layer "B.Fab")
		)
		(fp_line
			(start 0.12065 0.3048)
			(end 0.67945 0.3048)
			(stroke
				(width 0.1)
				(type default)
			)
			(layer "B.Fab")
		)
		(fp_line
			(start -0.120396 0.3048)
			(end -0.120396 0.2794)
			(stroke
				(width 0.1)
				(type default)
			)
			(layer "B.Fab")
		)
		(fp_line
			(start -0.67945 0.3048)
			(end -0.120396 0.3048)
			(stroke
				(width 0.1)
				(type default)
			)
			(layer "B.Fab")
		)
		(pad "1" smd circle
			(at 0.40005 0 270)
			(size 0 0)
			(layers "B.Cu" "B.Mask" "B.Paste")
			(net "P1V8_PEX")
		)
		(pad "2" smd circle
			(at -0.40005 0 270)
			(size 0 0)
			(layers "B.Cu" "B.Mask" "B.Paste")
			(net "SMB_PEX3_MUX_SDA")
		)
	)
	(footprint ""
		(layer "B.Cu")
		(at 203.474828 -368.951764 -90)
		(property "Reference" "PC4"
			(at 0 0 90)
			(layer "B.SilkS")
			(hide yes)
			(effects
				(font
					(size 1.27 1.27)
				)
				(justify mirror)
			)
		)
		(property "Value" ""
			(at 0 0 90)
			(layer "B.Fab")
			(effects
				(font
					(size 1.27 1.27)
				)
				(justify mirror)
			)
		)
		(duplicate_pad_numbers_are_jumpers no)
		(fp_line
			(start -0.7874 0.4064)
			(end 0.7874 0.4064)
			(stroke
				(width 0.1524)
				(type default)
			)
			(layer "B.SilkS")
		)
		(fp_line
			(start 0.7874 0.4064)
			(end 0.7874 -0.4064)
			(stroke
				(width 0.1524)
				(type default)
			)
			(layer "B.SilkS")
		)
		(fp_line
			(start -0.7874 -0.4064)
			(end -0.7874 0.4064)
			(stroke
				(width 0.1524)
				(type default)
			)
			(layer "B.SilkS")
		)
		(fp_line
			(start 0.7874 -0.4064)
			(end -0.7874 -0.4064)
			(stroke
				(width 0.1524)
				(type default)
			)
			(layer "B.SilkS")
		)
		(fp_line
			(start -0.67945 0.3048)
			(end -0.120396 0.3048)
			(stroke
				(width 0.1)
				(type default)
			)
			(layer "B.Fab")
		)
		(fp_line
			(start -0.120396 0.3048)
			(end -0.120396 0.2794)
			(stroke
				(width 0.1)
				(type default)
			)
			(layer "B.Fab")
		)
		(fp_line
			(start 0.12065 0.3048)
			(end 0.67945 0.3048)
			(stroke
				(width 0.1)
				(type default)
			)
			(layer "B.Fab")
		)
		(fp_line
			(start 0.67945 0.3048)
			(end 0.67945 -0.305054)
			(stroke
				(width 0.1)
				(type default)
			)
			(layer "B.Fab")
		)
		(fp_line
			(start -0.120396 0.2794)
			(end 0.12065 0.2794)
			(stroke
				(width 0.1)
				(type default)
			)
			(layer "B.Fab")
		)
		(fp_line
			(start 0.12065 0.2794)
			(end 0.12065 0.3048)
			(stroke
				(width 0.1)
				(type default)
			)
			(layer "B.Fab")
		)
		(fp_line
			(start -0.12065 -0.2794)
			(end -0.12065 -0.3048)
			(stroke
				(width 0.1)
				(type default)
			)
			(layer "B.Fab")
		)
		(fp_line
			(start 0.12065 -0.2794)
			(end -0.12065 -0.2794)
			(stroke
				(width 0.1)
				(type default)
			)
			(layer "B.Fab")
		)
		(fp_line
			(start -0.67945 -0.3048)
			(end -0.67945 0.3048)
			(stroke
				(width 0.1)
				(type default)
			)
			(layer "B.Fab")
		)
		(fp_line
			(start -0.12065 -0.3048)
			(end -0.67945 -0.3048)
			(stroke
				(width 0.1)
				(type default)
			)
			(layer "B.Fab")
		)
		(fp_line
			(start 0.12065 -0.305054)
			(end 0.12065 -0.2794)
			(stroke
				(width 0.1)
				(type default)
			)
			(layer "B.Fab")
		)
		(fp_line
			(start 0.67945 -0.305054)
			(end 0.12065 -0.305054)
			(stroke
				(width 0.1)
				(type default)
			)
			(layer "B.Fab")
		)
		(pad "1" smd circle
			(at 0.40005 0 90)
			(size 0 0)
			(layers "B.Cu" "B.Mask" "B.Paste")
			(net "HSC_VDD_R")
		)
		(pad "2" smd circle
			(at -0.40005 0 90)
			(size 0 0)
			(layers "B.Cu" "B.Mask" "B.Paste")
			(net "AGND_HSC")
		)
	)
	(footprint ""
		(layer "B.Cu")
		(at 145.804382 -225.76663 180)
		(property "Reference" "R6166"
			(at 0 0 0)
			(layer "B.SilkS")
			(hide yes)
			(effects
				(font
					(size 1.27 1.27)
				)
				(justify mirror)
			)
		)
		(property "Value" ""
			(at 0 0 0)
			(layer "B.Fab")
			(effects
				(font
					(size 1.27 1.27)
				)
				(justify mirror)
			)
		)
		(duplicate_pad_numbers_are_jumpers no)
		(fp_line
			(start 0.7874 0.4064)
			(end 0.7874 -0.4064)
			(stroke
				(width 0.1524)
				(type default)
			)
			(layer "B.SilkS")
		)
		(fp_line
			(start 0.7874 -0.4064)
			(end -0.7874 -0.4064)
			(stroke
				(width 0.1524)
				(type default)
			)
			(layer "B.SilkS")
		)
		(fp_line
			(start -0.7874 0.4064)
			(end 0.7874 0.4064)
			(stroke
				(width 0.1524)
				(type default)
			)
			(layer "B.SilkS")
		)
		(fp_line
			(start -0.7874 -0.4064)
			(end -0.7874 0.4064)
			(stroke
				(width 0.1524)
				(type default)
			)
			(layer "B.SilkS")
		)
		(fp_line
			(start 0.67945 0.3048)
			(end 0.67945 -0.305054)
			(stroke
				(width 0.1)
				(type default)
			)
			(layer "B.Fab")
		)
		(fp_line
			(start 0.67945 -0.305054)
			(end 0.12065 -0.305054)
			(stroke
				(width 0.1)
				(type default)
			)
			(layer "B.Fab")
		)
		(fp_line
			(start 0.12065 0.3048)
			(end 0.67945 0.3048)
			(stroke
				(width 0.1)
				(type default)
			)
			(layer "B.Fab")
		)
		(fp_line
			(start 0.12065 0.2794)
			(end 0.12065 0.3048)
			(stroke
				(width 0.1)
				(type default)
			)
			(layer "B.Fab")
		)
		(fp_line
			(start 0.12065 -0.2794)
			(end -0.12065 -0.2794)
			(stroke
				(width 0.1)
				(type default)
			)
			(layer "B.Fab")
		)
		(fp_line
			(start 0.12065 -0.305054)
			(end 0.12065 -0.2794)
			(stroke
				(width 0.1)
				(type default)
			)
			(layer "B.Fab")
		)
		(fp_line
			(start -0.120396 0.3048)
			(end -0.120396 0.2794)
			(stroke
				(width 0.1)
				(type default)
			)
			(layer "B.Fab")
		)
		(fp_line
			(start -0.120396 0.2794)
			(end 0.12065 0.2794)
			(stroke
				(width 0.1)
				(type default)
			)
			(layer "B.Fab")
		)
		(fp_line
			(start -0.12065 -0.2794)
			(end -0.12065 -0.3048)
			(stroke
				(width 0.1)
				(type default)
			)
			(layer "B.Fab")
		)
		(fp_line
			(start -0.12065 -0.3048)
			(end -0.67945 -0.3048)
			(stroke
				(width 0.1)
				(type default)
			)
			(layer "B.Fab")
		)
		(fp_line
			(start -0.67945 0.3048)
			(end -0.120396 0.3048)
			(stroke
				(width 0.1)
				(type default)
			)
			(layer "B.Fab")
		)
		(fp_line
			(start -0.67945 -0.3048)
			(end -0.67945 0.3048)
			(stroke
				(width 0.1)
				(type default)
			)
			(layer "B.Fab")
		)
		(pad "1" smd circle
			(at 0.40005 0)
			(size 0 0)
			(layers "B.Cu" "B.Mask" "B.Paste")
			(net "SPI_PEX1_RST_R_N")
		)
		(pad "2" smd circle
			(at -0.40005 0)
			(size 0 0)
			(layers "B.Cu" "B.Mask" "B.Paste")
			(net "P1V8_PEX")
		)
	)
	(footprint ""
		(layer "B.Cu")
		(at 241.060732 -234.051094 90)
		(property "Reference" "R6816"
			(at 0 0 90)
			(layer "B.SilkS")
			(hide yes)
			(effects
				(font
					(size 1.27 1.27)
				)
				(justify mirror)
			)
		)
		(property "Value" ""
			(at 0 0 90)
			(layer "B.Fab")
			(effects
				(font
					(size 1.27 1.27)
				)
				(justify mirror)
			)
		)
		(duplicate_pad_numbers_are_jumpers no)
		(fp_line
			(start 0.7874 -0.4064)
			(end -0.7874 -0.4064)
			(stroke
				(width 0.1524)
				(type default)
			)
			(layer "B.SilkS")
		)
		(fp_line
			(start -0.7874 -0.4064)
			(end -0.7874 0.4064)
			(stroke
				(width 0.1524)
				(type default)
			)
			(layer "B.SilkS")
		)
		(fp_line
			(start 0.7874 0.4064)
			(end 0.7874 -0.4064)
			(stroke
				(width 0.1524)
				(type default)
			)
			(layer "B.SilkS")
		)
		(fp_line
			(start -0.7874 0.4064)
			(end 0.7874 0.4064)
			(stroke
				(width 0.1524)
				(type default)
			)
			(layer "B.SilkS")
		)
		(fp_line
			(start 0.67945 -0.305054)
			(end 0.12065 -0.305054)
			(stroke
				(width 0.1)
				(type default)
			)
			(layer "B.Fab")
		)
		(fp_line
			(start 0.12065 -0.305054)
			(end 0.12065 -0.2794)
			(stroke
				(width 0.1)
				(type default)
			)
			(layer "B.Fab")
		)
		(fp_line
			(start -0.12065 -0.3048)
			(end -0.67945 -0.3048)
			(stroke
				(width 0.1)
				(type default)
			)
			(layer "B.Fab")
		)
		(fp_line
			(start -0.67945 -0.3048)
			(end -0.67945 0.3048)
			(stroke
				(width 0.1)
				(type default)
			)
			(layer "B.Fab")
		)
		(fp_line
			(start 0.12065 -0.2794)
			(end -0.12065 -0.2794)
			(stroke
				(width 0.1)
				(type default)
			)
			(layer "B.Fab")
		)
		(fp_line
			(start -0.12065 -0.2794)
			(end -0.12065 -0.3048)
			(stroke
				(width 0.1)
				(type default)
			)
			(layer "B.Fab")
		)
		(fp_line
			(start 0.12065 0.2794)
			(end 0.12065 0.3048)
			(stroke
				(width 0.1)
				(type default)
			)
			(layer "B.Fab")
		)
		(fp_line
			(start -0.120396 0.2794)
			(end 0.12065 0.2794)
			(stroke
				(width 0.1)
				(type default)
			)
			(layer "B.Fab")
		)
		(fp_line
			(start 0.67945 0.3048)
			(end 0.67945 -0.305054)
			(stroke
				(width 0.1)
				(type default)
			)
			(layer "B.Fab")
		)
		(fp_line
			(start 0.12065 0.3048)
			(end 0.67945 0.3048)
			(stroke
				(width 0.1)
				(type default)
			)
			(layer "B.Fab")
		)
		(fp_line
			(start -0.120396 0.3048)
			(end -0.120396 0.2794)
			(stroke
				(width 0.1)
				(type default)
			)
			(layer "B.Fab")
		)
		(fp_line
			(start -0.67945 0.3048)
			(end -0.120396 0.3048)
			(stroke
				(width 0.1)
				(type default)
			)
			(layer "B.Fab")
		)
		(pad "1" smd circle
			(at 0.40005 0 270)
			(size 0 0)
			(layers "B.Cu" "B.Mask" "B.Paste")
			(net "GND")
		)
		(pad "2" smd circle
			(at -0.40005 0 270)
			(size 0 0)
			(layers "B.Cu" "B.Mask" "B.Paste")
			(net "BOARD_TYPE_2_ADC_R")
		)
	)
	(footprint ""
		(layer "B.Cu")
		(at 290.89985 -290.199826 90)
		(property "Reference" "C1690"
			(at 0 0 90)
			(layer "B.SilkS")
			(hide yes)
			(effects
				(font
					(size 1.27 1.27)
				)
				(justify mirror)
			)
		)
		(property "Value" ""
			(at 0 0 90)
			(layer "B.Fab")
			(effects
				(font
					(size 1.27 1.27)
				)
				(justify mirror)
			)
		)
		(duplicate_pad_numbers_are_jumpers no)
		(fp_line
			(start 0.299974 -0.150114)
			(end -0.299974 -0.150114)
			(stroke
				(width 0.1)
				(type default)
			)
			(layer "B.Fab")
		)
		(fp_line
			(start -0.299974 -0.150114)
			(end -0.299974 0.150114)
			(stroke
				(width 0.1)
				(type default)
			)
			(layer "B.Fab")
		)
		(fp_line
			(start 0.299974 0.150114)
			(end 0.299974 -0.150114)
			(stroke
				(width 0.1)
				(type default)
			)
			(layer "B.Fab")
		)
		(fp_line
			(start -0.299974 0.150114)
			(end 0.299974 0.150114)
			(stroke
				(width 0.1)
				(type default)
			)
			(layer "B.Fab")
		)
		(pad "1" smd rect
			(at 0.2667 0 270)
			(size 0.3048 0.381)
			(layers "B.Cu" "B.Mask" "B.Paste")
			(net "P0V8_SERDES_VDDA_PEX2")
		)
		(pad "2" smd rect
			(at -0.2667 0 270)
			(size 0.3048 0.381)
			(layers "B.Cu" "B.Mask" "B.Paste")
			(net "GND")
		)
	)
	(footprint ""
		(layer "B.Cu")
		(at 351.645982 -154.305)
		(property "Reference" "R4806"
			(at 0 0 0)
			(layer "B.SilkS")
			(hide yes)
			(effects
				(font
					(size 1.27 1.27)
				)
				(justify mirror)
			)
		)
		(property "Value" ""
			(at 0 0 0)
			(layer "B.Fab")
			(effects
				(font
					(size 1.27 1.27)
				)
				(justify mirror)
			)
		)
		(duplicate_pad_numbers_are_jumpers no)
		(fp_line
			(start -0.7874 -0.4064)
			(end -0.7874 0.4064)
			(stroke
				(width 0.1524)
				(type default)
			)
			(layer "B.SilkS")
		)
		(fp_line
			(start -0.7874 0.4064)
			(end 0.7874 0.4064)
			(stroke
				(width 0.1524)
				(type default)
			)
			(layer "B.SilkS")
		)
		(fp_line
			(start 0.7874 -0.4064)
			(end -0.7874 -0.4064)
			(stroke
				(width 0.1524)
				(type default)
			)
			(layer "B.SilkS")
		)
		(fp_line
			(start 0.7874 0.4064)
			(end 0.7874 -0.4064)
			(stroke
				(width 0.1524)
				(type default)
			)
			(layer "B.SilkS")
		)
		(fp_line
			(start -0.67945 -0.3048)
			(end -0.67945 0.3048)
			(stroke
				(width 0.1)
				(type default)
			)
			(layer "B.Fab")
		)
		(fp_line
			(start -0.67945 0.3048)
			(end -0.120396 0.3048)
			(stroke
				(width 0.1)
				(type default)
			)
			(layer "B.Fab")
		)
		(fp_line
			(start -0.12065 -0.3048)
			(end -0.67945 -0.3048)
			(stroke
				(width 0.1)
				(type default)
			)
			(layer "B.Fab")
		)
		(fp_line
			(start -0.12065 -0.2794)
			(end -0.12065 -0.3048)
			(stroke
				(width 0.1)
				(type default)
			)
			(layer "B.Fab")
		)
		(fp_line
			(start -0.120396 0.2794)
			(end 0.12065 0.2794)
			(stroke
				(width 0.1)
				(type default)
			)
			(layer "B.Fab")
		)
		(fp_line
			(start -0.120396 0.3048)
			(end -0.120396 0.2794)
			(stroke
				(width 0.1)
				(type default)
			)
			(layer "B.Fab")
		)
		(fp_line
			(start 0.12065 -0.305054)
			(end 0.12065 -0.2794)
			(stroke
				(width 0.1)
				(type default)
			)
			(layer "B.Fab")
		)
		(fp_line
			(start 0.12065 -0.2794)
			(end -0.12065 -0.2794)
			(stroke
				(width 0.1)
				(type default)
			)
			(layer "B.Fab")
		)
		(fp_line
			(start 0.12065 0.2794)
			(end 0.12065 0.3048)
			(stroke
				(width 0.1)
				(type default)
			)
			(layer "B.Fab")
		)
		(fp_line
			(start 0.12065 0.3048)
			(end 0.67945 0.3048)
			(stroke
				(width 0.1)
				(type default)
			)
			(layer "B.Fab")
		)
		(fp_line
			(start 0.67945 -0.305054)
			(end 0.12065 -0.305054)
			(stroke
				(width 0.1)
				(type default)
			)
			(layer "B.Fab")
		)
		(fp_line
			(start 0.67945 0.3048)
			(end 0.67945 -0.305054)
			(stroke
				(width 0.1)
				(type default)
			)
			(layer "B.Fab")
		)
		(pad "1" smd circle
			(at 0.40005 0 180)
			(size 0 0)
			(layers "B.Cu" "B.Mask" "B.Paste")
			(net "NIC6_PEX_PWR_EN_R")
		)
		(pad "2" smd circle
			(at -0.40005 0 180)
			(size 0 0)
			(layers "B.Cu" "B.Mask" "B.Paste")
			(net "GND")
		)
	)
	(footprint ""
		(layer "B.Cu")
		(at 296.599864 -301.599854 -90)
		(property "Reference" "C1717"
			(at 0 0 90)
			(layer "B.SilkS")
			(hide yes)
			(effects
				(font
					(size 1.27 1.27)
				)
				(justify mirror)
			)
		)
		(property "Value" ""
			(at 0 0 90)
			(layer "B.Fab")
			(effects
				(font
					(size 1.27 1.27)
				)
				(justify mirror)
			)
		)
		(duplicate_pad_numbers_are_jumpers no)
		(fp_line
			(start -0.299974 0.150114)
			(end 0.299974 0.150114)
			(stroke
				(width 0.1)
				(type default)
			)
			(layer "B.Fab")
		)
		(fp_line
			(start 0.299974 0.150114)
			(end 0.299974 -0.150114)
			(stroke
				(width 0.1)
				(type default)
			)
			(layer "B.Fab")
		)
		(fp_line
			(start -0.299974 -0.150114)
			(end -0.299974 0.150114)
			(stroke
				(width 0.1)
				(type default)
			)
			(layer "B.Fab")
		)
		(fp_line
			(start 0.299974 -0.150114)
			(end -0.299974 -0.150114)
			(stroke
				(width 0.1)
				(type default)
			)
			(layer "B.Fab")
		)
		(pad "1" smd rect
			(at 0.2667 0 90)
			(size 0.3048 0.381)
			(layers "B.Cu" "B.Mask" "B.Paste")
			(net "P0V8_SERDES_VDDA_PEX2")
		)
		(pad "2" smd rect
			(at -0.2667 0 90)
			(size 0.3048 0.381)
			(layers "B.Cu" "B.Mask" "B.Paste")
			(net "GND")
		)
	)
	(footprint ""
		(layer "B.Cu")
		(at 408.424888 -286.399732 90)
		(property "Reference" "C3479"
			(at 0 0 90)
			(layer "B.SilkS")
			(hide yes)
			(effects
				(font
					(size 1.27 1.27)
				)
				(justify mirror)
			)
		)
		(property "Value" ""
			(at 0 0 90)
			(layer "B.Fab")
			(effects
				(font
					(size 1.27 1.27)
				)
				(justify mirror)
			)
		)
		(duplicate_pad_numbers_are_jumpers no)
		(fp_line
			(start 0.299974 -0.150114)
			(end -0.299974 -0.150114)
			(stroke
				(width 0.1)
				(type default)
			)
			(layer "B.Fab")
		)
		(fp_line
			(start -0.299974 -0.150114)
			(end -0.299974 0.150114)
			(stroke
				(width 0.1)
				(type default)
			)
			(layer "B.Fab")
		)
		(fp_line
			(start 0.299974 0.150114)
			(end 0.299974 -0.150114)
			(stroke
				(width 0.1)
				(type default)
			)
			(layer "B.Fab")
		)
		(fp_line
			(start -0.299974 0.150114)
			(end 0.299974 0.150114)
			(stroke
				(width 0.1)
				(type default)
			)
			(layer "B.Fab")
		)
		(pad "1" smd rect
			(at 0.2667 0 270)
			(size 0.3048 0.381)
			(layers "B.Cu" "B.Mask" "B.Paste")
			(net "P1V25_SERDES_VDDPLL_PEX3")
		)
		(pad "2" smd rect
			(at -0.2667 0 270)
			(size 0.3048 0.381)
			(layers "B.Cu" "B.Mask" "B.Paste")
			(net "GND")
		)
	)
	(footprint ""
		(layer "B.Cu")
		(at 384.409696 -247.311926 90)
		(property "Reference" "R938"
			(at 0 0 90)
			(layer "B.SilkS")
			(hide yes)
			(effects
				(font
					(size 1.27 1.27)
				)
				(justify mirror)
			)
		)
		(property "Value" ""
			(at 0 0 90)
			(layer "B.Fab")
			(effects
				(font
					(size 1.27 1.27)
				)
				(justify mirror)
			)
		)
		(duplicate_pad_numbers_are_jumpers no)
		(fp_line
			(start 0.7874 -0.4064)
			(end -0.7874 -0.4064)
			(stroke
				(width 0.1524)
				(type default)
			)
			(layer "B.SilkS")
		)
		(fp_line
			(start -0.7874 -0.4064)
			(end -0.7874 0.4064)
			(stroke
				(width 0.1524)
				(type default)
			)
			(layer "B.SilkS")
		)
		(fp_line
			(start 0.7874 0.4064)
			(end 0.7874 -0.4064)
			(stroke
				(width 0.1524)
				(type default)
			)
			(layer "B.SilkS")
		)
		(fp_line
			(start -0.7874 0.4064)
			(end 0.7874 0.4064)
			(stroke
				(width 0.1524)
				(type default)
			)
			(layer "B.SilkS")
		)
		(fp_line
			(start 0.67945 -0.305054)
			(end 0.12065 -0.305054)
			(stroke
				(width 0.1)
				(type default)
			)
			(layer "B.Fab")
		)
		(fp_line
			(start 0.12065 -0.305054)
			(end 0.12065 -0.2794)
			(stroke
				(width 0.1)
				(type default)
			)
			(layer "B.Fab")
		)
		(fp_line
			(start -0.12065 -0.3048)
			(end -0.67945 -0.3048)
			(stroke
				(width 0.1)
				(type default)
			)
			(layer "B.Fab")
		)
		(fp_line
			(start -0.67945 -0.3048)
			(end -0.67945 0.3048)
			(stroke
				(width 0.1)
				(type default)
			)
			(layer "B.Fab")
		)
		(fp_line
			(start 0.12065 -0.2794)
			(end -0.12065 -0.2794)
			(stroke
				(width 0.1)
				(type default)
			)
			(layer "B.Fab")
		)
		(fp_line
			(start -0.12065 -0.2794)
			(end -0.12065 -0.3048)
			(stroke
				(width 0.1)
				(type default)
			)
			(layer "B.Fab")
		)
		(fp_line
			(start 0.12065 0.2794)
			(end 0.12065 0.3048)
			(stroke
				(width 0.1)
				(type default)
			)
			(layer "B.Fab")
		)
		(fp_line
			(start -0.120396 0.2794)
			(end 0.12065 0.2794)
			(stroke
				(width 0.1)
				(type default)
			)
			(layer "B.Fab")
		)
		(fp_line
			(start 0.67945 0.3048)
			(end 0.67945 -0.305054)
			(stroke
				(width 0.1)
				(type default)
			)
			(layer "B.Fab")
		)
		(fp_line
			(start 0.12065 0.3048)
			(end 0.67945 0.3048)
			(stroke
				(width 0.1)
				(type default)
			)
			(layer "B.Fab")
		)
		(fp_line
			(start -0.120396 0.3048)
			(end -0.120396 0.2794)
			(stroke
				(width 0.1)
				(type default)
			)
			(layer "B.Fab")
		)
		(fp_line
			(start -0.67945 0.3048)
			(end -0.120396 0.3048)
			(stroke
				(width 0.1)
				(type default)
			)
			(layer "B.Fab")
		)
		(pad "1" smd circle
			(at 0.40005 0 270)
			(size 0 0)
			(layers "B.Cu" "B.Mask" "B.Paste")
			(net "UART_PEX3_SDB_BUF_RX")
		)
		(pad "2" smd circle
			(at -0.40005 0 270)
			(size 0 0)
			(layers "B.Cu" "B.Mask" "B.Paste")
			(net "P1V8_PEX")
		)
	)
	(footprint ""
		(layer "B.Cu")
		(at 137.846816 -211.045806)
		(property "Reference" "C2587"
			(at 0 0 0)
			(layer "B.SilkS")
			(hide yes)
			(effects
				(font
					(size 1.27 1.27)
				)
				(justify mirror)
			)
		)
		(property "Value" ""
			(at 0 0 0)
			(layer "B.Fab")
			(effects
				(font
					(size 1.27 1.27)
				)
				(justify mirror)
			)
		)
		(duplicate_pad_numbers_are_jumpers no)
		(fp_line
			(start -0.7874 -0.4064)
			(end -0.7874 0.4064)
			(stroke
				(width 0.1524)
				(type default)
			)
			(layer "B.SilkS")
		)
		(fp_line
			(start -0.7874 0.4064)
			(end 0.7874 0.4064)
			(stroke
				(width 0.1524)
				(type default)
			)
			(layer "B.SilkS")
		)
		(fp_line
			(start 0.7874 -0.4064)
			(end -0.7874 -0.4064)
			(stroke
				(width 0.1524)
				(type default)
			)
			(layer "B.SilkS")
		)
		(fp_line
			(start 0.7874 0.4064)
			(end 0.7874 -0.4064)
			(stroke
				(width 0.1524)
				(type default)
			)
			(layer "B.SilkS")
		)
		(fp_line
			(start -0.67945 -0.3048)
			(end -0.67945 0.3048)
			(stroke
				(width 0.1)
				(type default)
			)
			(layer "B.Fab")
		)
		(fp_line
			(start -0.67945 0.3048)
			(end -0.120396 0.3048)
			(stroke
				(width 0.1)
				(type default)
			)
			(layer "B.Fab")
		)
		(fp_line
			(start -0.12065 -0.3048)
			(end -0.67945 -0.3048)
			(stroke
				(width 0.1)
				(type default)
			)
			(layer "B.Fab")
		)
		(fp_line
			(start -0.12065 -0.2794)
			(end -0.12065 -0.3048)
			(stroke
				(width 0.1)
				(type default)
			)
			(layer "B.Fab")
		)
		(fp_line
			(start -0.120396 0.2794)
			(end 0.12065 0.2794)
			(stroke
				(width 0.1)
				(type default)
			)
			(layer "B.Fab")
		)
		(fp_line
			(start -0.120396 0.3048)
			(end -0.120396 0.2794)
			(stroke
				(width 0.1)
				(type default)
			)
			(layer "B.Fab")
		)
		(fp_line
			(start 0.12065 -0.305054)
			(end 0.12065 -0.2794)
			(stroke
				(width 0.1)
				(type default)
			)
			(layer "B.Fab")
		)
		(fp_line
			(start 0.12065 -0.2794)
			(end -0.12065 -0.2794)
			(stroke
				(width 0.1)
				(type default)
			)
			(layer "B.Fab")
		)
		(fp_line
			(start 0.12065 0.2794)
			(end 0.12065 0.3048)
			(stroke
				(width 0.1)
				(type default)
			)
			(layer "B.Fab")
		)
		(fp_line
			(start 0.12065 0.3048)
			(end 0.67945 0.3048)
			(stroke
				(width 0.1)
				(type default)
			)
			(layer "B.Fab")
		)
		(fp_line
			(start 0.67945 -0.305054)
			(end 0.12065 -0.305054)
			(stroke
				(width 0.1)
				(type default)
			)
			(layer "B.Fab")
		)
		(fp_line
			(start 0.67945 0.3048)
			(end 0.67945 -0.305054)
			(stroke
				(width 0.1)
				(type default)
			)
			(layer "B.Fab")
		)
		(pad "1" smd circle
			(at 0.40005 0 180)
			(size 0 0)
			(layers "B.Cu" "B.Mask" "B.Paste")
			(net "P3V3_AUX")
		)
		(pad "2" smd circle
			(at -0.40005 0 180)
			(size 0 0)
			(layers "B.Cu" "B.Mask" "B.Paste")
			(net "GND")
		)
	)
	(footprint ""
		(layer "B.Cu")
		(at 228.531928 -286.538162 180)
		(property "Reference" "PC235"
			(at 0 0 0)
			(layer "B.SilkS")
			(hide yes)
			(effects
				(font
					(size 1.27 1.27)
				)
				(justify mirror)
			)
		)
		(property "Value" ""
			(at 0 0 0)
			(layer "B.Fab")
			(effects
				(font
					(size 1.27 1.27)
				)
				(justify mirror)
			)
		)
		(duplicate_pad_numbers_are_jumpers no)
		(fp_line
			(start 1.524 0.762)
			(end 1.524 -0.762)
			(stroke
				(width 0.1524)
				(type default)
			)
			(layer "B.SilkS")
		)
		(fp_line
			(start 1.524 -0.762)
			(end -1.524 -0.762)
			(stroke
				(width 0.1524)
				(type default)
			)
			(layer "B.SilkS")
		)
		(fp_line
			(start -1.524 0.762)
			(end 1.524 0.762)
			(stroke
				(width 0.1524)
				(type default)
			)
			(layer "B.SilkS")
		)
		(fp_line
			(start -1.524 -0.762)
			(end -1.524 0.762)
			(stroke
				(width 0.1524)
				(type default)
			)
			(layer "B.SilkS")
		)
		(fp_line
			(start 1.1049 0.724916)
			(end -1.1049 0.724916)
			(stroke
				(width 0.1)
				(type default)
			)
			(layer "B.Fab")
		)
		(fp_line
			(start 1.1049 -0.724916)
			(end 1.1049 0.724916)
			(stroke
				(width 0.1)
				(type default)
			)
			(layer "B.Fab")
		)
		(fp_line
			(start -1.1049 0.724916)
			(end -1.1049 -0.724916)
			(stroke
				(width 0.1)
				(type default)
			)
			(layer "B.Fab")
		)
		(fp_line
			(start -1.1049 -0.724916)
			(end 1.1049 -0.724916)
			(stroke
				(width 0.1)
				(type default)
			)
			(layer "B.Fab")
		)
		(pad "1" smd rect
			(at 0.889 0 180)
			(size 1.016 1.27)
			(layers "B.Cu" "B.Mask" "B.Paste")
			(net "P1V25_PEX1_R")
		)
		(pad "2" smd rect
			(at -0.889 0 180)
			(size 1.016 1.27)
			(layers "B.Cu" "B.Mask" "B.Paste")
			(net "GND")
		)
	)
	(footprint ""
		(layer "B.Cu")
		(at 302.877474 -221.694502 90)
		(property "Reference" "R1867"
			(at 0 0 90)
			(layer "B.SilkS")
			(hide yes)
			(effects
				(font
					(size 1.27 1.27)
				)
				(justify mirror)
			)
		)
		(property "Value" ""
			(at 0 0 90)
			(layer "B.Fab")
			(effects
				(font
					(size 1.27 1.27)
				)
				(justify mirror)
			)
		)
		(duplicate_pad_numbers_are_jumpers no)
		(fp_line
			(start 0.7874 -0.4064)
			(end -0.7874 -0.4064)
			(stroke
				(width 0.1524)
				(type default)
			)
			(layer "B.SilkS")
		)
		(fp_line
			(start -0.7874 -0.4064)
			(end -0.7874 0.4064)
			(stroke
				(width 0.1524)
				(type default)
			)
			(layer "B.SilkS")
		)
		(fp_line
			(start 0.7874 0.4064)
			(end 0.7874 -0.4064)
			(stroke
				(width 0.1524)
				(type default)
			)
			(layer "B.SilkS")
		)
		(fp_line
			(start -0.7874 0.4064)
			(end 0.7874 0.4064)
			(stroke
				(width 0.1524)
				(type default)
			)
			(layer "B.SilkS")
		)
		(fp_line
			(start 0.67945 -0.305054)
			(end 0.12065 -0.305054)
			(stroke
				(width 0.1)
				(type default)
			)
			(layer "B.Fab")
		)
		(fp_line
			(start 0.12065 -0.305054)
			(end 0.12065 -0.2794)
			(stroke
				(width 0.1)
				(type default)
			)
			(layer "B.Fab")
		)
		(fp_line
			(start -0.12065 -0.3048)
			(end -0.67945 -0.3048)
			(stroke
				(width 0.1)
				(type default)
			)
			(layer "B.Fab")
		)
		(fp_line
			(start -0.67945 -0.3048)
			(end -0.67945 0.3048)
			(stroke
				(width 0.1)
				(type default)
			)
			(layer "B.Fab")
		)
		(fp_line
			(start 0.12065 -0.2794)
			(end -0.12065 -0.2794)
			(stroke
				(width 0.1)
				(type default)
			)
			(layer "B.Fab")
		)
		(fp_line
			(start -0.12065 -0.2794)
			(end -0.12065 -0.3048)
			(stroke
				(width 0.1)
				(type default)
			)
			(layer "B.Fab")
		)
		(fp_line
			(start 0.12065 0.2794)
			(end 0.12065 0.3048)
			(stroke
				(width 0.1)
				(type default)
			)
			(layer "B.Fab")
		)
		(fp_line
			(start -0.120396 0.2794)
			(end 0.12065 0.2794)
			(stroke
				(width 0.1)
				(type default)
			)
			(layer "B.Fab")
		)
		(fp_line
			(start 0.67945 0.3048)
			(end 0.67945 -0.305054)
			(stroke
				(width 0.1)
				(type default)
			)
			(layer "B.Fab")
		)
		(fp_line
			(start 0.12065 0.3048)
			(end 0.67945 0.3048)
			(stroke
				(width 0.1)
				(type default)
			)
			(layer "B.Fab")
		)
		(fp_line
			(start -0.120396 0.3048)
			(end -0.120396 0.2794)
			(stroke
				(width 0.1)
				(type default)
			)
			(layer "B.Fab")
		)
		(fp_line
			(start -0.67945 0.3048)
			(end -0.120396 0.3048)
			(stroke
				(width 0.1)
				(type default)
			)
			(layer "B.Fab")
		)
		(pad "1" smd circle
			(at 0.40005 0 270)
			(size 0 0)
			(layers "B.Cu" "B.Mask" "B.Paste")
			(net "RST_GPU_PERST_1_BUF_N")
		)
		(pad "2" smd circle
			(at -0.40005 0 270)
			(size 0 0)
			(layers "B.Cu" "B.Mask" "B.Paste")
			(net "RST_GPU_PERST_1_BUF_R_N")
		)
	)
	(footprint ""
		(layer "B.Cu")
		(at 77.541882 -97.005648 180)
		(property "Reference" "R63"
			(at 0 0 0)
			(layer "B.SilkS")
			(hide yes)
			(effects
				(font
					(size 1.27 1.27)
				)
				(justify mirror)
			)
		)
		(property "Value" ""
			(at 0 0 0)
			(layer "B.Fab")
			(effects
				(font
					(size 1.27 1.27)
				)
				(justify mirror)
			)
		)
		(duplicate_pad_numbers_are_jumpers no)
		(fp_line
			(start 0.7874 0.4064)
			(end 0.7874 -0.4064)
			(stroke
				(width 0.1524)
				(type default)
			)
			(layer "B.SilkS")
		)
		(fp_line
			(start 0.7874 -0.4064)
			(end -0.7874 -0.4064)
			(stroke
				(width 0.1524)
				(type default)
			)
			(layer "B.SilkS")
		)
		(fp_line
			(start -0.7874 0.4064)
			(end 0.7874 0.4064)
			(stroke
				(width 0.1524)
				(type default)
			)
			(layer "B.SilkS")
		)
		(fp_line
			(start -0.7874 -0.4064)
			(end -0.7874 0.4064)
			(stroke
				(width 0.1524)
				(type default)
			)
			(layer "B.SilkS")
		)
		(fp_line
			(start 0.67945 0.3048)
			(end 0.67945 -0.305054)
			(stroke
				(width 0.1)
				(type default)
			)
			(layer "B.Fab")
		)
		(fp_line
			(start 0.67945 -0.305054)
			(end 0.12065 -0.305054)
			(stroke
				(width 0.1)
				(type default)
			)
			(layer "B.Fab")
		)
		(fp_line
			(start 0.12065 0.3048)
			(end 0.67945 0.3048)
			(stroke
				(width 0.1)
				(type default)
			)
			(layer "B.Fab")
		)
		(fp_line
			(start 0.12065 0.2794)
			(end 0.12065 0.3048)
			(stroke
				(width 0.1)
				(type default)
			)
			(layer "B.Fab")
		)
		(fp_line
			(start 0.12065 -0.2794)
			(end -0.12065 -0.2794)
			(stroke
				(width 0.1)
				(type default)
			)
			(layer "B.Fab")
		)
		(fp_line
			(start 0.12065 -0.305054)
			(end 0.12065 -0.2794)
			(stroke
				(width 0.1)
				(type default)
			)
			(layer "B.Fab")
		)
		(fp_line
			(start -0.120396 0.3048)
			(end -0.120396 0.2794)
			(stroke
				(width 0.1)
				(type default)
			)
			(layer "B.Fab")
		)
		(fp_line
			(start -0.120396 0.2794)
			(end 0.12065 0.2794)
			(stroke
				(width 0.1)
				(type default)
			)
			(layer "B.Fab")
		)
		(fp_line
			(start -0.12065 -0.2794)
			(end -0.12065 -0.3048)
			(stroke
				(width 0.1)
				(type default)
			)
			(layer "B.Fab")
		)
		(fp_line
			(start -0.12065 -0.3048)
			(end -0.67945 -0.3048)
			(stroke
				(width 0.1)
				(type default)
			)
			(layer "B.Fab")
		)
		(fp_line
			(start -0.67945 0.3048)
			(end -0.120396 0.3048)
			(stroke
				(width 0.1)
				(type default)
			)
			(layer "B.Fab")
		)
		(fp_line
			(start -0.67945 -0.3048)
			(end -0.67945 0.3048)
			(stroke
				(width 0.1)
				(type default)
			)
			(layer "B.Fab")
		)
		(pad "1" smd circle
			(at 0.40005 0)
			(size 0 0)
			(layers "B.Cu" "B.Mask" "B.Paste")
			(net "NIC1_DATA_IN")
		)
		(pad "2" smd circle
			(at -0.40005 0)
			(size 0 0)
			(layers "B.Cu" "B.Mask" "B.Paste")
			(net "P3V3_NIC1")
		)
	)
	(footprint ""
		(layer "B.Cu")
		(at 401.299934 -299.699934 -90)
		(property "Reference" "C1994"
			(at 0 0 90)
			(layer "B.SilkS")
			(hide yes)
			(effects
				(font
					(size 1.27 1.27)
				)
				(justify mirror)
			)
		)
		(property "Value" ""
			(at 0 0 90)
			(layer "B.Fab")
			(effects
				(font
					(size 1.27 1.27)
				)
				(justify mirror)
			)
		)
		(duplicate_pad_numbers_are_jumpers no)
		(fp_line
			(start -0.299974 0.150114)
			(end 0.299974 0.150114)
			(stroke
				(width 0.1)
				(type default)
			)
			(layer "B.Fab")
		)
		(fp_line
			(start 0.299974 0.150114)
			(end 0.299974 -0.150114)
			(stroke
				(width 0.1)
				(type default)
			)
			(layer "B.Fab")
		)
		(fp_line
			(start -0.299974 -0.150114)
			(end -0.299974 0.150114)
			(stroke
				(width 0.1)
				(type default)
			)
			(layer "B.Fab")
		)
		(fp_line
			(start 0.299974 -0.150114)
			(end -0.299974 -0.150114)
			(stroke
				(width 0.1)
				(type default)
			)
			(layer "B.Fab")
		)
		(pad "1" smd rect
			(at 0.2667 0 90)
			(size 0.3048 0.381)
			(layers "B.Cu" "B.Mask" "B.Paste")
			(net "P0V8_SERDES_VDDA_PEX3")
		)
		(pad "2" smd rect
			(at -0.2667 0 90)
			(size 0.3048 0.381)
			(layers "B.Cu" "B.Mask" "B.Paste")
			(net "GND")
		)
	)
	(footprint ""
		(layer "B.Cu")
		(at 333.89824 -219.902278 -90)
		(property "Reference" "C2084"
			(at 0 0 90)
			(layer "B.SilkS")
			(hide yes)
			(effects
				(font
					(size 1.27 1.27)
				)
				(justify mirror)
			)
		)
		(property "Value" ""
			(at 0 0 90)
			(layer "B.Fab")
			(effects
				(font
					(size 1.27 1.27)
				)
				(justify mirror)
			)
		)
		(duplicate_pad_numbers_are_jumpers no)
		(fp_line
			(start -0.69215 0.2921)
			(end 0.69215 0.2921)
			(stroke
				(width 0.1524)
				(type default)
			)
			(layer "B.SilkS")
		)
		(fp_line
			(start 0.69215 0.2921)
			(end 0.69215 -0.2921)
			(stroke
				(width 0.1524)
				(type default)
			)
			(layer "B.SilkS")
		)
		(fp_line
			(start -0.69215 -0.2921)
			(end -0.69215 0.2921)
			(stroke
				(width 0.1524)
				(type default)
			)
			(layer "B.SilkS")
		)
		(fp_line
			(start 0.69215 -0.2921)
			(end -0.69215 -0.2921)
			(stroke
				(width 0.1524)
				(type default)
			)
			(layer "B.SilkS")
		)
		(fp_line
			(start -0.51435 0.2794)
			(end 0.51435 0.2794)
			(stroke
				(width 0.1)
				(type default)
			)
			(layer "B.Fab")
		)
		(fp_line
			(start 0.51435 0.2794)
			(end 0.51435 -0.2794)
			(stroke
				(width 0.1)
				(type default)
			)
			(layer "B.Fab")
		)
		(fp_line
			(start -0.51435 -0.2794)
			(end -0.51435 0.2794)
			(stroke
				(width 0.1)
				(type default)
			)
			(layer "B.Fab")
		)
		(fp_line
			(start 0.51435 -0.2794)
			(end -0.51435 -0.2794)
			(stroke
				(width 0.1)
				(type default)
			)
			(layer "B.Fab")
		)
		(pad "1" smd circle
			(at 0.40005 0 90)
			(size 0 0)
			(layers "B.Cu" "B.Mask" "B.Paste")
			(net "P3V3_FPGA_VCCIO4")
		)
		(pad "2" smd circle
			(at -0.40005 0 90)
			(size 0 0)
			(layers "B.Cu" "B.Mask" "B.Paste")
			(net "GND")
		)
		(zone
			(layer "B.Cu")
			(hatch none 0.5)
			(connect_pads
				(clearance 0)
			)
			(min_thickness 0.25)
			(keepout
				(tracks not_allowed)
				(vias allowed)
				(pads allowed)
				(copperpour not_allowed)
				(footprints allowed)
			)
			(placement
				(enabled no)
				(sheetname "")
			)
			(fill
				(thermal_gap 0.5)
				(thermal_bridge_width 0.5)
				(island_removal_mode 0)
			)
			(polygon
				(pts
					(xy 333.81061 -219.711778) (xy 333.752444 -219.803218) (xy 333.752444 -220.002608) (xy 333.81061 -220.092778)
					(xy 333.98587 -220.092778) (xy 334.04429 -220.002608) (xy 334.04429 -219.803218) (xy 333.986124 -219.711778)
				)
			)
		)
	)
	(footprint ""
		(layer "B.Cu")
		(at 213.801198 -219.306902)
		(property "Reference" "R4887"
			(at 0 0 0)
			(layer "B.SilkS")
			(hide yes)
			(effects
				(font
					(size 1.27 1.27)
				)
				(justify mirror)
			)
		)
		(property "Value" ""
			(at 0 0 0)
			(layer "B.Fab")
			(effects
				(font
					(size 1.27 1.27)
				)
				(justify mirror)
			)
		)
		(duplicate_pad_numbers_are_jumpers no)
		(fp_line
			(start -0.7874 -0.4064)
			(end -0.7874 0.4064)
			(stroke
				(width 0.1524)
				(type default)
			)
			(layer "B.SilkS")
		)
		(fp_line
			(start -0.7874 0.4064)
			(end 0.7874 0.4064)
			(stroke
				(width 0.1524)
				(type default)
			)
			(layer "B.SilkS")
		)
		(fp_line
			(start 0.7874 -0.4064)
			(end -0.7874 -0.4064)
			(stroke
				(width 0.1524)
				(type default)
			)
			(layer "B.SilkS")
		)
		(fp_line
			(start 0.7874 0.4064)
			(end 0.7874 -0.4064)
			(stroke
				(width 0.1524)
				(type default)
			)
			(layer "B.SilkS")
		)
		(fp_line
			(start -0.67945 -0.3048)
			(end -0.67945 0.3048)
			(stroke
				(width 0.1)
				(type default)
			)
			(layer "B.Fab")
		)
		(fp_line
			(start -0.67945 0.3048)
			(end -0.120396 0.3048)
			(stroke
				(width 0.1)
				(type default)
			)
			(layer "B.Fab")
		)
		(fp_line
			(start -0.12065 -0.3048)
			(end -0.67945 -0.3048)
			(stroke
				(width 0.1)
				(type default)
			)
			(layer "B.Fab")
		)
		(fp_line
			(start -0.12065 -0.2794)
			(end -0.12065 -0.3048)
			(stroke
				(width 0.1)
				(type default)
			)
			(layer "B.Fab")
		)
		(fp_line
			(start -0.120396 0.2794)
			(end 0.12065 0.2794)
			(stroke
				(width 0.1)
				(type default)
			)
			(layer "B.Fab")
		)
		(fp_line
			(start -0.120396 0.3048)
			(end -0.120396 0.2794)
			(stroke
				(width 0.1)
				(type default)
			)
			(layer "B.Fab")
		)
		(fp_line
			(start 0.12065 -0.305054)
			(end 0.12065 -0.2794)
			(stroke
				(width 0.1)
				(type default)
			)
			(layer "B.Fab")
		)
		(fp_line
			(start 0.12065 -0.2794)
			(end -0.12065 -0.2794)
			(stroke
				(width 0.1)
				(type default)
			)
			(layer "B.Fab")
		)
		(fp_line
			(start 0.12065 0.2794)
			(end 0.12065 0.3048)
			(stroke
				(width 0.1)
				(type default)
			)
			(layer "B.Fab")
		)
		(fp_line
			(start 0.12065 0.3048)
			(end 0.67945 0.3048)
			(stroke
				(width 0.1)
				(type default)
			)
			(layer "B.Fab")
		)
		(fp_line
			(start 0.67945 -0.305054)
			(end 0.12065 -0.305054)
			(stroke
				(width 0.1)
				(type default)
			)
			(layer "B.Fab")
		)
		(fp_line
			(start 0.67945 0.3048)
			(end 0.67945 -0.305054)
			(stroke
				(width 0.1)
				(type default)
			)
			(layer "B.Fab")
		)
		(pad "1" smd circle
			(at 0.40005 0 180)
			(size 0 0)
			(layers "B.Cu" "B.Mask" "B.Paste")
			(net "SMB_PEX_R_SCL")
		)
		(pad "2" smd circle
			(at -0.40005 0 180)
			(size 0 0)
			(layers "B.Cu" "B.Mask" "B.Paste")
			(net "P3V3_AUX")
		)
	)
	(footprint ""
		(layer "B.Cu")
		(at 49.5554 -156.0576)
		(property "Reference" "R28"
			(at 0 0 0)
			(layer "B.SilkS")
			(hide yes)
			(effects
				(font
					(size 1.27 1.27)
				)
				(justify mirror)
			)
		)
		(property "Value" ""
			(at 0 0 0)
			(layer "B.Fab")
			(effects
				(font
					(size 1.27 1.27)
				)
				(justify mirror)
			)
		)
		(duplicate_pad_numbers_are_jumpers no)
		(fp_line
			(start -0.7874 -0.4064)
			(end -0.7874 0.4064)
			(stroke
				(width 0.1524)
				(type default)
			)
			(layer "B.SilkS")
		)
		(fp_line
			(start -0.7874 0.4064)
			(end 0.7874 0.4064)
			(stroke
				(width 0.1524)
				(type default)
			)
			(layer "B.SilkS")
		)
		(fp_line
			(start 0.7874 -0.4064)
			(end -0.7874 -0.4064)
			(stroke
				(width 0.1524)
				(type default)
			)
			(layer "B.SilkS")
		)
		(fp_line
			(start 0.7874 0.4064)
			(end 0.7874 -0.4064)
			(stroke
				(width 0.1524)
				(type default)
			)
			(layer "B.SilkS")
		)
		(fp_line
			(start -0.67945 -0.3048)
			(end -0.67945 0.3048)
			(stroke
				(width 0.1)
				(type default)
			)
			(layer "B.Fab")
		)
		(fp_line
			(start -0.67945 0.3048)
			(end -0.120396 0.3048)
			(stroke
				(width 0.1)
				(type default)
			)
			(layer "B.Fab")
		)
		(fp_line
			(start -0.12065 -0.3048)
			(end -0.67945 -0.3048)
			(stroke
				(width 0.1)
				(type default)
			)
			(layer "B.Fab")
		)
		(fp_line
			(start -0.12065 -0.2794)
			(end -0.12065 -0.3048)
			(stroke
				(width 0.1)
				(type default)
			)
			(layer "B.Fab")
		)
		(fp_line
			(start -0.120396 0.2794)
			(end 0.12065 0.2794)
			(stroke
				(width 0.1)
				(type default)
			)
			(layer "B.Fab")
		)
		(fp_line
			(start -0.120396 0.3048)
			(end -0.120396 0.2794)
			(stroke
				(width 0.1)
				(type default)
			)
			(layer "B.Fab")
		)
		(fp_line
			(start 0.12065 -0.305054)
			(end 0.12065 -0.2794)
			(stroke
				(width 0.1)
				(type default)
			)
			(layer "B.Fab")
		)
		(fp_line
			(start 0.12065 -0.2794)
			(end -0.12065 -0.2794)
			(stroke
				(width 0.1)
				(type default)
			)
			(layer "B.Fab")
		)
		(fp_line
			(start 0.12065 0.2794)
			(end 0.12065 0.3048)
			(stroke
				(width 0.1)
				(type default)
			)
			(layer "B.Fab")
		)
		(fp_line
			(start 0.12065 0.3048)
			(end 0.67945 0.3048)
			(stroke
				(width 0.1)
				(type default)
			)
			(layer "B.Fab")
		)
		(fp_line
			(start 0.67945 -0.305054)
			(end 0.12065 -0.305054)
			(stroke
				(width 0.1)
				(type default)
			)
			(layer "B.Fab")
		)
		(fp_line
			(start 0.67945 0.3048)
			(end 0.67945 -0.305054)
			(stroke
				(width 0.1)
				(type default)
			)
			(layer "B.Fab")
		)
		(pad "1" smd circle
			(at 0.40005 0 180)
			(size 0 0)
			(layers "B.Cu" "B.Mask" "B.Paste")
			(net "NIC0_SLOT_ID1")
		)
		(pad "2" smd circle
			(at -0.40005 0 180)
			(size 0 0)
			(layers "B.Cu" "B.Mask" "B.Paste")
			(net "GND")
		)
	)
	(footprint ""
		(layer "B.Cu")
		(at 394.65504 -296.37482)
		(property "Reference" "C3551"
			(at 0 0 0)
			(layer "B.SilkS")
			(hide yes)
			(effects
				(font
					(size 1.27 1.27)
				)
				(justify mirror)
			)
		)
		(property "Value" ""
			(at 0 0 0)
			(layer "B.Fab")
			(effects
				(font
					(size 1.27 1.27)
				)
				(justify mirror)
			)
		)
		(duplicate_pad_numbers_are_jumpers no)
		(fp_line
			(start -0.299974 -0.150114)
			(end -0.299974 0.150114)
			(stroke
				(width 0.1)
				(type default)
			)
			(layer "B.Fab")
		)
		(fp_line
			(start -0.299974 0.150114)
			(end 0.299974 0.150114)
			(stroke
				(width 0.1)
				(type default)
			)
			(layer "B.Fab")
		)
		(fp_line
			(start 0.299974 -0.150114)
			(end -0.299974 -0.150114)
			(stroke
				(width 0.1)
				(type default)
			)
			(layer "B.Fab")
		)
		(fp_line
			(start 0.299974 0.150114)
			(end 0.299974 -0.150114)
			(stroke
				(width 0.1)
				(type default)
			)
			(layer "B.Fab")
		)
		(pad "1" smd rect
			(at 0.2667 0 180)
			(size 0.3048 0.381)
			(layers "B.Cu" "B.Mask" "B.Paste")
			(net "PCEPLL2_VDDA18_PEX3")
		)
		(pad "2" smd rect
			(at -0.2667 0 180)
			(size 0.3048 0.381)
			(layers "B.Cu" "B.Mask" "B.Paste")
			(net "GND")
		)
	)
	(footprint ""
		(layer "B.Cu")
		(at 339.694012 -218.787218 90)
		(property "Reference" "C2081"
			(at 0 0 90)
			(layer "B.SilkS")
			(hide yes)
			(effects
				(font
					(size 1.27 1.27)
				)
				(justify mirror)
			)
		)
		(property "Value" ""
			(at 0 0 90)
			(layer "B.Fab")
			(effects
				(font
					(size 1.27 1.27)
				)
				(justify mirror)
			)
		)
		(duplicate_pad_numbers_are_jumpers no)
		(fp_line
			(start 0.69215 -0.2921)
			(end -0.69215 -0.2921)
			(stroke
				(width 0.1524)
				(type default)
			)
			(layer "B.SilkS")
		)
		(fp_line
			(start -0.69215 -0.2921)
			(end -0.69215 0.2921)
			(stroke
				(width 0.1524)
				(type default)
			)
			(layer "B.SilkS")
		)
		(fp_line
			(start 0.69215 0.2921)
			(end 0.69215 -0.2921)
			(stroke
				(width 0.1524)
				(type default)
			)
			(layer "B.SilkS")
		)
		(fp_line
			(start -0.69215 0.2921)
			(end 0.69215 0.2921)
			(stroke
				(width 0.1524)
				(type default)
			)
			(layer "B.SilkS")
		)
		(fp_line
			(start 0.51435 -0.2794)
			(end -0.51435 -0.2794)
			(stroke
				(width 0.1)
				(type default)
			)
			(layer "B.Fab")
		)
		(fp_line
			(start -0.51435 -0.2794)
			(end -0.51435 0.2794)
			(stroke
				(width 0.1)
				(type default)
			)
			(layer "B.Fab")
		)
		(fp_line
			(start 0.51435 0.2794)
			(end 0.51435 -0.2794)
			(stroke
				(width 0.1)
				(type default)
			)
			(layer "B.Fab")
		)
		(fp_line
			(start -0.51435 0.2794)
			(end 0.51435 0.2794)
			(stroke
				(width 0.1)
				(type default)
			)
			(layer "B.Fab")
		)
		(pad "1" smd circle
			(at 0.40005 0 270)
			(size 0 0)
			(layers "B.Cu" "B.Mask" "B.Paste")
			(net "P3V3_FPGA_VCCIO4")
		)
		(pad "2" smd circle
			(at -0.40005 0 270)
			(size 0 0)
			(layers "B.Cu" "B.Mask" "B.Paste")
			(net "GND")
		)
		(zone
			(layer "B.Cu")
			(hatch none 0.5)
			(connect_pads
				(clearance 0)
			)
			(min_thickness 0.25)
			(keepout
				(tracks not_allowed)
				(vias allowed)
				(pads allowed)
				(copperpour not_allowed)
				(footprints allowed)
			)
			(placement
				(enabled no)
				(sheetname "")
			)
			(fill
				(thermal_gap 0.5)
				(thermal_bridge_width 0.5)
				(island_removal_mode 0)
			)
			(polygon
				(pts
					(xy 339.781642 -218.977718) (xy 339.839808 -218.886278) (xy 339.839808 -218.686888) (xy 339.781642 -218.596718)
					(xy 339.606382 -218.596718) (xy 339.547962 -218.686888) (xy 339.547962 -218.886278) (xy 339.606128 -218.977718)
				)
			)
		)
	)
	(footprint ""
		(layer "B.Cu")
		(at 203.414376 -371.088666 180)
		(property "Reference" "R6248"
			(at 0 0 0)
			(layer "B.SilkS")
			(hide yes)
			(effects
				(font
					(size 1.27 1.27)
				)
				(justify mirror)
			)
		)
		(property "Value" ""
			(at 0 0 0)
			(layer "B.Fab")
			(effects
				(font
					(size 1.27 1.27)
				)
				(justify mirror)
			)
		)
		(duplicate_pad_numbers_are_jumpers no)
		(fp_line
			(start 0.7874 0.4064)
			(end 0.7874 -0.4064)
			(stroke
				(width 0.1524)
				(type default)
			)
			(layer "B.SilkS")
		)
		(fp_line
			(start 0.7874 -0.4064)
			(end -0.7874 -0.4064)
			(stroke
				(width 0.1524)
				(type default)
			)
			(layer "B.SilkS")
		)
		(fp_line
			(start -0.7874 0.4064)
			(end 0.7874 0.4064)
			(stroke
				(width 0.1524)
				(type default)
			)
			(layer "B.SilkS")
		)
		(fp_line
			(start -0.7874 -0.4064)
			(end -0.7874 0.4064)
			(stroke
				(width 0.1524)
				(type default)
			)
			(layer "B.SilkS")
		)
		(fp_line
			(start 0.67945 0.3048)
			(end 0.67945 -0.305054)
			(stroke
				(width 0.1)
				(type default)
			)
			(layer "B.Fab")
		)
		(fp_line
			(start 0.67945 -0.305054)
			(end 0.12065 -0.305054)
			(stroke
				(width 0.1)
				(type default)
			)
			(layer "B.Fab")
		)
		(fp_line
			(start 0.12065 0.3048)
			(end 0.67945 0.3048)
			(stroke
				(width 0.1)
				(type default)
			)
			(layer "B.Fab")
		)
		(fp_line
			(start 0.12065 0.2794)
			(end 0.12065 0.3048)
			(stroke
				(width 0.1)
				(type default)
			)
			(layer "B.Fab")
		)
		(fp_line
			(start 0.12065 -0.2794)
			(end -0.12065 -0.2794)
			(stroke
				(width 0.1)
				(type default)
			)
			(layer "B.Fab")
		)
		(fp_line
			(start 0.12065 -0.305054)
			(end 0.12065 -0.2794)
			(stroke
				(width 0.1)
				(type default)
			)
			(layer "B.Fab")
		)
		(fp_line
			(start -0.120396 0.3048)
			(end -0.120396 0.2794)
			(stroke
				(width 0.1)
				(type default)
			)
			(layer "B.Fab")
		)
		(fp_line
			(start -0.120396 0.2794)
			(end 0.12065 0.2794)
			(stroke
				(width 0.1)
				(type default)
			)
			(layer "B.Fab")
		)
		(fp_line
			(start -0.12065 -0.2794)
			(end -0.12065 -0.3048)
			(stroke
				(width 0.1)
				(type default)
			)
			(layer "B.Fab")
		)
		(fp_line
			(start -0.12065 -0.3048)
			(end -0.67945 -0.3048)
			(stroke
				(width 0.1)
				(type default)
			)
			(layer "B.Fab")
		)
		(fp_line
			(start -0.67945 0.3048)
			(end -0.120396 0.3048)
			(stroke
				(width 0.1)
				(type default)
			)
			(layer "B.Fab")
		)
		(fp_line
			(start -0.67945 -0.3048)
			(end -0.67945 0.3048)
			(stroke
				(width 0.1)
				(type default)
			)
			(layer "B.Fab")
		)
		(pad "1" smd circle
			(at 0.40005 0)
			(size 0 0)
			(layers "B.Cu" "B.Mask" "B.Paste")
			(net "HSC_ALERT1_R_N")
		)
		(pad "2" smd circle
			(at -0.40005 0)
			(size 0 0)
			(layers "B.Cu" "B.Mask" "B.Paste")
			(net "HSC_ALERT1_N")
		)
	)
	(footprint ""
		(layer "B.Cu")
		(at 293.921942 -296.3926)
		(property "Reference" "C1635"
			(at 0 0 0)
			(layer "B.SilkS")
			(hide yes)
			(effects
				(font
					(size 1.27 1.27)
				)
				(justify mirror)
			)
		)
		(property "Value" ""
			(at 0 0 0)
			(layer "B.Fab")
			(effects
				(font
					(size 1.27 1.27)
				)
				(justify mirror)
			)
		)
		(duplicate_pad_numbers_are_jumpers no)
		(fp_line
			(start -0.299974 -0.150114)
			(end -0.299974 0.150114)
			(stroke
				(width 0.1)
				(type default)
			)
			(layer "B.Fab")
		)
		(fp_line
			(start -0.299974 0.150114)
			(end 0.299974 0.150114)
			(stroke
				(width 0.1)
				(type default)
			)
			(layer "B.Fab")
		)
		(fp_line
			(start 0.299974 -0.150114)
			(end -0.299974 -0.150114)
			(stroke
				(width 0.1)
				(type default)
			)
			(layer "B.Fab")
		)
		(fp_line
			(start 0.299974 0.150114)
			(end 0.299974 -0.150114)
			(stroke
				(width 0.1)
				(type default)
			)
			(layer "B.Fab")
		)
		(pad "1" smd rect
			(at 0.2667 0 180)
			(size 0.3048 0.381)
			(layers "B.Cu" "B.Mask" "B.Paste")
			(net "P0V8_PEX2")
		)
		(pad "2" smd rect
			(at -0.2667 0 180)
			(size 0.3048 0.381)
			(layers "B.Cu" "B.Mask" "B.Paste")
			(net "GND")
		)
	)
	(footprint ""
		(layer "B.Cu")
		(at 65.824862 -293.99992 -90)
		(property "Reference" "C1120"
			(at 0 0 90)
			(layer "B.SilkS")
			(hide yes)
			(effects
				(font
					(size 1.27 1.27)
				)
				(justify mirror)
			)
		)
		(property "Value" ""
			(at 0 0 90)
			(layer "B.Fab")
			(effects
				(font
					(size 1.27 1.27)
				)
				(justify mirror)
			)
		)
		(duplicate_pad_numbers_are_jumpers no)
		(fp_line
			(start -0.299974 0.150114)
			(end 0.299974 0.150114)
			(stroke
				(width 0.1)
				(type default)
			)
			(layer "B.Fab")
		)
		(fp_line
			(start 0.299974 0.150114)
			(end 0.299974 -0.150114)
			(stroke
				(width 0.1)
				(type default)
			)
			(layer "B.Fab")
		)
		(fp_line
			(start -0.299974 -0.150114)
			(end -0.299974 0.150114)
			(stroke
				(width 0.1)
				(type default)
			)
			(layer "B.Fab")
		)
		(fp_line
			(start 0.299974 -0.150114)
			(end -0.299974 -0.150114)
			(stroke
				(width 0.1)
				(type default)
			)
			(layer "B.Fab")
		)
		(pad "1" smd rect
			(at 0.2667 0 90)
			(size 0.3048 0.381)
			(layers "B.Cu" "B.Mask" "B.Paste")
			(net "P0V8_PEX0")
		)
		(pad "2" smd rect
			(at -0.2667 0 90)
			(size 0.3048 0.381)
			(layers "B.Cu" "B.Mask" "B.Paste")
			(net "GND")
		)
	)
	(footprint ""
		(layer "B.Cu")
		(at 165.249098 -301.0154 180)
		(property "Reference" "C1365"
			(at 0 0 0)
			(layer "B.SilkS")
			(hide yes)
			(effects
				(font
					(size 1.27 1.27)
				)
				(justify mirror)
			)
		)
		(property "Value" ""
			(at 0 0 0)
			(layer "B.Fab")
			(effects
				(font
					(size 1.27 1.27)
				)
				(justify mirror)
			)
		)
		(duplicate_pad_numbers_are_jumpers no)
		(fp_line
			(start 0.299974 0.150114)
			(end 0.299974 -0.150114)
			(stroke
				(width 0.1)
				(type default)
			)
			(layer "B.Fab")
		)
		(fp_line
			(start 0.299974 -0.150114)
			(end -0.299974 -0.150114)
			(stroke
				(width 0.1)
				(type default)
			)
			(layer "B.Fab")
		)
		(fp_line
			(start -0.299974 0.150114)
			(end 0.299974 0.150114)
			(stroke
				(width 0.1)
				(type default)
			)
			(layer "B.Fab")
		)
		(fp_line
			(start -0.299974 -0.150114)
			(end -0.299974 0.150114)
			(stroke
				(width 0.1)
				(type default)
			)
			(layer "B.Fab")
		)
		(pad "1" smd rect
			(at 0.2667 0)
			(size 0.3048 0.381)
			(layers "B.Cu" "B.Mask" "B.Paste")
			(net "P0V8_PEX1")
		)
		(pad "2" smd rect
			(at -0.2667 0)
			(size 0.3048 0.381)
			(layers "B.Cu" "B.Mask" "B.Paste")
			(net "GND")
		)
	)
	(footprint ""
		(layer "B.Cu")
		(at 367.258854 -308.685184 90)
		(property "Reference" "C4362"
			(at 0 0 90)
			(layer "B.SilkS")
			(hide yes)
			(effects
				(font
					(size 1.27 1.27)
				)
				(justify mirror)
			)
		)
		(property "Value" ""
			(at 0 0 90)
			(layer "B.Fab")
			(effects
				(font
					(size 1.27 1.27)
				)
				(justify mirror)
			)
		)
		(duplicate_pad_numbers_are_jumpers no)
		(fp_line
			(start 0.299974 -0.150114)
			(end -0.299974 -0.150114)
			(stroke
				(width 0.1)
				(type default)
			)
			(layer "B.Fab")
		)
		(fp_line
			(start -0.299974 -0.150114)
			(end -0.299974 0.150114)
			(stroke
				(width 0.1)
				(type default)
			)
			(layer "B.Fab")
		)
		(fp_line
			(start 0.299974 0.150114)
			(end 0.299974 -0.150114)
			(stroke
				(width 0.1)
				(type default)
			)
			(layer "B.Fab")
		)
		(fp_line
			(start -0.299974 0.150114)
			(end 0.299974 0.150114)
			(stroke
				(width 0.1)
				(type default)
			)
			(layer "B.Fab")
		)
		(pad "1" smd rect
			(at 0.2667 0 270)
			(size 0.3048 0.381)
			(layers "B.Cu" "B.Mask" "B.Paste")
			(net "P0V8_PEX3")
		)
		(pad "2" smd rect
			(at -0.2667 0 270)
			(size 0.3048 0.381)
			(layers "B.Cu" "B.Mask" "B.Paste")
			(net "GND")
		)
	)
	(footprint ""
		(layer "B.Cu")
		(at 172.424852 -297.79976 -90)
		(property "Reference" "C1404"
			(at 0 0 90)
			(layer "B.SilkS")
			(hide yes)
			(effects
				(font
					(size 1.27 1.27)
				)
				(justify mirror)
			)
		)
		(property "Value" ""
			(at 0 0 90)
			(layer "B.Fab")
			(effects
				(font
					(size 1.27 1.27)
				)
				(justify mirror)
			)
		)
		(duplicate_pad_numbers_are_jumpers no)
		(fp_line
			(start -0.299974 0.150114)
			(end 0.299974 0.150114)
			(stroke
				(width 0.1)
				(type default)
			)
			(layer "B.Fab")
		)
		(fp_line
			(start 0.299974 0.150114)
			(end 0.299974 -0.150114)
			(stroke
				(width 0.1)
				(type default)
			)
			(layer "B.Fab")
		)
		(fp_line
			(start -0.299974 -0.150114)
			(end -0.299974 0.150114)
			(stroke
				(width 0.1)
				(type default)
			)
			(layer "B.Fab")
		)
		(fp_line
			(start 0.299974 -0.150114)
			(end -0.299974 -0.150114)
			(stroke
				(width 0.1)
				(type default)
			)
			(layer "B.Fab")
		)
		(pad "1" smd rect
			(at 0.2667 0 90)
			(size 0.3048 0.381)
			(layers "B.Cu" "B.Mask" "B.Paste")
			(net "P0V8_PEX1")
		)
		(pad "2" smd rect
			(at -0.2667 0 90)
			(size 0.3048 0.381)
			(layers "B.Cu" "B.Mask" "B.Paste")
			(net "GND")
		)
	)
	(gr_poly
		(pts
			(xy 9.228836 -304.691034) (xy 9.228836 -304.340514) (xy 9.073896 -304.185574) (xy 7.144258 -304.185574)
			(xy 7.098284 -304.231548) (xy 7.098284 -304.681636) (xy 7.150862 -304.734214) (xy 9.185656 -304.734214)
		)
		(stroke
			(width 0)
			(type solid)
		)
		(fill yes)
		(layer "F.Cu")
		(net "P1V25_PEX0_VCC")
	)
	(gr_poly
		(pts
			(xy 10.62609 -156.307282) (xy 10.62609 -151.581358) (xy 10.517124 -151.472392) (xy 9.889998 -151.472392)
			(xy 9.763252 -151.599138) (xy 9.763252 -155.936696) (xy 10.14222 -156.315664) (xy 10.617708 -156.315664)
		)
		(stroke
			(width 0)
			(type solid)
		)
		(fill yes)
		(layer "F.Cu")
		(net "P12V_NIC0_CO_AVIN_PD")
	)
	(gr_poly
		(pts
			(xy 12.359894 -21.884894) (xy 12.359894 -18.637758) (xy 12.24661 -18.524474) (xy 10.113518 -18.524474)
			(xy 10.028428 -18.609564) (xy 10.028428 -21.946362) (xy 10.056622 -21.974556) (xy 12.270232 -21.974556)
		)
		(stroke
			(width 0)
			(type solid)
		)
		(fill yes)
		(layer "F.Cu")
		(net "GND")
	)
	(gr_poly
		(pts
			(xy 13.119608 -389.210296) (xy 13.119608 -383.808732) (xy 12.848844 -383.537968) (xy 7.48411 -383.537968)
			(xy 7.262622 -383.759456) (xy 7.262622 -389.370062) (xy 7.324344 -389.431784) (xy 12.89812 -389.431784)
		)
		(stroke
			(width 0)
			(type solid)
		)
		(fill yes)
		(layer "F.Cu")
		(net "GND")
	)
	(gr_poly
		(pts
			(xy 14.22273 -276.305772) (xy 14.22273 -274.703032) (xy 14.17701 -274.657312) (xy 12.585954 -274.657312)
			(xy 12.543536 -274.69973) (xy 12.543536 -276.322536) (xy 12.56919 -276.34819) (xy 14.180312 -276.34819)
		)
		(stroke
			(width 0)
			(type solid)
		)
		(fill yes)
		(layer "F.Cu")
		(net "GND")
	)
	(gr_poly
		(pts
			(xy 14.668246 -210.722972) (xy 14.668246 -209.300572) (xy 14.541246 -209.173572) (xy 13.982446 -209.173572)
			(xy 13.880846 -209.275172) (xy 13.880846 -210.799172) (xy 13.906246 -210.824572) (xy 14.566646 -210.824572)
		)
		(stroke
			(width 0)
			(type solid)
		)
		(fill yes)
		(layer "F.Cu")
		(net "P5V_AUX")
	)
	(gr_poly
		(pts
			(xy 19.028156 -168.479978) (xy 19.028156 -167.438578) (xy 19.002756 -167.413178) (xy 18.545556 -167.413178)
			(xy 18.520156 -167.438578) (xy 18.520156 -168.479978) (xy 18.570956 -168.530778) (xy 18.977356 -168.530778)
		)
		(stroke
			(width 0)
			(type solid)
		)
		(fill yes)
		(layer "F.Cu")
		(net "SW_P5V_AUX_BT")
	)
	(gr_poly
		(pts
			(xy 19.125946 -214.342472) (xy 19.125946 -213.821772) (xy 19.075146 -213.770972) (xy 18.097246 -213.770972)
			(xy 18.046446 -213.821772) (xy 18.046446 -214.380572) (xy 18.071846 -214.405972) (xy 19.062446 -214.405972)
		)
		(stroke
			(width 0)
			(type solid)
		)
		(fill yes)
		(layer "F.Cu")
		(net "PWRGD_PEX0_P1V8_PLL_R")
	)
	(gr_poly
		(pts
			(xy 20.145756 -167.667178) (xy 20.145756 -166.663878) (xy 20.069556 -166.587678) (xy 19.625056 -166.587678)
			(xy 19.536156 -166.676578) (xy 19.536156 -167.692578) (xy 19.612356 -167.768778) (xy 20.044156 -167.768778)
		)
		(stroke
			(width 0)
			(type solid)
		)
		(fill yes)
		(layer "F.Cu")
		(net "GND")
	)
	(gr_poly
		(pts
			(xy 21.268182 -170.63212) (xy 21.268182 -170.1165) (xy 21.144992 -169.99331) (xy 20.380706 -169.99331)
			(xy 20.300442 -170.073574) (xy 20.300442 -170.744896) (xy 20.3454 -170.789854) (xy 21.110448 -170.789854)
		)
		(stroke
			(width 0)
			(type solid)
		)
		(fill yes)
		(layer "F.Cu")
		(net "P5V_AUX_EN")
	)
	(gr_poly
		(pts
			(xy 21.669756 -174.499778) (xy 21.669756 -174.042578) (xy 21.644356 -174.017178) (xy 20.577556 -174.017178)
			(xy 20.526756 -174.067978) (xy 20.526756 -174.474378) (xy 20.577556 -174.525178) (xy 21.644356 -174.525178)
		)
		(stroke
			(width 0)
			(type solid)
		)
		(fill yes)
		(layer "F.Cu")
		(net "P5V_AUX")
	)
	(gr_poly
		(pts
			(xy 22.533356 -174.093378) (xy 22.533356 -173.026578) (xy 22.507956 -173.001178) (xy 22.050756 -173.001178)
			(xy 22.025356 -173.026578) (xy 22.025356 -174.093378) (xy 22.076156 -174.144178) (xy 22.482556 -174.144178)
		)
		(stroke
			(width 0)
			(type solid)
		)
		(fill yes)
		(layer "F.Cu")
		(net "GND")
	)
	(gr_poly
		(pts
			(xy 38.359842 -21.884894) (xy 38.359842 -18.637758) (xy 38.246558 -18.524474) (xy 36.113466 -18.524474)
			(xy 36.028376 -18.609564) (xy 36.028376 -21.946362) (xy 36.05657 -21.974556) (xy 38.27018 -21.974556)
		)
		(stroke
			(width 0)
			(type solid)
		)
		(fill yes)
		(layer "F.Cu")
		(net "GND")
	)
	(gr_poly
		(pts
			(xy 64.35979 -21.884894) (xy 64.35979 -18.637758) (xy 64.246506 -18.524474) (xy 62.113414 -18.524474)
			(xy 62.028324 -18.609564) (xy 62.028324 -21.946362) (xy 62.056518 -21.974556) (xy 64.270128 -21.974556)
		)
		(stroke
			(width 0)
			(type solid)
		)
		(fill yes)
		(layer "F.Cu")
		(net "GND")
	)
	(gr_poly
		(pts
			(xy 69.457824 -112.152176) (xy 69.457824 -109.0676) (xy 69.37756 -108.987336) (xy 67.384168 -108.987336)
			(xy 67.281044 -109.09046) (xy 67.281044 -112.00003) (xy 67.546728 -112.265714) (xy 69.344286 -112.265714)
		)
		(stroke
			(width 0)
			(type solid)
		)
		(fill yes)
		(layer "F.Cu")
		(net "GND")
	)
	(gr_poly
		(pts
			(xy 90.359738 -21.884894) (xy 90.359738 -18.637758) (xy 90.246454 -18.524474) (xy 88.113362 -18.524474)
			(xy 88.028272 -18.609564) (xy 88.028272 -21.946362) (xy 88.056466 -21.974556) (xy 90.270076 -21.974556)
		)
		(stroke
			(width 0)
			(type solid)
		)
		(fill yes)
		(layer "F.Cu")
		(net "GND")
	)
	(gr_poly
		(pts
			(xy 92.15501 -101.027738) (xy 92.15501 -99.416616) (xy 92.112592 -99.374198) (xy 90.509852 -99.374198)
			(xy 90.464132 -99.419918) (xy 90.464132 -101.010974) (xy 90.50655 -101.053392) (xy 92.129356 -101.053392)
		)
		(stroke
			(width 0)
			(type solid)
		)
		(fill yes)
		(layer "F.Cu")
		(net "GND")
	)
	(gr_poly
		(pts
			(xy 102.480872 -216.372186) (xy 102.480872 -213.7283) (xy 102.30993 -213.557358) (xy 100.977954 -213.557358)
			(xy 100.829872 -213.70544) (xy 100.829872 -216.326466) (xy 100.989638 -216.486232) (xy 102.366826 -216.486232)
		)
		(stroke
			(width 0)
			(type solid)
		)
		(fill yes)
		(layer "F.Cu")
		(net "GND")
	)
	(gr_poly
		(pts
			(xy 105.8418 -195.834) (xy 105.8418 -191.6938) (xy 105.7656 -191.6176) (xy 101.6254 -191.6176) (xy 101.5746 -191.6684)
			(xy 101.5746 -195.8594) (xy 101.6 -195.8848) (xy 105.791 -195.8848)
		)
		(stroke
			(width 0)
			(type solid)
		)
		(fill yes)
		(layer "F.Cu")
		(net "GND")
	)
	(gr_poly
		(pts
			(xy 106.623612 -114.138202) (xy 106.623612 -113.662714) (xy 106.61523 -113.654332) (xy 101.643434 -113.654332)
			(xy 101.608382 -113.689384) (xy 101.608382 -114.395504) (xy 101.730048 -114.51717) (xy 106.244644 -114.51717)
		)
		(stroke
			(width 0)
			(type solid)
		)
		(fill yes)
		(layer "F.Cu")
		(net "P12V_NIC1_CO_AVIN_PD")
	)
	(gr_poly
		(pts
			(xy 108.232956 -238.798354) (xy 108.232956 -237.655354) (xy 108.105956 -237.528354) (xy 99.088956 -237.528354)
			(xy 98.961956 -237.655354) (xy 98.961956 -238.925354) (xy 99.088956 -239.052354) (xy 107.978956 -239.052354)
		)
		(stroke
			(width 0)
			(type solid)
		)
		(fill yes)
		(layer "F.Cu")
		(net "GND")
	)
	(gr_poly
		(pts
			(xy 108.881164 -159.181292) (xy 108.881164 -158.830772) (xy 108.726224 -158.675832) (xy 106.796586 -158.675832)
			(xy 106.750612 -158.721806) (xy 106.750612 -159.171894) (xy 106.80319 -159.224472) (xy 108.837984 -159.224472)
		)
		(stroke
			(width 0)
			(type solid)
		)
		(fill yes)
		(layer "F.Cu")
		(net "P3V3_AUX_VCC")
	)
	(gr_poly
		(pts
			(xy 108.901738 -224.75698) (xy 108.901738 -224.306892) (xy 108.84916 -224.254314) (xy 106.814366 -224.254314)
			(xy 106.771186 -224.297494) (xy 106.771186 -224.648014) (xy 106.926126 -224.802954) (xy 108.855764 -224.802954)
		)
		(stroke
			(width 0)
			(type solid)
		)
		(fill yes)
		(layer "F.Cu")
		(net "P1V8_PEX_VCC")
	)
	(gr_poly
		(pts
			(xy 126.725934 -156.307282) (xy 126.725934 -151.461216) (xy 126.669038 -151.40432) (xy 125.978158 -151.40432)
			(xy 125.863096 -151.519382) (xy 125.863096 -155.936696) (xy 126.242064 -156.315664) (xy 126.717552 -156.315664)
		)
		(stroke
			(width 0)
			(type solid)
		)
		(fill yes)
		(layer "F.Cu")
		(net "P12V_NIC2_CO_AVIN_PD")
	)
	(gr_poly
		(pts
			(xy 128.459992 -21.884894) (xy 128.459992 -18.637758) (xy 128.346708 -18.524474) (xy 126.213616 -18.524474)
			(xy 126.128526 -18.609564) (xy 126.128526 -21.946362) (xy 126.15672 -21.974556) (xy 128.37033 -21.974556)
		)
		(stroke
			(width 0)
			(type solid)
		)
		(fill yes)
		(layer "F.Cu")
		(net "GND")
	)
	(gr_poly
		(pts
			(xy 134.741412 -74.937874) (xy 134.741412 -70.840346) (xy 134.680198 -70.779132) (xy 130.425698 -70.779132)
			(xy 130.10261 -71.10222) (xy 130.10261 -75.164696) (xy 131.002532 -76.064618) (xy 133.614668 -76.064618)
		)
		(stroke
			(width 0)
			(type solid)
		)
		(fill yes)
		(layer "F.Cu")
		(net "GND")
	)
	(gr_poly
		(pts
			(xy 145.999962 -239.701578) (xy 145.999962 -238.279178) (xy 145.872962 -238.152178) (xy 145.314162 -238.152178)
			(xy 145.212562 -238.253778) (xy 145.212562 -239.777778) (xy 145.237962 -239.803178) (xy 145.898362 -239.803178)
		)
		(stroke
			(width 0)
			(type solid)
		)
		(fill yes)
		(layer "F.Cu")
		(net "P5V_AUX")
	)
	(gr_poly
		(pts
			(xy 150.457662 -243.321078) (xy 150.457662 -242.800378) (xy 150.406862 -242.749578) (xy 149.428962 -242.749578)
			(xy 149.378162 -242.800378) (xy 149.378162 -243.359178) (xy 149.403562 -243.384578) (xy 150.394162 -243.384578)
		)
		(stroke
			(width 0)
			(type solid)
		)
		(fill yes)
		(layer "F.Cu")
		(net "PWRGD_PEX1_P1V8_PLL_R")
	)
	(gr_poly
		(pts
			(xy 154.45994 -21.884894) (xy 154.45994 -18.637758) (xy 154.346656 -18.524474) (xy 152.213564 -18.524474)
			(xy 152.128474 -18.609564) (xy 152.128474 -21.946362) (xy 152.156668 -21.974556) (xy 154.370278 -21.974556)
		)
		(stroke
			(width 0)
			(type solid)
		)
		(fill yes)
		(layer "F.Cu")
		(net "GND")
	)
	(gr_poly
		(pts
			(xy 160.74136 -74.937874) (xy 160.74136 -70.840346) (xy 160.680146 -70.779132) (xy 156.425646 -70.779132)
			(xy 156.102558 -71.10222) (xy 156.102558 -75.164696) (xy 157.00248 -76.064618) (xy 159.614616 -76.064618)
		)
		(stroke
			(width 0)
			(type solid)
		)
		(fill yes)
		(layer "F.Cu")
		(net "GND")
	)
	(gr_poly
		(pts
			(xy 180.459888 -21.884894) (xy 180.459888 -18.637758) (xy 180.346604 -18.524474) (xy 178.213512 -18.524474)
			(xy 178.128422 -18.609564) (xy 178.128422 -21.946362) (xy 178.156616 -21.974556) (xy 180.370226 -21.974556)
		)
		(stroke
			(width 0)
			(type solid)
		)
		(fill yes)
		(layer "F.Cu")
		(net "GND")
	)
	(gr_poly
		(pts
			(xy 185.557668 -112.130332) (xy 185.557668 -109.0676) (xy 185.477404 -108.987336) (xy 183.484012 -108.987336)
			(xy 183.380888 -109.09046) (xy 183.380888 -111.879888) (xy 183.766714 -112.265714) (xy 185.422286 -112.265714)
		)
		(stroke
			(width 0)
			(type solid)
		)
		(fill yes)
		(layer "F.Cu")
		(net "GND")
	)
	(gr_poly
		(pts
			(xy 186.741308 -74.937874) (xy 186.741308 -70.840346) (xy 186.680094 -70.779132) (xy 182.425594 -70.779132)
			(xy 182.102506 -71.10222) (xy 182.102506 -75.164696) (xy 183.002428 -76.064618) (xy 185.614564 -76.064618)
		)
		(stroke
			(width 0)
			(type solid)
		)
		(fill yes)
		(layer "F.Cu")
		(net "GND")
	)
	(gr_poly
		(pts
			(xy 206.459836 -21.884894) (xy 206.459836 -18.637758) (xy 206.346552 -18.524474) (xy 204.21346 -18.524474)
			(xy 204.12837 -18.609564) (xy 204.12837 -21.946362) (xy 204.156564 -21.974556) (xy 206.370174 -21.974556)
		)
		(stroke
			(width 0)
			(type solid)
		)
		(fill yes)
		(layer "F.Cu")
		(net "GND")
	)
	(gr_poly
		(pts
			(xy 212.741256 -74.937874) (xy 212.741256 -70.840346) (xy 212.680042 -70.779132) (xy 208.425542 -70.779132)
			(xy 208.102454 -71.10222) (xy 208.102454 -75.164696) (xy 208.756758 -75.819) (xy 211.86013 -75.819)
		)
		(stroke
			(width 0)
			(type solid)
		)
		(fill yes)
		(layer "F.Cu")
		(net "GND")
	)
	(gr_poly
		(pts
			(xy 223.526096 -306.977796) (xy 223.526096 -306.627276) (xy 223.371156 -306.472336) (xy 221.441518 -306.472336)
			(xy 221.395544 -306.51831) (xy 221.395544 -306.968398) (xy 221.448122 -307.020976) (xy 223.482916 -307.020976)
		)
		(stroke
			(width 0)
			(type solid)
		)
		(fill yes)
		(layer "F.Cu")
		(net "P1V25_PEX1_VCC")
	)
	(gr_poly
		(pts
			(xy 229.28199 -278.592534) (xy 229.28199 -276.989794) (xy 229.23627 -276.944074) (xy 227.645214 -276.944074)
			(xy 227.602796 -276.986492) (xy 227.602796 -278.609298) (xy 227.62845 -278.634952) (xy 229.239572 -278.634952)
		)
		(stroke
			(width 0)
			(type solid)
		)
		(fill yes)
		(layer "F.Cu")
		(net "GND")
	)
	(gr_poly
		(pts
			(xy 232.436416 -118.288816) (xy 232.436416 -117.813328) (xy 232.428034 -117.804946) (xy 227.456238 -117.804946)
			(xy 227.350828 -117.910356) (xy 227.350828 -118.61419) (xy 227.404422 -118.667784) (xy 232.057448 -118.667784)
		)
		(stroke
			(width 0)
			(type solid)
		)
		(fill yes)
		(layer "F.Cu")
		(net "P12V_NIC3_CO_AVIN_PD")
	)
	(gr_poly
		(pts
			(xy 239.776254 -306.977796) (xy 239.776254 -306.627276) (xy 239.621314 -306.472336) (xy 237.691676 -306.472336)
			(xy 237.645702 -306.51831) (xy 237.645702 -306.968398) (xy 237.69828 -307.020976) (xy 239.733074 -307.020976)
		)
		(stroke
			(width 0)
			(type solid)
		)
		(fill yes)
		(layer "F.Cu")
		(net "P1V25_PEX2_VCC")
	)
	(gr_poly
		(pts
			(xy 244.559836 -21.884894) (xy 244.559836 -18.637758) (xy 244.446552 -18.524474) (xy 242.31346 -18.524474)
			(xy 242.22837 -18.609564) (xy 242.22837 -21.946362) (xy 242.256564 -21.974556) (xy 244.470174 -21.974556)
		)
		(stroke
			(width 0)
			(type solid)
		)
		(fill yes)
		(layer "F.Cu")
		(net "GND")
	)
	(gr_poly
		(pts
			(xy 245.532148 -278.592534) (xy 245.532148 -276.989794) (xy 245.486428 -276.944074) (xy 243.895372 -276.944074)
			(xy 243.852954 -276.986492) (xy 243.852954 -278.609298) (xy 243.878608 -278.634952) (xy 245.48973 -278.634952)
		)
		(stroke
			(width 0)
			(type solid)
		)
		(fill yes)
		(layer "F.Cu")
		(net "GND")
	)
	(gr_poly
		(pts
			(xy 250.841256 -74.937874) (xy 250.841256 -70.840346) (xy 250.780042 -70.779132) (xy 246.525542 -70.779132)
			(xy 246.202454 -71.10222) (xy 246.202454 -75.164696) (xy 247.102376 -76.064618) (xy 249.714512 -76.064618)
		)
		(stroke
			(width 0)
			(type solid)
		)
		(fill yes)
		(layer "F.Cu")
		(net "GND")
	)
	(gr_poly
		(pts
			(xy 258.170426 -238.943388) (xy 258.170426 -237.520988) (xy 258.043426 -237.393988) (xy 257.484626 -237.393988)
			(xy 257.383026 -237.495588) (xy 257.383026 -239.019588) (xy 257.408426 -239.044988) (xy 258.068826 -239.044988)
		)
		(stroke
			(width 0)
			(type solid)
		)
		(fill yes)
		(layer "F.Cu")
		(net "P5V_AUX")
	)
	(gr_poly
		(pts
			(xy 262.628126 -242.562888) (xy 262.628126 -242.042188) (xy 262.577326 -241.991388) (xy 261.599426 -241.991388)
			(xy 261.548626 -242.042188) (xy 261.548626 -242.600988) (xy 261.574026 -242.626388) (xy 262.564626 -242.626388)
		)
		(stroke
			(width 0)
			(type solid)
		)
		(fill yes)
		(layer "F.Cu")
		(net "PWRGD_PEX2_P1V8_PLL_R")
	)
	(gr_poly
		(pts
			(xy 270.559784 -21.884894) (xy 270.559784 -18.637758) (xy 270.4465 -18.524474) (xy 268.313408 -18.524474)
			(xy 268.228318 -18.609564) (xy 268.228318 -21.946362) (xy 268.256512 -21.974556) (xy 270.470122 -21.974556)
		)
		(stroke
			(width 0)
			(type solid)
		)
		(fill yes)
		(layer "F.Cu")
		(net "GND")
	)
	(gr_poly
		(pts
			(xy 276.841204 -74.937874) (xy 276.841204 -70.840346) (xy 276.77999 -70.779132) (xy 272.52549 -70.779132)
			(xy 272.202402 -71.10222) (xy 272.202402 -74.844402) (xy 273.422618 -76.064618) (xy 275.71446 -76.064618)
		)
		(stroke
			(width 0)
			(type solid)
		)
		(fill yes)
		(layer "F.Cu")
		(net "GND")
	)
	(gr_poly
		(pts
			(xy 296.559732 -21.884894) (xy 296.559732 -18.637758) (xy 296.446448 -18.524474) (xy 294.313356 -18.524474)
			(xy 294.228266 -18.609564) (xy 294.228266 -21.946362) (xy 294.25646 -21.974556) (xy 296.47007 -21.974556)
		)
		(stroke
			(width 0)
			(type solid)
		)
		(fill yes)
		(layer "F.Cu")
		(net "GND")
	)
	(gr_poly
		(pts
			(xy 301.657766 -112.108234) (xy 301.657766 -109.0676) (xy 301.577502 -108.987336) (xy 299.58411 -108.987336)
			(xy 299.480986 -109.09046) (xy 299.480986 -111.901986) (xy 299.844714 -112.265714) (xy 301.500286 -112.265714)
		)
		(stroke
			(width 0)
			(type solid)
		)
		(fill yes)
		(layer "F.Cu")
		(net "GND")
	)
	(gr_poly
		(pts
			(xy 302.841152 -74.937874) (xy 302.841152 -70.840346) (xy 302.779938 -70.779132) (xy 298.525438 -70.779132)
			(xy 298.20235 -71.10222) (xy 298.20235 -75.164696) (xy 299.102272 -76.064618) (xy 301.714408 -76.064618)
		)
		(stroke
			(width 0)
			(type solid)
		)
		(fill yes)
		(layer "F.Cu")
		(net "GND")
	)
	(gr_poly
		(pts
			(xy 322.55968 -21.884894) (xy 322.55968 -18.637758) (xy 322.446396 -18.524474) (xy 320.313304 -18.524474)
			(xy 320.228214 -18.609564) (xy 320.228214 -21.946362) (xy 320.256408 -21.974556) (xy 322.470018 -21.974556)
		)
		(stroke
			(width 0)
			(type solid)
		)
		(fill yes)
		(layer "F.Cu")
		(net "GND")
	)
	(gr_poly
		(pts
			(xy 324.354952 -101.027738) (xy 324.354952 -99.416616) (xy 324.312534 -99.374198) (xy 322.709794 -99.374198)
			(xy 322.664074 -99.419918) (xy 322.664074 -101.010974) (xy 322.706492 -101.053392) (xy 324.329298 -101.053392)
		)
		(stroke
			(width 0)
			(type solid)
		)
		(fill yes)
		(layer "F.Cu")
		(net "GND")
	)
	(gr_poly
		(pts
			(xy 328.8411 -74.937874) (xy 328.8411 -70.840346) (xy 328.779886 -70.779132) (xy 324.525386 -70.779132)
			(xy 324.202298 -71.10222) (xy 324.202298 -75.164696) (xy 325.10222 -76.064618) (xy 327.714356 -76.064618)
		)
		(stroke
			(width 0)
			(type solid)
		)
		(fill yes)
		(layer "F.Cu")
		(net "GND")
	)
	(gr_poly
		(pts
			(xy 338.581746 -271.671796) (xy 338.581746 -268.645894) (xy 338.425536 -268.489684) (xy 334.7593 -268.489684)
			(xy 334.503014 -268.74597) (xy 334.503014 -271.620996) (xy 334.844136 -271.962118) (xy 338.291424 -271.962118)
		)
		(stroke
			(width 0)
			(type solid)
		)
		(fill yes)
		(layer "F.Cu")
		(net "P12V_AUX")
	)
	(gr_poly
		(pts
			(xy 338.823554 -114.138202) (xy 338.823554 -113.662714) (xy 338.815172 -113.654332) (xy 333.843376 -113.654332)
			(xy 333.735426 -113.762282) (xy 333.735426 -114.461036) (xy 333.79156 -114.51717) (xy 338.444586 -114.51717)
		)
		(stroke
			(width 0)
			(type solid)
		)
		(fill yes)
		(layer "F.Cu")
		(net "P12V_NIC5_CO_AVIN_PD")
	)
	(gr_poly
		(pts
			(xy 358.90073 -156.28747) (xy 358.90073 -151.48433) (xy 358.8512 -151.4348) (xy 358.190292 -151.4348)
			(xy 358.063292 -151.5618) (xy 358.063292 -155.936696) (xy 358.44226 -156.315664) (xy 358.872536 -156.315664)
		)
		(stroke
			(width 0)
			(type solid)
		)
		(fill yes)
		(layer "F.Cu")
		(net "P12V_NIC6_CO_AVIN_PD")
	)
	(gr_poly
		(pts
			(xy 360.659934 -21.884894) (xy 360.659934 -18.637758) (xy 360.54665 -18.524474) (xy 358.413558 -18.524474)
			(xy 358.328468 -18.609564) (xy 358.328468 -21.946362) (xy 358.356662 -21.974556) (xy 360.570272 -21.974556)
		)
		(stroke
			(width 0)
			(type solid)
		)
		(fill yes)
		(layer "F.Cu")
		(net "GND")
	)
	(gr_poly
		(pts
			(xy 366.941354 -74.937874) (xy 366.941354 -70.840346) (xy 366.88014 -70.779132) (xy 362.62564 -70.779132)
			(xy 362.302552 -71.10222) (xy 362.302552 -75.164696) (xy 363.202474 -76.064618) (xy 365.81461 -76.064618)
		)
		(stroke
			(width 0)
			(type solid)
		)
		(fill yes)
		(layer "F.Cu")
		(net "GND")
	)
	(gr_poly
		(pts
			(xy 386.659882 -21.884894) (xy 386.659882 -18.637758) (xy 386.546598 -18.524474) (xy 384.413506 -18.524474)
			(xy 384.328416 -18.609564) (xy 384.328416 -21.946362) (xy 384.35661 -21.974556) (xy 386.57022 -21.974556)
		)
		(stroke
			(width 0)
			(type solid)
		)
		(fill yes)
		(layer "F.Cu")
		(net "GND")
	)
	(gr_poly
		(pts
			(xy 392.941302 -74.937874) (xy 392.941302 -70.840346) (xy 392.880088 -70.779132) (xy 388.625588 -70.779132)
			(xy 388.3025 -71.10222) (xy 388.3025 -75.164696) (xy 389.202422 -76.064618) (xy 391.814558 -76.064618)
		)
		(stroke
			(width 0)
			(type solid)
		)
		(fill yes)
		(layer "F.Cu")
		(net "GND")
	)
	(gr_poly
		(pts
			(xy 412.65983 -21.884894) (xy 412.65983 -18.637758) (xy 412.546546 -18.524474) (xy 410.413454 -18.524474)
			(xy 410.328364 -18.609564) (xy 410.328364 -21.946362) (xy 410.356558 -21.974556) (xy 412.570168 -21.974556)
		)
		(stroke
			(width 0)
			(type solid)
		)
		(fill yes)
		(layer "F.Cu")
		(net "GND")
	)
	(gr_poly
		(pts
			(xy 417.757864 -112.213136) (xy 417.757864 -109.0676) (xy 417.6776 -108.987336) (xy 415.684208 -108.987336)
			(xy 415.581084 -109.09046) (xy 415.581084 -111.924084) (xy 415.922714 -112.265714) (xy 417.705286 -112.265714)
		)
		(stroke
			(width 0)
			(type solid)
		)
		(fill yes)
		(layer "F.Cu")
		(net "GND")
	)
	(gr_poly
		(pts
			(xy 418.94125 -74.937874) (xy 418.94125 -70.840346) (xy 418.880036 -70.779132) (xy 414.625536 -70.779132)
			(xy 414.302448 -71.10222) (xy 414.302448 -75.164696) (xy 415.20237 -76.064618) (xy 417.814506 -76.064618)
		)
		(stroke
			(width 0)
			(type solid)
		)
		(fill yes)
		(layer "F.Cu")
		(net "GND")
	)
	(gr_poly
		(pts
			(xy 438.659778 -21.884894) (xy 438.659778 -18.637758) (xy 438.546494 -18.524474) (xy 436.413402 -18.524474)
			(xy 436.328312 -18.609564) (xy 436.328312 -21.946362) (xy 436.356506 -21.974556) (xy 438.570116 -21.974556)
		)
		(stroke
			(width 0)
			(type solid)
		)
		(fill yes)
		(layer "F.Cu")
		(net "GND")
	)
	(gr_poly
		(pts
			(xy 440.45505 -101.027738) (xy 440.45505 -99.416616) (xy 440.412632 -99.374198) (xy 438.809892 -99.374198)
			(xy 438.764172 -99.419918) (xy 438.764172 -101.010974) (xy 438.80659 -101.053392) (xy 440.429396 -101.053392)
		)
		(stroke
			(width 0)
			(type solid)
		)
		(fill yes)
		(layer "F.Cu")
		(net "GND")
	)
	(gr_poly
		(pts
			(xy 444.941198 -74.937874) (xy 444.941198 -70.840346) (xy 444.879984 -70.779132) (xy 440.625484 -70.779132)
			(xy 440.302396 -71.10222) (xy 440.302396 -75.164696) (xy 441.202318 -76.064618) (xy 443.814454 -76.064618)
		)
		(stroke
			(width 0)
			(type solid)
		)
		(fill yes)
		(layer "F.Cu")
		(net "GND")
	)
	(gr_poly
		(pts
			(xy 454.147174 -307.10124) (xy 454.147174 -306.75072) (xy 453.992234 -306.59578) (xy 452.062596 -306.59578)
			(xy 452.016622 -306.641754) (xy 452.016622 -307.091842) (xy 452.06412 -307.13934) (xy 454.109074 -307.13934)
		)
		(stroke
			(width 0)
			(type solid)
		)
		(fill yes)
		(layer "F.Cu")
		(net "P1V25_PEX3_VCC")
	)
	(gr_poly
		(pts
			(xy 454.5076 -229.4382) (xy 454.5076 -225.425) (xy 454.3806 -225.298) (xy 450.3928 -225.298) (xy 450.2404 -225.4504)
			(xy 450.2404 -229.4636) (xy 450.342 -229.5652) (xy 454.3806 -229.5652)
		)
		(stroke
			(width 0)
			(type solid)
		)
		(fill yes)
		(layer "F.Cu")
		(net "GND")
	)
	(gr_poly
		(pts
			(xy 454.923652 -114.138202) (xy 454.923652 -113.662714) (xy 454.91527 -113.654332) (xy 449.943474 -113.654332)
			(xy 449.848224 -113.749582) (xy 449.848224 -114.473736) (xy 449.891658 -114.51717) (xy 454.544684 -114.51717)
		)
		(stroke
			(width 0)
			(type solid)
		)
		(fill yes)
		(layer "F.Cu")
		(net "P12V_NIC7_CO_AVIN_PD")
	)
	(gr_poly
		(pts
			(xy 454.930002 -246.77624) (xy 454.930002 -245.35384) (xy 454.803002 -245.22684) (xy 454.244202 -245.22684)
			(xy 454.142602 -245.32844) (xy 454.142602 -246.85244) (xy 454.168002 -246.87784) (xy 454.828402 -246.87784)
		)
		(stroke
			(width 0)
			(type solid)
		)
		(fill yes)
		(layer "F.Cu")
		(net "P5V_AUX")
	)
	(gr_poly
		(pts
			(xy 459.387702 -250.39574) (xy 459.387702 -249.87504) (xy 459.336902 -249.82424) (xy 458.359002 -249.82424)
			(xy 458.308202 -249.87504) (xy 458.308202 -250.43384) (xy 458.333602 -250.45924) (xy 459.324202 -250.45924)
		)
		(stroke
			(width 0)
			(type solid)
		)
		(fill yes)
		(layer "F.Cu")
		(net "PWRGD_PEX3_P1V8_PLL_R")
	)
	(gr_poly
		(pts
			(xy 459.903068 -278.715978) (xy 459.903068 -277.113238) (xy 459.857348 -277.067518) (xy 458.266292 -277.067518)
			(xy 458.223874 -277.109936) (xy 458.223874 -278.732742) (xy 458.249528 -278.758396) (xy 459.86065 -278.758396)
		)
		(stroke
			(width 0)
			(type solid)
		)
		(fill yes)
		(layer "F.Cu")
		(net "GND")
	)
	(gr_poly
		(pts
			(xy 5.476494 -53.081936) (xy 5.754878 -52.803552) (xy 5.754878 -47.507398) (xy 5.51434 -47.26686)
			(xy 2.778252 -47.26686) (xy 2.411476 -47.633636) (xy 2.411476 -53.329586) (xy 2.62128 -53.53939)
			(xy 5.01904 -53.53939)
		)
		(stroke
			(width 0)
			(type solid)
		)
		(fill yes)
		(layer "F.Cu")
		(net "GND")
	)
	(gr_poly
		(pts
			(xy 8.087614 -173.374812) (xy 8.087614 -168.207436) (xy 7.852664 -167.972486) (xy 5.96265 -167.972486)
			(xy 5.624576 -168.31056) (xy 5.624576 -173.304708) (xy 5.856986 -173.537118) (xy 6.205474 -173.537118)
			(xy 7.925308 -173.537118)
		)
		(stroke
			(width 0)
			(type solid)
		)
		(fill yes)
		(layer "F.Cu")
		(net "GND")
	)
	(gr_poly
		(pts
			(xy 15.838932 -163.249864) (xy 15.838932 -163.11118) (xy 15.838932 -162.15995) (xy 15.766542 -162.08756)
			(xy 8.715248 -162.08756) (xy 8.63219 -162.170618) (xy 8.63219 -163.162996) (xy 8.77697 -163.307776)
			(xy 15.78102 -163.307776)
		)
		(stroke
			(width 0)
			(type solid)
		)
		(fill yes)
		(layer "F.Cu")
		(net "GND")
	)
	(gr_poly
		(pts
			(xy 19.147536 -23.92045) (xy 19.147536 -23.150576) (xy 19.056604 -23.059644) (xy 17.236186 -23.059644)
			(xy 17.22628 -23.049738) (xy 17.155922 -23.120096) (xy 17.155922 -24.123904) (xy 17.175988 -24.14397)
			(xy 18.924016 -24.14397)
		)
		(stroke
			(width 0)
			(type solid)
		)
		(fill yes)
		(layer "F.Cu")
		(net "GND")
	)
	(gr_poly
		(pts
			(xy 22.128226 -123.768104) (xy 22.128226 -121.032016) (xy 21.76145 -120.66524) (xy 16.0655 -120.66524)
			(xy 15.855696 -120.875044) (xy 15.855696 -123.272804) (xy 16.31315 -123.730258) (xy 16.591534 -124.008642)
			(xy 21.887688 -124.008642)
		)
		(stroke
			(width 0)
			(type solid)
		)
		(fill yes)
		(layer "F.Cu")
		(net "GND")
	)
	(gr_poly
		(pts
			(xy 31.476442 -53.081936) (xy 31.754826 -52.803552) (xy 31.754826 -47.507398) (xy 31.514288 -47.26686)
			(xy 28.7782 -47.26686) (xy 28.411424 -47.633636) (xy 28.411424 -53.329586) (xy 28.621228 -53.53939)
			(xy 31.018988 -53.53939)
		)
		(stroke
			(width 0)
			(type solid)
		)
		(fill yes)
		(layer "F.Cu")
		(net "GND")
	)
	(gr_poly
		(pts
			(xy 57.47639 -53.081936) (xy 57.754774 -52.803552) (xy 57.754774 -47.507398) (xy 57.514236 -47.26686)
			(xy 54.778148 -47.26686) (xy 54.411372 -47.633636) (xy 54.411372 -53.329586) (xy 54.621176 -53.53939)
			(xy 57.018936 -53.53939)
		)
		(stroke
			(width 0)
			(type solid)
		)
		(fill yes)
		(layer "F.Cu")
		(net "GND")
	)
	(gr_poly
		(pts
			(xy 83.476338 -53.081936) (xy 83.754722 -52.803552) (xy 83.754722 -47.507398) (xy 83.514184 -47.26686)
			(xy 80.778096 -47.26686) (xy 80.41132 -47.633636) (xy 80.41132 -53.329586) (xy 80.621124 -53.53939)
			(xy 83.018884 -53.53939)
		)
		(stroke
			(width 0)
			(type solid)
		)
		(fill yes)
		(layer "F.Cu")
		(net "GND")
	)
	(gr_poly
		(pts
			(xy 93.796866 -126.064772) (xy 93.796866 -123.667012) (xy 93.339412 -123.209558) (xy 93.061028 -122.931174)
			(xy 87.764874 -122.931174) (xy 87.524336 -123.171712) (xy 87.524336 -125.9078) (xy 87.891112 -126.274576)
			(xy 93.587062 -126.274576)
		)
		(stroke
			(width 0)
			(type solid)
		)
		(fill yes)
		(layer "F.Cu")
		(net "GND")
	)
	(gr_poly
		(pts
			(xy 112.607344 -181.025546) (xy 112.607344 -180.517546) (xy 112.607344 -178.739546) (xy 112.480344 -178.612546)
			(xy 108.149644 -178.612546) (xy 107.972352 -178.789838) (xy 107.972352 -181.176168) (xy 108.07573 -181.279546)
			(xy 112.353344 -181.279546)
		)
		(stroke
			(width 0)
			(type solid)
		)
		(fill yes)
		(layer "F.Cu")
		(net "P12V_AUX")
	)
	(gr_poly
		(pts
			(xy 113.615724 -115.503452) (xy 113.615724 -108.499402) (xy 113.557812 -108.44149) (xy 113.419128 -108.44149)
			(xy 112.467898 -108.44149) (xy 112.395508 -108.51388) (xy 112.395508 -115.565174) (xy 112.478566 -115.648232)
			(xy 113.470944 -115.648232)
		)
		(stroke
			(width 0)
			(type solid)
		)
		(fill yes)
		(layer "F.Cu")
		(net "GND")
	)
	(gr_poly
		(pts
			(xy 119.584216 -137.25906) (xy 119.584216 -134.08152) (xy 119.231156 -133.72846) (xy 106.037634 -133.72846)
			(xy 105.765854 -134.00024) (xy 105.765854 -137.202164) (xy 105.97515 -137.41146) (xy 119.381016 -137.41146)
			(xy 119.431816 -137.41146)
		)
		(stroke
			(width 0)
			(type solid)
		)
		(fill yes)
		(layer "F.Cu")
		(net "GND")
	)
	(gr_poly
		(pts
			(xy 121.576592 -53.081936) (xy 121.854976 -52.803552) (xy 121.854976 -47.507398) (xy 121.614438 -47.26686)
			(xy 118.87835 -47.26686) (xy 118.511574 -47.633636) (xy 118.511574 -53.329586) (xy 118.721378 -53.53939)
			(xy 121.119138 -53.53939)
		)
		(stroke
			(width 0)
			(type solid)
		)
		(fill yes)
		(layer "F.Cu")
		(net "GND")
	)
	(gr_poly
		(pts
			(xy 131.938776 -163.249864) (xy 131.938776 -163.11118) (xy 131.938776 -162.15995) (xy 131.866386 -162.08756)
			(xy 124.815092 -162.08756) (xy 124.732034 -162.170618) (xy 124.732034 -163.162996) (xy 124.876814 -163.307776)
			(xy 131.880864 -163.307776)
		)
		(stroke
			(width 0)
			(type solid)
		)
		(fill yes)
		(layer "F.Cu")
		(net "GND")
	)
	(gr_poly
		(pts
			(xy 138.22807 -123.768104) (xy 138.22807 -121.032016) (xy 137.861294 -120.66524) (xy 132.165344 -120.66524)
			(xy 131.95554 -120.875044) (xy 131.95554 -123.272804) (xy 132.412994 -123.730258) (xy 132.691378 -124.008642)
			(xy 137.987532 -124.008642)
		)
		(stroke
			(width 0)
			(type solid)
		)
		(fill yes)
		(layer "F.Cu")
		(net "GND")
	)
	(gr_poly
		(pts
			(xy 147.57654 -53.081936) (xy 147.854924 -52.803552) (xy 147.854924 -47.507398) (xy 147.614386 -47.26686)
			(xy 144.878298 -47.26686) (xy 144.511522 -47.633636) (xy 144.511522 -53.329586) (xy 144.721326 -53.53939)
			(xy 147.119086 -53.53939)
		)
		(stroke
			(width 0)
			(type solid)
		)
		(fill yes)
		(layer "F.Cu")
		(net "GND")
	)
	(gr_poly
		(pts
			(xy 173.576488 -53.081936) (xy 173.854872 -52.803552) (xy 173.854872 -47.507398) (xy 173.614334 -47.26686)
			(xy 170.878246 -47.26686) (xy 170.51147 -47.633636) (xy 170.51147 -53.329586) (xy 170.721274 -53.53939)
			(xy 173.119034 -53.53939)
		)
		(stroke
			(width 0)
			(type solid)
		)
		(fill yes)
		(layer "F.Cu")
		(net "GND")
	)
	(gr_poly
		(pts
			(xy 199.576436 -53.081936) (xy 199.85482 -52.803552) (xy 199.85482 -47.507398) (xy 199.614282 -47.26686)
			(xy 196.878194 -47.26686) (xy 196.511418 -47.633636) (xy 196.511418 -53.329586) (xy 196.721222 -53.53939)
			(xy 199.118982 -53.53939)
		)
		(stroke
			(width 0)
			(type solid)
		)
		(fill yes)
		(layer "F.Cu")
		(net "GND")
	)
	(gr_poly
		(pts
			(xy 209.89671 -124.794772) (xy 209.89671 -122.397012) (xy 209.439256 -121.939558) (xy 209.160872 -121.661174)
			(xy 203.864718 -121.661174) (xy 203.62418 -121.901712) (xy 203.62418 -124.6378) (xy 203.990956 -125.004576)
			(xy 209.686906 -125.004576)
		)
		(stroke
			(width 0)
			(type solid)
		)
		(fill yes)
		(layer "F.Cu")
		(net "GND")
	)
	(gr_poly
		(pts
			(xy 237.8456 -49.31537) (xy 238.123984 -49.036986) (xy 238.123984 -43.740832) (xy 237.883446 -43.500294)
			(xy 235.147358 -43.500294) (xy 234.780582 -43.86707) (xy 234.780582 -49.56302) (xy 234.990386 -49.772824)
			(xy 237.388146 -49.772824)
		)
		(stroke
			(width 0)
			(type solid)
		)
		(fill yes)
		(layer "F.Cu")
		(net "GND")
	)
	(gr_poly
		(pts
			(xy 239.428528 -119.654066) (xy 239.428528 -112.650016) (xy 239.370616 -112.592104) (xy 239.231932 -112.592104)
			(xy 238.280702 -112.592104) (xy 238.208312 -112.664494) (xy 238.208312 -119.715788) (xy 238.29137 -119.798846)
			(xy 239.283748 -119.798846)
		)
		(stroke
			(width 0)
			(type solid)
		)
		(fill yes)
		(layer "F.Cu")
		(net "GND")
	)
	(gr_poly
		(pts
			(xy 248.038874 -163.249864) (xy 248.038874 -163.11118) (xy 248.038874 -162.15995) (xy 247.966484 -162.08756)
			(xy 240.91519 -162.08756) (xy 240.832132 -162.170618) (xy 240.832132 -163.162996) (xy 240.976912 -163.307776)
			(xy 247.980962 -163.307776)
		)
		(stroke
			(width 0)
			(type solid)
		)
		(fill yes)
		(layer "F.Cu")
		(net "GND")
	)
	(gr_poly
		(pts
			(xy 254.328168 -123.768104) (xy 254.328168 -121.032016) (xy 253.961392 -120.66524) (xy 248.265442 -120.66524)
			(xy 248.055638 -120.875044) (xy 248.055638 -123.272804) (xy 248.513092 -123.730258) (xy 248.791476 -124.008642)
			(xy 254.08763 -124.008642)
		)
		(stroke
			(width 0)
			(type solid)
		)
		(fill yes)
		(layer "F.Cu")
		(net "GND")
	)
	(gr_poly
		(pts
			(xy 263.676384 -53.081936) (xy 263.954768 -52.803552) (xy 263.954768 -47.507398) (xy 263.71423 -47.26686)
			(xy 260.978142 -47.26686) (xy 260.611366 -47.633636) (xy 260.611366 -53.329586) (xy 260.82117 -53.53939)
			(xy 263.21893 -53.53939)
		)
		(stroke
			(width 0)
			(type solid)
		)
		(fill yes)
		(layer "F.Cu")
		(net "GND")
	)
	(gr_poly
		(pts
			(xy 289.676332 -53.081936) (xy 289.954716 -52.803552) (xy 289.954716 -47.507398) (xy 289.714178 -47.26686)
			(xy 286.97809 -47.26686) (xy 286.611314 -47.633636) (xy 286.611314 -53.329586) (xy 286.821118 -53.53939)
			(xy 289.218878 -53.53939)
		)
		(stroke
			(width 0)
			(type solid)
		)
		(fill yes)
		(layer "F.Cu")
		(net "GND")
	)
	(gr_poly
		(pts
			(xy 315.67628 -53.081936) (xy 315.954664 -52.803552) (xy 315.954664 -47.507398) (xy 315.714126 -47.26686)
			(xy 312.978038 -47.26686) (xy 312.611262 -47.633636) (xy 312.611262 -53.329586) (xy 312.821066 -53.53939)
			(xy 315.218826 -53.53939)
		)
		(stroke
			(width 0)
			(type solid)
		)
		(fill yes)
		(layer "F.Cu")
		(net "GND")
	)
	(gr_poly
		(pts
			(xy 325.996808 -126.064772) (xy 325.996808 -123.667012) (xy 325.539354 -123.209558) (xy 325.26097 -122.931174)
			(xy 319.964816 -122.931174) (xy 319.724278 -123.171712) (xy 319.724278 -125.9078) (xy 320.091054 -126.274576)
			(xy 325.787004 -126.274576)
		)
		(stroke
			(width 0)
			(type solid)
		)
		(fill yes)
		(layer "F.Cu")
		(net "GND")
	)
	(gr_poly
		(pts
			(xy 345.815666 -115.503452) (xy 345.815666 -108.499402) (xy 345.757754 -108.44149) (xy 345.61907 -108.44149)
			(xy 344.66784 -108.44149) (xy 344.59545 -108.51388) (xy 344.59545 -115.565174) (xy 344.678508 -115.648232)
			(xy 345.670886 -115.648232)
		)
		(stroke
			(width 0)
			(type solid)
		)
		(fill yes)
		(layer "F.Cu")
		(net "GND")
	)
	(gr_poly
		(pts
			(xy 353.776534 -53.081936) (xy 354.054918 -52.803552) (xy 354.054918 -47.507398) (xy 353.81438 -47.26686)
			(xy 351.078292 -47.26686) (xy 350.711516 -47.633636) (xy 350.711516 -53.329586) (xy 350.92132 -53.53939)
			(xy 353.31908 -53.53939)
		)
		(stroke
			(width 0)
			(type solid)
		)
		(fill yes)
		(layer "F.Cu")
		(net "GND")
	)
	(gr_poly
		(pts
			(xy 364.138972 -163.249864) (xy 364.138972 -163.11118) (xy 364.138972 -162.15995) (xy 364.066582 -162.08756)
			(xy 357.015288 -162.08756) (xy 356.93223 -162.170618) (xy 356.93223 -163.162996) (xy 357.07701 -163.307776)
			(xy 364.08106 -163.307776)
		)
		(stroke
			(width 0)
			(type solid)
		)
		(fill yes)
		(layer "F.Cu")
		(net "GND")
	)
	(gr_poly
		(pts
			(xy 370.428266 -123.768104) (xy 370.428266 -121.032016) (xy 370.06149 -120.66524) (xy 364.36554 -120.66524)
			(xy 364.155736 -120.875044) (xy 364.155736 -123.272804) (xy 364.61319 -123.730258) (xy 364.891574 -124.008642)
			(xy 370.187728 -124.008642)
		)
		(stroke
			(width 0)
			(type solid)
		)
		(fill yes)
		(layer "F.Cu")
		(net "GND")
	)
	(gr_poly
		(pts
			(xy 379.776482 -53.081936) (xy 380.054866 -52.803552) (xy 380.054866 -47.507398) (xy 379.814328 -47.26686)
			(xy 377.07824 -47.26686) (xy 376.711464 -47.633636) (xy 376.711464 -53.329586) (xy 376.921268 -53.53939)
			(xy 379.319028 -53.53939)
		)
		(stroke
			(width 0)
			(type solid)
		)
		(fill yes)
		(layer "F.Cu")
		(net "GND")
	)
	(gr_poly
		(pts
			(xy 405.77643 -53.081936) (xy 406.054814 -52.803552) (xy 406.054814 -47.507398) (xy 405.814276 -47.26686)
			(xy 403.078188 -47.26686) (xy 402.711412 -47.633636) (xy 402.711412 -53.329586) (xy 402.921216 -53.53939)
			(xy 405.318976 -53.53939)
		)
		(stroke
			(width 0)
			(type solid)
		)
		(fill yes)
		(layer "F.Cu")
		(net "GND")
	)
	(gr_poly
		(pts
			(xy 431.776378 -53.081936) (xy 432.054762 -52.803552) (xy 432.054762 -47.507398) (xy 431.814224 -47.26686)
			(xy 429.078136 -47.26686) (xy 428.71136 -47.633636) (xy 428.71136 -53.329586) (xy 428.921164 -53.53939)
			(xy 431.318924 -53.53939)
		)
		(stroke
			(width 0)
			(type solid)
		)
		(fill yes)
		(layer "F.Cu")
		(net "GND")
	)
	(gr_poly
		(pts
			(xy 442.096906 -126.064772) (xy 442.096906 -123.667012) (xy 441.639452 -123.209558) (xy 441.361068 -122.931174)
			(xy 436.064914 -122.931174) (xy 435.824376 -123.171712) (xy 435.824376 -125.9078) (xy 436.191152 -126.274576)
			(xy 441.887102 -126.274576)
		)
		(stroke
			(width 0)
			(type solid)
		)
		(fill yes)
		(layer "F.Cu")
		(net "GND")
	)
	(gr_poly
		(pts
			(xy 461.915764 -115.503452) (xy 461.915764 -108.499402) (xy 461.857852 -108.44149) (xy 461.719168 -108.44149)
			(xy 460.767938 -108.44149) (xy 460.695548 -108.51388) (xy 460.695548 -115.565174) (xy 460.778606 -115.648232)
			(xy 461.770984 -115.648232)
		)
		(stroke
			(width 0)
			(type solid)
		)
		(fill yes)
		(layer "F.Cu")
		(net "GND")
	)
	(gr_poly
		(pts
			(xy 9.128506 -155.997656) (xy 9.128506 -153.867866) (xy 9.06653 -153.80589) (xy 8.33755 -153.80589)
			(xy 8.285734 -153.857706) (xy 8.285734 -155.997656) (xy 8.285734 -156.111194) (xy 8.311896 -156.137356)
			(xy 8.425434 -156.137356) (xy 8.988806 -156.137356)
		)
		(stroke
			(width 0)
			(type solid)
		)
		(fill yes)
		(layer "F.Cu")
		(net "GND")
	)
	(gr_poly
		(pts
			(xy 19.291046 -213.313772) (xy 19.316446 -213.288372) (xy 19.316446 -212.856572) (xy 19.265646 -212.805772)
			(xy 19.240246 -212.805772) (xy 18.249646 -212.805772) (xy 18.173446 -212.881972) (xy 18.173446 -213.237572)
			(xy 18.275046 -213.339172) (xy 19.265646 -213.339172)
		)
		(stroke
			(width 0)
			(type solid)
		)
		(fill yes)
		(layer "F.Cu")
		(net "GND")
	)
	(gr_poly
		(pts
			(xy 20.522692 -63.477648) (xy 20.522692 -59.593734) (xy 20.522692 -56.26608) (xy 20.065238 -55.808626)
			(xy 19.786854 -55.530242) (xy 13.98524 -55.530242) (xy 13.546328 -55.969154) (xy 13.546328 -64.139064)
			(xy 13.879322 -64.472058) (xy 19.528282 -64.472058)
		)
		(stroke
			(width 0)
			(type solid)
		)
		(fill yes)
		(layer "F.Cu")
		(net "GND")
	)
	(gr_poly
		(pts
			(xy 24.639016 -167.381174) (xy 24.639016 -167.143938) (xy 24.639016 -166.350442) (xy 24.48179 -166.193216)
			(xy 22.25167 -166.193216) (xy 22.10943 -166.335456) (xy 22.10943 -167.143938) (xy 22.10943 -167.428672)
			(xy 22.191472 -167.510714) (xy 24.509476 -167.510714)
		)
		(stroke
			(width 0)
			(type solid)
		)
		(fill yes)
		(layer "F.Cu")
		(net "P12V_AUX")
	)
	(gr_poly
		(pts
			(xy 26.650188 -222.850964) (xy 26.650188 -221.808802) (xy 26.592784 -221.751398) (xy 23.819104 -221.751398)
			(xy 23.720552 -221.84995) (xy 23.720552 -222.654114) (xy 23.802594 -222.736156) (xy 25.55875 -222.736156)
			(xy 25.936194 -223.1136) (xy 26.387552 -223.1136)
		)
		(stroke
			(width 0)
			(type solid)
		)
		(fill yes)
		(layer "F.Cu")
		(net "P1V8_PEX")
	)
	(gr_poly
		(pts
			(xy 46.52264 -63.477648) (xy 46.52264 -59.593734) (xy 46.52264 -56.26608) (xy 46.065186 -55.808626)
			(xy 45.786802 -55.530242) (xy 39.985188 -55.530242) (xy 39.546276 -55.969154) (xy 39.546276 -64.139064)
			(xy 39.87927 -64.472058) (xy 45.52823 -64.472058)
		)
		(stroke
			(width 0)
			(type solid)
		)
		(fill yes)
		(layer "F.Cu")
		(net "GND")
	)
	(gr_poly
		(pts
			(xy 52.018946 -146.309588) (xy 52.018946 -143.458946) (xy 51.816 -143.256) (xy 51.562 -143.256) (xy 51.43881 -143.13281)
			(xy 49.90719 -143.13281) (xy 49.842166 -143.197834) (xy 49.842166 -146.332448) (xy 49.92243 -146.412712)
			(xy 51.915822 -146.412712)
		)
		(stroke
			(width 0)
			(type solid)
		)
		(fill yes)
		(layer "F.Cu")
		(net "GND")
	)
	(gr_poly
		(pts
			(xy 72.522588 -63.477648) (xy 72.522588 -59.593734) (xy 72.522588 -56.26608) (xy 72.065134 -55.808626)
			(xy 71.78675 -55.530242) (xy 65.985136 -55.530242) (xy 65.546224 -55.969154) (xy 65.546224 -64.139064)
			(xy 65.879218 -64.472058) (xy 71.528178 -64.472058)
		)
		(stroke
			(width 0)
			(type solid)
		)
		(fill yes)
		(layer "F.Cu")
		(net "GND")
	)
	(gr_poly
		(pts
			(xy 81.99882 -106.556048) (xy 81.99882 -104.288082) (xy 81.583784 -103.873046) (xy 78.375256 -103.873046)
			(xy 77.456538 -103.873046) (xy 77.272134 -104.05745) (xy 77.272134 -106.62539) (xy 77.756004 -107.10926)
			(xy 78.513432 -107.10926) (xy 81.445608 -107.10926)
		)
		(stroke
			(width 0)
			(type solid)
		)
		(fill yes)
		(layer "F.Cu")
		(net "GND")
	)
	(gr_poly
		(pts
			(xy 98.522536 -63.477648) (xy 98.522536 -59.593734) (xy 98.522536 -56.26608) (xy 98.065082 -55.808626)
			(xy 97.786698 -55.530242) (xy 91.985084 -55.530242) (xy 91.546172 -55.969154) (xy 91.546172 -64.139064)
			(xy 91.879166 -64.472058) (xy 97.528126 -64.472058)
		)
		(stroke
			(width 0)
			(type solid)
		)
		(fill yes)
		(layer "F.Cu")
		(net "GND")
	)
	(gr_poly
		(pts
			(xy 106.445304 -115.968526) (xy 106.445304 -115.854988) (xy 106.445304 -115.291616) (xy 106.305604 -115.151916)
			(xy 104.175814 -115.151916) (xy 104.113838 -115.213892) (xy 104.113838 -115.942872) (xy 104.165654 -115.994688)
			(xy 106.305604 -115.994688) (xy 106.419142 -115.994688)
		)
		(stroke
			(width 0)
			(type solid)
		)
		(fill yes)
		(layer "F.Cu")
		(net "GND")
	)
	(gr_poly
		(pts
			(xy 106.591354 -271.715992) (xy 106.591354 -269.187168) (xy 106.591354 -268.7955) (xy 106.302302 -268.506448)
			(xy 102.345236 -268.506448) (xy 102.032816 -268.818868) (xy 102.032816 -269.023084) (xy 102.032816 -271.692116)
			(xy 102.302818 -271.962118) (xy 106.345228 -271.962118)
		)
		(stroke
			(width 0)
			(type solid)
		)
		(fill yes)
		(layer "F.Cu")
		(net "P12V_AUX")
	)
	(gr_poly
		(pts
			(xy 111.675672 -159.17545) (xy 111.675672 -158.921958) (xy 112.772444 -157.825186) (xy 112.772444 -157.391862)
			(xy 112.717326 -157.336744) (xy 112.383062 -157.336744) (xy 110.776258 -158.943548) (xy 110.776258 -159.189166)
			(xy 110.816644 -159.229552) (xy 111.621824 -159.229552)
		)
		(stroke
			(width 0)
			(type solid)
		)
		(fill yes)
		(layer "F.Cu")
		(net "SW_P3V3_AUX_BT")
	)
	(gr_poly
		(pts
			(xy 125.22835 -155.997656) (xy 125.22835 -153.867866) (xy 125.166374 -153.80589) (xy 124.437394 -153.80589)
			(xy 124.385578 -153.857706) (xy 124.385578 -155.997656) (xy 124.385578 -156.111194) (xy 124.41174 -156.137356)
			(xy 124.525278 -156.137356) (xy 125.08865 -156.137356)
		)
		(stroke
			(width 0)
			(type solid)
		)
		(fill yes)
		(layer "F.Cu")
		(net "GND")
	)
	(gr_poly
		(pts
			(xy 136.62279 -63.477648) (xy 136.62279 -59.593734) (xy 136.62279 -56.26608) (xy 136.165336 -55.808626)
			(xy 135.886952 -55.530242) (xy 130.085338 -55.530242) (xy 129.646426 -55.969154) (xy 129.646426 -64.139064)
			(xy 129.97942 -64.472058) (xy 135.62838 -64.472058)
		)
		(stroke
			(width 0)
			(type solid)
		)
		(fill yes)
		(layer "F.Cu")
		(net "GND")
	)
	(gr_poly
		(pts
			(xy 142.712948 -222.850964) (xy 142.712948 -221.808802) (xy 142.655544 -221.751398) (xy 139.881864 -221.751398)
			(xy 139.783312 -221.84995) (xy 139.783312 -222.654114) (xy 139.865354 -222.736156) (xy 141.62151 -222.736156)
			(xy 141.998954 -223.1136) (xy 142.450312 -223.1136)
		)
		(stroke
			(width 0)
			(type solid)
		)
		(fill yes)
		(layer "F.Cu")
		(net "P1V8_PEX")
	)
	(gr_poly
		(pts
			(xy 150.622762 -242.292378) (xy 150.648162 -242.266978) (xy 150.648162 -241.835178) (xy 150.597362 -241.784378)
			(xy 150.571962 -241.784378) (xy 149.581362 -241.784378) (xy 149.505162 -241.860578) (xy 149.505162 -242.216178)
			(xy 149.606762 -242.317778) (xy 150.597362 -242.317778)
		)
		(stroke
			(width 0)
			(type solid)
		)
		(fill yes)
		(layer "F.Cu")
		(net "GND")
	)
	(gr_poly
		(pts
			(xy 162.622738 -63.477648) (xy 162.622738 -59.593734) (xy 162.622738 -56.26608) (xy 162.165284 -55.808626)
			(xy 161.8869 -55.530242) (xy 156.085286 -55.530242) (xy 155.646374 -55.969154) (xy 155.646374 -64.139064)
			(xy 155.979368 -64.472058) (xy 161.628328 -64.472058)
		)
		(stroke
			(width 0)
			(type solid)
		)
		(fill yes)
		(layer "F.Cu")
		(net "GND")
	)
	(gr_poly
		(pts
			(xy 168.11879 -146.309588) (xy 168.11879 -143.400018) (xy 167.974772 -143.256) (xy 167.64 -143.256)
			(xy 167.51681 -143.13281) (xy 165.98519 -143.13281) (xy 165.94201 -143.17599) (xy 165.94201 -146.332448)
			(xy 166.022274 -146.412712) (xy 168.015666 -146.412712)
		)
		(stroke
			(width 0)
			(type solid)
		)
		(fill yes)
		(layer "F.Cu")
		(net "GND")
	)
	(gr_poly
		(pts
			(xy 188.622686 -63.477648) (xy 188.622686 -59.593734) (xy 188.622686 -56.26608) (xy 188.165232 -55.808626)
			(xy 187.886848 -55.530242) (xy 182.085234 -55.530242) (xy 181.646322 -55.969154) (xy 181.646322 -64.139064)
			(xy 181.979316 -64.472058) (xy 187.628276 -64.472058)
		)
		(stroke
			(width 0)
			(type solid)
		)
		(fill yes)
		(layer "F.Cu")
		(net "GND")
	)
	(gr_poly
		(pts
			(xy 214.622634 -63.477648) (xy 214.622634 -59.593734) (xy 214.622634 -56.26608) (xy 214.16518 -55.808626)
			(xy 213.886796 -55.530242) (xy 208.085182 -55.530242) (xy 207.64627 -55.969154) (xy 207.64627 -64.139064)
			(xy 207.979264 -64.472058) (xy 213.628224 -64.472058)
		)
		(stroke
			(width 0)
			(type solid)
		)
		(fill yes)
		(layer "F.Cu")
		(net "GND")
	)
	(gr_poly
		(pts
			(xy 226.514914 -121.023126) (xy 226.514914 -118.341394) (xy 226.121468 -117.947948) (xy 217.075512 -117.947948)
			(xy 216.902284 -118.121176) (xy 216.902284 -119.507) (xy 217.081354 -119.68607) (xy 217.081354 -120.687846)
			(xy 217.725498 -121.33199) (xy 226.20605 -121.33199)
		)
		(stroke
			(width 0)
			(type solid)
		)
		(fill yes)
		(layer "F.Cu")
		(net "GND")
	)
	(gr_poly
		(pts
			(xy 231.14381 -150.66391) (xy 231.24414 -150.56358) (xy 231.24414 -150.51532) (xy 231.24414 -150.00732)
			(xy 230.93934 -150.00732) (xy 230.93934 -150.536656) (xy 231.051608 -150.648416) (xy 231.052116 -150.648924)
			(xy 231.052116 -151.34844) (xy 231.14381 -151.34844)
		)
		(stroke
			(width 0)
			(type solid)
		)
		(fill yes)
		(layer "F.Cu")
		(net "P3V3_CLK_GEN_VDD_CK440_PEX")
	)
	(gr_poly
		(pts
			(xy 232.258108 -120.11914) (xy 232.258108 -120.005602) (xy 232.258108 -119.44223) (xy 232.118408 -119.30253)
			(xy 229.988618 -119.30253) (xy 229.926642 -119.364506) (xy 229.926642 -120.093486) (xy 229.978458 -120.145302)
			(xy 232.118408 -120.145302) (xy 232.231946 -120.145302)
		)
		(stroke
			(width 0)
			(type solid)
		)
		(fill yes)
		(layer "F.Cu")
		(net "GND")
	)
	(gr_poly
		(pts
			(xy 233.803444 -204.241654) (xy 233.803444 -203.583032) (xy 233.33202 -203.111608) (xy 231.938576 -203.111608)
			(xy 231.817164 -203.23302) (xy 231.817164 -203.544932) (xy 232.100628 -203.828396) (xy 232.100628 -204.215746)
			(xy 232.250996 -204.366114) (xy 233.678984 -204.366114)
		)
		(stroke
			(width 0)
			(type solid)
		)
		(fill yes)
		(layer "F.Cu")
		(net "GND")
	)
	(gr_poly
		(pts
			(xy 241.328448 -155.997656) (xy 241.328448 -153.867866) (xy 241.266472 -153.80589) (xy 240.537492 -153.80589)
			(xy 240.485676 -153.857706) (xy 240.485676 -155.997656) (xy 240.485676 -156.111194) (xy 240.511838 -156.137356)
			(xy 240.625376 -156.137356) (xy 241.188748 -156.137356)
		)
		(stroke
			(width 0)
			(type solid)
		)
		(fill yes)
		(layer "F.Cu")
		(net "GND")
	)
	(gr_poly
		(pts
			(xy 242.800632 -156.284168) (xy 242.800632 -151.457406) (xy 242.772946 -151.42972) (xy 242.756944 -151.42972)
			(xy 242.044982 -151.42972) (xy 242.044982 -151.441912) (xy 241.963194 -151.5237) (xy 241.963194 -155.936696)
			(xy 242.342162 -156.315664) (xy 242.769136 -156.315664)
		)
		(stroke
			(width 0)
			(type solid)
		)
		(fill yes)
		(layer "F.Cu")
		(net "P12V_NIC4_CO_AVIN_PD")
	)
	(gr_poly
		(pts
			(xy 252.722634 -63.477648) (xy 252.722634 -59.593734) (xy 252.722634 -56.26608) (xy 252.26518 -55.808626)
			(xy 251.986796 -55.530242) (xy 246.185182 -55.530242) (xy 245.74627 -55.969154) (xy 245.74627 -64.139064)
			(xy 246.079264 -64.472058) (xy 251.728224 -64.472058)
		)
		(stroke
			(width 0)
			(type solid)
		)
		(fill yes)
		(layer "F.Cu")
		(net "GND")
	)
	(gr_poly
		(pts
			(xy 258.812792 -222.850964) (xy 258.812792 -221.808802) (xy 258.755388 -221.751398) (xy 255.981708 -221.751398)
			(xy 255.883156 -221.84995) (xy 255.883156 -222.654114) (xy 255.965198 -222.736156) (xy 257.721354 -222.736156)
			(xy 258.098798 -223.1136) (xy 258.550156 -223.1136)
		)
		(stroke
			(width 0)
			(type solid)
		)
		(fill yes)
		(layer "F.Cu")
		(net "P1V8_PEX")
	)
	(gr_poly
		(pts
			(xy 262.793226 -241.534188) (xy 262.818626 -241.508788) (xy 262.818626 -241.076988) (xy 262.767826 -241.026188)
			(xy 262.742426 -241.026188) (xy 261.751826 -241.026188) (xy 261.675626 -241.102388) (xy 261.675626 -241.457988)
			(xy 261.777226 -241.559588) (xy 262.767826 -241.559588)
		)
		(stroke
			(width 0)
			(type solid)
		)
		(fill yes)
		(layer "F.Cu")
		(net "GND")
	)
	(gr_poly
		(pts
			(xy 263.184894 -81.851754) (xy 263.185402 -81.851246) (xy 263.884918 -81.851246) (xy 263.884918 -81.759552)
			(xy 263.200388 -81.759552) (xy 263.100058 -81.659222) (xy 263.051798 -81.659222) (xy 262.543798 -81.659222)
			(xy 262.543798 -81.964022) (xy 263.073134 -81.964022)
		)
		(stroke
			(width 0)
			(type solid)
		)
		(fill yes)
		(layer "F.Cu")
		(net "P3V3_CLK_GEN_VDD_CK440")
	)
	(gr_poly
		(pts
			(xy 278.722582 -63.477648) (xy 278.722582 -59.593734) (xy 278.722582 -56.26608) (xy 278.265128 -55.808626)
			(xy 277.986744 -55.530242) (xy 272.18513 -55.530242) (xy 271.746218 -55.969154) (xy 271.746218 -64.139064)
			(xy 272.079212 -64.472058) (xy 277.728172 -64.472058)
		)
		(stroke
			(width 0)
			(type solid)
		)
		(fill yes)
		(layer "F.Cu")
		(net "GND")
	)
	(gr_poly
		(pts
			(xy 284.218888 -146.309588) (xy 284.218888 -143.400018) (xy 284.086808 -143.268192) (xy 283.724858 -143.268192)
			(xy 283.591 -143.134334) (xy 282.061666 -143.134334) (xy 282.042108 -143.153892) (xy 282.042108 -146.332448)
			(xy 282.122372 -146.412712) (xy 284.115764 -146.412712)
		)
		(stroke
			(width 0)
			(type solid)
		)
		(fill yes)
		(layer "F.Cu")
		(net "GND")
	)
	(gr_poly
		(pts
			(xy 304.72253 -63.477648) (xy 304.72253 -59.593734) (xy 304.72253 -56.26608) (xy 304.265076 -55.808626)
			(xy 303.986692 -55.530242) (xy 298.185078 -55.530242) (xy 297.746166 -55.969154) (xy 297.746166 -64.139064)
			(xy 298.07916 -64.472058) (xy 303.72812 -64.472058)
		)
		(stroke
			(width 0)
			(type solid)
		)
		(fill yes)
		(layer "F.Cu")
		(net "GND")
	)
	(gr_poly
		(pts
			(xy 330.722478 -63.477648) (xy 330.722478 -59.593734) (xy 330.722478 -56.26608) (xy 330.265024 -55.808626)
			(xy 329.98664 -55.530242) (xy 324.185026 -55.530242) (xy 323.746114 -55.969154) (xy 323.746114 -64.139064)
			(xy 324.079108 -64.472058) (xy 329.728068 -64.472058)
		)
		(stroke
			(width 0)
			(type solid)
		)
		(fill yes)
		(layer "F.Cu")
		(net "GND")
	)
	(gr_poly
		(pts
			(xy 333.707486 -90.593926) (xy 333.707486 -88.847168) (xy 333.932022 -88.622632) (xy 333.932022 -88.04783)
			(xy 333.891636 -88.007444) (xy 331.921104 -88.007444) (xy 331.83576 -88.092788) (xy 331.83576 -90.874088)
			(xy 332.16469 -91.203018) (xy 333.098394 -91.203018)
		)
		(stroke
			(width 0)
			(type solid)
		)
		(fill yes)
		(layer "F.Cu")
		(net "P3V3_VDDAR_9ZXL0851_8_15")
	)
	(gr_poly
		(pts
			(xy 338.645246 -115.968526) (xy 338.645246 -115.854988) (xy 338.645246 -115.291616) (xy 338.505546 -115.151916)
			(xy 336.375756 -115.151916) (xy 336.31378 -115.213892) (xy 336.31378 -115.942872) (xy 336.365596 -115.994688)
			(xy 338.505546 -115.994688) (xy 338.619084 -115.994688)
		)
		(stroke
			(width 0)
			(type solid)
		)
		(fill yes)
		(layer "F.Cu")
		(net "GND")
	)
	(gr_poly
		(pts
			(xy 357.428546 -155.997656) (xy 357.428546 -153.867866) (xy 357.36657 -153.80589) (xy 356.63759 -153.80589)
			(xy 356.585774 -153.857706) (xy 356.585774 -155.997656) (xy 356.585774 -156.111194) (xy 356.611936 -156.137356)
			(xy 356.725474 -156.137356) (xy 357.288846 -156.137356)
		)
		(stroke
			(width 0)
			(type solid)
		)
		(fill yes)
		(layer "F.Cu")
		(net "GND")
	)
	(gr_poly
		(pts
			(xy 368.822732 -63.477648) (xy 368.822732 -59.593734) (xy 368.822732 -56.26608) (xy 368.365278 -55.808626)
			(xy 368.086894 -55.530242) (xy 362.28528 -55.530242) (xy 361.846368 -55.969154) (xy 361.846368 -64.139064)
			(xy 362.179362 -64.472058) (xy 367.828322 -64.472058)
		)
		(stroke
			(width 0)
			(type solid)
		)
		(fill yes)
		(layer "F.Cu")
		(net "GND")
	)
	(gr_poly
		(pts
			(xy 374.91289 -222.850964) (xy 374.91289 -221.808802) (xy 374.855486 -221.751398) (xy 372.081806 -221.751398)
			(xy 371.983254 -221.84995) (xy 371.983254 -222.654114) (xy 372.065296 -222.736156) (xy 373.821452 -222.736156)
			(xy 374.198896 -223.1136) (xy 374.650254 -223.1136)
		)
		(stroke
			(width 0)
			(type solid)
		)
		(fill yes)
		(layer "F.Cu")
		(net "P1V8_PEX")
	)
	(gr_poly
		(pts
			(xy 394.82268 -63.477648) (xy 394.82268 -59.593734) (xy 394.82268 -56.26608) (xy 394.365226 -55.808626)
			(xy 394.086842 -55.530242) (xy 388.285228 -55.530242) (xy 387.846316 -55.969154) (xy 387.846316 -64.139064)
			(xy 388.17931 -64.472058) (xy 393.82827 -64.472058)
		)
		(stroke
			(width 0)
			(type solid)
		)
		(fill yes)
		(layer "F.Cu")
		(net "GND")
	)
	(gr_poly
		(pts
			(xy 400.318986 -146.309588) (xy 400.318986 -143.400018) (xy 400.175984 -143.257016) (xy 399.796762 -143.257016)
			(xy 399.67408 -143.134334) (xy 398.266666 -143.134334) (xy 398.142206 -143.258794) (xy 398.142206 -146.332448)
			(xy 398.22247 -146.412712) (xy 400.215862 -146.412712)
		)
		(stroke
			(width 0)
			(type solid)
		)
		(fill yes)
		(layer "F.Cu")
		(net "GND")
	)
	(gr_poly
		(pts
			(xy 420.822628 -63.477648) (xy 420.822628 -59.593734) (xy 420.822628 -56.26608) (xy 420.365174 -55.808626)
			(xy 420.08679 -55.530242) (xy 414.285176 -55.530242) (xy 413.846264 -55.969154) (xy 413.846264 -64.139064)
			(xy 414.179258 -64.472058) (xy 419.828218 -64.472058)
		)
		(stroke
			(width 0)
			(type solid)
		)
		(fill yes)
		(layer "F.Cu")
		(net "GND")
	)
	(gr_poly
		(pts
			(xy 430.29886 -106.556048) (xy 430.29886 -104.288082) (xy 429.883824 -103.873046) (xy 426.675296 -103.873046)
			(xy 425.756578 -103.873046) (xy 425.572174 -104.05745) (xy 425.572174 -106.62539) (xy 426.056044 -107.10926)
			(xy 426.813472 -107.10926) (xy 429.745648 -107.10926)
		)
		(stroke
			(width 0)
			(type solid)
		)
		(fill yes)
		(layer "F.Cu")
		(net "GND")
	)
	(gr_poly
		(pts
			(xy 446.822576 -63.477648) (xy 446.822576 -59.593734) (xy 446.822576 -56.26608) (xy 446.365122 -55.808626)
			(xy 446.086738 -55.530242) (xy 440.285124 -55.530242) (xy 439.846212 -55.969154) (xy 439.846212 -64.139064)
			(xy 440.179206 -64.472058) (xy 445.828166 -64.472058)
		)
		(stroke
			(width 0)
			(type solid)
		)
		(fill yes)
		(layer "F.Cu")
		(net "GND")
	)
	(gr_poly
		(pts
			(xy 454.745344 -115.968526) (xy 454.745344 -115.854988) (xy 454.745344 -115.291616) (xy 454.605644 -115.151916)
			(xy 452.475854 -115.151916) (xy 452.413878 -115.213892) (xy 452.413878 -115.942872) (xy 452.465694 -115.994688)
			(xy 454.605644 -115.994688) (xy 454.719182 -115.994688)
		)
		(stroke
			(width 0)
			(type solid)
		)
		(fill yes)
		(layer "F.Cu")
		(net "GND")
	)
	(gr_poly
		(pts
			(xy 459.552802 -249.36704) (xy 459.578202 -249.34164) (xy 459.578202 -248.90984) (xy 459.527402 -248.85904)
			(xy 459.502002 -248.85904) (xy 458.511402 -248.85904) (xy 458.435202 -248.93524) (xy 458.435202 -249.29084)
			(xy 458.536802 -249.39244) (xy 459.527402 -249.39244)
		)
		(stroke
			(width 0)
			(type solid)
		)
		(fill yes)
		(layer "F.Cu")
		(net "GND")
	)
	(gr_poly
		(pts
			(xy 7.724394 -41.70172) (xy 7.724394 -40.283638) (xy 7.60222 -40.161464) (xy 5.145024 -40.161464)
			(xy 4.5466 -40.161464) (xy 4.458208 -40.249856) (xy 4.458208 -41.034716) (xy 4.498848 -41.075356)
			(xy 5.374132 -41.075356) (xy 6.094476 -41.7957) (xy 7.630414 -41.7957)
		)
		(stroke
			(width 0)
			(type solid)
		)
		(fill yes)
		(layer "F.Cu")
		(net "P3V3_SSD0")
	)
	(gr_poly
		(pts
			(xy 10.498074 -156.938218) (xy 10.498074 -156.671518) (xy 10.484104 -156.657548) (xy 9.623806 -156.657548)
			(xy 9.375648 -156.40939) (xy 9.186418 -156.40939) (xy 6.36905 -156.40939) (xy 6.327648 -156.450792)
			(xy 6.327648 -156.910786) (xy 6.36397 -156.947108) (xy 10.489184 -156.947108)
		)
		(stroke
			(width 0)
			(type solid)
		)
		(fill yes)
		(layer "F.Cu")
		(net "P12V_NIC0_CO_OV_FB")
	)
	(gr_poly
		(pts
			(xy 12.283694 -274.849082) (xy 12.283694 -274.636738) (xy 12.283694 -274.563332) (xy 11.000486 -273.280124)
			(xy 9.873996 -273.280124) (xy 9.481566 -273.672554) (xy 9.481566 -274.301458) (xy 9.631172 -274.451064)
			(xy 11.117072 -274.451064) (xy 11.533124 -274.867116) (xy 12.26566 -274.867116)
		)
		(stroke
			(width 0)
			(type solid)
		)
		(fill yes)
		(layer "F.Cu")
		(net "P12V_PEX0_P1V25_VIN_N")
	)
	(gr_poly
		(pts
			(xy 19.467322 -114.660426) (xy 19.467322 -113.421668) (xy 19.318986 -113.273332) (xy 17.68221 -113.273332)
			(xy 17.267936 -113.273332) (xy 17.079976 -113.461292) (xy 17.079976 -114.723164) (xy 17.144238 -114.787426)
			(xy 17.540986 -114.787426) (xy 17.816322 -114.787426) (xy 19.340322 -114.787426)
		)
		(stroke
			(width 0)
			(type solid)
		)
		(fill yes)
		(layer "F.Cu")
		(net "GND")
	)
	(gr_poly
		(pts
			(xy 20.770596 -135.007096) (xy 20.770596 -132.305298) (xy 20.770596 -128.208278) (xy 20.476464 -127.914146)
			(xy 13.767308 -127.914146) (xy 13.358622 -128.322832) (xy 13.358622 -131.818126) (xy 13.358622 -135.14578)
			(xy 13.816076 -135.603234) (xy 14.09446 -135.881618) (xy 19.896074 -135.881618)
		)
		(stroke
			(width 0)
			(type solid)
		)
		(fill yes)
		(layer "F.Cu")
		(net "GND")
	)
	(gr_poly
		(pts
			(xy 32.209486 -30.912054) (xy 32.209486 -29.493972) (xy 32.087312 -29.371798) (xy 29.630116 -29.371798)
			(xy 29.031692 -29.371798) (xy 28.9433 -29.46019) (xy 28.9433 -30.24505) (xy 28.98394 -30.28569) (xy 29.859224 -30.28569)
			(xy 30.579568 -31.006034) (xy 32.115506 -31.006034)
		)
		(stroke
			(width 0)
			(type solid)
		)
		(fill yes)
		(layer "F.Cu")
		(net "P3V3_SSD1")
	)
	(gr_poly
		(pts
			(xy 58.209434 -30.912054) (xy 58.209434 -29.493972) (xy 58.08726 -29.371798) (xy 55.630064 -29.371798)
			(xy 55.03164 -29.371798) (xy 54.943248 -29.46019) (xy 54.943248 -30.24505) (xy 54.983888 -30.28569)
			(xy 55.859172 -30.28569) (xy 56.579516 -31.006034) (xy 58.115454 -31.006034)
		)
		(stroke
			(width 0)
			(type solid)
		)
		(fill yes)
		(layer "F.Cu")
		(net "P3V3_SSD2")
	)
	(gr_poly
		(pts
			(xy 84.209382 -30.912054) (xy 84.209382 -29.493972) (xy 84.087208 -29.371798) (xy 81.630012 -29.371798)
			(xy 81.031588 -29.371798) (xy 80.943196 -29.46019) (xy 80.943196 -30.24505) (xy 80.983836 -30.28569)
			(xy 81.85912 -30.28569) (xy 82.579464 -31.006034) (xy 84.115402 -31.006034)
		)
		(stroke
			(width 0)
			(type solid)
		)
		(fill yes)
		(layer "F.Cu")
		(net "P3V3_SSD3")
	)
	(gr_poly
		(pts
			(xy 90.257884 -103.965756) (xy 90.257884 -102.479856) (xy 90.673936 -102.063804) (xy 90.673936 -101.331268)
			(xy 90.655902 -101.313234) (xy 90.443558 -101.313234) (xy 90.370152 -101.313234) (xy 89.086944 -102.596442)
			(xy 89.086944 -103.722932) (xy 89.479374 -104.115362) (xy 90.108278 -104.115362)
		)
		(stroke
			(width 0)
			(type solid)
		)
		(fill yes)
		(layer "F.Cu")
		(net "P12V_NIC1_VIN_N")
	)
	(gr_poly
		(pts
			(xy 107.255056 -117.916452) (xy 107.255056 -113.791238) (xy 106.989372 -113.791238) (xy 106.98099 -113.791238)
			(xy 106.965496 -113.806732) (xy 106.965496 -114.656616) (xy 106.717338 -114.904774) (xy 106.717338 -115.094004)
			(xy 106.717338 -117.911372) (xy 106.75874 -117.952774) (xy 107.218734 -117.952774)
		)
		(stroke
			(width 0)
			(type solid)
		)
		(fill yes)
		(layer "F.Cu")
		(net "P12V_NIC1_CO_OV_FB")
	)
	(gr_poly
		(pts
			(xy 112.726978 -131.339082) (xy 112.726978 -128.703832) (xy 112.726978 -128.415542) (xy 112.624362 -128.312926)
			(xy 112.336072 -128.312926) (xy 111.632238 -128.312926) (xy 104.786938 -128.312926) (xy 104.434386 -128.665478)
			(xy 104.434386 -131.312666) (xy 104.714802 -131.593082) (xy 112.472978 -131.593082)
		)
		(stroke
			(width 0)
			(type solid)
		)
		(fill yes)
		(layer "F.Cu")
		(net "GND")
	)
	(gr_poly
		(pts
			(xy 122.309636 -30.912054) (xy 122.309636 -29.493972) (xy 122.187462 -29.371798) (xy 119.730266 -29.371798)
			(xy 119.131842 -29.371798) (xy 119.04345 -29.46019) (xy 119.04345 -30.24505) (xy 119.08409 -30.28569)
			(xy 119.959374 -30.28569) (xy 120.679718 -31.006034) (xy 122.215656 -31.006034)
		)
		(stroke
			(width 0)
			(type solid)
		)
		(fill yes)
		(layer "F.Cu")
		(net "P3V3_SSD4")
	)
	(gr_poly
		(pts
			(xy 126.5936 -156.9212) (xy 126.5936 -156.6926) (xy 126.558548 -156.657548) (xy 125.72365 -156.657548)
			(xy 125.475492 -156.40939) (xy 125.286262 -156.40939) (xy 122.468894 -156.40939) (xy 122.427492 -156.450792)
			(xy 122.427492 -156.910786) (xy 122.463814 -156.947108) (xy 126.567692 -156.947108)
		)
		(stroke
			(width 0)
			(type solid)
		)
		(fill yes)
		(layer "F.Cu")
		(net "P12V_NIC2_CO_OV_FB")
	)
	(gr_poly
		(pts
			(xy 135.059166 -113.898426) (xy 135.059166 -112.659668) (xy 134.91083 -112.511332) (xy 133.274054 -112.511332)
			(xy 132.85978 -112.511332) (xy 132.67182 -112.699292) (xy 132.67182 -113.961164) (xy 132.736082 -114.025426)
			(xy 133.13283 -114.025426) (xy 133.408166 -114.025426) (xy 134.932166 -114.025426)
		)
		(stroke
			(width 0)
			(type solid)
		)
		(fill yes)
		(layer "F.Cu")
		(net "GND")
	)
	(gr_poly
		(pts
			(xy 136.87044 -135.007096) (xy 136.87044 -132.305298) (xy 136.87044 -128.208278) (xy 136.576308 -127.914146)
			(xy 129.867152 -127.914146) (xy 129.458466 -128.322832) (xy 129.458466 -131.818126) (xy 129.458466 -135.14578)
			(xy 129.91592 -135.603234) (xy 130.194304 -135.881618) (xy 135.995918 -135.881618)
		)
		(stroke
			(width 0)
			(type solid)
		)
		(fill yes)
		(layer "F.Cu")
		(net "GND")
	)
	(gr_poly
		(pts
			(xy 148.309584 -30.912054) (xy 148.309584 -29.493972) (xy 148.18741 -29.371798) (xy 145.730214 -29.371798)
			(xy 145.13179 -29.371798) (xy 145.043398 -29.46019) (xy 145.043398 -30.24505) (xy 145.084038 -30.28569)
			(xy 145.959322 -30.28569) (xy 146.679666 -31.006034) (xy 148.215604 -31.006034)
		)
		(stroke
			(width 0)
			(type solid)
		)
		(fill yes)
		(layer "F.Cu")
		(net "P3V3_SSD5")
	)
	(gr_poly
		(pts
			(xy 174.309532 -30.912054) (xy 174.309532 -29.493972) (xy 174.187358 -29.371798) (xy 171.730162 -29.371798)
			(xy 171.131738 -29.371798) (xy 171.043346 -29.46019) (xy 171.043346 -30.24505) (xy 171.083986 -30.28569)
			(xy 171.95927 -30.28569) (xy 172.679614 -31.006034) (xy 174.215552 -31.006034)
		)
		(stroke
			(width 0)
			(type solid)
		)
		(fill yes)
		(layer "F.Cu")
		(net "P3V3_SSD6")
	)
	(gr_poly
		(pts
			(xy 200.30948 -30.912054) (xy 200.30948 -29.493972) (xy 200.187306 -29.371798) (xy 197.73011 -29.371798)
			(xy 197.131686 -29.371798) (xy 197.043294 -29.46019) (xy 197.043294 -30.24505) (xy 197.083934 -30.28569)
			(xy 197.959218 -30.28569) (xy 198.679562 -31.006034) (xy 200.2155 -31.006034)
		)
		(stroke
			(width 0)
			(type solid)
		)
		(fill yes)
		(layer "F.Cu")
		(net "P3V3_SSD7")
	)
	(gr_poly
		(pts
			(xy 227.342954 -277.135844) (xy 227.342954 -276.9235) (xy 227.342954 -276.850094) (xy 226.059746 -275.566886)
			(xy 224.933256 -275.566886) (xy 224.540826 -275.959316) (xy 224.540826 -276.58822) (xy 224.690432 -276.737826)
			(xy 226.176332 -276.737826) (xy 226.592384 -277.153878) (xy 227.32492 -277.153878)
		)
		(stroke
			(width 0)
			(type solid)
		)
		(fill yes)
		(layer "F.Cu")
		(net "P12V_PEX1_P1V25_VIN_N")
	)
	(gr_poly
		(pts
			(xy 233.06786 -122.067066) (xy 233.06786 -117.941852) (xy 233.057192 -117.931184) (xy 232.794048 -117.931184)
			(xy 232.7783 -117.946932) (xy 232.7783 -118.80723) (xy 232.530142 -119.055388) (xy 232.530142 -119.244618)
			(xy 232.530142 -122.061986) (xy 232.571544 -122.103388) (xy 233.031538 -122.103388)
		)
		(stroke
			(width 0)
			(type solid)
		)
		(fill yes)
		(layer "F.Cu")
		(net "P12V_NIC3_CO_OV_FB")
	)
	(gr_poly
		(pts
			(xy 238.40948 -30.912054) (xy 238.40948 -29.493972) (xy 238.287306 -29.371798) (xy 235.83011 -29.371798)
			(xy 235.231686 -29.371798) (xy 235.143294 -29.46019) (xy 235.143294 -30.24505) (xy 235.183934 -30.28569)
			(xy 236.059218 -30.28569) (xy 236.779562 -31.006034) (xy 238.3155 -31.006034)
		)
		(stroke
			(width 0)
			(type solid)
		)
		(fill yes)
		(layer "F.Cu")
		(net "P3V3_SSD8")
	)
	(gr_poly
		(pts
			(xy 242.697 -156.9212) (xy 242.697 -156.6926) (xy 242.661948 -156.657548) (xy 241.823748 -156.657548)
			(xy 241.57559 -156.40939) (xy 241.38636 -156.40939) (xy 238.568992 -156.40939) (xy 238.52759 -156.450792)
			(xy 238.52759 -156.910786) (xy 238.563912 -156.947108) (xy 242.671092 -156.947108)
		)
		(stroke
			(width 0)
			(type solid)
		)
		(fill yes)
		(layer "F.Cu")
		(net "P12V_NIC4_CO_OV_FB")
	)
	(gr_poly
		(pts
			(xy 243.593112 -277.135844) (xy 243.593112 -276.9235) (xy 243.593112 -276.850094) (xy 242.309904 -275.566886)
			(xy 241.183414 -275.566886) (xy 240.790984 -275.959316) (xy 240.790984 -276.58822) (xy 240.94059 -276.737826)
			(xy 242.42649 -276.737826) (xy 242.842542 -277.153878) (xy 243.575078 -277.153878)
		)
		(stroke
			(width 0)
			(type solid)
		)
		(fill yes)
		(layer "F.Cu")
		(net "P12V_PEX2_P1V25_VIN_N")
	)
	(gr_poly
		(pts
			(xy 251.667264 -114.660426) (xy 251.667264 -113.421668) (xy 251.518928 -113.273332) (xy 249.882152 -113.273332)
			(xy 249.467878 -113.273332) (xy 249.279918 -113.461292) (xy 249.279918 -114.723164) (xy 249.34418 -114.787426)
			(xy 249.740928 -114.787426) (xy 250.016264 -114.787426) (xy 251.540264 -114.787426)
		)
		(stroke
			(width 0)
			(type solid)
		)
		(fill yes)
		(layer "F.Cu")
		(net "GND")
	)
	(gr_poly
		(pts
			(xy 252.970538 -135.007096) (xy 252.970538 -132.305298) (xy 252.970538 -128.208278) (xy 252.676406 -127.914146)
			(xy 245.96725 -127.914146) (xy 245.558564 -128.322832) (xy 245.558564 -131.818126) (xy 245.558564 -135.14578)
			(xy 246.016018 -135.603234) (xy 246.294402 -135.881618) (xy 252.096016 -135.881618)
		)
		(stroke
			(width 0)
			(type solid)
		)
		(fill yes)
		(layer "F.Cu")
		(net "GND")
	)
	(gr_poly
		(pts
			(xy 264.409428 -30.912054) (xy 264.409428 -29.493972) (xy 264.287254 -29.371798) (xy 261.830058 -29.371798)
			(xy 261.231634 -29.371798) (xy 261.143242 -29.46019) (xy 261.143242 -30.24505) (xy 261.183882 -30.28569)
			(xy 262.059166 -30.28569) (xy 262.77951 -31.006034) (xy 264.315448 -31.006034)
		)
		(stroke
			(width 0)
			(type solid)
		)
		(fill yes)
		(layer "F.Cu")
		(net "P3V3_SSD9")
	)
	(gr_poly
		(pts
			(xy 290.409376 -30.912054) (xy 290.409376 -29.493972) (xy 290.287202 -29.371798) (xy 287.830006 -29.371798)
			(xy 287.231582 -29.371798) (xy 287.14319 -29.46019) (xy 287.14319 -30.24505) (xy 287.18383 -30.28569)
			(xy 288.059114 -30.28569) (xy 288.779458 -31.006034) (xy 290.315396 -31.006034)
		)
		(stroke
			(width 0)
			(type solid)
		)
		(fill yes)
		(layer "F.Cu")
		(net "P3V3_SSD10")
	)
	(gr_poly
		(pts
			(xy 314.198762 -106.894884) (xy 314.198762 -106.556048) (xy 314.198762 -104.288082) (xy 313.783726 -103.873046)
			(xy 310.70423 -103.873046) (xy 309.472076 -105.1052) (xy 309.472076 -106.62539) (xy 309.4736 -106.62666)
			(xy 309.4736 -106.90987) (xy 309.738776 -107.175046) (xy 313.9186 -107.175046)
		)
		(stroke
			(width 0)
			(type solid)
		)
		(fill yes)
		(layer "F.Cu")
		(net "GND")
	)
	(gr_poly
		(pts
			(xy 316.409324 -30.912054) (xy 316.409324 -29.493972) (xy 316.28715 -29.371798) (xy 313.829954 -29.371798)
			(xy 313.23153 -29.371798) (xy 313.143138 -29.46019) (xy 313.143138 -30.24505) (xy 313.183778 -30.28569)
			(xy 314.059062 -30.28569) (xy 314.779406 -31.006034) (xy 316.315344 -31.006034)
		)
		(stroke
			(width 0)
			(type solid)
		)
		(fill yes)
		(layer "F.Cu")
		(net "P3V3_SSD11")
	)
	(gr_poly
		(pts
			(xy 322.457826 -103.965756) (xy 322.457826 -102.479856) (xy 322.873878 -102.063804) (xy 322.873878 -101.331268)
			(xy 322.855844 -101.313234) (xy 322.6435 -101.313234) (xy 322.570094 -101.313234) (xy 321.286886 -102.596442)
			(xy 321.286886 -103.722932) (xy 321.679316 -104.115362) (xy 322.30822 -104.115362)
		)
		(stroke
			(width 0)
			(type solid)
		)
		(fill yes)
		(layer "F.Cu")
		(net "P12V_NIC5_VIN_N")
	)
	(gr_poly
		(pts
			(xy 339.454998 -117.916452) (xy 339.454998 -113.791238) (xy 339.451696 -113.787936) (xy 339.17382 -113.787936)
			(xy 339.165438 -113.796318) (xy 339.165438 -114.656616) (xy 338.91728 -114.904774) (xy 338.91728 -115.094004)
			(xy 338.91728 -117.911372) (xy 338.958682 -117.952774) (xy 339.418676 -117.952774)
		)
		(stroke
			(width 0)
			(type solid)
		)
		(fill yes)
		(layer "F.Cu")
		(net "P12V_NIC5_CO_OV_FB")
	)
	(gr_poly
		(pts
			(xy 354.509578 -30.912054) (xy 354.509578 -29.493972) (xy 354.387404 -29.371798) (xy 351.930208 -29.371798)
			(xy 351.331784 -29.371798) (xy 351.243392 -29.46019) (xy 351.243392 -30.24505) (xy 351.284032 -30.28569)
			(xy 352.159316 -30.28569) (xy 352.87966 -31.006034) (xy 354.415598 -31.006034)
		)
		(stroke
			(width 0)
			(type solid)
		)
		(fill yes)
		(layer "F.Cu")
		(net "P3V3_SSD12")
	)
	(gr_poly
		(pts
			(xy 361.17657 -271.715992) (xy 361.17657 -269.187168) (xy 361.161076 -269.171674) (xy 361.161076 -268.750796)
			(xy 360.907076 -268.496796) (xy 356.824534 -268.496796) (xy 356.618032 -268.703298) (xy 356.618032 -269.023084)
			(xy 356.618032 -271.692116) (xy 356.888034 -271.962118) (xy 360.930444 -271.962118)
		)
		(stroke
			(width 0)
			(type solid)
		)
		(fill yes)
		(layer "F.Cu")
		(net "P12V_AUX")
	)
	(gr_poly
		(pts
			(xy 367.259362 -113.898426) (xy 367.259362 -112.659668) (xy 367.111026 -112.511332) (xy 365.47425 -112.511332)
			(xy 365.059976 -112.511332) (xy 364.872016 -112.699292) (xy 364.872016 -113.961164) (xy 364.936278 -114.025426)
			(xy 365.333026 -114.025426) (xy 365.608362 -114.025426) (xy 367.132362 -114.025426)
		)
		(stroke
			(width 0)
			(type solid)
		)
		(fill yes)
		(layer "F.Cu")
		(net "GND")
	)
	(gr_poly
		(pts
			(xy 369.070636 -135.007096) (xy 369.070636 -132.305298) (xy 369.070636 -128.208278) (xy 368.776504 -127.914146)
			(xy 362.067348 -127.914146) (xy 361.658662 -128.322832) (xy 361.658662 -131.818126) (xy 361.658662 -135.14578)
			(xy 362.116116 -135.603234) (xy 362.3945 -135.881618) (xy 368.196114 -135.881618)
		)
		(stroke
			(width 0)
			(type solid)
		)
		(fill yes)
		(layer "F.Cu")
		(net "GND")
	)
	(gr_poly
		(pts
			(xy 380.509526 -30.912054) (xy 380.509526 -29.493972) (xy 380.387352 -29.371798) (xy 377.930156 -29.371798)
			(xy 377.331732 -29.371798) (xy 377.24334 -29.46019) (xy 377.24334 -30.24505) (xy 377.28398 -30.28569)
			(xy 378.159264 -30.28569) (xy 378.879608 -31.006034) (xy 380.415546 -31.006034)
		)
		(stroke
			(width 0)
			(type solid)
		)
		(fill yes)
		(layer "F.Cu")
		(net "P3V3_SSD13")
	)
	(gr_poly
		(pts
			(xy 406.509474 -30.912054) (xy 406.509474 -29.493972) (xy 406.3873 -29.371798) (xy 403.930104 -29.371798)
			(xy 403.33168 -29.371798) (xy 403.243288 -29.46019) (xy 403.243288 -30.24505) (xy 403.283928 -30.28569)
			(xy 404.159212 -30.28569) (xy 404.879556 -31.006034) (xy 406.415494 -31.006034)
		)
		(stroke
			(width 0)
			(type solid)
		)
		(fill yes)
		(layer "F.Cu")
		(net "P3V3_SSD14")
	)
	(gr_poly
		(pts
			(xy 432.509422 -30.912054) (xy 432.509422 -29.493972) (xy 432.387248 -29.371798) (xy 429.930052 -29.371798)
			(xy 429.331628 -29.371798) (xy 429.243236 -29.46019) (xy 429.243236 -30.24505) (xy 429.283876 -30.28569)
			(xy 430.15916 -30.28569) (xy 430.879504 -31.006034) (xy 432.415442 -31.006034)
		)
		(stroke
			(width 0)
			(type solid)
		)
		(fill yes)
		(layer "F.Cu")
		(net "P3V3_SSD15")
	)
	(gr_poly
		(pts
			(xy 438.557924 -103.965756) (xy 438.557924 -102.479856) (xy 438.973976 -102.063804) (xy 438.973976 -101.331268)
			(xy 438.955942 -101.313234) (xy 438.743598 -101.313234) (xy 438.670192 -101.313234) (xy 437.386984 -102.596442)
			(xy 437.386984 -103.722932) (xy 437.779414 -104.115362) (xy 438.408318 -104.115362)
		)
		(stroke
			(width 0)
			(type solid)
		)
		(fill yes)
		(layer "F.Cu")
		(net "P12V_NIC7_VIN_N")
	)
	(gr_poly
		(pts
			(xy 457.964032 -277.259288) (xy 457.964032 -277.046944) (xy 457.964032 -276.973538) (xy 456.680824 -275.69033)
			(xy 455.554334 -275.69033) (xy 455.161904 -276.08276) (xy 455.161904 -276.711664) (xy 455.31151 -276.86127)
			(xy 456.79741 -276.86127) (xy 457.213462 -277.277322) (xy 457.945998 -277.277322)
		)
		(stroke
			(width 0)
			(type solid)
		)
		(fill yes)
		(layer "F.Cu")
		(net "P12V_PEX3_P1V25_VIN_N")
	)
	(gr_poly
		(pts
			(xy 10.483088 -150.000716) (xy 10.483088 -141.020038) (xy 10.229596 -140.766546) (xy 9.05637 -140.766546)
			(xy 8.909304 -140.913612) (xy 6.850126 -140.913612) (xy 6.760972 -141.002766) (xy 6.662674 -141.101064)
			(xy 6.662674 -141.252448) (xy 6.662674 -150.321772) (xy 6.735064 -150.394162) (xy 10.089642 -150.394162)
		)
		(stroke
			(width 0)
			(type solid)
		)
		(fill yes)
		(layer "F.Cu")
		(net "GND")
	)
	(gr_poly
		(pts
			(xy 12.745466 -274.348702) (xy 12.745466 -273.764756) (xy 12.95908 -273.551142) (xy 12.95908 -273.155664)
			(xy 12.965176 -273.149568) (xy 12.965176 -272.066766) (xy 12.893548 -271.995138) (xy 11.923776 -271.995138)
			(xy 11.1125 -272.806414) (xy 11.1125 -272.998438) (xy 12.505944 -274.391882) (xy 12.702286 -274.391882)
		)
		(stroke
			(width 0)
			(type solid)
		)
		(fill yes)
		(layer "F.Cu")
		(net "P12V_PEX0_P1V25_VIN_P")
	)
	(gr_poly
		(pts
			(xy 13.499846 -212.983572) (xy 13.499846 -212.602572) (xy 13.753846 -212.348572) (xy 14.693646 -212.348572)
			(xy 14.769846 -212.272372) (xy 14.769846 -211.205572) (xy 14.719046 -211.154772) (xy 11.518646 -211.154772)
			(xy 11.442446 -211.230972) (xy 11.442446 -213.110572) (xy 11.569446 -213.237572) (xy 13.245846 -213.237572)
		)
		(stroke
			(width 0)
			(type solid)
		)
		(fill yes)
		(layer "F.Cu")
		(net "P3V3_AUX")
	)
	(gr_poly
		(pts
			(xy 21.23567 -158.644336) (xy 21.23567 -155.680156) (xy 21.080984 -155.52547) (xy 16.191484 -155.52547)
			(xy 15.067026 -156.649928) (xy 10.776204 -156.649928) (xy 10.754614 -156.671518) (xy 10.754614 -157.938978)
			(xy 10.767568 -157.951932) (xy 14.9733 -157.951932) (xy 16.052038 -159.03067) (xy 20.849336 -159.03067)
		)
		(stroke
			(width 0)
			(type solid)
		)
		(fill yes)
		(layer "F.Cu")
		(net "P12V_AUX")
	)
	(gr_poly
		(pts
			(xy 23.752556 -172.772578) (xy 23.752556 -172.023278) (xy 23.727156 -171.997878) (xy 23.638256 -171.997878)
			(xy 22.076156 -171.997878) (xy 22.038056 -172.035978) (xy 22.038056 -172.493178) (xy 22.069806 -172.524928)
			(xy 22.666706 -172.524928) (xy 22.939756 -172.797978) (xy 23.625556 -172.797978) (xy 23.727156 -172.797978)
		)
		(stroke
			(width 0)
			(type solid)
		)
		(fill yes)
		(layer "F.Cu")
		(net "SH_P5V_AUX_FB")
	)
	(gr_poly
		(pts
			(xy 90.206576 -101.08311) (xy 90.206576 -100.902516) (xy 90.155522 -100.851462) (xy 89.571576 -100.851462)
			(xy 89.357962 -100.637848) (xy 88.962484 -100.637848) (xy 88.956388 -100.631752) (xy 87.873586 -100.631752)
			(xy 87.801958 -100.70338) (xy 87.801958 -101.673152) (xy 88.613234 -102.484428) (xy 88.805258 -102.484428)
		)
		(stroke
			(width 0)
			(type solid)
		)
		(fill yes)
		(layer "F.Cu")
		(net "P12V_NIC1_VIN_P")
	)
	(gr_poly
		(pts
			(xy 91.848686 -309.284116) (xy 92.357194 -309.284116) (xy 92.912946 -308.728364) (xy 92.912946 -308.360572)
			(xy 91.632024 -307.07965) (xy 90.275156 -307.07965) (xy 89.431876 -307.92293) (xy 89.431876 -308.111144)
			(xy 90.793316 -309.472584) (xy 90.793316 -309.49138) (xy 91.160854 -309.858918) (xy 91.273884 -309.858918)
		)
		(stroke
			(width 0)
			(type solid)
		)
		(fill yes)
		(layer "F.Cu")
		(net "GND")
	)
	(gr_poly
		(pts
			(xy 99.695 -196.5452) (xy 99.695 -196.4182) (xy 99.6188 -196.342) (xy 98.298 -196.342) (xy 96.5962 -194.6402)
			(xy 94.742 -194.6402) (xy 94.5642 -194.818) (xy 94.5642 -196.215) (xy 94.7166 -196.3674) (xy 96.7486 -196.3674)
			(xy 97.028 -196.6468) (xy 99.5934 -196.6468)
		)
		(stroke
			(width 0)
			(type solid)
		)
		(fill yes)
		(layer "F.Cu")
		(net "P3V3_AUX")
	)
	(gr_poly
		(pts
			(xy 102.0318 -202.381866) (xy 102.0318 -199.644) (xy 102.089458 -199.586342) (xy 102.089458 -197.847458)
			(xy 102.0064 -197.7644) (xy 101.3968 -197.7644) (xy 101.3206 -197.8406) (xy 101.3206 -199.800972)
			(xy 100.3808 -200.740772) (xy 100.3808 -202.43292) (xy 100.582476 -202.634596) (xy 101.77907 -202.634596)
		)
		(stroke
			(width 0)
			(type solid)
		)
		(fill yes)
		(layer "F.Cu")
		(net "P3V3_AUX")
	)
	(gr_poly
		(pts
			(xy 103.9876 -202.1586) (xy 103.9876 -200.4822) (xy 102.59314 -199.08774) (xy 102.59314 -197.84314)
			(xy 102.5144 -197.7644) (xy 102.4128 -197.7644) (xy 102.325678 -197.851522) (xy 102.325678 -199.744584)
			(xy 102.29723 -199.773032) (xy 102.29723 -202.27163) (xy 102.4382 -202.4126) (xy 103.7336 -202.4126)
		)
		(stroke
			(width 0)
			(type solid)
		)
		(fill yes)
		(layer "F.Cu")
		(net "GND")
	)
	(gr_poly
		(pts
			(xy 122.57659 -260.121908) (xy 122.57659 -259.83692) (xy 122.57659 -256.65049) (xy 122.52579 -256.59969)
			(xy 118.99519 -256.59969) (xy 118.96979 -256.62509) (xy 118.961662 -256.633218) (xy 118.961662 -259.427218)
			(xy 118.961662 -260.130798) (xy 119.038878 -260.208014) (xy 119.161306 -260.208014) (xy 122.490484 -260.208014)
		)
		(stroke
			(width 0)
			(type solid)
		)
		(fill yes)
		(layer "F.Cu")
		(net "GND")
	)
	(gr_poly
		(pts
			(xy 126.582932 -150.000716) (xy 126.582932 -141.020038) (xy 126.32944 -140.766546) (xy 125.156214 -140.766546)
			(xy 125.009148 -140.913612) (xy 122.94997 -140.913612) (xy 122.860816 -141.002766) (xy 122.762518 -141.101064)
			(xy 122.762518 -141.252448) (xy 122.762518 -150.321772) (xy 122.834908 -150.394162) (xy 126.189486 -150.394162)
		)
		(stroke
			(width 0)
			(type solid)
		)
		(fill yes)
		(layer "F.Cu")
		(net "GND")
	)
	(gr_poly
		(pts
			(xy 128.976374 -271.715992) (xy 128.976374 -269.187168) (xy 128.976374 -269.016226) (xy 128.976374 -268.727936)
			(xy 128.735582 -268.487144) (xy 124.953776 -268.487144) (xy 124.768102 -268.672818) (xy 124.555758 -268.885162)
			(xy 124.417836 -269.023084) (xy 124.417836 -271.692116) (xy 124.687838 -271.962118) (xy 128.730248 -271.962118)
		)
		(stroke
			(width 0)
			(type solid)
		)
		(fill yes)
		(layer "F.Cu")
		(net "P12V_AUX")
	)
	(gr_poly
		(pts
			(xy 137.335514 -158.644336) (xy 137.335514 -155.680156) (xy 137.180828 -155.52547) (xy 132.291328 -155.52547)
			(xy 131.16687 -156.649928) (xy 126.876048 -156.649928) (xy 126.854458 -156.671518) (xy 126.854458 -157.938978)
			(xy 126.867412 -157.951932) (xy 131.073144 -157.951932) (xy 132.151882 -159.03067) (xy 136.94918 -159.03067)
		)
		(stroke
			(width 0)
			(type solid)
		)
		(fill yes)
		(layer "F.Cu")
		(net "P12V_AUX")
	)
	(gr_poly
		(pts
			(xy 144.831562 -241.962178) (xy 144.831562 -241.581178) (xy 145.085562 -241.327178) (xy 146.025362 -241.327178)
			(xy 146.101562 -241.250978) (xy 146.101562 -240.184178) (xy 146.050762 -240.133378) (xy 142.850362 -240.133378)
			(xy 142.774162 -240.209578) (xy 142.774162 -242.089178) (xy 142.901162 -242.216178) (xy 144.577562 -242.216178)
		)
		(stroke
			(width 0)
			(type solid)
		)
		(fill yes)
		(layer "F.Cu")
		(net "P3V3_AUX")
	)
	(gr_poly
		(pts
			(xy 154.543252 -152.421844) (xy 154.543252 -149.79777) (xy 154.823668 -149.517354) (xy 155.534106 -149.517354)
			(xy 155.68295 -149.36851) (xy 155.68295 -148.389086) (xy 155.591256 -148.297392) (xy 152.07996 -148.297392)
			(xy 151.913844 -148.463508) (xy 151.913844 -152.398222) (xy 152.046178 -152.530556) (xy 154.43454 -152.530556)
		)
		(stroke
			(width 0)
			(type solid)
		)
		(fill yes)
		(layer "F.Cu")
		(net "GND")
	)
	(gr_poly
		(pts
			(xy 199.78116 -106.811826) (xy 199.78116 -105.144316) (xy 199.78116 -104.636316) (xy 199.665844 -104.521)
			(xy 195.855844 -104.521) (xy 195.699126 -104.677718) (xy 195.699126 -105.185718) (xy 195.699126 -106.104436)
			(xy 195.699126 -107.021376) (xy 195.888102 -107.210352) (xy 198.94677 -107.210352) (xy 199.382634 -107.210352)
		)
		(stroke
			(width 0)
			(type solid)
		)
		(fill yes)
		(layer "F.Cu")
		(net "GND")
	)
	(gr_poly
		(pts
			(xy 207.948784 -309.284116) (xy 208.457292 -309.284116) (xy 209.013044 -308.728364) (xy 209.013044 -308.360572)
			(xy 207.732122 -307.07965) (xy 206.375254 -307.07965) (xy 205.531974 -307.92293) (xy 205.531974 -308.111144)
			(xy 206.893414 -309.472584) (xy 206.893414 -309.49138) (xy 207.260952 -309.858918) (xy 207.373982 -309.858918)
		)
		(stroke
			(width 0)
			(type solid)
		)
		(fill yes)
		(layer "F.Cu")
		(net "GND")
	)
	(gr_poly
		(pts
			(xy 227.804726 -276.635464) (xy 227.804726 -276.051518) (xy 228.01834 -275.837904) (xy 228.01834 -275.442426)
			(xy 228.024436 -275.43633) (xy 228.024436 -274.353528) (xy 227.952808 -274.2819) (xy 226.983036 -274.2819)
			(xy 226.17176 -275.093176) (xy 226.17176 -275.2852) (xy 227.565204 -276.678644) (xy 227.761546 -276.678644)
		)
		(stroke
			(width 0)
			(type solid)
		)
		(fill yes)
		(layer "F.Cu")
		(net "P12V_PEX1_P1V25_VIN_P")
	)
	(gr_poly
		(pts
			(xy 242.68303 -150.000716) (xy 242.68303 -141.020038) (xy 242.429538 -140.766546) (xy 241.256312 -140.766546)
			(xy 241.109246 -140.913612) (xy 239.050068 -140.913612) (xy 238.960914 -141.002766) (xy 238.862616 -141.101064)
			(xy 238.862616 -141.252448) (xy 238.862616 -150.321772) (xy 238.935006 -150.394162) (xy 242.289584 -150.394162)
		)
		(stroke
			(width 0)
			(type solid)
		)
		(fill yes)
		(layer "F.Cu")
		(net "GND")
	)
	(gr_poly
		(pts
			(xy 244.054884 -276.635464) (xy 244.054884 -276.051518) (xy 244.268498 -275.837904) (xy 244.268498 -275.442426)
			(xy 244.274594 -275.43633) (xy 244.274594 -274.353528) (xy 244.202966 -274.2819) (xy 243.233194 -274.2819)
			(xy 242.421918 -275.093176) (xy 242.421918 -275.2852) (xy 243.815362 -276.678644) (xy 244.011704 -276.678644)
		)
		(stroke
			(width 0)
			(type solid)
		)
		(fill yes)
		(layer "F.Cu")
		(net "P12V_PEX2_P1V25_VIN_P")
	)
	(gr_poly
		(pts
			(xy 253.435612 -158.644336) (xy 253.435612 -155.680156) (xy 253.280926 -155.52547) (xy 248.391426 -155.52547)
			(xy 247.266968 -156.649928) (xy 242.976146 -156.649928) (xy 242.954556 -156.671518) (xy 242.954556 -157.938978)
			(xy 242.96751 -157.951932) (xy 247.173242 -157.951932) (xy 248.25198 -159.03067) (xy 253.049278 -159.03067)
		)
		(stroke
			(width 0)
			(type solid)
		)
		(fill yes)
		(layer "F.Cu")
		(net "P12V_AUX")
	)
	(gr_poly
		(pts
			(xy 257.002026 -241.203988) (xy 257.002026 -240.822988) (xy 257.256026 -240.568988) (xy 258.195826 -240.568988)
			(xy 258.272026 -240.492788) (xy 258.272026 -239.425988) (xy 258.221226 -239.375188) (xy 255.020826 -239.375188)
			(xy 254.944626 -239.451388) (xy 254.944626 -241.330988) (xy 255.071626 -241.457988) (xy 256.748026 -241.457988)
		)
		(stroke
			(width 0)
			(type solid)
		)
		(fill yes)
		(layer "F.Cu")
		(net "P3V3_AUX")
	)
	(gr_poly
		(pts
			(xy 270.64335 -152.421844) (xy 270.64335 -149.79777) (xy 270.923766 -149.517354) (xy 271.634204 -149.517354)
			(xy 271.783048 -149.36851) (xy 271.783048 -148.389086) (xy 271.691354 -148.297392) (xy 268.180058 -148.297392)
			(xy 268.013942 -148.463508) (xy 268.013942 -152.398222) (xy 268.146276 -152.530556) (xy 270.534638 -152.530556)
		)
		(stroke
			(width 0)
			(type solid)
		)
		(fill yes)
		(layer "F.Cu")
		(net "GND")
	)
	(gr_poly
		(pts
			(xy 322.410074 -101.079554) (xy 322.410074 -100.906072) (xy 322.355464 -100.851462) (xy 321.771518 -100.851462)
			(xy 321.557904 -100.637848) (xy 321.162426 -100.637848) (xy 321.15633 -100.631752) (xy 320.073528 -100.631752)
			(xy 320.0019 -100.70338) (xy 320.0019 -101.673152) (xy 320.813176 -102.484428) (xy 321.0052 -102.484428)
		)
		(stroke
			(width 0)
			(type solid)
		)
		(fill yes)
		(layer "F.Cu")
		(net "P12V_NIC5_VIN_P")
	)
	(gr_poly
		(pts
			(xy 324.048628 -309.284116) (xy 324.557136 -309.284116) (xy 325.112888 -308.728364) (xy 325.112888 -308.360572)
			(xy 323.831966 -307.07965) (xy 322.475098 -307.07965) (xy 321.631818 -307.92293) (xy 321.631818 -308.111144)
			(xy 322.993258 -309.472584) (xy 322.993258 -309.49138) (xy 323.360796 -309.858918) (xy 323.473826 -309.858918)
		)
		(stroke
			(width 0)
			(type solid)
		)
		(fill yes)
		(layer "F.Cu")
		(net "GND")
	)
	(gr_poly
		(pts
			(xy 354.776786 -260.121908) (xy 354.776786 -259.83692) (xy 354.776786 -256.65049) (xy 354.725986 -256.59969)
			(xy 351.195386 -256.59969) (xy 351.169986 -256.62509) (xy 351.161858 -256.633218) (xy 351.161858 -259.427218)
			(xy 351.161858 -260.130798) (xy 351.239074 -260.208014) (xy 351.361502 -260.208014) (xy 354.69068 -260.208014)
		)
		(stroke
			(width 0)
			(type solid)
		)
		(fill yes)
		(layer "F.Cu")
		(net "GND")
	)
	(gr_poly
		(pts
			(xy 358.783128 -150.000716) (xy 358.783128 -141.020038) (xy 358.529636 -140.766546) (xy 357.35641 -140.766546)
			(xy 357.209344 -140.913612) (xy 355.150166 -140.913612) (xy 355.061012 -141.002766) (xy 354.962714 -141.101064)
			(xy 354.962714 -141.252448) (xy 354.962714 -150.321772) (xy 355.035104 -150.394162) (xy 358.389682 -150.394162)
		)
		(stroke
			(width 0)
			(type solid)
		)
		(fill yes)
		(layer "F.Cu")
		(net "GND")
	)
	(gr_poly
		(pts
			(xy 358.785668 -156.919676) (xy 358.785668 -156.70657) (xy 358.784144 -156.705046) (xy 358.784144 -156.657548)
			(xy 357.923846 -156.657548) (xy 357.675688 -156.40939) (xy 357.486458 -156.40939) (xy 354.66909 -156.40939)
			(xy 354.627688 -156.450792) (xy 354.627688 -156.910786) (xy 354.66401 -156.947108) (xy 358.758236 -156.947108)
		)
		(stroke
			(width 0)
			(type solid)
		)
		(fill yes)
		(layer "F.Cu")
		(net "P12V_NIC6_CO_OV_FB")
	)
	(gr_poly
		(pts
			(xy 369.53571 -158.644336) (xy 369.53571 -155.680156) (xy 369.381024 -155.52547) (xy 364.491524 -155.52547)
			(xy 363.367066 -156.649928) (xy 359.076244 -156.649928) (xy 359.054654 -156.671518) (xy 359.054654 -157.938978)
			(xy 359.067608 -157.951932) (xy 363.27334 -157.951932) (xy 364.352078 -159.03067) (xy 369.149376 -159.03067)
		)
		(stroke
			(width 0)
			(type solid)
		)
		(fill yes)
		(layer "F.Cu")
		(net "P12V_AUX")
	)
	(gr_poly
		(pts
			(xy 386.743448 -152.421844) (xy 386.743448 -149.79777) (xy 387.023864 -149.517354) (xy 387.734302 -149.517354)
			(xy 387.883146 -149.36851) (xy 387.883146 -148.389086) (xy 387.791452 -148.297392) (xy 384.280156 -148.297392)
			(xy 384.11404 -148.463508) (xy 384.11404 -152.398222) (xy 384.246374 -152.530556) (xy 386.634736 -152.530556)
		)
		(stroke
			(width 0)
			(type solid)
		)
		(fill yes)
		(layer "F.Cu")
		(net "GND")
	)
	(gr_poly
		(pts
			(xy 438.510172 -101.079554) (xy 438.510172 -100.906072) (xy 438.455562 -100.851462) (xy 437.871616 -100.851462)
			(xy 437.658002 -100.637848) (xy 437.262524 -100.637848) (xy 437.256428 -100.631752) (xy 436.173626 -100.631752)
			(xy 436.101998 -100.70338) (xy 436.101998 -101.673152) (xy 436.913274 -102.484428) (xy 437.105298 -102.484428)
		)
		(stroke
			(width 0)
			(type solid)
		)
		(fill yes)
		(layer "F.Cu")
		(net "P12V_NIC7_VIN_P")
	)
	(gr_poly
		(pts
			(xy 440.148726 -309.284116) (xy 440.657234 -309.284116) (xy 441.212986 -308.728364) (xy 441.212986 -308.360572)
			(xy 439.932064 -307.07965) (xy 438.575196 -307.07965) (xy 437.731916 -307.92293) (xy 437.731916 -308.111144)
			(xy 439.093356 -309.472584) (xy 439.093356 -309.49138) (xy 439.460894 -309.858918) (xy 439.573924 -309.858918)
		)
		(stroke
			(width 0)
			(type solid)
		)
		(fill yes)
		(layer "F.Cu")
		(net "GND")
	)
	(gr_poly
		(pts
			(xy 453.761602 -249.03684) (xy 453.761602 -248.65584) (xy 454.015602 -248.40184) (xy 454.955402 -248.40184)
			(xy 455.031602 -248.32564) (xy 455.031602 -247.25884) (xy 454.980802 -247.20804) (xy 451.780402 -247.20804)
			(xy 451.704202 -247.28424) (xy 451.704202 -249.16384) (xy 451.831202 -249.29084) (xy 453.507602 -249.29084)
		)
		(stroke
			(width 0)
			(type solid)
		)
		(fill yes)
		(layer "F.Cu")
		(net "P3V3_AUX")
	)
	(gr_poly
		(pts
			(xy 455.555096 -117.916452) (xy 455.555096 -113.791238) (xy 455.543666 -113.779808) (xy 455.288396 -113.779808)
			(xy 455.285348 -113.77676) (xy 455.265536 -113.796318) (xy 455.265536 -114.656616) (xy 455.017378 -114.904774)
			(xy 455.017378 -115.094004) (xy 455.017378 -117.911372) (xy 455.05878 -117.952774) (xy 455.518774 -117.952774)
		)
		(stroke
			(width 0)
			(type solid)
		)
		(fill yes)
		(layer "F.Cu")
		(net "P12V_NIC7_CO_OV_FB")
	)
	(gr_poly
		(pts
			(xy 458.425804 -276.758908) (xy 458.425804 -276.174962) (xy 458.639418 -275.961348) (xy 458.639418 -275.56587)
			(xy 458.645514 -275.559774) (xy 458.645514 -274.476972) (xy 458.573886 -274.405344) (xy 457.604114 -274.405344)
			(xy 456.792838 -275.21662) (xy 456.792838 -275.408644) (xy 458.186282 -276.802088) (xy 458.382624 -276.802088)
		)
		(stroke
			(width 0)
			(type solid)
		)
		(fill yes)
		(layer "F.Cu")
		(net "P12V_PEX3_P1V25_VIN_P")
	)
	(gr_poly
		(pts
			(xy 7.926578 -156.126434) (xy 7.926578 -153.538936) (xy 8.168132 -153.297382) (xy 9.07796 -153.297382)
			(xy 9.14019 -153.235152) (xy 9.14019 -152.3619) (xy 9.07796 -152.29967) (xy 7.594346 -152.29967)
			(xy 7.377176 -152.51684) (xy 7.377176 -156.11475) (xy 7.408164 -156.145738) (xy 7.863078 -156.145738)
			(xy 7.907274 -156.145738)
		)
		(stroke
			(width 0)
			(type solid)
		)
		(fill yes)
		(layer "F.Cu")
		(net "P12V_AUX")
	)
	(gr_poly
		(pts
			(xy 12.579604 -318.717168) (xy 12.67079 -318.625982) (xy 12.67079 -318.0842) (xy 12.67079 -316.67069)
			(xy 12.605512 -316.605412) (xy 12.419838 -316.605412) (xy 10.68705 -316.605412) (xy 10.516108 -316.776354)
			(xy 10.516108 -318.149986) (xy 10.516108 -318.671702) (xy 10.561574 -318.717168) (xy 10.64133 -318.796924)
			(xy 12.499848 -318.796924)
		)
		(stroke
			(width 0)
			(type solid)
		)
		(fill yes)
		(layer "F.Cu")
		(net "P12V_AUX")
	)
	(gr_poly
		(pts
			(xy 17.758156 -215.521286) (xy 17.758156 -214.422482) (xy 17.665446 -214.329772) (xy 17.665446 -212.678772)
			(xy 17.614646 -212.627972) (xy 17.563846 -212.627972) (xy 17.106646 -212.627972) (xy 17.055846 -212.678772)
			(xy 17.055846 -214.228172) (xy 17.055846 -214.329772) (xy 17.055846 -215.537034) (xy 17.096232 -215.57742)
			(xy 17.702022 -215.57742)
		)
		(stroke
			(width 0)
			(type solid)
		)
		(fill yes)
		(layer "F.Cu")
		(net "PWRGD_PEX0_P1V8_PLL")
	)
	(gr_poly
		(pts
			(xy 18.516346 -211.675472) (xy 18.516346 -210.761072) (xy 18.605246 -210.672172) (xy 18.732246 -210.545172)
			(xy 19.367246 -210.545172) (xy 19.392646 -210.519772) (xy 19.392646 -208.360772) (xy 19.214846 -208.182972)
			(xy 17.157446 -208.182972) (xy 17.005046 -208.335372) (xy 17.005046 -211.789772) (xy 17.081246 -211.865972)
			(xy 18.325846 -211.865972)
		)
		(stroke
			(width 0)
			(type solid)
		)
		(fill yes)
		(layer "F.Cu")
		(net "P1V8_PLL0_PEX0")
	)
	(gr_poly
		(pts
			(xy 103.426006 -226.204526) (xy 103.426006 -226.092766) (xy 104.876092 -224.64268) (xy 104.876092 -224.28962)
			(xy 104.835706 -224.249234) (xy 104.030526 -224.249234) (xy 103.976678 -224.303336) (xy 103.976678 -224.556828)
			(xy 102.879906 -225.6536) (xy 102.879906 -226.163886) (xy 102.879906 -226.245166) (xy 102.890066 -226.255326)
			(xy 103.375206 -226.255326)
		)
		(stroke
			(width 0)
			(type solid)
		)
		(fill yes)
		(layer "F.Cu")
		(net "SW_P1V8_PEX_BT")
	)
	(gr_poly
		(pts
			(xy 106.17454 -212.34146) (xy 106.17454 -210.967828) (xy 106.17454 -210.446112) (xy 106.129074 -210.400646)
			(xy 106.049318 -210.32089) (xy 104.1908 -210.32089) (xy 104.111044 -210.400646) (xy 104.019858 -210.491832)
			(xy 104.019858 -211.033614) (xy 104.019858 -212.447124) (xy 104.085136 -212.512402) (xy 104.27081 -212.512402)
			(xy 106.003598 -212.512402)
		)
		(stroke
			(width 0)
			(type solid)
		)
		(fill yes)
		(layer "F.Cu")
		(net "P12V_AUX")
	)
	(gr_poly
		(pts
			(xy 106.453686 -116.872258) (xy 106.453686 -116.417344) (xy 106.453686 -116.373148) (xy 106.434382 -116.353844)
			(xy 103.846884 -116.353844) (xy 103.60533 -116.11229) (xy 103.60533 -115.202462) (xy 103.5431 -115.140232)
			(xy 102.669848 -115.140232) (xy 102.607618 -115.202462) (xy 102.607618 -116.686076) (xy 102.824788 -116.903246)
			(xy 106.422698 -116.903246)
		)
		(stroke
			(width 0)
			(type solid)
		)
		(fill yes)
		(layer "F.Cu")
		(net "P12V_AUX")
	)
	(gr_poly
		(pts
			(xy 108.17733 -291.991796) (xy 108.17733 -287.501838) (xy 108.12653 -287.451038) (xy 103.80853 -287.451038)
			(xy 103.766366 -287.492948) (xy 103.766366 -288.050478) (xy 103.766366 -291.792914) (xy 103.766366 -291.996876)
			(xy 103.909368 -292.139878) (xy 104.11333 -292.139878) (xy 105.186988 -292.139878) (xy 105.476802 -292.139878)
			(xy 108.029248 -292.139878)
		)
		(stroke
			(width 0)
			(type solid)
		)
		(fill yes)
		(layer "F.Cu")
		(net "SW_P0V8_PEX0_PH1")
	)
	(gr_poly
		(pts
			(xy 116.337842 -291.991796) (xy 116.337842 -287.501838) (xy 116.287042 -287.451038) (xy 111.969042 -287.451038)
			(xy 111.926878 -287.492948) (xy 111.926878 -288.050478) (xy 111.926878 -291.792914) (xy 111.926878 -291.996876)
			(xy 112.06988 -292.139878) (xy 112.273842 -292.139878) (xy 113.3475 -292.139878) (xy 113.637314 -292.139878)
			(xy 116.18976 -292.139878)
		)
		(stroke
			(width 0)
			(type solid)
		)
		(fill yes)
		(layer "F.Cu")
		(net "SW_P0V8_PEX0_PH2")
	)
	(gr_poly
		(pts
			(xy 124.026422 -156.126434) (xy 124.026422 -153.538936) (xy 124.267976 -153.297382) (xy 125.177804 -153.297382)
			(xy 125.240034 -153.235152) (xy 125.240034 -152.3619) (xy 125.177804 -152.29967) (xy 123.69419 -152.29967)
			(xy 123.47702 -152.51684) (xy 123.47702 -156.11475) (xy 123.508008 -156.145738) (xy 123.962922 -156.145738)
			(xy 124.007118 -156.145738)
		)
		(stroke
			(width 0)
			(type solid)
		)
		(fill yes)
		(layer "F.Cu")
		(net "P12V_AUX")
	)
	(gr_poly
		(pts
			(xy 124.836428 -291.991796) (xy 124.836428 -287.501838) (xy 124.785628 -287.451038) (xy 120.467628 -287.451038)
			(xy 120.425464 -287.492948) (xy 120.425464 -288.050478) (xy 120.425464 -291.792914) (xy 120.425464 -291.996876)
			(xy 120.568466 -292.139878) (xy 120.772428 -292.139878) (xy 121.846086 -292.139878) (xy 122.1359 -292.139878)
			(xy 124.688346 -292.139878)
		)
		(stroke
			(width 0)
			(type solid)
		)
		(fill yes)
		(layer "F.Cu")
		(net "SW_P0V8_PEX1_PH1")
	)
	(gr_poly
		(pts
			(xy 132.99694 -291.991796) (xy 132.99694 -287.501838) (xy 132.94614 -287.451038) (xy 128.62814 -287.451038)
			(xy 128.585976 -287.492948) (xy 128.585976 -288.050478) (xy 128.585976 -291.792914) (xy 128.585976 -291.996876)
			(xy 128.728978 -292.139878) (xy 128.93294 -292.139878) (xy 130.006598 -292.139878) (xy 130.296412 -292.139878)
			(xy 132.848858 -292.139878)
		)
		(stroke
			(width 0)
			(type solid)
		)
		(fill yes)
		(layer "F.Cu")
		(net "SW_P0V8_PEX1_PH2")
	)
	(gr_poly
		(pts
			(xy 137.39368 -162.881564) (xy 137.39368 -159.554418) (xy 137.155936 -159.316674) (xy 132.062728 -159.316674)
			(xy 131.975606 -159.403796) (xy 131.975606 -160.255712) (xy 131.975606 -160.53435) (xy 132.11556 -160.674304)
			(xy 133.154674 -160.674304) (xy 133.283706 -160.803336) (xy 133.283706 -162.762692) (xy 133.542278 -163.021264)
			(xy 137.25398 -163.021264)
		)
		(stroke
			(width 0)
			(type solid)
		)
		(fill yes)
		(layer "F.Cu")
		(net "GND")
	)
	(gr_poly
		(pts
			(xy 149.089872 -244.499892) (xy 149.089872 -243.401088) (xy 148.997162 -243.308378) (xy 148.997162 -241.657378)
			(xy 148.946362 -241.606578) (xy 148.895562 -241.606578) (xy 148.438362 -241.606578) (xy 148.387562 -241.657378)
			(xy 148.387562 -243.206778) (xy 148.387562 -243.308378) (xy 148.387562 -244.51564) (xy 148.427948 -244.556026)
			(xy 149.033738 -244.556026)
		)
		(stroke
			(width 0)
			(type solid)
		)
		(fill yes)
		(layer "F.Cu")
		(net "PWRGD_PEX1_P1V8_PLL")
	)
	(gr_poly
		(pts
			(xy 149.848062 -240.654078) (xy 149.848062 -239.739678) (xy 149.936962 -239.650778) (xy 150.063962 -239.523778)
			(xy 150.698962 -239.523778) (xy 150.724362 -239.498378) (xy 150.724362 -237.339378) (xy 150.546562 -237.161578)
			(xy 148.489162 -237.161578) (xy 148.336762 -237.313978) (xy 148.336762 -240.768378) (xy 148.412962 -240.844578)
			(xy 149.657562 -240.844578)
		)
		(stroke
			(width 0)
			(type solid)
		)
		(fill yes)
		(layer "F.Cu")
		(net "P1V8_PLL0_PEX1")
	)
	(gr_poly
		(pts
			(xy 226.320604 -306.901342) (xy 226.320604 -306.569364) (xy 226.977702 -305.912266) (xy 226.977702 -304.78603)
			(xy 226.91725 -304.725578) (xy 226.422712 -304.725578) (xy 226.351338 -304.725578) (xy 226.230434 -304.846482)
			(xy 226.230434 -305.57724) (xy 225.42119 -306.386484) (xy 225.42119 -306.95519) (xy 225.4504 -306.9844)
			(xy 226.2378 -306.9844)
		)
		(stroke
			(width 0)
			(type solid)
		)
		(fill yes)
		(layer "F.Cu")
		(net "SW_P1V25_PEX1_BT")
	)
	(gr_poly
		(pts
			(xy 226.876864 -321.00393) (xy 226.96805 -320.912744) (xy 226.96805 -320.370962) (xy 226.96805 -318.957452)
			(xy 226.902772 -318.892174) (xy 226.717098 -318.892174) (xy 224.98431 -318.892174) (xy 224.813368 -319.063116)
			(xy 224.813368 -320.436748) (xy 224.813368 -320.958464) (xy 224.858834 -321.00393) (xy 224.93859 -321.083686)
			(xy 226.797108 -321.083686)
		)
		(stroke
			(width 0)
			(type solid)
		)
		(fill yes)
		(layer "F.Cu")
		(net "P12V_AUX")
	)
	(gr_poly
		(pts
			(xy 232.0798 -149.196552) (xy 232.081578 -149.196552) (xy 232.094532 -149.183598) (xy 232.652824 -149.183598)
			(xy 232.652824 -149.094952) (xy 232.128314 -149.094952) (xy 232.126536 -149.093174) (xy 232.111042 -149.07768)
			(xy 232.018078 -148.984716) (xy 231.969818 -148.984716) (xy 231.461818 -148.984716) (xy 231.461818 -149.289516)
			(xy 231.986836 -149.289516)
		)
		(stroke
			(width 0)
			(type solid)
		)
		(fill yes)
		(layer "F.Cu")
		(net "P3V3_CLK_GEN_VDD_CK440_PEX")
	)
	(gr_poly
		(pts
			(xy 232.26649 -121.022872) (xy 232.26649 -120.567958) (xy 232.26649 -120.523762) (xy 232.247186 -120.504458)
			(xy 229.659688 -120.504458) (xy 229.418134 -120.262904) (xy 229.418134 -119.353076) (xy 229.355904 -119.290846)
			(xy 228.482652 -119.290846) (xy 228.420422 -119.353076) (xy 228.420422 -120.83669) (xy 228.637592 -121.05386)
			(xy 232.235502 -121.05386)
		)
		(stroke
			(width 0)
			(type solid)
		)
		(fill yes)
		(layer "F.Cu")
		(net "P12V_AUX")
	)
	(gr_poly
		(pts
			(xy 240.12652 -156.126434) (xy 240.12652 -153.538936) (xy 240.368074 -153.297382) (xy 241.277902 -153.297382)
			(xy 241.340132 -153.235152) (xy 241.340132 -152.3619) (xy 241.277902 -152.29967) (xy 239.794288 -152.29967)
			(xy 239.577118 -152.51684) (xy 239.577118 -156.11475) (xy 239.608106 -156.145738) (xy 240.06302 -156.145738)
			(xy 240.107216 -156.145738)
		)
		(stroke
			(width 0)
			(type solid)
		)
		(fill yes)
		(layer "F.Cu")
		(net "P12V_AUX")
	)
	(gr_poly
		(pts
			(xy 243.127022 -321.00393) (xy 243.218208 -320.912744) (xy 243.218208 -320.370962) (xy 243.218208 -318.957452)
			(xy 243.15293 -318.892174) (xy 242.967256 -318.892174) (xy 241.234468 -318.892174) (xy 241.063526 -319.063116)
			(xy 241.063526 -320.436748) (xy 241.063526 -320.958464) (xy 241.108992 -321.00393) (xy 241.188748 -321.083686)
			(xy 243.047266 -321.083686)
		)
		(stroke
			(width 0)
			(type solid)
		)
		(fill yes)
		(layer "F.Cu")
		(net "P12V_AUX")
	)
	(gr_poly
		(pts
			(xy 253.493778 -162.881564) (xy 253.493778 -159.554418) (xy 253.256034 -159.316674) (xy 248.162826 -159.316674)
			(xy 248.075704 -159.403796) (xy 248.075704 -160.255712) (xy 248.075704 -160.53435) (xy 248.215658 -160.674304)
			(xy 249.254772 -160.674304) (xy 249.383804 -160.803336) (xy 249.383804 -162.762692) (xy 249.642376 -163.021264)
			(xy 253.354078 -163.021264)
		)
		(stroke
			(width 0)
			(type solid)
		)
		(fill yes)
		(layer "F.Cu")
		(net "GND")
	)
	(gr_poly
		(pts
			(xy 261.260336 -243.741702) (xy 261.260336 -242.642898) (xy 261.167626 -242.550188) (xy 261.167626 -240.899188)
			(xy 261.116826 -240.848388) (xy 261.066026 -240.848388) (xy 260.608826 -240.848388) (xy 260.558026 -240.899188)
			(xy 260.558026 -242.448588) (xy 260.558026 -242.550188) (xy 260.558026 -243.75745) (xy 260.598412 -243.797836)
			(xy 261.204202 -243.797836)
		)
		(stroke
			(width 0)
			(type solid)
		)
		(fill yes)
		(layer "F.Cu")
		(net "PWRGD_PEX2_P1V8_PLL")
	)
	(gr_poly
		(pts
			(xy 261.825994 -80.916526) (xy 261.73303 -80.823562) (xy 261.73303 -80.821784) (xy 261.720076 -80.80883)
			(xy 261.720076 -80.250538) (xy 261.63143 -80.250538) (xy 261.63143 -80.775048) (xy 261.629652 -80.776826)
			(xy 261.614158 -80.79232) (xy 261.521194 -80.885284) (xy 261.521194 -80.933544) (xy 261.521194 -81.441544)
			(xy 261.825994 -81.441544)
		)
		(stroke
			(width 0)
			(type solid)
		)
		(fill yes)
		(layer "F.Cu")
		(net "P3V3_CLK_GEN_VDD_CK440")
	)
	(gr_poly
		(pts
			(xy 262.018526 -239.895888) (xy 262.018526 -238.981488) (xy 262.107426 -238.892588) (xy 262.234426 -238.765588)
			(xy 262.869426 -238.765588) (xy 262.894826 -238.740188) (xy 262.894826 -236.581188) (xy 262.717026 -236.403388)
			(xy 260.659626 -236.403388) (xy 260.507226 -236.555788) (xy 260.507226 -240.010188) (xy 260.583426 -240.086388)
			(xy 261.828026 -240.086388)
		)
		(stroke
			(width 0)
			(type solid)
		)
		(fill yes)
		(layer "F.Cu")
		(net "P1V8_PLL0_PEX2")
	)
	(gr_poly
		(pts
			(xy 338.653628 -116.872258) (xy 338.653628 -116.417344) (xy 338.653628 -116.373148) (xy 338.634324 -116.353844)
			(xy 336.046826 -116.353844) (xy 335.805272 -116.11229) (xy 335.805272 -115.202462) (xy 335.743042 -115.140232)
			(xy 334.86979 -115.140232) (xy 334.80756 -115.202462) (xy 334.80756 -116.686076) (xy 335.02473 -116.903246)
			(xy 338.62264 -116.903246)
		)
		(stroke
			(width 0)
			(type solid)
		)
		(fill yes)
		(layer "F.Cu")
		(net "P12V_AUX")
	)
	(gr_poly
		(pts
			(xy 340.377526 -291.991796) (xy 340.377526 -287.501838) (xy 340.326726 -287.451038) (xy 336.008726 -287.451038)
			(xy 335.966562 -287.492948) (xy 335.966562 -288.050478) (xy 335.966562 -291.792914) (xy 335.966562 -291.996876)
			(xy 336.109564 -292.139878) (xy 336.313526 -292.139878) (xy 337.387184 -292.139878) (xy 337.676998 -292.139878)
			(xy 340.229444 -292.139878)
		)
		(stroke
			(width 0)
			(type solid)
		)
		(fill yes)
		(layer "F.Cu")
		(net "SW_P0V8_PEX2_PH1")
	)
	(gr_poly
		(pts
			(xy 348.538038 -291.991796) (xy 348.538038 -287.501838) (xy 348.487238 -287.451038) (xy 344.169238 -287.451038)
			(xy 344.127074 -287.492948) (xy 344.127074 -288.050478) (xy 344.127074 -291.792914) (xy 344.127074 -291.996876)
			(xy 344.270076 -292.139878) (xy 344.474038 -292.139878) (xy 345.547696 -292.139878) (xy 345.83751 -292.139878)
			(xy 348.389956 -292.139878)
		)
		(stroke
			(width 0)
			(type solid)
		)
		(fill yes)
		(layer "F.Cu")
		(net "SW_P0V8_PEX2_PH2")
	)
	(gr_poly
		(pts
			(xy 356.226618 -156.126434) (xy 356.226618 -153.538936) (xy 356.468172 -153.297382) (xy 357.378 -153.297382)
			(xy 357.44023 -153.235152) (xy 357.44023 -152.3619) (xy 357.378 -152.29967) (xy 355.894386 -152.29967)
			(xy 355.677216 -152.51684) (xy 355.677216 -156.11475) (xy 355.708204 -156.145738) (xy 356.163118 -156.145738)
			(xy 356.207314 -156.145738)
		)
		(stroke
			(width 0)
			(type solid)
		)
		(fill yes)
		(layer "F.Cu")
		(net "P12V_AUX")
	)
	(gr_poly
		(pts
			(xy 357.036624 -291.991796) (xy 357.036624 -287.501838) (xy 356.985824 -287.451038) (xy 352.667824 -287.451038)
			(xy 352.62566 -287.492948) (xy 352.62566 -288.050478) (xy 352.62566 -291.792914) (xy 352.62566 -291.996876)
			(xy 352.768662 -292.139878) (xy 352.972624 -292.139878) (xy 354.046282 -292.139878) (xy 354.336096 -292.139878)
			(xy 356.888542 -292.139878)
		)
		(stroke
			(width 0)
			(type solid)
		)
		(fill yes)
		(layer "F.Cu")
		(net "SW_P0V8_PEX3_PH1")
	)
	(gr_poly
		(pts
			(xy 365.197136 -291.991796) (xy 365.197136 -287.501838) (xy 365.146336 -287.451038) (xy 360.828336 -287.451038)
			(xy 360.786172 -287.492948) (xy 360.786172 -288.050478) (xy 360.786172 -291.792914) (xy 360.786172 -291.996876)
			(xy 360.929174 -292.139878) (xy 361.133136 -292.139878) (xy 362.206794 -292.139878) (xy 362.496608 -292.139878)
			(xy 365.049054 -292.139878)
		)
		(stroke
			(width 0)
			(type solid)
		)
		(fill yes)
		(layer "F.Cu")
		(net "SW_P0V8_PEX3_PH2")
	)
	(gr_poly
		(pts
			(xy 369.593876 -162.881564) (xy 369.593876 -159.554418) (xy 369.356132 -159.316674) (xy 364.262924 -159.316674)
			(xy 364.175802 -159.403796) (xy 364.175802 -160.255712) (xy 364.175802 -160.53435) (xy 364.315756 -160.674304)
			(xy 365.35487 -160.674304) (xy 365.483902 -160.803336) (xy 365.483902 -162.762692) (xy 365.742474 -163.021264)
			(xy 369.454176 -163.021264)
		)
		(stroke
			(width 0)
			(type solid)
		)
		(fill yes)
		(layer "F.Cu")
		(net "GND")
	)
	(gr_poly
		(pts
			(xy 454.753726 -116.872258) (xy 454.753726 -116.417344) (xy 454.753726 -116.373148) (xy 454.734422 -116.353844)
			(xy 452.146924 -116.353844) (xy 451.90537 -116.11229) (xy 451.90537 -115.202462) (xy 451.84314 -115.140232)
			(xy 450.969888 -115.140232) (xy 450.907658 -115.202462) (xy 450.907658 -116.686076) (xy 451.124828 -116.903246)
			(xy 454.722738 -116.903246)
		)
		(stroke
			(width 0)
			(type solid)
		)
		(fill yes)
		(layer "F.Cu")
		(net "P12V_AUX")
	)
	(gr_poly
		(pts
			(xy 454.777602 -251.72924) (xy 454.777602 -249.51944) (xy 454.777602 -249.431556) (xy 455.0537 -249.155458)
			(xy 455.0537 -248.677938) (xy 455.03211 -248.656348) (xy 454.167494 -248.656348) (xy 454.117202 -248.70664)
			(xy 454.117202 -249.26544) (xy 453.279002 -250.10364) (xy 453.279002 -251.67844) (xy 453.482202 -251.88164)
			(xy 454.625202 -251.88164)
		)
		(stroke
			(width 0)
			(type solid)
		)
		(fill yes)
		(layer "F.Cu")
		(net "PEX3_P1V8_PLL_EN")
	)
	(gr_poly
		(pts
			(xy 457.497942 -321.127374) (xy 457.589128 -321.036188) (xy 457.589128 -320.494406) (xy 457.589128 -319.080896)
			(xy 457.52385 -319.015618) (xy 457.338176 -319.015618) (xy 455.605388 -319.015618) (xy 455.434446 -319.18656)
			(xy 455.434446 -320.560192) (xy 455.434446 -321.081908) (xy 455.479912 -321.127374) (xy 455.559668 -321.20713)
			(xy 457.418186 -321.20713)
		)
		(stroke
			(width 0)
			(type solid)
		)
		(fill yes)
		(layer "F.Cu")
		(net "P12V_AUX")
	)
	(gr_poly
		(pts
			(xy 458.019912 -251.574554) (xy 458.019912 -250.47575) (xy 457.927202 -250.38304) (xy 457.927202 -248.73204)
			(xy 457.876402 -248.68124) (xy 457.825602 -248.68124) (xy 457.368402 -248.68124) (xy 457.317602 -248.73204)
			(xy 457.317602 -250.28144) (xy 457.317602 -250.38304) (xy 457.317602 -251.590302) (xy 457.357988 -251.630688)
			(xy 457.963778 -251.630688)
		)
		(stroke
			(width 0)
			(type solid)
		)
		(fill yes)
		(layer "F.Cu")
		(net "PWRGD_PEX3_P1V8_PLL")
	)
	(gr_poly
		(pts
			(xy 14.515846 -215.675972) (xy 14.515846 -213.466172) (xy 14.540738 -213.44128) (xy 14.540738 -213.436962)
			(xy 14.794738 -213.182962) (xy 14.794738 -212.627464) (xy 14.770354 -212.60308) (xy 13.905738 -212.60308)
			(xy 13.855446 -212.653372) (xy 13.855446 -213.212172) (xy 13.017246 -214.050372) (xy 13.017246 -215.625172)
			(xy 13.220446 -215.828372) (xy 14.363446 -215.828372)
		)
		(stroke
			(width 0)
			(type solid)
		)
		(fill yes)
		(layer "F.Cu")
		(net "PEX0_P1V8_PLL_EN")
	)
	(gr_poly
		(pts
			(xy 20.021042 -170.734228) (xy 20.021042 -169.9641) (xy 20.021042 -169.935398) (xy 20.33651 -169.61993)
			(xy 20.33651 -169.565574) (xy 20.33651 -169.438066) (xy 20.227544 -169.3291) (xy 20.166584 -169.26814)
			(xy 19.94916 -169.26814) (xy 19.797014 -169.420286) (xy 19.797014 -169.544746) (xy 19.797014 -170.731942)
			(xy 19.826986 -170.761914) (xy 19.993356 -170.761914)
		)
		(stroke
			(width 0)
			(type solid)
		)
		(fill yes)
		(layer "F.Cu")
		(net "SW_P5V_AUX_BT")
	)
	(gr_poly
		(pts
			(xy 21.695156 -173.459394) (xy 21.695156 -172.031406) (xy 21.669756 -172.006006) (xy 21.406612 -172.006006)
			(xy 20.388326 -172.006006) (xy 20.33016 -172.006006) (xy 20.32635 -172.009816) (xy 20.287996 -172.04817)
			(xy 20.287996 -172.106336) (xy 20.287996 -172.798232) (xy 20.782534 -173.29277) (xy 20.949158 -173.459394)
			(xy 21.024342 -173.534578) (xy 21.619972 -173.534578)
		)
		(stroke
			(width 0)
			(type solid)
		)
		(fill yes)
		(layer "F.Cu")
		(net "P5V_AUX_FB")
	)
	(gr_poly
		(pts
			(xy 98.6536 -197.1548) (xy 99.6188 -197.1548) (xy 99.695 -197.0786) (xy 99.695 -196.9262) (xy 99.6188 -196.85)
			(xy 97.028 -196.85) (xy 96.774 -196.596) (xy 94.9452 -196.596) (xy 94.6658 -196.596) (xy 94.6404 -196.6214)
			(xy 94.5134 -196.7484) (xy 94.5134 -198.2216) (xy 94.6658 -198.374) (xy 97.4344 -198.374)
		)
		(stroke
			(width 0)
			(type solid)
		)
		(fill yes)
		(layer "F.Cu")
		(net "GND")
	)
	(gr_poly
		(pts
			(xy 145.847562 -244.654578) (xy 145.847562 -242.444778) (xy 145.872454 -242.419886) (xy 145.872454 -242.415568)
			(xy 146.126454 -242.161568) (xy 146.126454 -241.60607) (xy 146.10207 -241.581686) (xy 145.237454 -241.581686)
			(xy 145.187162 -241.631978) (xy 145.187162 -242.190778) (xy 144.348962 -243.028978) (xy 144.348962 -244.603778)
			(xy 144.552162 -244.806978) (xy 145.695162 -244.806978)
		)
		(stroke
			(width 0)
			(type solid)
		)
		(fill yes)
		(layer "F.Cu")
		(net "PEX1_P1V8_PLL_EN")
	)
	(gr_poly
		(pts
			(xy 226.815396 -152.492456) (xy 226.815396 -151.578818) (xy 226.643692 -151.407114) (xy 226.643692 -150.64486)
			(xy 226.744022 -150.54453) (xy 226.744022 -150.00732) (xy 226.439222 -150.00732) (xy 226.439222 -150.551642)
			(xy 226.55022 -150.66264) (xy 226.55022 -151.366728) (xy 226.2251 -151.691848) (xy 226.2251 -152.54351)
			(xy 226.353624 -152.672034) (xy 226.635818 -152.672034)
		)
		(stroke
			(width 0)
			(type solid)
		)
		(fill yes)
		(layer "F.Cu")
		(net "P3V3_CLK_GEN_VDDMXCK_CK440_PEX")
	)
	(gr_poly
		(pts
			(xy 231.606344 -113.135918) (xy 231.606344 -107.06227) (xy 232.490264 -106.17835) (xy 232.490264 -104.690926)
			(xy 232.28046 -104.481122) (xy 232.249218 -104.481122) (xy 228.645466 -104.481122) (xy 225.317812 -104.481122)
			(xy 224.860358 -104.938576) (xy 224.581974 -105.21696) (xy 224.581974 -111.018574) (xy 224.581974 -112.994948)
			(xy 224.947734 -113.360708) (xy 231.381554 -113.360708)
		)
		(stroke
			(width 0)
			(type solid)
		)
		(fill yes)
		(layer "F.Cu")
		(net "GND")
	)
	(gr_poly
		(pts
			(xy 258.018026 -243.896388) (xy 258.018026 -241.686588) (xy 258.042918 -241.661696) (xy 258.042918 -241.657378)
			(xy 258.296918 -241.403378) (xy 258.296918 -240.84788) (xy 258.272534 -240.823496) (xy 257.407918 -240.823496)
			(xy 257.357626 -240.873788) (xy 257.357626 -241.432588) (xy 256.519426 -242.270788) (xy 256.519426 -243.845588)
			(xy 256.722626 -244.048788) (xy 257.865626 -244.048788)
		)
		(stroke
			(width 0)
			(type solid)
		)
		(fill yes)
		(layer "F.Cu")
		(net "PEX2_P1V8_PLL_EN")
	)
	(gr_poly
		(pts
			(xy 445.936624 -231.704896) (xy 446.818512 -230.823008) (xy 448.27444 -230.823008) (xy 448.356736 -230.740712)
			(xy 448.356736 -230.624888) (xy 448.273424 -230.541576) (xy 446.808098 -230.541576) (xy 446.603628 -230.337106)
			(xy 443.220856 -230.337106) (xy 443.02172 -230.337106) (xy 442.889894 -230.468932) (xy 442.889894 -231.853232)
			(xy 443.061344 -232.024682) (xy 445.616838 -232.024682)
		)
		(stroke
			(width 0)
			(type solid)
		)
		(fill yes)
		(layer "F.Cu")
		(net "GND")
	)
	(gr_poly
		(pts
			(xy 451.984618 -236.605572) (xy 451.984618 -234.682792) (xy 450.745352 -233.443526) (xy 450.745352 -231.51465)
			(xy 450.68109 -231.450388) (xy 450.068188 -231.450388) (xy 449.995544 -231.523032) (xy 449.995544 -233.976926)
			(xy 450.303392 -234.284774) (xy 450.303392 -235.11256) (xy 450.303392 -236.521244) (xy 450.459348 -236.6772)
			(xy 451.385178 -236.6772) (xy 451.91299 -236.6772)
		)
		(stroke
			(width 0)
			(type solid)
		)
		(fill yes)
		(layer "F.Cu")
		(net "P3V3_AUX")
	)
	(gr_poly
		(pts
			(xy 12.023344 -304.685192) (xy 12.023344 -304.4317) (xy 12.023344 -304.282602) (xy 12.680442 -303.625504)
			(xy 12.680442 -302.499268) (xy 12.61999 -302.438816) (xy 12.125452 -302.438816) (xy 12.054078 -302.438816)
			(xy 11.933174 -302.55972) (xy 11.933174 -303.290478) (xy 11.12393 -304.099722) (xy 11.12393 -304.345848)
			(xy 11.12393 -304.698908) (xy 11.164316 -304.739294) (xy 11.969496 -304.739294)
		)
		(stroke
			(width 0)
			(type solid)
		)
		(fill yes)
		(layer "F.Cu")
		(net "SW_P1V25_PEX0_BT")
	)
	(gr_poly
		(pts
			(xy 19.316446 -212.450172) (xy 19.316446 -212.348572) (xy 19.316446 -210.976972) (xy 19.240246 -210.900772)
			(xy 18.859246 -210.900772) (xy 18.808446 -210.951572) (xy 18.808446 -211.865972) (xy 18.554446 -212.119972)
			(xy 17.055846 -212.119972) (xy 17.005046 -212.170772) (xy 17.005046 -212.297772) (xy 17.030446 -212.323172)
			(xy 17.944846 -212.323172) (xy 18.122646 -212.500972) (xy 19.265646 -212.500972)
		)
		(stroke
			(width 0)
			(type solid)
		)
		(fill yes)
		(layer "F.Cu")
		(net "P1V8_PLL_PEX0_ADJ")
	)
	(gr_poly
		(pts
			(xy 69.959982 -44.710604) (xy 69.959982 -44.39793) (xy 70.153784 -44.204128) (xy 70.943216 -44.204128)
			(xy 71.092314 -44.05503) (xy 71.092314 -41.001442) (xy 70.913498 -40.822626) (xy 66.265552 -40.822626)
			(xy 66.265552 -40.82288) (xy 65.758568 -40.82288) (xy 65.565274 -41.016174) (xy 65.565274 -44.755562)
			(xy 65.714118 -44.904406) (xy 66.101722 -44.904406) (xy 69.76618 -44.904406)
		)
		(stroke
			(width 0)
			(type solid)
		)
		(fill yes)
		(layer "F.Cu")
		(net "P12V_SSD2")
	)
	(gr_poly
		(pts
			(xy 95.95993 -44.710604) (xy 95.95993 -44.39793) (xy 96.153732 -44.204128) (xy 96.943164 -44.204128)
			(xy 97.092262 -44.05503) (xy 97.092262 -41.001442) (xy 96.913446 -40.822626) (xy 92.2655 -40.822626)
			(xy 92.2655 -40.82288) (xy 91.758516 -40.82288) (xy 91.565222 -41.016174) (xy 91.565222 -44.755562)
			(xy 91.714066 -44.904406) (xy 92.10167 -44.904406) (xy 95.766128 -44.904406)
		)
		(stroke
			(width 0)
			(type solid)
		)
		(fill yes)
		(layer "F.Cu")
		(net "P12V_SSD3")
	)
	(gr_poly
		(pts
			(xy 134.060184 -44.710604) (xy 134.060184 -44.39793) (xy 134.253986 -44.204128) (xy 135.043418 -44.204128)
			(xy 135.192516 -44.05503) (xy 135.192516 -41.001442) (xy 135.0137 -40.822626) (xy 130.365754 -40.822626)
			(xy 130.365754 -40.82288) (xy 129.85877 -40.82288) (xy 129.665476 -41.016174) (xy 129.665476 -44.755562)
			(xy 129.81432 -44.904406) (xy 130.201924 -44.904406) (xy 133.866382 -44.904406)
		)
		(stroke
			(width 0)
			(type solid)
		)
		(fill yes)
		(layer "F.Cu")
		(net "P12V_SSD4")
	)
	(gr_poly
		(pts
			(xy 150.648162 -241.428778) (xy 150.648162 -241.327178) (xy 150.648162 -239.955578) (xy 150.571962 -239.879378)
			(xy 150.190962 -239.879378) (xy 150.140162 -239.930178) (xy 150.140162 -240.844578) (xy 149.886162 -241.098578)
			(xy 148.387562 -241.098578) (xy 148.336762 -241.149378) (xy 148.336762 -241.276378) (xy 148.362162 -241.301778)
			(xy 149.276562 -241.301778) (xy 149.454362 -241.479578) (xy 150.597362 -241.479578)
		)
		(stroke
			(width 0)
			(type solid)
		)
		(fill yes)
		(layer "F.Cu")
		(net "P1V8_PLL_PEX1_ADJ")
	)
	(gr_poly
		(pts
			(xy 160.060132 -44.710604) (xy 160.060132 -44.39793) (xy 160.253934 -44.204128) (xy 161.043366 -44.204128)
			(xy 161.192464 -44.05503) (xy 161.192464 -41.001442) (xy 161.013648 -40.822626) (xy 156.365702 -40.822626)
			(xy 156.365702 -40.82288) (xy 155.858718 -40.82288) (xy 155.665424 -41.016174) (xy 155.665424 -44.755562)
			(xy 155.814268 -44.904406) (xy 156.201872 -44.904406) (xy 159.86633 -44.904406)
		)
		(stroke
			(width 0)
			(type solid)
		)
		(fill yes)
		(layer "F.Cu")
		(net "P12V_SSD5")
	)
	(gr_poly
		(pts
			(xy 186.06008 -44.710604) (xy 186.06008 -44.39793) (xy 186.253882 -44.204128) (xy 187.043314 -44.204128)
			(xy 187.192412 -44.05503) (xy 187.192412 -41.001442) (xy 187.013596 -40.822626) (xy 182.36565 -40.822626)
			(xy 182.36565 -40.82288) (xy 181.858666 -40.82288) (xy 181.665372 -41.016174) (xy 181.665372 -44.755562)
			(xy 181.814216 -44.904406) (xy 182.20182 -44.904406) (xy 185.866278 -44.904406)
		)
		(stroke
			(width 0)
			(type solid)
		)
		(fill yes)
		(layer "F.Cu")
		(net "P12V_SSD6")
	)
	(gr_poly
		(pts
			(xy 212.060028 -44.710604) (xy 212.060028 -44.39793) (xy 212.25383 -44.204128) (xy 213.043262 -44.204128)
			(xy 213.19236 -44.05503) (xy 213.19236 -41.001442) (xy 213.013544 -40.822626) (xy 208.365598 -40.822626)
			(xy 208.365598 -40.82288) (xy 207.858614 -40.82288) (xy 207.66532 -41.016174) (xy 207.66532 -44.755562)
			(xy 207.814164 -44.904406) (xy 208.201768 -44.904406) (xy 211.866226 -44.904406)
		)
		(stroke
			(width 0)
			(type solid)
		)
		(fill yes)
		(layer "F.Cu")
		(net "P12V_SSD7")
	)
	(gr_poly
		(pts
			(xy 224.339404 -146.687286) (xy 225.06305 -146.687286) (xy 225.165158 -146.789394) (xy 225.213418 -146.789394)
			(xy 225.721418 -146.789394) (xy 225.721418 -146.484594) (xy 225.188526 -146.484594) (xy 225.07956 -146.59356)
			(xy 224.314258 -146.59356) (xy 224.181924 -146.461226) (xy 223.629982 -146.461226) (xy 223.582992 -146.508216)
			(xy 223.582992 -146.757898) (xy 223.664526 -146.839432) (xy 224.187258 -146.839432)
		)
		(stroke
			(width 0)
			(type solid)
		)
		(fill yes)
		(layer "F.Cu")
		(net "P3V3_CLK_GEN_VDDMXCK_CK440_PEX")
	)
	(gr_poly
		(pts
			(xy 228.744018 -143.712438) (xy 228.643688 -143.612108) (xy 228.643688 -142.574518) (xy 228.66731 -142.550388)
			(xy 228.66731 -142.050516) (xy 228.594158 -141.977364) (xy 228.481636 -141.977364) (xy 228.181408 -141.977364)
			(xy 228.119686 -142.039086) (xy 228.119686 -142.351506) (xy 228.550216 -142.782036) (xy 228.55047 -143.611092)
			(xy 228.439218 -143.722344) (xy 228.439218 -144.26692) (xy 228.744018 -144.26692)
		)
		(stroke
			(width 0)
			(type solid)
		)
		(fill yes)
		(layer "F.Cu")
		(net "P3V3_CLK_GEN_VDDPT_CK440_PEX")
	)
	(gr_poly
		(pts
			(xy 242.570762 -306.971954) (xy 242.570762 -306.718462) (xy 242.570762 -306.569364) (xy 243.22786 -305.912266)
			(xy 243.22786 -304.78603) (xy 243.167408 -304.725578) (xy 242.67287 -304.725578) (xy 242.601496 -304.725578)
			(xy 242.480592 -304.846482) (xy 242.480592 -305.57724) (xy 241.671348 -306.386484) (xy 241.671348 -306.63261)
			(xy 241.671348 -306.98567) (xy 241.711734 -307.026056) (xy 242.516914 -307.026056)
		)
		(stroke
			(width 0)
			(type solid)
		)
		(fill yes)
		(layer "F.Cu")
		(net "SW_P1V25_PEX2_BT")
	)
	(gr_poly
		(pts
			(xy 250.160028 -44.710604) (xy 250.160028 -44.39793) (xy 250.35383 -44.204128) (xy 251.143262 -44.204128)
			(xy 251.29236 -44.05503) (xy 251.29236 -41.001442) (xy 251.113544 -40.822626) (xy 246.465598 -40.822626)
			(xy 246.465598 -40.82288) (xy 245.958614 -40.82288) (xy 245.76532 -41.016174) (xy 245.76532 -44.755562)
			(xy 245.914164 -44.904406) (xy 246.301768 -44.904406) (xy 249.966226 -44.904406)
		)
		(stroke
			(width 0)
			(type solid)
		)
		(fill yes)
		(layer "F.Cu")
		(net "P12V_SSD8")
	)
	(gr_poly
		(pts
			(xy 259.37591 -89.238836) (xy 259.37591 -88.716104) (xy 259.223256 -88.56345) (xy 259.223256 -87.84082)
			(xy 259.325872 -87.738204) (xy 259.325872 -87.689944) (xy 259.325872 -87.181944) (xy 259.021072 -87.181944)
			(xy 259.021072 -87.714836) (xy 259.130038 -87.823802) (xy 259.130038 -88.589104) (xy 258.997704 -88.721438)
			(xy 258.997704 -89.27338) (xy 259.044694 -89.32037) (xy 259.294376 -89.32037)
		)
		(stroke
			(width 0)
			(type solid)
		)
		(fill yes)
		(layer "F.Cu")
		(net "P3V3_CLK_GEN_VDDMXCK_CK440")
	)
	(gr_poly
		(pts
			(xy 262.818626 -240.670588) (xy 262.818626 -240.568988) (xy 262.818626 -239.197388) (xy 262.742426 -239.121188)
			(xy 262.361426 -239.121188) (xy 262.310626 -239.171988) (xy 262.310626 -240.086388) (xy 262.056626 -240.340388)
			(xy 260.558026 -240.340388) (xy 260.507226 -240.391188) (xy 260.507226 -240.518188) (xy 260.532626 -240.543588)
			(xy 261.447026 -240.543588) (xy 261.624826 -240.721388) (xy 262.767826 -240.721388)
		)
		(stroke
			(width 0)
			(type solid)
		)
		(fill yes)
		(layer "F.Cu")
		(net "P1V8_PLL_PEX2_ADJ")
	)
	(gr_poly
		(pts
			(xy 276.159976 -44.710604) (xy 276.159976 -44.39793) (xy 276.353778 -44.204128) (xy 277.14321 -44.204128)
			(xy 277.292308 -44.05503) (xy 277.292308 -41.001442) (xy 277.113492 -40.822626) (xy 272.465546 -40.822626)
			(xy 272.465546 -40.82288) (xy 271.958562 -40.82288) (xy 271.765268 -41.016174) (xy 271.765268 -44.755562)
			(xy 271.914112 -44.904406) (xy 272.301716 -44.904406) (xy 275.966174 -44.904406)
		)
		(stroke
			(width 0)
			(type solid)
		)
		(fill yes)
		(layer "F.Cu")
		(net "P12V_SSD9")
	)
	(gr_poly
		(pts
			(xy 302.159924 -44.710604) (xy 302.159924 -44.39793) (xy 302.353726 -44.204128) (xy 303.143158 -44.204128)
			(xy 303.292256 -44.05503) (xy 303.292256 -41.001442) (xy 303.11344 -40.822626) (xy 298.465494 -40.822626)
			(xy 298.465494 -40.82288) (xy 297.95851 -40.82288) (xy 297.765216 -41.016174) (xy 297.765216 -44.755562)
			(xy 297.91406 -44.904406) (xy 298.301664 -44.904406) (xy 301.966122 -44.904406)
		)
		(stroke
			(width 0)
			(type solid)
		)
		(fill yes)
		(layer "F.Cu")
		(net "P12V_SSD10")
	)
	(gr_poly
		(pts
			(xy 328.159872 -44.710604) (xy 328.159872 -44.39793) (xy 328.353674 -44.204128) (xy 329.143106 -44.204128)
			(xy 329.292204 -44.05503) (xy 329.292204 -41.001442) (xy 329.113388 -40.822626) (xy 324.465442 -40.822626)
			(xy 324.465442 -40.82288) (xy 323.958458 -40.82288) (xy 323.765164 -41.016174) (xy 323.765164 -44.755562)
			(xy 323.914008 -44.904406) (xy 324.301612 -44.904406) (xy 327.96607 -44.904406)
		)
		(stroke
			(width 0)
			(type solid)
		)
		(fill yes)
		(layer "F.Cu")
		(net "P12V_SSD11")
	)
	(gr_poly
		(pts
			(xy 366.260126 -44.710604) (xy 366.260126 -44.39793) (xy 366.453928 -44.204128) (xy 367.24336 -44.204128)
			(xy 367.392458 -44.05503) (xy 367.392458 -41.001442) (xy 367.213642 -40.822626) (xy 362.565696 -40.822626)
			(xy 362.565696 -40.82288) (xy 362.058712 -40.82288) (xy 361.865418 -41.016174) (xy 361.865418 -44.755562)
			(xy 362.014262 -44.904406) (xy 362.401866 -44.904406) (xy 366.066324 -44.904406)
		)
		(stroke
			(width 0)
			(type solid)
		)
		(fill yes)
		(layer "F.Cu")
		(net "P12V_SSD12")
	)
	(gr_poly
		(pts
			(xy 366.706912 -308.245002) (xy 366.706912 -303.883568) (xy 366.634522 -303.811178) (xy 351.846134 -303.811178)
			(xy 351.689416 -303.967896) (xy 351.689416 -304.97907) (xy 351.445322 -305.223164) (xy 348.304104 -305.223164)
			(xy 348.113604 -305.032664) (xy 348.113604 -303.811178) (xy 333.252826 -303.811178) (xy 333.096108 -303.967896)
			(xy 333.096108 -308.07406) (xy 333.347568 -308.32552) (xy 366.626394 -308.32552)
		)
		(stroke
			(width 0)
			(type solid)
		)
		(fill yes)
		(layer "F.Cu")
		(net "GND")
	)
	(gr_poly
		(pts
			(xy 392.260074 -44.710604) (xy 392.260074 -44.39793) (xy 392.453876 -44.204128) (xy 393.243308 -44.204128)
			(xy 393.392406 -44.05503) (xy 393.392406 -41.001442) (xy 393.21359 -40.822626) (xy 388.565644 -40.822626)
			(xy 388.565644 -40.82288) (xy 388.05866 -40.82288) (xy 387.865366 -41.016174) (xy 387.865366 -44.755562)
			(xy 388.01421 -44.904406) (xy 388.401814 -44.904406) (xy 392.066272 -44.904406)
		)
		(stroke
			(width 0)
			(type solid)
		)
		(fill yes)
		(layer "F.Cu")
		(net "P12V_SSD13")
	)
	(gr_poly
		(pts
			(xy 418.260022 -44.710604) (xy 418.260022 -44.39793) (xy 418.453824 -44.204128) (xy 419.243256 -44.204128)
			(xy 419.392354 -44.05503) (xy 419.392354 -41.001442) (xy 419.213538 -40.822626) (xy 414.565592 -40.822626)
			(xy 414.565592 -40.82288) (xy 414.058608 -40.82288) (xy 413.865314 -41.016174) (xy 413.865314 -44.755562)
			(xy 414.014158 -44.904406) (xy 414.401762 -44.904406) (xy 418.06622 -44.904406)
		)
		(stroke
			(width 0)
			(type solid)
		)
		(fill yes)
		(layer "F.Cu")
		(net "P12V_SSD14")
	)
	(gr_poly
		(pts
			(xy 444.25997 -44.710604) (xy 444.25997 -44.39793) (xy 444.453772 -44.204128) (xy 445.243204 -44.204128)
			(xy 445.392302 -44.05503) (xy 445.392302 -41.001442) (xy 445.213486 -40.822626) (xy 440.56554 -40.822626)
			(xy 440.56554 -40.82288) (xy 440.058556 -40.82288) (xy 439.865262 -41.016174) (xy 439.865262 -44.755562)
			(xy 440.014106 -44.904406) (xy 440.40171 -44.904406) (xy 444.066168 -44.904406)
		)
		(stroke
			(width 0)
			(type solid)
		)
		(fill yes)
		(layer "F.Cu")
		(net "P12V_SSD15")
	)
	(gr_poly
		(pts
			(xy 456.941682 -307.095398) (xy 456.941682 -306.841906) (xy 456.941682 -306.692808) (xy 457.59878 -306.03571)
			(xy 457.59878 -304.909474) (xy 457.538328 -304.849022) (xy 457.04379 -304.849022) (xy 456.972416 -304.849022)
			(xy 456.851512 -304.969926) (xy 456.851512 -305.700684) (xy 456.042268 -306.509928) (xy 456.042268 -306.756054)
			(xy 456.042268 -307.109114) (xy 456.082654 -307.1495) (xy 456.887834 -307.1495)
		)
		(stroke
			(width 0)
			(type solid)
		)
		(fill yes)
		(layer "F.Cu")
		(net "SW_P1V25_PEX3_BT")
	)
	(gr_poly
		(pts
			(xy 459.578202 -248.50344) (xy 459.578202 -248.40184) (xy 459.578202 -247.03024) (xy 459.502002 -246.95404)
			(xy 459.121002 -246.95404) (xy 459.070202 -247.00484) (xy 459.070202 -247.91924) (xy 458.816202 -248.17324)
			(xy 457.317602 -248.17324) (xy 457.268834 -248.222008) (xy 457.268834 -248.353072) (xy 457.292202 -248.37644)
			(xy 458.206602 -248.37644) (xy 458.384402 -248.55424) (xy 459.527402 -248.55424)
		)
		(stroke
			(width 0)
			(type solid)
		)
		(fill yes)
		(layer "F.Cu")
		(net "P1V8_PLL_PEX3_ADJ")
	)
	(gr_poly
		(pts
			(xy 18.046954 -172.268134) (xy 18.046954 -171.447206) (xy 18.71218 -170.78198) (xy 18.942304 -170.78198)
			(xy 19.00174 -170.72229) (xy 19.00174 -170.063922) (xy 19.00174 -169.928794) (xy 19.00174 -168.878504)
			(xy 18.970752 -168.847516) (xy 15.747238 -168.847516) (xy 15.611348 -168.983406) (xy 15.611348 -172.36313)
			(xy 15.762732 -172.514514) (xy 15.938754 -172.514514) (xy 16.208756 -172.514514) (xy 17.800574 -172.514514)
		)
		(stroke
			(width 0)
			(type solid)
		)
		(fill yes)
		(layer "F.Cu")
		(net "SW_P5V_AUX_PH")
	)
	(gr_poly
		(pts
			(xy 19.66341 -69.8881) (xy 20.318476 -69.8881) (xy 20.388326 -69.81825) (xy 20.388326 -69.189092)
			(xy 20.248626 -69.049392) (xy 19.60245 -69.049392) (xy 19.576034 -69.075808) (xy 18.641314 -68.141088)
			(xy 18.641314 -67.450716) (xy 17.829022 -66.638424) (xy 14.124686 -66.638424) (xy 13.949934 -66.813176)
			(xy 13.949934 -70.1675) (xy 14.142212 -70.359778) (xy 16.029178 -70.359778) (xy 19.191732 -70.359778)
		)
		(stroke
			(width 0)
			(type solid)
		)
		(fill yes)
		(layer "F.Cu")
		(net "P12V_SSD0_R")
	)
	(gr_poly
		(pts
			(xy 45.663358 -69.8881) (xy 46.318424 -69.8881) (xy 46.388274 -69.81825) (xy 46.388274 -69.189092)
			(xy 46.248574 -69.049392) (xy 45.602398 -69.049392) (xy 45.575982 -69.075808) (xy 44.641262 -68.141088)
			(xy 44.641262 -67.450716) (xy 43.82897 -66.638424) (xy 40.124634 -66.638424) (xy 39.949882 -66.813176)
			(xy 39.949882 -70.1675) (xy 40.14216 -70.359778) (xy 42.029126 -70.359778) (xy 45.19168 -70.359778)
		)
		(stroke
			(width 0)
			(type solid)
		)
		(fill yes)
		(layer "F.Cu")
		(net "P12V_SSD1_R")
	)
	(gr_poly
		(pts
			(xy 71.663306 -69.8881) (xy 72.318372 -69.8881) (xy 72.388222 -69.81825) (xy 72.388222 -69.189092)
			(xy 72.248522 -69.049392) (xy 71.602346 -69.049392) (xy 71.57593 -69.075808) (xy 70.64121 -68.141088)
			(xy 70.64121 -67.450716) (xy 69.828918 -66.638424) (xy 66.124582 -66.638424) (xy 65.94983 -66.813176)
			(xy 65.94983 -70.1675) (xy 66.142108 -70.359778) (xy 68.029074 -70.359778) (xy 71.191628 -70.359778)
		)
		(stroke
			(width 0)
			(type solid)
		)
		(fill yes)
		(layer "F.Cu")
		(net "P12V_SSD2_R")
	)
	(gr_poly
		(pts
			(xy 97.663254 -69.8881) (xy 98.31832 -69.8881) (xy 98.38817 -69.81825) (xy 98.38817 -69.189092) (xy 98.24847 -69.049392)
			(xy 97.602294 -69.049392) (xy 97.575878 -69.075808) (xy 96.641158 -68.141088) (xy 96.641158 -67.450716)
			(xy 95.828866 -66.638424) (xy 92.12453 -66.638424) (xy 91.949778 -66.813176) (xy 91.949778 -70.1675)
			(xy 92.142056 -70.359778) (xy 94.029022 -70.359778) (xy 97.191576 -70.359778)
		)
		(stroke
			(width 0)
			(type solid)
		)
		(fill yes)
		(layer "F.Cu")
		(net "P12V_SSD3_R")
	)
	(gr_poly
		(pts
			(xy 114.144552 -231.587548) (xy 115.092734 -231.587548) (xy 115.448588 -231.231694) (xy 115.448588 -213.98611)
			(xy 115.207034 -213.744556) (xy 113.962434 -213.744556) (xy 110.064804 -213.744556) (xy 106.970068 -213.744556)
			(xy 106.753406 -213.961218) (xy 106.753406 -223.949006) (xy 106.804714 -224.000314) (xy 109.066584 -224.000314)
			(xy 109.265466 -224.199196) (xy 109.265466 -231.310942) (xy 109.56163 -231.607106) (xy 114.124994 -231.607106)
		)
		(stroke
			(width 0)
			(type solid)
		)
		(fill yes)
		(layer "F.Cu")
		(net "GND")
	)
	(gr_poly
		(pts
			(xy 135.763508 -69.8881) (xy 136.418574 -69.8881) (xy 136.488424 -69.81825) (xy 136.488424 -69.189092)
			(xy 136.348724 -69.049392) (xy 135.702548 -69.049392) (xy 135.676132 -69.075808) (xy 134.741412 -68.141088)
			(xy 134.741412 -67.450716) (xy 133.92912 -66.638424) (xy 130.224784 -66.638424) (xy 130.050032 -66.813176)
			(xy 130.050032 -70.1675) (xy 130.24231 -70.359778) (xy 132.129276 -70.359778) (xy 135.29183 -70.359778)
		)
		(stroke
			(width 0)
			(type solid)
		)
		(fill yes)
		(layer "F.Cu")
		(net "P12V_SSD4_R")
	)
	(gr_poly
		(pts
			(xy 161.763456 -69.8881) (xy 162.418522 -69.8881) (xy 162.488372 -69.81825) (xy 162.488372 -69.189092)
			(xy 162.348672 -69.049392) (xy 161.702496 -69.049392) (xy 161.67608 -69.075808) (xy 160.74136 -68.141088)
			(xy 160.74136 -67.450716) (xy 159.929068 -66.638424) (xy 156.224732 -66.638424) (xy 156.04998 -66.813176)
			(xy 156.04998 -70.1675) (xy 156.242258 -70.359778) (xy 158.129224 -70.359778) (xy 161.291778 -70.359778)
		)
		(stroke
			(width 0)
			(type solid)
		)
		(fill yes)
		(layer "F.Cu")
		(net "P12V_SSD5_R")
	)
	(gr_poly
		(pts
			(xy 187.763404 -69.8881) (xy 188.41847 -69.8881) (xy 188.48832 -69.81825) (xy 188.48832 -69.189092)
			(xy 188.34862 -69.049392) (xy 187.702444 -69.049392) (xy 187.676028 -69.075808) (xy 186.741308 -68.141088)
			(xy 186.741308 -67.450716) (xy 185.929016 -66.638424) (xy 182.22468 -66.638424) (xy 182.049928 -66.813176)
			(xy 182.049928 -70.1675) (xy 182.242206 -70.359778) (xy 184.129172 -70.359778) (xy 187.291726 -70.359778)
		)
		(stroke
			(width 0)
			(type solid)
		)
		(fill yes)
		(layer "F.Cu")
		(net "P12V_SSD6_R")
	)
	(gr_poly
		(pts
			(xy 213.047072 -124.76226) (xy 213.047072 -121.139966) (xy 213.028022 -121.120916) (xy 212.943948 -121.120916)
			(xy 212.51418 -121.120916) (xy 212.398864 -121.0056) (xy 212.398864 -118.560088) (xy 212.335618 -118.496842)
			(xy 210.486498 -118.496842) (xy 210.385406 -118.597934) (xy 210.385406 -121.614692) (xy 210.187286 -121.812812)
			(xy 210.187286 -124.553472) (xy 210.187286 -124.915676) (xy 210.265772 -124.994162) (xy 212.81517 -124.994162)
		)
		(stroke
			(width 0)
			(type solid)
		)
		(fill yes)
		(layer "F.Cu")
		(net "P3V3_AUX")
	)
	(gr_poly
		(pts
			(xy 213.763352 -69.8881) (xy 214.418418 -69.8881) (xy 214.488268 -69.81825) (xy 214.488268 -69.189092)
			(xy 214.348568 -69.049392) (xy 213.702392 -69.049392) (xy 213.675976 -69.075808) (xy 212.741256 -68.141088)
			(xy 212.741256 -67.450716) (xy 211.928964 -66.638424) (xy 208.224628 -66.638424) (xy 208.049876 -66.813176)
			(xy 208.049876 -70.1675) (xy 208.242154 -70.359778) (xy 210.12912 -70.359778) (xy 213.291674 -70.359778)
		)
		(stroke
			(width 0)
			(type solid)
		)
		(fill yes)
		(layer "F.Cu")
		(net "P12V_SSD7_R")
	)
	(gr_poly
		(pts
			(xy 251.863352 -69.8881) (xy 252.518418 -69.8881) (xy 252.588268 -69.81825) (xy 252.588268 -69.189092)
			(xy 252.448568 -69.049392) (xy 251.802392 -69.049392) (xy 251.775976 -69.075808) (xy 250.841256 -68.141088)
			(xy 250.841256 -67.450716) (xy 250.028964 -66.638424) (xy 246.324628 -66.638424) (xy 246.149876 -66.813176)
			(xy 246.149876 -70.1675) (xy 246.342154 -70.359778) (xy 248.22912 -70.359778) (xy 251.391674 -70.359778)
		)
		(stroke
			(width 0)
			(type solid)
		)
		(fill yes)
		(layer "F.Cu")
		(net "P12V_SSD8_R")
	)
	(gr_poly
		(pts
			(xy 255.240536 -84.353146) (xy 256.147824 -84.353146) (xy 256.258822 -84.464144) (xy 256.803398 -84.464144)
			(xy 256.803398 -84.159344) (xy 256.248916 -84.159344) (xy 256.148586 -84.259674) (xy 255.110996 -84.259674)
			(xy 255.086866 -84.236052) (xy 254.96647 -84.236052) (xy 254.586994 -84.236052) (xy 254.513842 -84.309204)
			(xy 254.513842 -84.421726) (xy 254.513842 -84.721954) (xy 254.575564 -84.783676) (xy 254.810006 -84.783676)
		)
		(stroke
			(width 0)
			(type solid)
		)
		(fill yes)
		(layer "F.Cu")
		(net "P3V3_CLK_GEN_VDDPT_CK440")
	)
	(gr_poly
		(pts
			(xy 265.208512 -86.549738) (xy 265.208512 -86.267544) (xy 265.028934 -86.087966) (xy 264.115296 -86.087966)
			(xy 263.943592 -86.25967) (xy 263.181338 -86.25967) (xy 263.081008 -86.15934) (xy 262.543798 -86.15934)
			(xy 262.543798 -86.46414) (xy 263.08812 -86.46414) (xy 263.199118 -86.353142) (xy 263.899142 -86.353142)
			(xy 263.906 -86.36) (xy 264.224262 -86.678262) (xy 264.228326 -86.678262) (xy 265.079988 -86.678262)
		)
		(stroke
			(width 0)
			(type solid)
		)
		(fill yes)
		(layer "F.Cu")
		(net "P3V3_CLK_GEN_VDDMXCK_CK440")
	)
	(gr_poly
		(pts
			(xy 277.8633 -69.8881) (xy 278.518366 -69.8881) (xy 278.588216 -69.81825) (xy 278.588216 -69.189092)
			(xy 278.448516 -69.049392) (xy 277.80234 -69.049392) (xy 277.775924 -69.075808) (xy 276.841204 -68.141088)
			(xy 276.841204 -67.450716) (xy 276.028912 -66.638424) (xy 272.324576 -66.638424) (xy 272.149824 -66.813176)
			(xy 272.149824 -70.1675) (xy 272.342102 -70.359778) (xy 274.229068 -70.359778) (xy 277.391622 -70.359778)
		)
		(stroke
			(width 0)
			(type solid)
		)
		(fill yes)
		(layer "F.Cu")
		(net "P12V_SSD9_R")
	)
	(gr_poly
		(pts
			(xy 303.863248 -69.8881) (xy 304.518314 -69.8881) (xy 304.588164 -69.81825) (xy 304.588164 -69.189092)
			(xy 304.448464 -69.049392) (xy 303.802288 -69.049392) (xy 303.775872 -69.075808) (xy 302.841152 -68.141088)
			(xy 302.841152 -67.450716) (xy 302.02886 -66.638424) (xy 298.324524 -66.638424) (xy 298.149772 -66.813176)
			(xy 298.149772 -70.1675) (xy 298.34205 -70.359778) (xy 300.229016 -70.359778) (xy 303.39157 -70.359778)
		)
		(stroke
			(width 0)
			(type solid)
		)
		(fill yes)
		(layer "F.Cu")
		(net "P12V_SSD10_R")
	)
	(gr_poly
		(pts
			(xy 329.863196 -69.8881) (xy 330.518262 -69.8881) (xy 330.588112 -69.81825) (xy 330.588112 -69.189092)
			(xy 330.448412 -69.049392) (xy 329.802236 -69.049392) (xy 329.77582 -69.075808) (xy 328.8411 -68.141088)
			(xy 328.8411 -67.450716) (xy 328.028808 -66.638424) (xy 324.324472 -66.638424) (xy 324.14972 -66.813176)
			(xy 324.14972 -70.1675) (xy 324.341998 -70.359778) (xy 326.228964 -70.359778) (xy 329.391518 -70.359778)
		)
		(stroke
			(width 0)
			(type solid)
		)
		(fill yes)
		(layer "F.Cu")
		(net "P12V_SSD11_R")
	)
	(gr_poly
		(pts
			(xy 367.96345 -69.8881) (xy 368.618516 -69.8881) (xy 368.688366 -69.81825) (xy 368.688366 -69.189092)
			(xy 368.548666 -69.049392) (xy 367.90249 -69.049392) (xy 367.876074 -69.075808) (xy 366.941354 -68.141088)
			(xy 366.941354 -67.450716) (xy 366.129062 -66.638424) (xy 362.424726 -66.638424) (xy 362.249974 -66.813176)
			(xy 362.249974 -70.1675) (xy 362.442252 -70.359778) (xy 364.329218 -70.359778) (xy 367.491772 -70.359778)
		)
		(stroke
			(width 0)
			(type solid)
		)
		(fill yes)
		(layer "F.Cu")
		(net "P12V_SSD12_R")
	)
	(gr_poly
		(pts
			(xy 393.963398 -69.8881) (xy 394.618464 -69.8881) (xy 394.688314 -69.81825) (xy 394.688314 -69.189092)
			(xy 394.548614 -69.049392) (xy 393.902438 -69.049392) (xy 393.876022 -69.075808) (xy 392.941302 -68.141088)
			(xy 392.941302 -67.450716) (xy 392.12901 -66.638424) (xy 388.424674 -66.638424) (xy 388.249922 -66.813176)
			(xy 388.249922 -70.1675) (xy 388.4422 -70.359778) (xy 390.329166 -70.359778) (xy 393.49172 -70.359778)
		)
		(stroke
			(width 0)
			(type solid)
		)
		(fill yes)
		(layer "F.Cu")
		(net "P12V_SSD13_R")
	)
	(gr_poly
		(pts
			(xy 419.963346 -69.8881) (xy 420.618412 -69.8881) (xy 420.688262 -69.81825) (xy 420.688262 -69.189092)
			(xy 420.548562 -69.049392) (xy 419.902386 -69.049392) (xy 419.87597 -69.075808) (xy 418.94125 -68.141088)
			(xy 418.94125 -67.450716) (xy 418.128958 -66.638424) (xy 414.424622 -66.638424) (xy 414.24987 -66.813176)
			(xy 414.24987 -70.1675) (xy 414.442148 -70.359778) (xy 416.329114 -70.359778) (xy 419.491668 -70.359778)
		)
		(stroke
			(width 0)
			(type solid)
		)
		(fill yes)
		(layer "F.Cu")
		(net "P12V_SSD14_R")
	)
	(gr_poly
		(pts
			(xy 445.963294 -69.8881) (xy 446.61836 -69.8881) (xy 446.68821 -69.81825) (xy 446.68821 -69.189092)
			(xy 446.54851 -69.049392) (xy 445.902334 -69.049392) (xy 445.875918 -69.075808) (xy 444.941198 -68.141088)
			(xy 444.941198 -67.450716) (xy 444.128906 -66.638424) (xy 440.42457 -66.638424) (xy 440.249818 -66.813176)
			(xy 440.249818 -70.1675) (xy 440.442096 -70.359778) (xy 442.329062 -70.359778) (xy 445.491616 -70.359778)
		)
		(stroke
			(width 0)
			(type solid)
		)
		(fill yes)
		(layer "F.Cu")
		(net "P12V_SSD15_R")
	)
	(gr_poly
		(pts
			(xy 453.966326 -236.516926) (xy 453.966326 -234.82808) (xy 453.41286 -234.274614) (xy 452.744586 -234.274614)
			(xy 451.565772 -233.0958) (xy 451.448932 -233.0958) (xy 451.239636 -232.886504) (xy 451.239636 -231.5083)
			(xy 451.185026 -231.45369) (xy 451.063614 -231.45369) (xy 451.0024 -231.514904) (xy 451.0024 -233.294682)
			(xy 452.24827 -234.540552) (xy 452.24827 -236.600492) (xy 452.338694 -236.690916) (xy 453.792336 -236.690916)
		)
		(stroke
			(width 0)
			(type solid)
		)
		(fill yes)
		(layer "F.Cu")
		(net "GND")
	)
	(gr_poly
		(pts
			(xy 105.633266 -226.156266) (xy 105.633266 -222.778066) (xy 106.000804 -222.410528) (xy 106.471974 -221.939358)
			(xy 106.471974 -213.242652) (xy 106.312462 -213.08314) (xy 103.045006 -213.08314) (xy 102.91953 -213.208616)
			(xy 102.91953 -218.120976) (xy 103.408734 -218.61018) (xy 105.21823 -220.419676) (xy 105.323386 -220.525086)
			(xy 105.323386 -225.036126) (xy 104.990646 -225.368866) (xy 104.990646 -226.176586) (xy 105.023666 -226.209606)
			(xy 105.579926 -226.209606)
		)
		(stroke
			(width 0)
			(type solid)
		)
		(fill yes)
		(layer "F.Cu")
		(net "SW_P12V_P1V8_PEX_FLT")
	)
	(gr_poly
		(pts
			(arc
				(start 204.238352 -367.3094)
				(mid 204.234451 -367.289877)
				(end 204.223366 -367.273332)
			)
			(xy 204.22108 -367.271046) (xy 204.202538 -367.263426)
			(arc
				(start 202.723496 -367.263426)
				(mid 202.703973 -367.267327)
				(end 202.687428 -367.278412)
			)
			(arc
				(start 202.668124 -367.297716)
				(mid 202.657013 -367.31425)
				(end 202.653138 -367.333784)
			)
			(xy 202.653138 -368.346736) (xy 202.687428 -368.38128) (xy 204.238352 -368.38128)
		)
		(stroke
			(width 0)
			(type solid)
		)
		(fill yes)
		(layer "F.Cu")
		(net "HSC_VDD_R")
	)
	(gr_poly
		(pts
			(xy 224.149666 -149.506686) (xy 224.149666 -149.354286) (xy 224.316798 -149.187154) (xy 225.062796 -149.187154)
			(xy 225.165158 -149.289516) (xy 225.213418 -149.289516) (xy 225.721418 -149.289516) (xy 225.721418 -148.984716)
			(xy 225.179636 -148.984716) (xy 225.07067 -149.093682) (xy 223.908112 -149.093682) (xy 223.857566 -149.144228)
			(xy 223.800924 -149.144228) (xy 223.616266 -149.328886) (xy 223.616266 -149.50948) (xy 223.759776 -149.65299)
			(xy 224.003362 -149.65299)
		)
		(stroke
			(width 0)
			(type solid)
		)
		(fill yes)
		(layer "F.Cu")
		(net "P3V3_CLK_GEN_VDDMXCK_CK440_PEX")
	)
	(gr_poly
		(pts
			(xy 262.189468 -89.143586) (xy 262.189468 -88.9) (xy 262.043164 -88.753696) (xy 261.890764 -88.753696)
			(xy 261.723632 -88.586564) (xy 261.723632 -87.840566) (xy 261.825994 -87.738204) (xy 261.825994 -87.689944)
			(xy 261.825994 -87.181944) (xy 261.521194 -87.181944) (xy 261.521194 -87.723726) (xy 261.63016 -87.832692)
			(xy 261.63016 -88.99525) (xy 261.680706 -89.045796) (xy 261.680706 -89.102438) (xy 261.865364 -89.287096)
			(xy 262.045958 -89.287096)
		)
		(stroke
			(width 0)
			(type solid)
		)
		(fill yes)
		(layer "F.Cu")
		(net "P3V3_CLK_GEN_VDDMXCK_CK440")
	)
	(gr_poly
		(pts
			(xy 13.080492 -315.957712) (xy 13.080492 -311.659524) (xy 13.080492 -310.062372) (xy 12.481306 -309.463186)
			(xy 12.09294 -309.463186) (xy 10.676636 -308.046882) (xy 10.676636 -303.952402) (xy 10.922254 -303.706784)
			(xy 10.922254 -302.872394) (xy 10.828782 -302.778922) (xy 10.420096 -302.778922) (xy 10.366756 -302.832262)
			(xy 10.366756 -306.210462) (xy 9.999218 -306.578) (xy 9.528048 -307.04917) (xy 9.528048 -316.001654)
			(xy 9.725914 -316.19952) (xy 12.838684 -316.19952)
		)
		(stroke
			(width 0)
			(type solid)
		)
		(fill yes)
		(layer "F.Cu")
		(net "SW_P12V_P1V25_PEX0_FLT")
	)
	(gr_poly
		(pts
			(xy 14.85011 -117.544596) (xy 14.85011 -117.331998) (xy 14.85138 -117.330982) (xy 14.85138 -116.96319)
			(xy 14.85138 -116.240814) (xy 15.018766 -116.073428) (xy 15.689326 -116.073428) (xy 15.84198 -115.920774)
			(xy 15.84198 -115.324128) (xy 15.839186 -115.321334) (xy 13.607796 -115.321334) (xy 13.471906 -115.457224)
			(xy 13.471906 -116.513864) (xy 13.471906 -117.07114) (xy 13.471906 -117.39753) (xy 13.471906 -117.545866)
			(xy 13.65377 -117.72773) (xy 14.666976 -117.72773)
		)
		(stroke
			(width 0)
			(type solid)
		)
		(fill yes)
		(layer "F.Cu")
		(net "P3V3_AUX")
	)
	(gr_poly
		(pts
			(xy 20.221956 -174.85487) (xy 20.221956 -174.525178) (xy 20.221956 -174.194978) (xy 20.221956 -173.178978)
			(xy 20.044156 -173.001178) (xy 20.018756 -172.975778) (xy 20.018756 -172.035978) (xy 19.993356 -172.010578)
			(xy 19.790156 -172.010578) (xy 19.764756 -172.035978) (xy 19.764756 -174.169578) (xy 19.764756 -174.30242)
			(xy 19.69008 -174.377096) (xy 18.723102 -174.377096) (xy 18.69948 -174.400718) (xy 18.69948 -174.919386)
			(xy 18.734786 -174.954692) (xy 20.122134 -174.954692)
		)
		(stroke
			(width 0)
			(type solid)
		)
		(fill yes)
		(layer "F.Cu")
		(net "PWRGD_P5V_AUX")
	)
	(gr_poly
		(pts
			(xy 46.99508 -24.13889) (xy 48.01235 -24.13889) (xy 48.193452 -23.957788) (xy 48.193452 -18.992342)
			(xy 47.974758 -18.773648) (xy 47.311564 -18.773648) (xy 47.244508 -18.773648) (xy 47.127922 -18.890234)
			(xy 47.127922 -23.028402) (xy 47.09668 -23.059644) (xy 46.917356 -23.059644) (xy 46.217586 -23.059644)
			(xy 43.236134 -23.059644) (xy 43.226228 -23.049738) (xy 43.15587 -23.120096) (xy 43.15587 -24.123904)
			(xy 43.175936 -24.14397) (xy 46.99 -24.14397)
		)
		(stroke
			(width 0)
			(type solid)
		)
		(fill yes)
		(layer "F.Cu")
		(net "GND")
	)
	(gr_poly
		(pts
			(xy 72.995028 -24.13889) (xy 74.012298 -24.13889) (xy 74.1934 -23.957788) (xy 74.1934 -18.992342)
			(xy 73.974706 -18.773648) (xy 73.311512 -18.773648) (xy 73.244456 -18.773648) (xy 73.12787 -18.890234)
			(xy 73.12787 -23.028402) (xy 73.096628 -23.059644) (xy 72.917304 -23.059644) (xy 72.217534 -23.059644)
			(xy 69.236082 -23.059644) (xy 69.226176 -23.049738) (xy 69.155818 -23.120096) (xy 69.155818 -24.123904)
			(xy 69.175884 -24.14397) (xy 72.989948 -24.14397)
		)
		(stroke
			(width 0)
			(type solid)
		)
		(fill yes)
		(layer "F.Cu")
		(net "GND")
	)
	(gr_poly
		(pts
			(xy 98.994976 -24.13889) (xy 100.012246 -24.13889) (xy 100.193348 -23.957788) (xy 100.193348 -18.992342)
			(xy 99.974654 -18.773648) (xy 99.31146 -18.773648) (xy 99.244404 -18.773648) (xy 99.127818 -18.890234)
			(xy 99.127818 -23.028402) (xy 99.096576 -23.059644) (xy 98.917252 -23.059644) (xy 98.217482 -23.059644)
			(xy 95.23603 -23.059644) (xy 95.226124 -23.049738) (xy 95.155766 -23.120096) (xy 95.155766 -24.123904)
			(xy 95.175832 -24.14397) (xy 98.989896 -24.14397)
		)
		(stroke
			(width 0)
			(type solid)
		)
		(fill yes)
		(layer "F.Cu")
		(net "GND")
	)
	(gr_poly
		(pts
			(xy 130.441954 -116.782596) (xy 130.441954 -116.569998) (xy 130.443224 -116.568982) (xy 130.443224 -116.20119)
			(xy 130.443224 -115.478814) (xy 130.61061 -115.311428) (xy 131.28117 -115.311428) (xy 131.433824 -115.158774)
			(xy 131.433824 -114.562128) (xy 131.43103 -114.559334) (xy 129.19964 -114.559334) (xy 129.06375 -114.695224)
			(xy 129.06375 -115.751864) (xy 129.06375 -116.30914) (xy 129.06375 -116.63553) (xy 129.06375 -116.783866)
			(xy 129.245614 -116.96573) (xy 130.25882 -116.96573)
		)
		(stroke
			(width 0)
			(type solid)
		)
		(fill yes)
		(layer "F.Cu")
		(net "P3V3_AUX")
	)
	(gr_poly
		(pts
			(xy 135.835136 -323.396356) (xy 135.835136 -322.851272) (xy 135.835136 -322.136262) (xy 135.835136 -319.269872)
			(xy 135.676132 -319.110868) (xy 134.723124 -319.110868) (xy 123.380754 -319.110868) (xy 123.178062 -318.908176)
			(xy 123.178062 -308.800754) (xy 123.070874 -308.693566) (xy 122.106182 -308.693566) (xy 118.873016 -308.693566)
			(xy 118.19128 -308.693566) (xy 118.059962 -308.824884) (xy 118.059962 -323.468238) (xy 118.24716 -323.655436)
			(xy 118.857014 -323.655436) (xy 135.576056 -323.655436)
		)
		(stroke
			(width 0)
			(type solid)
		)
		(fill yes)
		(layer "F.Cu")
		(net "P0V8_SERDES_VDDA_PEX1")
	)
	(gr_poly
		(pts
			(xy 137.09523 -24.13889) (xy 138.1125 -24.13889) (xy 138.293602 -23.957788) (xy 138.293602 -18.992342)
			(xy 138.074908 -18.773648) (xy 137.411714 -18.773648) (xy 137.344658 -18.773648) (xy 137.228072 -18.890234)
			(xy 137.228072 -23.028402) (xy 137.19683 -23.059644) (xy 137.017506 -23.059644) (xy 136.317736 -23.059644)
			(xy 133.336284 -23.059644) (xy 133.326378 -23.049738) (xy 133.25602 -23.120096) (xy 133.25602 -24.123904)
			(xy 133.276086 -24.14397) (xy 137.09015 -24.14397)
		)
		(stroke
			(width 0)
			(type solid)
		)
		(fill yes)
		(layer "F.Cu")
		(net "GND")
	)
	(gr_poly
		(pts
			(xy 163.095178 -24.13889) (xy 164.112448 -24.13889) (xy 164.29355 -23.957788) (xy 164.29355 -18.992342)
			(xy 164.074856 -18.773648) (xy 163.411662 -18.773648) (xy 163.344606 -18.773648) (xy 163.22802 -18.890234)
			(xy 163.22802 -23.028402) (xy 163.196778 -23.059644) (xy 163.017454 -23.059644) (xy 162.317684 -23.059644)
			(xy 159.336232 -23.059644) (xy 159.326326 -23.049738) (xy 159.255968 -23.120096) (xy 159.255968 -24.123904)
			(xy 159.276034 -24.14397) (xy 163.090098 -24.14397)
		)
		(stroke
			(width 0)
			(type solid)
		)
		(fill yes)
		(layer "F.Cu")
		(net "GND")
	)
	(gr_poly
		(pts
			(xy 189.095126 -24.13889) (xy 190.112396 -24.13889) (xy 190.293498 -23.957788) (xy 190.293498 -18.992342)
			(xy 190.074804 -18.773648) (xy 189.41161 -18.773648) (xy 189.344554 -18.773648) (xy 189.227968 -18.890234)
			(xy 189.227968 -23.028402) (xy 189.196726 -23.059644) (xy 189.017402 -23.059644) (xy 188.317632 -23.059644)
			(xy 185.33618 -23.059644) (xy 185.326274 -23.049738) (xy 185.255916 -23.120096) (xy 185.255916 -24.123904)
			(xy 185.275982 -24.14397) (xy 189.090046 -24.14397)
		)
		(stroke
			(width 0)
			(type solid)
		)
		(fill yes)
		(layer "F.Cu")
		(net "GND")
	)
	(gr_poly
		(pts
			(xy 215.095074 -24.13889) (xy 216.112344 -24.13889) (xy 216.293446 -23.957788) (xy 216.293446 -18.992342)
			(xy 216.074752 -18.773648) (xy 215.411558 -18.773648) (xy 215.344502 -18.773648) (xy 215.227916 -18.890234)
			(xy 215.227916 -23.028402) (xy 215.196674 -23.059644) (xy 215.01735 -23.059644) (xy 214.31758 -23.059644)
			(xy 211.336128 -23.059644) (xy 211.326222 -23.049738) (xy 211.255864 -23.120096) (xy 211.255864 -24.123904)
			(xy 211.27593 -24.14397) (xy 215.089994 -24.14397)
		)
		(stroke
			(width 0)
			(type solid)
		)
		(fill yes)
		(layer "F.Cu")
		(net "GND")
	)
	(gr_poly
		(pts
			(xy 247.050052 -117.544596) (xy 247.050052 -117.331998) (xy 247.051322 -117.330982) (xy 247.051322 -116.96319)
			(xy 247.051322 -116.240814) (xy 247.218708 -116.073428) (xy 247.889268 -116.073428) (xy 248.041922 -115.920774)
			(xy 248.041922 -115.324128) (xy 248.039128 -115.321334) (xy 245.807738 -115.321334) (xy 245.671848 -115.457224)
			(xy 245.671848 -116.513864) (xy 245.671848 -117.07114) (xy 245.671848 -117.39753) (xy 245.671848 -117.545866)
			(xy 245.853712 -117.72773) (xy 246.866918 -117.72773)
		)
		(stroke
			(width 0)
			(type solid)
		)
		(fill yes)
		(layer "F.Cu")
		(net "P3V3_AUX")
	)
	(gr_poly
		(pts
			(xy 253.195074 -24.13889) (xy 254.212344 -24.13889) (xy 254.393446 -23.957788) (xy 254.393446 -18.992342)
			(xy 254.174752 -18.773648) (xy 253.511558 -18.773648) (xy 253.444502 -18.773648) (xy 253.327916 -18.890234)
			(xy 253.327916 -23.028402) (xy 253.296674 -23.059644) (xy 253.11735 -23.059644) (xy 252.41758 -23.059644)
			(xy 249.436128 -23.059644) (xy 249.426222 -23.049738) (xy 249.355864 -23.120096) (xy 249.355864 -24.123904)
			(xy 249.37593 -24.14397) (xy 253.189994 -24.14397)
		)
		(stroke
			(width 0)
			(type solid)
		)
		(fill yes)
		(layer "F.Cu")
		(net "GND")
	)
	(gr_poly
		(pts
			(xy 260.283452 -215.772238) (xy 260.283452 -215.521794) (xy 260.819392 -214.985854) (xy 260.819392 -213.702138)
			(xy 260.744716 -213.627462)
			(arc
				(start 258.511802 -213.627462)
				(mid 258.50074 -213.643879)
				(end 258.496816 -213.663276)
			)
			(arc
				(start 258.496816 -215.938862)
				(mid 258.500766 -215.958249)
				(end 258.511802 -215.974676)
			)
			(arc
				(start 258.531614 -215.994488)
				(mid 258.548148 -216.005599)
				(end 258.567682 -216.009474)
			)
			(xy 260.046216 -216.009474)
		)
		(stroke
			(width 0)
			(type solid)
		)
		(fill yes)
		(layer "F.Cu")
		(net "GND")
	)
	(gr_poly
		(pts
			(xy 279.195022 -24.13889) (xy 280.212292 -24.13889) (xy 280.393394 -23.957788) (xy 280.393394 -18.992342)
			(xy 280.1747 -18.773648) (xy 279.511506 -18.773648) (xy 279.44445 -18.773648) (xy 279.327864 -18.890234)
			(xy 279.327864 -23.028402) (xy 279.296622 -23.059644) (xy 279.117298 -23.059644) (xy 278.417528 -23.059644)
			(xy 275.436076 -23.059644) (xy 275.42617 -23.049738) (xy 275.355812 -23.120096) (xy 275.355812 -24.123904)
			(xy 275.375878 -24.14397) (xy 279.189942 -24.14397)
		)
		(stroke
			(width 0)
			(type solid)
		)
		(fill yes)
		(layer "F.Cu")
		(net "GND")
	)
	(gr_poly
		(pts
			(xy 305.19497 -24.13889) (xy 306.21224 -24.13889) (xy 306.393342 -23.957788) (xy 306.393342 -18.992342)
			(xy 306.174648 -18.773648) (xy 305.511454 -18.773648) (xy 305.444398 -18.773648) (xy 305.327812 -18.890234)
			(xy 305.327812 -23.028402) (xy 305.29657 -23.059644) (xy 305.117246 -23.059644) (xy 304.417476 -23.059644)
			(xy 301.436024 -23.059644) (xy 301.426118 -23.049738) (xy 301.35576 -23.120096) (xy 301.35576 -24.123904)
			(xy 301.375826 -24.14397) (xy 305.18989 -24.14397)
		)
		(stroke
			(width 0)
			(type solid)
		)
		(fill yes)
		(layer "F.Cu")
		(net "GND")
	)
	(gr_poly
		(pts
			(xy 331.194918 -24.13889) (xy 332.212188 -24.13889) (xy 332.39329 -23.957788) (xy 332.39329 -18.992342)
			(xy 332.174596 -18.773648) (xy 331.511402 -18.773648) (xy 331.444346 -18.773648) (xy 331.32776 -18.890234)
			(xy 331.32776 -23.028402) (xy 331.296518 -23.059644) (xy 331.117194 -23.059644) (xy 330.417424 -23.059644)
			(xy 327.435972 -23.059644) (xy 327.426066 -23.049738) (xy 327.355708 -23.120096) (xy 327.355708 -24.123904)
			(xy 327.375774 -24.14397) (xy 331.189838 -24.14397)
		)
		(stroke
			(width 0)
			(type solid)
		)
		(fill yes)
		(layer "F.Cu")
		(net "GND")
	)
	(gr_poly
		(pts
			(xy 362.64215 -116.782596) (xy 362.64215 -116.569998) (xy 362.64342 -116.568982) (xy 362.64342 -116.20119)
			(xy 362.64342 -115.478814) (xy 362.810806 -115.311428) (xy 363.481366 -115.311428) (xy 363.63402 -115.158774)
			(xy 363.63402 -114.562128) (xy 363.631226 -114.559334) (xy 361.399836 -114.559334) (xy 361.263946 -114.695224)
			(xy 361.263946 -115.751864) (xy 361.263946 -116.30914) (xy 361.263946 -116.63553) (xy 361.263946 -116.783866)
			(xy 361.44581 -116.96573) (xy 362.459016 -116.96573)
		)
		(stroke
			(width 0)
			(type solid)
		)
		(fill yes)
		(layer "F.Cu")
		(net "P3V3_AUX")
	)
	(gr_poly
		(pts
			(xy 368.035332 -323.396356) (xy 368.035332 -322.851272) (xy 368.035332 -322.136262) (xy 368.035332 -319.269872)
			(xy 367.876328 -319.110868) (xy 366.92332 -319.110868) (xy 355.58095 -319.110868) (xy 355.378258 -318.908176)
			(xy 355.378258 -308.800754) (xy 355.27107 -308.693566) (xy 354.306378 -308.693566) (xy 351.073212 -308.693566)
			(xy 350.391476 -308.693566) (xy 350.260158 -308.824884) (xy 350.260158 -323.468238) (xy 350.447356 -323.655436)
			(xy 351.05721 -323.655436) (xy 367.776252 -323.655436)
		)
		(stroke
			(width 0)
			(type solid)
		)
		(fill yes)
		(layer "F.Cu")
		(net "P0V8_SERDES_VDDA_PEX3")
	)
	(gr_poly
		(pts
			(xy 369.295172 -24.13889) (xy 370.312442 -24.13889) (xy 370.493544 -23.957788) (xy 370.493544 -18.992342)
			(xy 370.27485 -18.773648) (xy 369.611656 -18.773648) (xy 369.5446 -18.773648) (xy 369.428014 -18.890234)
			(xy 369.428014 -23.028402) (xy 369.396772 -23.059644) (xy 369.217448 -23.059644) (xy 368.517678 -23.059644)
			(xy 365.536226 -23.059644) (xy 365.52632 -23.049738) (xy 365.455962 -23.120096) (xy 365.455962 -24.123904)
			(xy 365.476028 -24.14397) (xy 369.290092 -24.14397)
		)
		(stroke
			(width 0)
			(type solid)
		)
		(fill yes)
		(layer "F.Cu")
		(net "GND")
	)
	(gr_poly
		(pts
			(xy 395.29512 -24.13889) (xy 396.31239 -24.13889) (xy 396.493492 -23.957788) (xy 396.493492 -18.992342)
			(xy 396.274798 -18.773648) (xy 395.611604 -18.773648) (xy 395.544548 -18.773648) (xy 395.427962 -18.890234)
			(xy 395.427962 -23.028402) (xy 395.39672 -23.059644) (xy 395.217396 -23.059644) (xy 394.517626 -23.059644)
			(xy 391.536174 -23.059644) (xy 391.526268 -23.049738) (xy 391.45591 -23.120096) (xy 391.45591 -24.123904)
			(xy 391.475976 -24.14397) (xy 395.29004 -24.14397)
		)
		(stroke
			(width 0)
			(type solid)
		)
		(fill yes)
		(layer "F.Cu")
		(net "GND")
	)
	(gr_poly
		(pts
			(xy 421.295068 -24.13889) (xy 422.312338 -24.13889) (xy 422.49344 -23.957788) (xy 422.49344 -18.992342)
			(xy 422.274746 -18.773648) (xy 421.611552 -18.773648) (xy 421.544496 -18.773648) (xy 421.42791 -18.890234)
			(xy 421.42791 -23.028402) (xy 421.396668 -23.059644) (xy 421.217344 -23.059644) (xy 420.517574 -23.059644)
			(xy 417.536122 -23.059644) (xy 417.526216 -23.049738) (xy 417.455858 -23.120096) (xy 417.455858 -24.123904)
			(xy 417.475924 -24.14397) (xy 421.289988 -24.14397)
		)
		(stroke
			(width 0)
			(type solid)
		)
		(fill yes)
		(layer "F.Cu")
		(net "GND")
	)
	(gr_poly
		(pts
			(xy 447.295016 -24.13889) (xy 448.312286 -24.13889) (xy 448.493388 -23.957788) (xy 448.493388 -18.992342)
			(xy 448.274694 -18.773648) (xy 447.6115 -18.773648) (xy 447.544444 -18.773648) (xy 447.427858 -18.890234)
			(xy 447.427858 -23.028402) (xy 447.396616 -23.059644) (xy 447.217292 -23.059644) (xy 446.517522 -23.059644)
			(xy 443.53607 -23.059644) (xy 443.526164 -23.049738) (xy 443.455806 -23.120096) (xy 443.455806 -24.123904)
			(xy 443.475872 -24.14397) (xy 447.289936 -24.14397)
		)
		(stroke
			(width 0)
			(type solid)
		)
		(fill yes)
		(layer "F.Cu")
		(net "GND")
	)
	(gr_poly
		(pts
			(xy 7.796022 -54.419754) (xy 7.796022 -54.088538) (xy 7.782814 -54.07533) (xy 7.782814 -53.975762)
			(xy 7.782814 -53.800756) (xy 7.892542 -53.691028) (xy 8.067548 -53.691028) (xy 9.140952 -53.691028)
			(xy 9.478264 -53.353716) (xy 9.478264 -52.280312) (xy 9.478264 -47.591726) (xy 9.184894 -47.298356)
			(xy 6.213602 -47.298356) (xy 6.014466 -47.497492) (xy 6.014466 -53.445918) (xy 5.504434 -53.95595)
			(xy 5.504434 -54.373018) (xy 5.604002 -54.472586) (xy 7.74319 -54.472586)
		)
		(stroke
			(width 0)
			(type solid)
		)
		(fill yes)
		(layer "F.Cu")
		(net "P3V3_SSD0")
	)
	(gr_poly
		(pts
			(xy 19.93392 -294.882062) (xy 19.93392 -279.216612) (xy 19.66468 -278.947372) (xy 17.685766 -278.947372)
			(xy 13.75537 -278.947372) (xy 13.662152 -279.04059) (xy 13.662152 -279.490678) (xy 13.662152 -291.30879)
			(xy 13.274548 -291.696394) (xy 5.178298 -291.696394) (xy 4.507738 -291.025834) (xy 4.507738 -282.364434)
			(xy 4.099814 -281.95651) (xy 1.6764 -281.95651) (xy 1.34747 -282.28544) (xy 1.34747 -292.942264)
			(xy 1.34747 -294.904668) (xy 1.799082 -295.35628) (xy 19.459702 -295.35628)
		)
		(stroke
			(width 0)
			(type solid)
		)
		(fill yes)
		(layer "F.Cu")
		(net "GND")
	)
	(gr_poly
		(pts
			(xy 33.79597 -54.419754) (xy 33.79597 -54.088538) (xy 33.782762 -54.07533) (xy 33.782762 -53.975762)
			(xy 33.782762 -53.766974) (xy 33.858708 -53.691028) (xy 34.067496 -53.691028) (xy 35.1409 -53.691028)
			(xy 35.478212 -53.353716) (xy 35.478212 -52.280312) (xy 35.478212 -47.591726) (xy 35.184842 -47.298356)
			(xy 32.21355 -47.298356) (xy 32.014414 -47.497492) (xy 32.014414 -53.445918) (xy 31.504382 -53.95595)
			(xy 31.504382 -54.373018) (xy 31.60395 -54.472586) (xy 33.743138 -54.472586)
		)
		(stroke
			(width 0)
			(type solid)
		)
		(fill yes)
		(layer "F.Cu")
		(net "P3V3_SSD1")
	)
	(gr_poly
		(pts
			(xy 85.795866 -54.419754) (xy 85.795866 -54.088538) (xy 85.782658 -54.07533) (xy 85.782658 -53.975762)
			(xy 85.782658 -53.829458) (xy 85.921088 -53.691028) (xy 86.067392 -53.691028) (xy 87.140796 -53.691028)
			(xy 87.478108 -53.353716) (xy 87.478108 -52.280312) (xy 87.478108 -47.591726) (xy 87.184738 -47.298356)
			(xy 84.213446 -47.298356) (xy 84.01431 -47.497492) (xy 84.01431 -53.445918) (xy 83.504278 -53.95595)
			(xy 83.504278 -54.373018) (xy 83.603846 -54.472586) (xy 85.743034 -54.472586)
		)
		(stroke
			(width 0)
			(type solid)
		)
		(fill yes)
		(layer "F.Cu")
		(net "P3V3_SSD3")
	)
	(gr_poly
		(pts
			(xy 115.349528 -306.768754) (xy 120.276112 -306.768754) (xy 121.832878 -308.32552) (xy 134.426198 -308.32552)
			(xy 134.506716 -308.245002) (xy 134.506716 -303.883568) (xy 134.434326 -303.811178) (xy 119.645938 -303.811178)
			(xy 119.48922 -303.967896) (xy 119.48922 -304.97907) (xy 119.245126 -305.223164) (xy 116.103908 -305.223164)
			(xy 115.913408 -305.032664) (xy 115.913408 -303.811178) (xy 101.05263 -303.811178) (xy 100.895912 -303.967896)
			(xy 100.895912 -308.07406) (xy 101.147372 -308.32552) (xy 113.792762 -308.32552)
		)
		(stroke
			(width 0)
			(type solid)
		)
		(fill yes)
		(layer "F.Cu")
		(net "GND")
	)
	(gr_poly
		(pts
			(xy 123.89612 -54.419754) (xy 123.89612 -54.088538) (xy 123.882912 -54.07533) (xy 123.882912 -53.975762)
			(xy 123.882912 -53.808122) (xy 124.000006 -53.691028) (xy 124.167646 -53.691028) (xy 125.24105 -53.691028)
			(xy 125.578362 -53.353716) (xy 125.578362 -52.280312) (xy 125.578362 -47.591726) (xy 125.284992 -47.298356)
			(xy 122.3137 -47.298356) (xy 122.114564 -47.497492) (xy 122.114564 -53.445918) (xy 121.604532 -53.95595)
			(xy 121.604532 -54.373018) (xy 121.7041 -54.472586) (xy 123.843288 -54.472586)
		)
		(stroke
			(width 0)
			(type solid)
		)
		(fill yes)
		(layer "F.Cu")
		(net "P3V3_SSD4")
	)
	(gr_poly
		(pts
			(xy 149.896068 -54.419754) (xy 149.896068 -54.088538) (xy 149.88286 -54.07533) (xy 149.88286 -53.975762)
			(xy 149.88286 -53.786278) (xy 149.97811 -53.691028) (xy 150.167594 -53.691028) (xy 151.240998 -53.691028)
			(xy 151.57831 -53.353716) (xy 151.57831 -52.280312) (xy 151.57831 -47.591726) (xy 151.28494 -47.298356)
			(xy 148.313648 -47.298356) (xy 148.114512 -47.497492) (xy 148.114512 -53.445918) (xy 147.60448 -53.95595)
			(xy 147.60448 -54.373018) (xy 147.704048 -54.472586) (xy 149.843236 -54.472586)
		)
		(stroke
			(width 0)
			(type solid)
		)
		(fill yes)
		(layer "F.Cu")
		(net "P3V3_SSD5")
	)
	(gr_poly
		(pts
			(xy 175.896016 -54.419754) (xy 175.896016 -54.088538) (xy 175.882808 -54.07533) (xy 175.882808 -53.975762)
			(xy 175.882808 -53.805328) (xy 175.997108 -53.691028) (xy 176.167542 -53.691028) (xy 177.240946 -53.691028)
			(xy 177.578258 -53.353716) (xy 177.578258 -52.280312) (xy 177.578258 -47.591726) (xy 177.284888 -47.298356)
			(xy 174.313596 -47.298356) (xy 174.11446 -47.497492) (xy 174.11446 -53.445918) (xy 173.604428 -53.95595)
			(xy 173.604428 -54.373018) (xy 173.703996 -54.472586) (xy 175.843184 -54.472586)
		)
		(stroke
			(width 0)
			(type solid)
		)
		(fill yes)
		(layer "F.Cu")
		(net "P3V3_SSD6")
	)
	(gr_poly
		(pts
			(xy 228.403658 -152.48001) (xy 228.403658 -151.959818) (xy 228.284532 -151.840692) (xy 228.284532 -151.604472)
			(xy 228.143816 -151.463756) (xy 228.143816 -150.651972) (xy 228.25456 -150.541228) (xy 228.25456 -150.5204)
			(xy 228.25456 -150.0124) (xy 227.94976 -150.0124) (xy 227.94976 -150.566882) (xy 228.05009 -150.667212)
			(xy 228.05009 -151.881332) (xy 227.859082 -152.07234) (xy 227.859082 -152.482804) (xy 227.878386 -152.502108)
			(xy 227.982272 -152.605994) (xy 228.157024 -152.605994) (xy 228.277674 -152.605994)
		)
		(stroke
			(width 0)
			(type solid)
		)
		(fill yes)
		(layer "F.Cu")
		(net "P3V3_CLK_GEN_VDDMXCK_CK440_PEX")
	)
	(gr_poly
		(pts
			(xy 233.604308 -147.392644) (xy 234.038648 -147.392644) (xy 234.291378 -147.139914) (xy 234.291378 -146.835114)
			(xy 234.215178 -146.758914) (xy 233.755438 -146.758914) (xy 233.598466 -146.915886) (xy 233.293666 -146.915886)
			(xy 233.115866 -147.093686) (xy 232.129838 -147.093686) (xy 232.023412 -146.98726) (xy 231.975152 -146.98726)
			(xy 231.467152 -146.98726) (xy 231.467152 -147.29206) (xy 232.003092 -147.29206) (xy 232.107994 -147.187158)
			(xy 233.107738 -147.187158) (xy 233.319066 -147.398486) (xy 233.598466 -147.398486)
		)
		(stroke
			(width 0)
			(type solid)
		)
		(fill yes)
		(layer "F.Cu")
		(net "P3V3_CLK_GEN_VDDA100M_CK440_PEX")
	)
	(gr_poly
		(pts
			(xy 240.165128 -50.653188) (xy 240.165128 -50.321972) (xy 240.15192 -50.308764) (xy 240.15192 -50.209196)
			(xy 240.15192 -50.053494) (xy 240.280952 -49.924462) (xy 240.436654 -49.924462) (xy 241.510058 -49.924462)
			(xy 241.84737 -49.58715) (xy 241.84737 -48.513746) (xy 241.84737 -43.82516) (xy 241.554 -43.53179)
			(xy 238.582708 -43.53179) (xy 238.383572 -43.730926) (xy 238.383572 -49.679352) (xy 237.87354 -50.189384)
			(xy 237.87354 -50.606452) (xy 237.973108 -50.70602) (xy 240.112296 -50.70602)
		)
		(stroke
			(width 0)
			(type solid)
		)
		(fill yes)
		(layer "F.Cu")
		(net "P3V3_SSD8")
	)
	(gr_poly
		(pts
			(xy 259.828538 -80.90027) (xy 259.723636 -80.795368) (xy 259.723636 -79.795624) (xy 259.934964 -79.584296)
			(xy 259.934964 -79.304896) (xy 259.929122 -79.299054) (xy 259.929122 -78.864714) (xy 259.676392 -78.611984)
			(xy 259.371592 -78.611984) (xy 259.295392 -78.688184) (xy 259.295392 -79.147924) (xy 259.452364 -79.304896)
			(xy 259.452364 -79.609696) (xy 259.630164 -79.787496) (xy 259.630164 -80.773524) (xy 259.523738 -80.87995)
			(xy 259.523738 -80.92821) (xy 259.523738 -81.43621) (xy 259.828538 -81.43621)
		)
		(stroke
			(width 0)
			(type solid)
		)
		(fill yes)
		(layer "F.Cu")
		(net "P3V3_CLK_GEN_VDDA100M_CK440")
	)
	(gr_poly
		(pts
			(xy 265.038586 -85.024976) (xy 265.142472 -84.92109) (xy 265.142472 -84.746338) (xy 265.142472 -84.625688)
			(xy 265.016488 -84.499704) (xy 264.496296 -84.499704) (xy 264.37717 -84.61883) (xy 264.14095 -84.61883)
			(xy 264.000234 -84.759546) (xy 263.18845 -84.759546) (xy 263.077706 -84.648802) (xy 263.056878 -84.648802)
			(xy 262.548878 -84.648802) (xy 262.548878 -84.953602) (xy 263.10336 -84.953602) (xy 263.20369 -84.853272)
			(xy 264.41781 -84.853272) (xy 264.608818 -85.04428) (xy 265.019282 -85.04428)
		)
		(stroke
			(width 0)
			(type solid)
		)
		(fill yes)
		(layer "F.Cu")
		(net "P3V3_CLK_GEN_VDDMXCK_CK440")
	)
	(gr_poly
		(pts
			(xy 265.995912 -54.419754) (xy 265.995912 -54.088538) (xy 265.982704 -54.07533) (xy 265.982704 -53.975762)
			(xy 265.982704 -53.803042) (xy 266.094718 -53.691028) (xy 266.267438 -53.691028) (xy 267.340842 -53.691028)
			(xy 267.678154 -53.353716) (xy 267.678154 -52.280312) (xy 267.678154 -47.591726) (xy 267.384784 -47.298356)
			(xy 264.413492 -47.298356) (xy 264.214356 -47.497492) (xy 264.214356 -53.445918) (xy 263.704324 -53.95595)
			(xy 263.704324 -54.373018) (xy 263.803892 -54.472586) (xy 265.94308 -54.472586)
		)
		(stroke
			(width 0)
			(type solid)
		)
		(fill yes)
		(layer "F.Cu")
		(net "P3V3_SSD9")
	)
	(gr_poly
		(pts
			(xy 291.99586 -54.419754) (xy 291.99586 -54.088538) (xy 291.982652 -54.07533) (xy 291.982652 -53.975762)
			(xy 291.982652 -53.742844) (xy 292.034468 -53.691028) (xy 292.267386 -53.691028) (xy 293.34079 -53.691028)
			(xy 293.678102 -53.353716) (xy 293.678102 -52.280312) (xy 293.678102 -47.591726) (xy 293.384732 -47.298356)
			(xy 290.41344 -47.298356) (xy 290.214304 -47.497492) (xy 290.214304 -53.445918) (xy 289.704272 -53.95595)
			(xy 289.704272 -54.373018) (xy 289.80384 -54.472586) (xy 291.943028 -54.472586)
		)
		(stroke
			(width 0)
			(type solid)
		)
		(fill yes)
		(layer "F.Cu")
		(net "P3V3_SSD10")
	)
	(gr_poly
		(pts
			(xy 356.096062 -54.419754) (xy 356.096062 -54.088538) (xy 356.082854 -54.07533) (xy 356.082854 -53.975762)
			(xy 356.082854 -53.738018) (xy 356.129844 -53.691028) (xy 356.367588 -53.691028) (xy 357.440992 -53.691028)
			(xy 357.778304 -53.353716) (xy 357.778304 -52.280312) (xy 357.778304 -47.591726) (xy 357.484934 -47.298356)
			(xy 354.513642 -47.298356) (xy 354.314506 -47.497492) (xy 354.314506 -53.445918) (xy 353.804474 -53.95595)
			(xy 353.804474 -54.373018) (xy 353.904042 -54.472586) (xy 356.04323 -54.472586)
		)
		(stroke
			(width 0)
			(type solid)
		)
		(fill yes)
		(layer "F.Cu")
		(net "P3V3_SSD12")
	)
	(gr_poly
		(pts
			(xy 382.09601 -54.419754) (xy 382.09601 -54.088538) (xy 382.082802 -54.07533) (xy 382.082802 -53.975762)
			(xy 382.082802 -53.776372) (xy 382.168146 -53.691028) (xy 382.367536 -53.691028) (xy 383.44094 -53.691028)
			(xy 383.778252 -53.353716) (xy 383.778252 -52.280312) (xy 383.778252 -47.591726) (xy 383.484882 -47.298356)
			(xy 380.51359 -47.298356) (xy 380.314454 -47.497492) (xy 380.314454 -53.445918) (xy 379.804422 -53.95595)
			(xy 379.804422 -54.373018) (xy 379.90399 -54.472586) (xy 382.043178 -54.472586)
		)
		(stroke
			(width 0)
			(type solid)
		)
		(fill yes)
		(layer "F.Cu")
		(net "P3V3_SSD13")
	)
	(gr_poly
		(pts
			(xy 408.095958 -54.419754) (xy 408.095958 -54.088538) (xy 408.08275 -54.07533) (xy 408.08275 -53.975762)
			(xy 408.08275 -53.812694) (xy 408.204416 -53.691028) (xy 408.367484 -53.691028) (xy 409.440888 -53.691028)
			(xy 409.7782 -53.353716) (xy 409.7782 -52.280312) (xy 409.7782 -47.591726) (xy 409.48483 -47.298356)
			(xy 406.513538 -47.298356) (xy 406.314402 -47.497492) (xy 406.314402 -53.445918) (xy 405.80437 -53.95595)
			(xy 405.80437 -54.373018) (xy 405.903938 -54.472586) (xy 408.043126 -54.472586)
		)
		(stroke
			(width 0)
			(type solid)
		)
		(fill yes)
		(layer "F.Cu")
		(net "P3V3_SSD14")
	)
	(gr_poly
		(pts
			(xy 59.795918 -54.419754) (xy 59.795918 -54.088538) (xy 59.78271 -54.07533) (xy 59.78271 -53.975762)
			(xy 59.784488 -53.973984) (xy 59.784488 -53.766466) (xy 59.859926 -53.691028) (xy 60.067444 -53.691028)
			(xy 61.140848 -53.691028) (xy 61.47816 -53.353716) (xy 61.47816 -52.280312) (xy 61.47816 -47.591726)
			(xy 61.18479 -47.298356) (xy 58.213498 -47.298356) (xy 58.014362 -47.497492) (xy 58.014362 -53.445918)
			(xy 57.50433 -53.95595) (xy 57.50433 -54.373018) (xy 57.603898 -54.472586) (xy 59.743086 -54.472586)
		)
		(stroke
			(width 0)
			(type solid)
		)
		(fill yes)
		(layer "F.Cu")
		(net "P3V3_SSD2")
	)
	(gr_poly
		(pts
			(xy 130.816858 -127.32131) (xy 130.816858 -126.810008) (xy 130.816858 -123.817634) (xy 130.816858 -123.516136)
			(xy 130.994404 -123.33859) (xy 131.295902 -123.33859) (xy 131.65074 -122.983752) (xy 131.65074 -122.718068)
			(xy 131.65074 -120.78081) (xy 131.4831 -120.61317) (xy 128.233424 -120.61317) (xy 128.068832 -120.777762)
			(xy 128.068832 -123.856242) (xy 128.258316 -124.045726) (xy 128.68021 -124.045726) (xy 128.8034 -124.168916)
			(xy 128.8034 -126.840996) (xy 128.8034 -127.301244) (xy 128.952498 -127.450342) (xy 130.687826 -127.450342)
		)
		(stroke
			(width 0)
			(type solid)
		)
		(fill yes)
		(layer "F.Cu")
		(net "P3V3_AUX")
	)
	(gr_poly
		(pts
			(xy 142.92834 -75.277726) (xy 142.92834 -72.927972) (xy 142.92834 -70.964298) (xy 142.46733 -70.503288)
			(xy 140.503656 -70.503288) (xy 140.495528 -70.49516) (xy 138.674094 -70.49516) (xy 138.665458 -70.503796)
			(xy 138.250168 -70.503796) (xy 137.88136 -70.134988) (xy 137.322306 -70.134988) (xy 137.315702 -70.12813)
			(xy 137.127996 -70.12813) (xy 137.049256 -70.20687) (xy 137.049256 -70.80504) (xy 137.503916 -71.2597)
			(xy 138.058398 -71.814182) (xy 138.058398 -74.95032) (xy 138.595608 -75.48753) (xy 142.718536 -75.48753)
		)
		(stroke
			(width 0)
			(type solid)
		)
		(fill yes)
		(layer "F.Cu")
		(net "GND")
	)
	(gr_poly
		(pts
			(xy 168.928288 -75.277726) (xy 168.928288 -72.927972) (xy 168.928288 -70.964298) (xy 168.467278 -70.503288)
			(xy 166.503604 -70.503288) (xy 166.495476 -70.49516) (xy 164.674042 -70.49516) (xy 164.665406 -70.503796)
			(xy 164.250116 -70.503796) (xy 163.881308 -70.134988) (xy 163.322254 -70.134988) (xy 163.31565 -70.12813)
			(xy 163.127944 -70.12813) (xy 163.049204 -70.20687) (xy 163.049204 -70.80504) (xy 163.503864 -71.2597)
			(xy 164.058346 -71.814182) (xy 164.058346 -74.95032) (xy 164.595556 -75.48753) (xy 168.718484 -75.48753)
		)
		(stroke
			(width 0)
			(type solid)
		)
		(fill yes)
		(layer "F.Cu")
		(net "GND")
	)
	(gr_poly
		(pts
			(xy 194.928236 -75.277726) (xy 194.928236 -72.927972) (xy 194.928236 -70.964298) (xy 194.467226 -70.503288)
			(xy 192.503552 -70.503288) (xy 192.495424 -70.49516) (xy 190.67399 -70.49516) (xy 190.665354 -70.503796)
			(xy 190.250064 -70.503796) (xy 189.881256 -70.134988) (xy 189.322202 -70.134988) (xy 189.315598 -70.12813)
			(xy 189.127892 -70.12813) (xy 189.049152 -70.20687) (xy 189.049152 -70.80504) (xy 189.503812 -71.2597)
			(xy 190.058294 -71.814182) (xy 190.058294 -74.95032) (xy 190.595504 -75.48753) (xy 194.718432 -75.48753)
		)
		(stroke
			(width 0)
			(type solid)
		)
		(fill yes)
		(layer "F.Cu")
		(net "GND")
	)
	(gr_poly
		(pts
			(xy 201.895964 -54.419754) (xy 201.895964 -54.088538) (xy 201.882756 -54.07533) (xy 201.882756 -53.975762)
			(xy 201.88301 -53.975508) (xy 201.88301 -53.817012) (xy 202.008994 -53.691028) (xy 202.16749 -53.691028)
			(xy 203.240894 -53.691028) (xy 203.578206 -53.353716) (xy 203.578206 -52.280312) (xy 203.578206 -47.591726)
			(xy 203.284836 -47.298356) (xy 200.313544 -47.298356) (xy 200.114408 -47.497492) (xy 200.114408 -53.445918)
			(xy 199.604376 -53.95595) (xy 199.604376 -54.373018) (xy 199.703944 -54.472586) (xy 201.843132 -54.472586)
		)
		(stroke
			(width 0)
			(type solid)
		)
		(fill yes)
		(layer "F.Cu")
		(net "P3V3_SSD7")
	)
	(gr_poly
		(pts
			(arc
				(start 219.340938 -103.088186)
				(mid 219.351104 -103.072092)
				(end 219.354654 -103.053388)
			)
			(arc
				(start 219.354654 -101.437948)
				(mid 219.339775 -101.402027)
				(end 219.303854 -101.387148)
			)
			(arc
				(start 217.700352 -101.387148)
				(mid 217.664431 -101.402027)
				(end 217.649552 -101.437948)
			)
			(arc
				(start 217.649552 -103.053388)
				(mid 217.653066 -103.0721)
				(end 217.663268 -103.088186)
			)
		)
		(stroke
			(width 0)
			(type solid)
		)
		(fill yes)
		(layer "F.Cu")
		(net "GND")
	)
	(gr_poly
		(pts
			(xy 220.928184 -75.277726) (xy 220.928184 -72.927972) (xy 220.928184 -70.964298) (xy 220.467174 -70.503288)
			(xy 218.5035 -70.503288) (xy 218.495372 -70.49516) (xy 216.673938 -70.49516) (xy 216.665302 -70.503796)
			(xy 216.250012 -70.503796) (xy 215.881204 -70.134988) (xy 215.32215 -70.134988) (xy 215.315546 -70.12813)
			(xy 215.12784 -70.12813) (xy 215.0491 -70.20687) (xy 215.0491 -70.80504) (xy 215.50376 -71.2597)
			(xy 216.058242 -71.814182) (xy 216.058242 -74.95032) (xy 216.595452 -75.48753) (xy 220.71838 -75.48753)
		)
		(stroke
			(width 0)
			(type solid)
		)
		(fill yes)
		(layer "F.Cu")
		(net "GND")
	)
	(gr_poly
		(pts
			(xy 227.377752 -318.244474) (xy 227.377752 -313.946286) (xy 227.377752 -312.7375) (xy 227.377752 -312.400696)
			(xy 226.998276 -312.02122) (xy 226.661472 -312.02122) (xy 226.3902 -311.749948) (xy 224.973896 -310.333644)
			(xy 224.973896 -306.239164) (xy 225.219514 -305.993546) (xy 225.219514 -305.159156) (xy 225.126042 -305.065684)
			(xy 224.717356 -305.065684) (xy 224.664016 -305.119024) (xy 224.664016 -308.497224) (xy 224.296478 -308.864762)
			(xy 223.825308 -309.335932) (xy 223.825308 -318.288416) (xy 224.023174 -318.486282) (xy 227.135944 -318.486282)
		)
		(stroke
			(width 0)
			(type solid)
		)
		(fill yes)
		(layer "F.Cu")
		(net "SW_P12V_P1V25_PEX1_FLT")
	)
	(gr_poly
		(pts
			(xy 243.62791 -318.244474) (xy 243.62791 -313.946286) (xy 243.62791 -312.7375) (xy 243.62791 -312.400696)
			(xy 243.248434 -312.02122) (xy 242.91163 -312.02122) (xy 242.640358 -311.749948) (xy 241.224054 -310.333644)
			(xy 241.224054 -306.239164) (xy 241.469672 -305.993546) (xy 241.469672 -305.159156) (xy 241.3762 -305.065684)
			(xy 240.967514 -305.065684) (xy 240.914174 -305.119024) (xy 240.914174 -308.497224) (xy 240.546636 -308.864762)
			(xy 240.075466 -309.335932) (xy 240.075466 -318.288416) (xy 240.211356 -318.424306) (xy 243.448078 -318.424306)
		)
		(stroke
			(width 0)
			(type solid)
		)
		(fill yes)
		(layer "F.Cu")
		(net "SW_P12V_P1V25_PEX2_FLT")
	)
	(gr_poly
		(pts
			(xy 245.72595 -322.445126) (xy 245.72595 -313.67984) (xy 245.714266 -313.668156) (xy 245.714266 -312.27268)
			(xy 245.427754 -311.986168) (xy 243.998242 -311.986168) (xy 243.904008 -312.080402) (xy 243.904008 -313.672474)
			(xy 243.904008 -321.057778) (xy 243.306346 -321.65544) (xy 240.962434 -321.65544) (xy 239.794034 -320.48704)
			(xy 239.794034 -307.332634) (xy 239.736376 -307.274976) (xy 234.959144 -307.274976) (xy 234.708954 -307.525166)
			(xy 234.708954 -322.973954) (xy 234.815126 -323.080126) (xy 236.694472 -323.080126) (xy 245.09095 -323.080126)
		)
		(stroke
			(width 0)
			(type solid)
		)
		(fill yes)
		(layer "F.Cu")
		(net "GND")
	)
	(gr_poly
		(pts
			(xy 246.916956 -127.32131) (xy 246.916956 -126.810008) (xy 246.916956 -123.817634) (xy 246.916956 -123.516136)
			(xy 247.094502 -123.33859) (xy 247.396 -123.33859) (xy 247.750838 -122.983752) (xy 247.750838 -122.718068)
			(xy 247.750838 -120.78081) (xy 247.583198 -120.61317) (xy 244.333522 -120.61317) (xy 244.16893 -120.777762)
			(xy 244.16893 -123.856242) (xy 244.358414 -124.045726) (xy 244.780308 -124.045726) (xy 244.903498 -124.168916)
			(xy 244.903498 -126.840996) (xy 244.903498 -127.301244) (xy 245.052596 -127.450342) (xy 246.787924 -127.450342)
		)
		(stroke
			(width 0)
			(type solid)
		)
		(fill yes)
		(layer "F.Cu")
		(net "P3V3_AUX")
	)
	(gr_poly
		(pts
			(xy 259.028184 -75.277726) (xy 259.028184 -72.927972) (xy 259.028184 -70.964298) (xy 258.567174 -70.503288)
			(xy 256.6035 -70.503288) (xy 256.595372 -70.49516) (xy 254.773938 -70.49516) (xy 254.765302 -70.503796)
			(xy 254.350012 -70.503796) (xy 253.981204 -70.134988) (xy 253.42215 -70.134988) (xy 253.415546 -70.12813)
			(xy 253.22784 -70.12813) (xy 253.1491 -70.20687) (xy 253.1491 -70.80504) (xy 253.60376 -71.2597)
			(xy 254.158242 -71.814182) (xy 254.158242 -74.95032) (xy 254.695452 -75.48753) (xy 258.81838 -75.48753)
		)
		(stroke
			(width 0)
			(type solid)
		)
		(fill yes)
		(layer "F.Cu")
		(net "GND")
	)
	(gr_poly
		(pts
			(xy 285.028132 -75.277726) (xy 285.028132 -72.927972) (xy 285.028132 -70.964298) (xy 284.567122 -70.503288)
			(xy 282.603448 -70.503288) (xy 282.59532 -70.49516) (xy 280.773886 -70.49516) (xy 280.76525 -70.503796)
			(xy 280.34996 -70.503796) (xy 279.981152 -70.134988) (xy 279.422098 -70.134988) (xy 279.415494 -70.12813)
			(xy 279.227788 -70.12813) (xy 279.149048 -70.20687) (xy 279.149048 -70.80504) (xy 279.603708 -71.2597)
			(xy 280.15819 -71.814182) (xy 280.15819 -74.95032) (xy 280.6954 -75.48753) (xy 284.818328 -75.48753)
		)
		(stroke
			(width 0)
			(type solid)
		)
		(fill yes)
		(layer "F.Cu")
		(net "GND")
	)
	(gr_poly
		(pts
			(xy 311.02808 -75.277726) (xy 311.02808 -72.927972) (xy 311.02808 -70.964298) (xy 310.56707 -70.503288)
			(xy 308.603396 -70.503288) (xy 308.595268 -70.49516) (xy 306.773834 -70.49516) (xy 306.765198 -70.503796)
			(xy 306.349908 -70.503796) (xy 305.9811 -70.134988) (xy 305.422046 -70.134988) (xy 305.415442 -70.12813)
			(xy 305.227736 -70.12813) (xy 305.148996 -70.20687) (xy 305.148996 -70.80504) (xy 305.603656 -71.2597)
			(xy 306.158138 -71.814182) (xy 306.158138 -74.95032) (xy 306.695348 -75.48753) (xy 310.818276 -75.48753)
		)
		(stroke
			(width 0)
			(type solid)
		)
		(fill yes)
		(layer "F.Cu")
		(net "GND")
	)
	(gr_poly
		(pts
			(xy 317.995808 -54.419754) (xy 317.995808 -54.088538) (xy 317.9826 -54.07533) (xy 317.9826 -53.975762)
			(xy 317.983108 -53.975508) (xy 317.983108 -53.80228) (xy 318.09436 -53.691028) (xy 318.267334 -53.691028)
			(xy 319.340738 -53.691028) (xy 319.67805 -53.353716) (xy 319.67805 -52.280312) (xy 319.67805 -47.591726)
			(xy 319.38468 -47.298356) (xy 316.413388 -47.298356) (xy 316.214252 -47.497492) (xy 316.214252 -53.445918)
			(xy 315.70422 -53.95595) (xy 315.70422 -54.373018) (xy 315.803788 -54.472586) (xy 317.942976 -54.472586)
		)
		(stroke
			(width 0)
			(type solid)
		)
		(fill yes)
		(layer "F.Cu")
		(net "P3V3_SSD11")
	)
	(gr_poly
		(pts
			(xy 337.028028 -75.277726) (xy 337.028028 -72.927972) (xy 337.028028 -70.964298) (xy 336.567018 -70.503288)
			(xy 334.603344 -70.503288) (xy 334.595216 -70.49516) (xy 332.773782 -70.49516) (xy 332.765146 -70.503796)
			(xy 332.349856 -70.503796) (xy 331.981048 -70.134988) (xy 331.421994 -70.134988) (xy 331.41539 -70.12813)
			(xy 331.227684 -70.12813) (xy 331.148944 -70.20687) (xy 331.148944 -70.80504) (xy 331.603604 -71.2597)
			(xy 332.158086 -71.814182) (xy 332.158086 -74.95032) (xy 332.695296 -75.48753) (xy 336.818224 -75.48753)
		)
		(stroke
			(width 0)
			(type solid)
		)
		(fill yes)
		(layer "F.Cu")
		(net "GND")
	)
	(gr_poly
		(pts
			(xy 363.017054 -127.32131) (xy 363.017054 -126.810008) (xy 363.017054 -123.817634) (xy 363.017054 -123.516136)
			(xy 363.1946 -123.33859) (xy 363.496098 -123.33859) (xy 363.850936 -122.983752) (xy 363.850936 -122.718068)
			(xy 363.850936 -120.78081) (xy 363.683296 -120.61317) (xy 360.43362 -120.61317) (xy 360.269028 -120.777762)
			(xy 360.269028 -123.769628) (xy 360.4514 -123.952) (xy 360.78668 -123.952) (xy 361.003596 -124.168916)
			(xy 361.003596 -126.840996) (xy 361.003596 -127.301244) (xy 361.152694 -127.450342) (xy 362.888022 -127.450342)
		)
		(stroke
			(width 0)
			(type solid)
		)
		(fill yes)
		(layer "F.Cu")
		(net "P3V3_AUX")
	)
	(gr_poly
		(pts
			(xy 375.128282 -75.277726) (xy 375.128282 -72.927972) (xy 375.128282 -70.964298) (xy 374.667272 -70.503288)
			(xy 372.703598 -70.503288) (xy 372.69547 -70.49516) (xy 370.874036 -70.49516) (xy 370.8654 -70.503796)
			(xy 370.45011 -70.503796) (xy 370.081302 -70.134988) (xy 369.522248 -70.134988) (xy 369.515644 -70.12813)
			(xy 369.327938 -70.12813) (xy 369.249198 -70.20687) (xy 369.249198 -70.80504) (xy 369.703858 -71.2597)
			(xy 370.25834 -71.814182) (xy 370.25834 -74.95032) (xy 370.79555 -75.48753) (xy 374.918478 -75.48753)
		)
		(stroke
			(width 0)
			(type solid)
		)
		(fill yes)
		(layer "F.Cu")
		(net "GND")
	)
	(gr_poly
		(pts
			(xy 401.12823 -75.277726) (xy 401.12823 -72.927972) (xy 401.12823 -70.964298) (xy 400.66722 -70.503288)
			(xy 398.703546 -70.503288) (xy 398.695418 -70.49516) (xy 396.873984 -70.49516) (xy 396.865348 -70.503796)
			(xy 396.450058 -70.503796) (xy 396.08125 -70.134988) (xy 395.522196 -70.134988) (xy 395.515592 -70.12813)
			(xy 395.327886 -70.12813) (xy 395.249146 -70.20687) (xy 395.249146 -70.80504) (xy 395.703806 -71.2597)
			(xy 396.258288 -71.814182) (xy 396.258288 -74.95032) (xy 396.795498 -75.48753) (xy 400.918426 -75.48753)
		)
		(stroke
			(width 0)
			(type solid)
		)
		(fill yes)
		(layer "F.Cu")
		(net "GND")
	)
	(gr_poly
		(pts
			(xy 427.128178 -75.277726) (xy 427.128178 -72.927972) (xy 427.128178 -70.964298) (xy 426.667168 -70.503288)
			(xy 424.703494 -70.503288) (xy 424.695366 -70.49516) (xy 422.873932 -70.49516) (xy 422.865296 -70.503796)
			(xy 422.450006 -70.503796) (xy 422.081198 -70.134988) (xy 421.522144 -70.134988) (xy 421.51554 -70.12813)
			(xy 421.327834 -70.12813) (xy 421.249094 -70.20687) (xy 421.249094 -70.80504) (xy 421.703754 -71.2597)
			(xy 422.258236 -71.814182) (xy 422.258236 -74.95032) (xy 422.795446 -75.48753) (xy 426.918374 -75.48753)
		)
		(stroke
			(width 0)
			(type solid)
		)
		(fill yes)
		(layer "F.Cu")
		(net "GND")
	)
	(gr_poly
		(pts
			(xy 434.095906 -54.419754) (xy 434.095906 -54.088538) (xy 434.082698 -54.07533) (xy 434.082698 -53.975762)
			(xy 434.08346 -53.975) (xy 434.08346 -53.751226) (xy 434.143658 -53.691028) (xy 434.367432 -53.691028)
			(xy 435.440836 -53.691028) (xy 435.778148 -53.353716) (xy 435.778148 -52.280312) (xy 435.778148 -47.591726)
			(xy 435.484778 -47.298356) (xy 432.513486 -47.298356) (xy 432.31435 -47.497492) (xy 432.31435 -53.445918)
			(xy 431.804318 -53.95595) (xy 431.804318 -54.373018) (xy 431.903886 -54.472586) (xy 434.043074 -54.472586)
		)
		(stroke
			(width 0)
			(type solid)
		)
		(fill yes)
		(layer "F.Cu")
		(net "P3V3_SSD15")
	)
	(gr_poly
		(pts
			(xy 453.128126 -75.277726) (xy 453.128126 -72.927972) (xy 453.128126 -70.964298) (xy 452.667116 -70.503288)
			(xy 450.703442 -70.503288) (xy 450.695314 -70.49516) (xy 448.87388 -70.49516) (xy 448.865244 -70.503796)
			(xy 448.449954 -70.503796) (xy 448.081146 -70.134988) (xy 447.522092 -70.134988) (xy 447.515488 -70.12813)
			(xy 447.327782 -70.12813) (xy 447.249042 -70.20687) (xy 447.249042 -70.80504) (xy 447.703702 -71.2597)
			(xy 448.258184 -71.814182) (xy 448.258184 -74.95032) (xy 448.795394 -75.48753) (xy 452.918322 -75.48753)
		)
		(stroke
			(width 0)
			(type solid)
		)
		(fill yes)
		(layer "F.Cu")
		(net "GND")
	)
	(gr_poly
		(pts
			(xy 457.99883 -318.367918) (xy 457.99883 -314.06973) (xy 457.99883 -312.860944) (xy 457.99883 -312.52414)
			(xy 457.619354 -312.144664) (xy 457.28255 -312.144664) (xy 457.011278 -311.873392) (xy 455.594974 -310.457088)
			(xy 455.594974 -306.362608) (xy 455.840592 -306.11699) (xy 455.840592 -305.2826) (xy 455.74712 -305.189128)
			(xy 455.338434 -305.189128) (xy 455.285094 -305.242468) (xy 455.285094 -308.620668) (xy 454.917556 -308.988206)
			(xy 454.446386 -309.459376) (xy 454.446386 -318.41186) (xy 454.644252 -318.609726) (xy 457.757022 -318.609726)
		)
		(stroke
			(width 0)
			(type solid)
		)
		(fill yes)
		(layer "F.Cu")
		(net "SW_P12V_P1V25_PEX3_FLT")
	)
	(gr_poly
		(pts
			(xy 16.725646 -214.456772) (xy 16.725646 -213.923372) (xy 16.725646 -213.161372) (xy 16.725646 -208.360772)
			(xy 16.547846 -208.182972) (xy 11.544046 -208.182972) (xy 11.417046 -208.309972) (xy 11.417046 -210.443572)
			(xy 11.467846 -210.494372) (xy 13.245846 -210.494372) (xy 13.398246 -210.341972) (xy 13.398246 -208.995772)
			(xy 13.550646 -208.843372) (xy 14.896846 -208.843372) (xy 15.049246 -208.995772) (xy 15.049246 -213.186772)
			(xy 15.049246 -213.288372) (xy 14.795246 -213.542372) (xy 14.795246 -214.456772) (xy 14.871446 -214.532972)
			(xy 16.649446 -214.532972)
		)
		(stroke
			(width 0)
			(type solid)
		)
		(fill yes)
		(layer "F.Cu")
		(net "GND")
	)
	(gr_poly
		(pts
			(xy 96.947228 -126.03226) (xy 96.947228 -122.421142) (xy 96.936052 -122.409966) (xy 96.300036 -122.409966)
			(xy 96.244156 -122.354086) (xy 96.244156 -122.297952) (xy 96.244156 -119.827294) (xy 96.244156 -119.096028)
			(xy 96.244156 -118.91899) (xy 96.182942 -118.857776) (xy 94.587568 -118.857776) (xy 94.285562 -119.159782)
			(xy 94.285562 -119.407432) (xy 94.285562 -119.482108) (xy 94.285562 -119.867934) (xy 94.285562 -122.884692)
			(xy 94.087442 -123.082812) (xy 94.087442 -125.823472) (xy 94.087442 -126.185676) (xy 94.165928 -126.264162)
			(xy 96.715326 -126.264162)
		)
		(stroke
			(width 0)
			(type solid)
		)
		(fill yes)
		(layer "F.Cu")
		(net "P3V3_AUX")
	)
	(gr_poly
		(pts
			(xy 148.057362 -243.435378) (xy 148.057362 -242.901978) (xy 148.057362 -242.139978) (xy 148.057362 -237.339378)
			(xy 147.879562 -237.161578) (xy 142.875762 -237.161578) (xy 142.748762 -237.288578) (xy 142.748762 -239.422178)
			(xy 142.799562 -239.472978) (xy 144.577562 -239.472978) (xy 144.729962 -239.320578) (xy 144.729962 -237.974378)
			(xy 144.882362 -237.821978) (xy 146.228562 -237.821978) (xy 146.380962 -237.974378) (xy 146.380962 -242.165378)
			(xy 146.380962 -242.266978) (xy 146.126962 -242.520978) (xy 146.126962 -243.435378) (xy 146.203162 -243.511578)
			(xy 147.981162 -243.511578)
		)
		(stroke
			(width 0)
			(type solid)
		)
		(fill yes)
		(layer "F.Cu")
		(net "GND")
	)
	(gr_poly
		(pts
			(xy 191.628268 -112.420908) (xy 195.765674 -112.420908) (xy 196.714618 -111.471964) (xy 197.173596 -111.471964)
			(xy 199.362822 -111.471964) (xy 212.160104 -111.471964) (xy 214.332058 -111.471964) (xy 214.736172 -111.06785)
			(xy 214.736172 -107.220766) (xy 214.481918 -106.966512) (xy 200.070466 -106.966512) (xy 199.432164 -107.604814)
			(xy 193.149474 -107.604814) (xy 191.711072 -109.043216) (xy 189.614048 -109.043216) (xy 188.759592 -109.043216)
			(xy 188.725556 -109.077252) (xy 188.725556 -112.386872) (xy 188.766958 -112.428274) (xy 189.614048 -112.428274)
			(xy 191.620902 -112.428274)
		)
		(stroke
			(width 0)
			(type solid)
		)
		(fill yes)
		(layer "F.Cu")
		(net "P12V_NIC3")
	)
	(gr_poly
		(pts
			(xy 260.227826 -242.677188) (xy 260.227826 -242.143788) (xy 260.227826 -241.381788) (xy 260.227826 -236.581188)
			(xy 260.050026 -236.403388) (xy 255.046226 -236.403388) (xy 254.919226 -236.530388) (xy 254.919226 -238.663988)
			(xy 254.970026 -238.714788) (xy 256.748026 -238.714788) (xy 256.900426 -238.562388) (xy 256.900426 -237.216188)
			(xy 257.052826 -237.063788) (xy 258.399026 -237.063788) (xy 258.551426 -237.216188) (xy 258.551426 -241.407188)
			(xy 258.551426 -241.508788) (xy 258.297426 -241.762788) (xy 258.297426 -242.677188) (xy 258.373626 -242.753388)
			(xy 260.151626 -242.753388)
		)
		(stroke
			(width 0)
			(type solid)
		)
		(fill yes)
		(layer "F.Cu")
		(net "GND")
	)
	(gr_poly
		(pts
			(xy 329.14717 -126.03226) (xy 329.14717 -122.421142) (xy 329.135994 -122.409966) (xy 328.499978 -122.409966)
			(xy 328.444098 -122.354086) (xy 328.444098 -122.297952) (xy 328.444098 -119.827294) (xy 328.444098 -119.096028)
			(xy 328.444098 -118.91899) (xy 328.382884 -118.857776) (xy 326.78751 -118.857776) (xy 326.485504 -119.159782)
			(xy 326.485504 -119.407432) (xy 326.485504 -119.482108) (xy 326.485504 -119.867934) (xy 326.485504 -122.884692)
			(xy 326.287384 -123.082812) (xy 326.287384 -125.823472) (xy 326.287384 -126.185676) (xy 326.36587 -126.264162)
			(xy 328.915268 -126.264162)
		)
		(stroke
			(width 0)
			(type solid)
		)
		(fill yes)
		(layer "F.Cu")
		(net "P3V3_AUX")
	)
	(gr_poly
		(pts
			(xy 445.247268 -126.03226) (xy 445.247268 -122.421142) (xy 445.236092 -122.409966) (xy 444.600076 -122.409966)
			(xy 444.544196 -122.354086) (xy 444.544196 -122.297952) (xy 444.544196 -119.827294) (xy 444.544196 -119.096028)
			(xy 444.544196 -118.91899) (xy 444.482982 -118.857776) (xy 442.887608 -118.857776) (xy 442.585602 -119.159782)
			(xy 442.585602 -119.407432) (xy 442.585602 -119.482108) (xy 442.585602 -119.867934) (xy 442.585602 -122.884692)
			(xy 442.387482 -123.082812) (xy 442.387482 -125.823472) (xy 442.387482 -126.185676) (xy 442.465968 -126.264162)
			(xy 445.015366 -126.264162)
		)
		(stroke
			(width 0)
			(type solid)
		)
		(fill yes)
		(layer "F.Cu")
		(net "P3V3_AUX")
	)
	(gr_poly
		(pts
			(xy 14.717014 -127.32131) (xy 14.717014 -126.810008) (xy 14.717014 -123.817634) (xy 14.717014 -123.516136)
			(xy 14.89456 -123.33859) (xy 15.196058 -123.33859) (xy 15.550896 -122.983752) (xy 15.550896 -122.718068)
			(xy 15.550896 -120.78081) (xy 15.487142 -120.717056) (xy 14.34846 -120.717056) (xy 14.244574 -120.61317)
			(xy 12.13358 -120.61317) (xy 11.968988 -120.777762) (xy 11.968988 -123.856242) (xy 12.158472 -124.045726)
			(xy 12.580366 -124.045726) (xy 12.703556 -124.168916) (xy 12.703556 -126.840996) (xy 12.703556 -127.301244)
			(xy 12.852654 -127.450342) (xy 14.587982 -127.450342)
		)
		(stroke
			(width 0)
			(type solid)
		)
		(fill yes)
		(layer "F.Cu")
		(net "P3V3_AUX")
	)
	(gr_poly
		(pts
			(arc
				(start 26.982928 -258.332224)
				(mid 27.002451 -258.328323)
				(end 27.018996 -258.317238)
			)
			(arc
				(start 27.056334 -258.2799)
				(mid 27.067445 -258.263366)
				(end 27.07132 -258.243832)
			)
			(arc
				(start 27.07132 -254.578866)
				(mid 27.067419 -254.559343)
				(end 27.056334 -254.542798)
			)
			(arc
				(start 26.907998 -254.394462)
				(mid 26.891464 -254.383351)
				(end 26.87193 -254.379476)
			)
			(xy 25.964896 -254.379476) (xy 25.539446 -254.379476) (xy 25.375616 -254.543306) (xy 25.375616 -258.227068)
			(xy 25.480772 -258.332224) (xy 25.680162 -258.332224)
		)
		(stroke
			(width 0)
			(type solid)
		)
		(fill yes)
		(layer "F.Cu")
		(net "P1V8_PLL0_PEX0")
	)
	(gr_poly
		(pts
			(xy 109.726984 -160.3629) (xy 109.726984 -157.0482) (xy 110.012734 -156.76245) (xy 110.014004 -156.76245)
			(xy 112.966754 -156.76245) (xy 113.063528 -156.859224) (xy 113.063528 -157.813756) (xy 113.129568 -157.879796)
			(xy 114.001042 -157.879796) (xy 114.09426 -157.786578) (xy 114.09426 -157.658054) (xy 114.09426 -153.336498)
			(xy 114.09426 -152.930098) (xy 113.970816 -152.806654) (xy 107.620816 -152.806654) (xy 107.496864 -152.930606)
			(xy 107.496864 -153.230072) (xy 107.496864 -156.740352) (xy 109.424724 -158.668212) (xy 109.424724 -160.39084)
			(xy 109.493304 -160.45942) (xy 109.630464 -160.45942)
		)
		(stroke
			(width 0)
			(type solid)
		)
		(fill yes)
		(layer "F.Cu")
		(net "SW_P3V3_AUX_PH")
	)
	(gr_poly
		(pts
			(arc
				(start 143.083026 -258.332224)
				(mid 143.102549 -258.328323)
				(end 143.119094 -258.317238)
			)
			(arc
				(start 143.156432 -258.2799)
				(mid 143.167543 -258.263366)
				(end 143.171418 -258.243832)
			)
			(arc
				(start 143.171418 -254.578866)
				(mid 143.167517 -254.559343)
				(end 143.156432 -254.542798)
			)
			(arc
				(start 143.008096 -254.394462)
				(mid 142.991562 -254.383351)
				(end 142.972028 -254.379476)
			)
			(xy 142.064994 -254.379476) (xy 141.639544 -254.379476) (xy 141.475714 -254.543306) (xy 141.475714 -258.227068)
			(xy 141.58087 -258.332224) (xy 141.78026 -258.332224)
		)
		(stroke
			(width 0)
			(type solid)
		)
		(fill yes)
		(layer "F.Cu")
		(net "P1V8_PLL0_PEX1")
	)
	(gr_poly
		(pts
			(xy 204.237844 -370.617496) (xy 204.237844 -369.567714) (xy 204.237844 -368.835686) (xy 204.047852 -368.645694)
			(xy 201.954384 -368.645694) (xy 201.93508 -368.664998) (xy 201.93508 -368.769138) (xy 201.93508 -368.819938)
			(xy 201.936858 -368.821716) (xy 202.504548 -368.821716) (xy 202.654154 -368.971322) (xy 202.654154 -369.59667)
			(arc
				(start 202.654154 -370.562632)
				(mid 202.667535 -370.59699)
				(end 202.700636 -370.613178)
			)
			(arc
				(start 202.700636 -370.613178)
				(mid 202.727132 -370.615992)
				(end 202.753468 -370.620036)
			)
			(xy 204.235304 -370.620036)
		)
		(stroke
			(width 0)
			(type solid)
		)
		(fill yes)
		(layer "F.Cu")
		(net "AGND_HSC")
	)
	(gr_poly
		(pts
			(xy 258.514088 -263.254236) (xy 258.514088 -262.798306) (xy 258.497578 -262.78205) (xy 257.988308 -262.78205)
			(xy 257.866388 -262.66013) (xy 257.614166 -262.66013) (xy 257.519678 -262.754618) (xy 256.764282 -262.754618)
			(xy 256.672588 -262.662924) (xy 256.672588 -262.607298) (xy 256.672588 -261.548372) (xy 256.749804 -261.471156)
			(xy 256.801112 -261.419848) (xy 257.392932 -261.419848) (xy 257.455416 -261.357364) (xy 257.455416 -260.651498)
			(xy 257.407664 -260.603746) (xy 256.113788 -260.603746) (xy 256.051304 -260.66623) (xy 256.051304 -263.10717)
			(xy 256.279142 -263.335008) (xy 258.433316 -263.335008)
		)
		(stroke
			(width 0)
			(type solid)
		)
		(fill yes)
		(layer "F.Cu")
		(net "GND")
	)
	(gr_poly
		(pts
			(arc
				(start 259.18287 -258.332224)
				(mid 259.202393 -258.328323)
				(end 259.218938 -258.317238)
			)
			(arc
				(start 259.256276 -258.2799)
				(mid 259.267387 -258.263366)
				(end 259.271262 -258.243832)
			)
			(arc
				(start 259.271262 -254.578866)
				(mid 259.267361 -254.559343)
				(end 259.256276 -254.542798)
			)
			(arc
				(start 259.10794 -254.394462)
				(mid 259.091406 -254.383351)
				(end 259.071872 -254.379476)
			)
			(xy 258.164838 -254.379476) (xy 257.739388 -254.379476) (xy 257.575558 -254.543306) (xy 257.575558 -258.227068)
			(xy 257.680714 -258.332224) (xy 257.880104 -258.332224)
		)
		(stroke
			(width 0)
			(type solid)
		)
		(fill yes)
		(layer "F.Cu")
		(net "P1V8_PLL0_PEX2")
	)
	(gr_poly
		(pts
			(arc
				(start 36.000944 -316.799468)
				(mid 35.797744 -316.799468)
				(end 36.000944 -316.799468)
			)
		)
		(stroke
			(width 0)
			(type solid)
		)
		(fill yes)
		(layer "F.Cu")
		(net "GND")
	)
	(gr_poly
		(pts
			(arc
				(start 36.000944 -314.899548)
				(mid 35.797744 -314.899548)
				(end 36.000944 -314.899548)
			)
		)
		(stroke
			(width 0)
			(type solid)
		)
		(fill yes)
		(layer "F.Cu")
		(net "GND")
	)
	(gr_poly
		(pts
			(arc
				(start 36.001198 -312.049668)
				(mid 35.797998 -312.049668)
				(end 36.001198 -312.049668)
			)
		)
		(stroke
			(width 0)
			(type solid)
		)
		(fill yes)
		(layer "F.Cu")
		(net "GND")
	)
	(gr_poly
		(pts
			(arc
				(start 36.001198 -310.150002)
				(mid 35.797998 -310.150002)
				(end 36.001198 -310.150002)
			)
		)
		(stroke
			(width 0)
			(type solid)
		)
		(fill yes)
		(layer "F.Cu")
		(net "GND")
	)
	(gr_poly
		(pts
			(arc
				(start 36.001198 -308.250082)
				(mid 35.797998 -308.250082)
				(end 36.001198 -308.250082)
			)
		)
		(stroke
			(width 0)
			(type solid)
		)
		(fill yes)
		(layer "F.Cu")
		(net "GND")
	)
	(gr_poly
		(pts
			(arc
				(start 36.001198 -306.350162)
				(mid 35.797998 -306.350162)
				(end 36.001198 -306.350162)
			)
		)
		(stroke
			(width 0)
			(type solid)
		)
		(fill yes)
		(layer "F.Cu")
		(net "GND")
	)
	(gr_poly
		(pts
			(arc
				(start 36.001198 -304.449988)
				(mid 35.797998 -304.449988)
				(end 36.001198 -304.449988)
			)
		)
		(stroke
			(width 0)
			(type solid)
		)
		(fill yes)
		(layer "F.Cu")
		(net "GND")
	)
	(gr_poly
		(pts
			(arc
				(start 36.001198 -302.550068)
				(mid 35.797998 -302.550068)
				(end 36.001198 -302.550068)
			)
		)
		(stroke
			(width 0)
			(type solid)
		)
		(fill yes)
		(layer "F.Cu")
		(net "GND")
	)
	(gr_poly
		(pts
			(arc
				(start 38.851586 -319.65011)
				(mid 38.648386 -319.65011)
				(end 38.851586 -319.65011)
			)
		)
		(stroke
			(width 0)
			(type solid)
		)
		(fill yes)
		(layer "F.Cu")
		(net "GND")
	)
	(gr_poly
		(pts
			(arc
				(start 40.751506 -319.65011)
				(mid 40.548306 -319.65011)
				(end 40.751506 -319.65011)
			)
		)
		(stroke
			(width 0)
			(type solid)
		)
		(fill yes)
		(layer "F.Cu")
		(net "GND")
	)
	(gr_poly
		(pts
			(arc
				(start 42.651426 -319.65011)
				(mid 42.448226 -319.65011)
				(end 42.651426 -319.65011)
			)
		)
		(stroke
			(width 0)
			(type solid)
		)
		(fill yes)
		(layer "F.Cu")
		(net "GND")
	)
	(gr_poly
		(pts
			(arc
				(start 44.551092 -272.14957)
				(mid 44.347892 -272.14957)
				(end 44.551092 -272.14957)
			)
		)
		(stroke
			(width 0)
			(type solid)
		)
		(fill yes)
		(layer "F.Cu")
		(net "GND")
	)
	(gr_poly
		(pts
			(arc
				(start 44.5516 -319.65011)
				(mid 44.3484 -319.65011)
				(end 44.5516 -319.65011)
			)
		)
		(stroke
			(width 0)
			(type solid)
		)
		(fill yes)
		(layer "F.Cu")
		(net "GND")
	)
	(gr_poly
		(pts
			(arc
				(start 46.451266 -272.14957)
				(mid 46.248066 -272.14957)
				(end 46.451266 -272.14957)
			)
		)
		(stroke
			(width 0)
			(type solid)
		)
		(fill yes)
		(layer "F.Cu")
		(net "GND")
	)
	(gr_poly
		(pts
			(arc
				(start 46.45152 -319.65011)
				(mid 46.24832 -319.65011)
				(end 46.45152 -319.65011)
			)
		)
		(stroke
			(width 0)
			(type solid)
		)
		(fill yes)
		(layer "F.Cu")
		(net "GND")
	)
	(gr_poly
		(pts
			(arc
				(start 48.351186 -272.14957)
				(mid 48.147986 -272.14957)
				(end 48.351186 -272.14957)
			)
		)
		(stroke
			(width 0)
			(type solid)
		)
		(fill yes)
		(layer "F.Cu")
		(net "GND")
	)
	(gr_poly
		(pts
			(arc
				(start 48.35144 -319.65011)
				(mid 48.14824 -319.65011)
				(end 48.35144 -319.65011)
			)
		)
		(stroke
			(width 0)
			(type solid)
		)
		(fill yes)
		(layer "F.Cu")
		(net "GND")
	)
	(gr_poly
		(pts
			(arc
				(start 50.251106 -272.14957)
				(mid 50.047906 -272.14957)
				(end 50.251106 -272.14957)
			)
		)
		(stroke
			(width 0)
			(type solid)
		)
		(fill yes)
		(layer "F.Cu")
		(net "GND")
	)
	(gr_poly
		(pts
			(arc
				(start 50.251614 -319.65011)
				(mid 50.048414 -319.65011)
				(end 50.251614 -319.65011)
			)
		)
		(stroke
			(width 0)
			(type solid)
		)
		(fill yes)
		(layer "F.Cu")
		(net "GND")
	)
	(gr_poly
		(pts
			(arc
				(start 52.15128 -272.14957)
				(mid 51.94808 -272.14957)
				(end 52.15128 -272.14957)
			)
		)
		(stroke
			(width 0)
			(type solid)
		)
		(fill yes)
		(layer "F.Cu")
		(net "GND")
	)
	(gr_poly
		(pts
			(arc
				(start 52.151534 -319.65011)
				(mid 51.948334 -319.65011)
				(end 52.151534 -319.65011)
			)
		)
		(stroke
			(width 0)
			(type solid)
		)
		(fill yes)
		(layer "F.Cu")
		(net "GND")
	)
	(gr_poly
		(pts
			(arc
				(start 54.0512 -272.14957)
				(mid 53.848 -272.14957)
				(end 54.0512 -272.14957)
			)
		)
		(stroke
			(width 0)
			(type solid)
		)
		(fill yes)
		(layer "F.Cu")
		(net "GND")
	)
	(gr_poly
		(pts
			(arc
				(start 54.051454 -319.65011)
				(mid 53.848254 -319.65011)
				(end 54.051454 -319.65011)
			)
		)
		(stroke
			(width 0)
			(type solid)
		)
		(fill yes)
		(layer "F.Cu")
		(net "GND")
	)
	(gr_poly
		(pts
			(arc
				(start 55.95112 -272.14957)
				(mid 55.74792 -272.14957)
				(end 55.95112 -272.14957)
			)
		)
		(stroke
			(width 0)
			(type solid)
		)
		(fill yes)
		(layer "F.Cu")
		(net "GND")
	)
	(gr_poly
		(pts
			(arc
				(start 55.951628 -319.65011)
				(mid 55.748428 -319.65011)
				(end 55.951628 -319.65011)
			)
		)
		(stroke
			(width 0)
			(type solid)
		)
		(fill yes)
		(layer "F.Cu")
		(net "GND")
	)
	(gr_poly
		(pts
			(arc
				(start 57.851294 -272.14957)
				(mid 57.648094 -272.14957)
				(end 57.851294 -272.14957)
			)
		)
		(stroke
			(width 0)
			(type solid)
		)
		(fill yes)
		(layer "F.Cu")
		(net "GND")
	)
	(gr_poly
		(pts
			(arc
				(start 57.851802 -319.65011)
				(mid 57.648602 -319.65011)
				(end 57.851802 -319.65011)
			)
		)
		(stroke
			(width 0)
			(type solid)
		)
		(fill yes)
		(layer "F.Cu")
		(net "GND")
	)
	(gr_poly
		(pts
			(arc
				(start 59.751214 -272.149316)
				(mid 59.548014 -272.149316)
				(end 59.751214 -272.149316)
			)
		)
		(stroke
			(width 0)
			(type solid)
		)
		(fill yes)
		(layer "F.Cu")
		(net "GND")
	)
	(gr_poly
		(pts
			(arc
				(start 59.751468 -319.65011)
				(mid 59.548268 -319.65011)
				(end 59.751468 -319.65011)
			)
		)
		(stroke
			(width 0)
			(type solid)
		)
		(fill yes)
		(layer "F.Cu")
		(net "GND")
	)
	(gr_poly
		(pts
			(arc
				(start 61.651134 -272.14957)
				(mid 61.447934 -272.14957)
				(end 61.651134 -272.14957)
			)
		)
		(stroke
			(width 0)
			(type solid)
		)
		(fill yes)
		(layer "F.Cu")
		(net "GND")
	)
	(gr_poly
		(pts
			(arc
				(start 61.651388 -319.65011)
				(mid 61.448188 -319.65011)
				(end 61.651388 -319.65011)
			)
		)
		(stroke
			(width 0)
			(type solid)
		)
		(fill yes)
		(layer "F.Cu")
		(net "GND")
	)
	(gr_poly
		(pts
			(arc
				(start 63.551308 -272.14957)
				(mid 63.348108 -272.14957)
				(end 63.551308 -272.14957)
			)
		)
		(stroke
			(width 0)
			(type solid)
		)
		(fill yes)
		(layer "F.Cu")
		(net "GND")
	)
	(gr_poly
		(pts
			(arc
				(start 63.551562 -319.65011)
				(mid 63.348362 -319.65011)
				(end 63.551562 -319.65011)
			)
		)
		(stroke
			(width 0)
			(type solid)
		)
		(fill yes)
		(layer "F.Cu")
		(net "GND")
	)
	(gr_poly
		(pts
			(arc
				(start 65.451228 -272.14957)
				(mid 65.248028 -272.14957)
				(end 65.451228 -272.14957)
			)
		)
		(stroke
			(width 0)
			(type solid)
		)
		(fill yes)
		(layer "F.Cu")
		(net "GND")
	)
	(gr_poly
		(pts
			(arc
				(start 65.451482 -319.65011)
				(mid 65.248282 -319.65011)
				(end 65.451482 -319.65011)
			)
		)
		(stroke
			(width 0)
			(type solid)
		)
		(fill yes)
		(layer "F.Cu")
		(net "GND")
	)
	(gr_poly
		(pts
			(arc
				(start 67.351148 -272.14957)
				(mid 67.147948 -272.14957)
				(end 67.351148 -272.14957)
			)
		)
		(stroke
			(width 0)
			(type solid)
		)
		(fill yes)
		(layer "F.Cu")
		(net "GND")
	)
	(gr_poly
		(pts
			(arc
				(start 67.351402 -319.65011)
				(mid 67.148202 -319.65011)
				(end 67.351402 -319.65011)
			)
		)
		(stroke
			(width 0)
			(type solid)
		)
		(fill yes)
		(layer "F.Cu")
		(net "GND")
	)
	(gr_poly
		(pts
			(arc
				(start 69.251322 -272.14957)
				(mid 69.048122 -272.14957)
				(end 69.251322 -272.14957)
			)
		)
		(stroke
			(width 0)
			(type solid)
		)
		(fill yes)
		(layer "F.Cu")
		(net "GND")
	)
	(gr_poly
		(pts
			(arc
				(start 69.251576 -319.65011)
				(mid 69.048376 -319.65011)
				(end 69.251576 -319.65011)
			)
		)
		(stroke
			(width 0)
			(type solid)
		)
		(fill yes)
		(layer "F.Cu")
		(net "GND")
	)
	(gr_poly
		(pts
			(arc
				(start 71.151242 -272.14957)
				(mid 70.948042 -272.14957)
				(end 71.151242 -272.14957)
			)
		)
		(stroke
			(width 0)
			(type solid)
		)
		(fill yes)
		(layer "F.Cu")
		(net "GND")
	)
	(gr_poly
		(pts
			(arc
				(start 71.151496 -319.65011)
				(mid 70.948296 -319.65011)
				(end 71.151496 -319.65011)
			)
		)
		(stroke
			(width 0)
			(type solid)
		)
		(fill yes)
		(layer "F.Cu")
		(net "GND")
	)
	(gr_poly
		(pts
			(arc
				(start 73.051162 -272.14957)
				(mid 72.847962 -272.14957)
				(end 73.051162 -272.14957)
			)
		)
		(stroke
			(width 0)
			(type solid)
		)
		(fill yes)
		(layer "F.Cu")
		(net "GND")
	)
	(gr_poly
		(pts
			(arc
				(start 73.051416 -319.65011)
				(mid 72.848216 -319.65011)
				(end 73.051416 -319.65011)
			)
		)
		(stroke
			(width 0)
			(type solid)
		)
		(fill yes)
		(layer "F.Cu")
		(net "GND")
	)
	(gr_poly
		(pts
			(arc
				(start 74.951336 -272.14957)
				(mid 74.748136 -272.14957)
				(end 74.951336 -272.14957)
			)
		)
		(stroke
			(width 0)
			(type solid)
		)
		(fill yes)
		(layer "F.Cu")
		(net "GND")
	)
	(gr_poly
		(pts
			(arc
				(start 74.95159 -319.65011)
				(mid 74.74839 -319.65011)
				(end 74.95159 -319.65011)
			)
		)
		(stroke
			(width 0)
			(type solid)
		)
		(fill yes)
		(layer "F.Cu")
		(net "GND")
	)
	(gr_poly
		(pts
			(arc
				(start 76.85151 -319.65011)
				(mid 76.64831 -319.65011)
				(end 76.85151 -319.65011)
			)
		)
		(stroke
			(width 0)
			(type solid)
		)
		(fill yes)
		(layer "F.Cu")
		(net "GND")
	)
	(gr_poly
		(pts
			(arc
				(start 76.85151 -272.14957)
				(mid 76.64831 -272.14957)
				(end 76.85151 -272.14957)
			)
		)
		(stroke
			(width 0)
			(type solid)
		)
		(fill yes)
		(layer "F.Cu")
		(net "GND")
	)
	(gr_poly
		(pts
			(arc
				(start 78.75143 -319.65011)
				(mid 78.54823 -319.65011)
				(end 78.75143 -319.65011)
			)
		)
		(stroke
			(width 0)
			(type solid)
		)
		(fill yes)
		(layer "F.Cu")
		(net "GND")
	)
	(gr_poly
		(pts
			(arc
				(start 78.75143 -272.14957)
				(mid 78.54823 -272.14957)
				(end 78.75143 -272.14957)
			)
		)
		(stroke
			(width 0)
			(type solid)
		)
		(fill yes)
		(layer "F.Cu")
		(net "GND")
	)
	(gr_poly
		(pts
			(arc
				(start 80.65135 -319.65011)
				(mid 80.44815 -319.65011)
				(end 80.65135 -319.65011)
			)
		)
		(stroke
			(width 0)
			(type solid)
		)
		(fill yes)
		(layer "F.Cu")
		(net "GND")
	)
	(gr_poly
		(pts
			(arc
				(start 80.65135 -272.14957)
				(mid 80.44815 -272.14957)
				(end 80.65135 -272.14957)
			)
		)
		(stroke
			(width 0)
			(type solid)
		)
		(fill yes)
		(layer "F.Cu")
		(net "GND")
	)
	(gr_poly
		(pts
			(arc
				(start 83.501738 -316.799722)
				(mid 83.298538 -316.799722)
				(end 83.501738 -316.799722)
			)
		)
		(stroke
			(width 0)
			(type solid)
		)
		(fill yes)
		(layer "F.Cu")
		(net "GND")
	)
	(gr_poly
		(pts
			(arc
				(start 83.501738 -314.899548)
				(mid 83.298538 -314.899548)
				(end 83.501738 -314.899548)
			)
		)
		(stroke
			(width 0)
			(type solid)
		)
		(fill yes)
		(layer "F.Cu")
		(net "GND")
	)
	(gr_poly
		(pts
			(arc
				(start 83.501738 -312.049922)
				(mid 83.298538 -312.049922)
				(end 83.501738 -312.049922)
			)
		)
		(stroke
			(width 0)
			(type solid)
		)
		(fill yes)
		(layer "F.Cu")
		(net "GND")
	)
	(gr_poly
		(pts
			(arc
				(start 83.501738 -310.149748)
				(mid 83.298538 -310.149748)
				(end 83.501738 -310.149748)
			)
		)
		(stroke
			(width 0)
			(type solid)
		)
		(fill yes)
		(layer "F.Cu")
		(net "GND")
	)
	(gr_poly
		(pts
			(arc
				(start 83.501738 -308.249828)
				(mid 83.298538 -308.249828)
				(end 83.501738 -308.249828)
			)
		)
		(stroke
			(width 0)
			(type solid)
		)
		(fill yes)
		(layer "F.Cu")
		(net "GND")
	)
	(gr_poly
		(pts
			(arc
				(start 83.501738 -306.349908)
				(mid 83.298538 -306.349908)
				(end 83.501738 -306.349908)
			)
		)
		(stroke
			(width 0)
			(type solid)
		)
		(fill yes)
		(layer "F.Cu")
		(net "GND")
	)
	(gr_poly
		(pts
			(arc
				(start 83.501738 -304.449734)
				(mid 83.298538 -304.449734)
				(end 83.501738 -304.449734)
			)
		)
		(stroke
			(width 0)
			(type solid)
		)
		(fill yes)
		(layer "F.Cu")
		(net "GND")
	)
	(gr_poly
		(pts
			(arc
				(start 83.501738 -287.3502)
				(mid 83.298538 -287.3502)
				(end 83.501738 -287.3502)
			)
		)
		(stroke
			(width 0)
			(type solid)
		)
		(fill yes)
		(layer "F.Cu")
		(net "GND")
	)
	(gr_poly
		(pts
			(arc
				(start 83.501738 -285.450026)
				(mid 83.298538 -285.450026)
				(end 83.501738 -285.450026)
			)
		)
		(stroke
			(width 0)
			(type solid)
		)
		(fill yes)
		(layer "F.Cu")
		(net "GND")
	)
	(gr_poly
		(pts
			(arc
				(start 83.501738 -283.550106)
				(mid 83.298538 -283.550106)
				(end 83.501738 -283.550106)
			)
		)
		(stroke
			(width 0)
			(type solid)
		)
		(fill yes)
		(layer "F.Cu")
		(net "GND")
	)
	(gr_poly
		(pts
			(arc
				(start 83.501738 -281.650186)
				(mid 83.298538 -281.650186)
				(end 83.501738 -281.650186)
			)
		)
		(stroke
			(width 0)
			(type solid)
		)
		(fill yes)
		(layer "F.Cu")
		(net "GND")
	)
	(gr_poly
		(pts
			(arc
				(start 83.501738 -279.750012)
				(mid 83.298538 -279.750012)
				(end 83.501738 -279.750012)
			)
		)
		(stroke
			(width 0)
			(type solid)
		)
		(fill yes)
		(layer "F.Cu")
		(net "GND")
	)
	(gr_poly
		(pts
			(arc
				(start 83.501738 -276.900132)
				(mid 83.298538 -276.900132)
				(end 83.501738 -276.900132)
			)
		)
		(stroke
			(width 0)
			(type solid)
		)
		(fill yes)
		(layer "F.Cu")
		(net "GND")
	)
	(gr_poly
		(pts
			(arc
				(start 83.501738 -274.999958)
				(mid 83.298538 -274.999958)
				(end 83.501738 -274.999958)
			)
		)
		(stroke
			(width 0)
			(type solid)
		)
		(fill yes)
		(layer "F.Cu")
		(net "GND")
	)
	(gr_poly
		(pts
			(arc
				(start 152.101042 -316.799468)
				(mid 151.897842 -316.799468)
				(end 152.101042 -316.799468)
			)
		)
		(stroke
			(width 0)
			(type solid)
		)
		(fill yes)
		(layer "F.Cu")
		(net "GND")
	)
	(gr_poly
		(pts
			(arc
				(start 152.101042 -314.899802)
				(mid 151.897842 -314.899802)
				(end 152.101042 -314.899802)
			)
		)
		(stroke
			(width 0)
			(type solid)
		)
		(fill yes)
		(layer "F.Cu")
		(net "GND")
	)
	(gr_poly
		(pts
			(arc
				(start 152.101296 -312.049668)
				(mid 151.898096 -312.049668)
				(end 152.101296 -312.049668)
			)
		)
		(stroke
			(width 0)
			(type solid)
		)
		(fill yes)
		(layer "F.Cu")
		(net "GND")
	)
	(gr_poly
		(pts
			(arc
				(start 152.101296 -310.150002)
				(mid 151.898096 -310.150002)
				(end 152.101296 -310.150002)
			)
		)
		(stroke
			(width 0)
			(type solid)
		)
		(fill yes)
		(layer "F.Cu")
		(net "GND")
	)
	(gr_poly
		(pts
			(arc
				(start 152.101296 -308.250082)
				(mid 151.898096 -308.250082)
				(end 152.101296 -308.250082)
			)
		)
		(stroke
			(width 0)
			(type solid)
		)
		(fill yes)
		(layer "F.Cu")
		(net "GND")
	)
	(gr_poly
		(pts
			(arc
				(start 152.101296 -306.350162)
				(mid 151.898096 -306.350162)
				(end 152.101296 -306.350162)
			)
		)
		(stroke
			(width 0)
			(type solid)
		)
		(fill yes)
		(layer "F.Cu")
		(net "GND")
	)
	(gr_poly
		(pts
			(arc
				(start 152.101296 -304.449988)
				(mid 151.898096 -304.449988)
				(end 152.101296 -304.449988)
			)
		)
		(stroke
			(width 0)
			(type solid)
		)
		(fill yes)
		(layer "F.Cu")
		(net "GND")
	)
	(gr_poly
		(pts
			(arc
				(start 152.101296 -302.550068)
				(mid 151.898096 -302.550068)
				(end 152.101296 -302.550068)
			)
		)
		(stroke
			(width 0)
			(type solid)
		)
		(fill yes)
		(layer "F.Cu")
		(net "GND")
	)
	(gr_poly
		(pts
			(arc
				(start 154.951684 -319.65011)
				(mid 154.748484 -319.65011)
				(end 154.951684 -319.65011)
			)
		)
		(stroke
			(width 0)
			(type solid)
		)
		(fill yes)
		(layer "F.Cu")
		(net "GND")
	)
	(gr_poly
		(pts
			(arc
				(start 156.851604 -319.65011)
				(mid 156.648404 -319.65011)
				(end 156.851604 -319.65011)
			)
		)
		(stroke
			(width 0)
			(type solid)
		)
		(fill yes)
		(layer "F.Cu")
		(net "GND")
	)
	(gr_poly
		(pts
			(arc
				(start 158.751524 -319.65011)
				(mid 158.548324 -319.65011)
				(end 158.751524 -319.65011)
			)
		)
		(stroke
			(width 0)
			(type solid)
		)
		(fill yes)
		(layer "F.Cu")
		(net "GND")
	)
	(gr_poly
		(pts
			(arc
				(start 160.65119 -272.14957)
				(mid 160.44799 -272.14957)
				(end 160.65119 -272.14957)
			)
		)
		(stroke
			(width 0)
			(type solid)
		)
		(fill yes)
		(layer "F.Cu")
		(net "GND")
	)
	(gr_poly
		(pts
			(arc
				(start 160.651698 -319.65011)
				(mid 160.448498 -319.65011)
				(end 160.651698 -319.65011)
			)
		)
		(stroke
			(width 0)
			(type solid)
		)
		(fill yes)
		(layer "F.Cu")
		(net "GND")
	)
	(gr_poly
		(pts
			(arc
				(start 162.551364 -272.14957)
				(mid 162.348164 -272.14957)
				(end 162.551364 -272.14957)
			)
		)
		(stroke
			(width 0)
			(type solid)
		)
		(fill yes)
		(layer "F.Cu")
		(net "GND")
	)
	(gr_poly
		(pts
			(arc
				(start 162.551618 -319.65011)
				(mid 162.348418 -319.65011)
				(end 162.551618 -319.65011)
			)
		)
		(stroke
			(width 0)
			(type solid)
		)
		(fill yes)
		(layer "F.Cu")
		(net "GND")
	)
	(gr_poly
		(pts
			(arc
				(start 164.451284 -272.14957)
				(mid 164.248084 -272.14957)
				(end 164.451284 -272.14957)
			)
		)
		(stroke
			(width 0)
			(type solid)
		)
		(fill yes)
		(layer "F.Cu")
		(net "GND")
	)
	(gr_poly
		(pts
			(arc
				(start 164.451538 -319.65011)
				(mid 164.248338 -319.65011)
				(end 164.451538 -319.65011)
			)
		)
		(stroke
			(width 0)
			(type solid)
		)
		(fill yes)
		(layer "F.Cu")
		(net "GND")
	)
	(gr_poly
		(pts
			(arc
				(start 166.351204 -272.14957)
				(mid 166.148004 -272.14957)
				(end 166.351204 -272.14957)
			)
		)
		(stroke
			(width 0)
			(type solid)
		)
		(fill yes)
		(layer "F.Cu")
		(net "GND")
	)
	(gr_poly
		(pts
			(arc
				(start 166.351712 -319.65011)
				(mid 166.148512 -319.65011)
				(end 166.351712 -319.65011)
			)
		)
		(stroke
			(width 0)
			(type solid)
		)
		(fill yes)
		(layer "F.Cu")
		(net "GND")
	)
	(gr_poly
		(pts
			(arc
				(start 168.251378 -272.14957)
				(mid 168.048178 -272.14957)
				(end 168.251378 -272.14957)
			)
		)
		(stroke
			(width 0)
			(type solid)
		)
		(fill yes)
		(layer "F.Cu")
		(net "GND")
	)
	(gr_poly
		(pts
			(arc
				(start 168.251632 -319.65011)
				(mid 168.048432 -319.65011)
				(end 168.251632 -319.65011)
			)
		)
		(stroke
			(width 0)
			(type solid)
		)
		(fill yes)
		(layer "F.Cu")
		(net "GND")
	)
	(gr_poly
		(pts
			(arc
				(start 170.151298 -272.14957)
				(mid 169.948098 -272.14957)
				(end 170.151298 -272.14957)
			)
		)
		(stroke
			(width 0)
			(type solid)
		)
		(fill yes)
		(layer "F.Cu")
		(net "GND")
	)
	(gr_poly
		(pts
			(arc
				(start 170.151552 -319.65011)
				(mid 169.948352 -319.65011)
				(end 170.151552 -319.65011)
			)
		)
		(stroke
			(width 0)
			(type solid)
		)
		(fill yes)
		(layer "F.Cu")
		(net "GND")
	)
	(gr_poly
		(pts
			(arc
				(start 172.051218 -272.14957)
				(mid 171.848018 -272.14957)
				(end 172.051218 -272.14957)
			)
		)
		(stroke
			(width 0)
			(type solid)
		)
		(fill yes)
		(layer "F.Cu")
		(net "GND")
	)
	(gr_poly
		(pts
			(arc
				(start 172.051726 -319.65011)
				(mid 171.848526 -319.65011)
				(end 172.051726 -319.65011)
			)
		)
		(stroke
			(width 0)
			(type solid)
		)
		(fill yes)
		(layer "F.Cu")
		(net "GND")
	)
	(gr_poly
		(pts
			(arc
				(start 173.951392 -272.14957)
				(mid 173.748192 -272.14957)
				(end 173.951392 -272.14957)
			)
		)
		(stroke
			(width 0)
			(type solid)
		)
		(fill yes)
		(layer "F.Cu")
		(net "GND")
	)
	(gr_poly
		(pts
			(arc
				(start 173.9519 -319.65011)
				(mid 173.7487 -319.65011)
				(end 173.9519 -319.65011)
			)
		)
		(stroke
			(width 0)
			(type solid)
		)
		(fill yes)
		(layer "F.Cu")
		(net "GND")
	)
	(gr_poly
		(pts
			(arc
				(start 175.851312 -272.149316)
				(mid 175.648112 -272.149316)
				(end 175.851312 -272.149316)
			)
		)
		(stroke
			(width 0)
			(type solid)
		)
		(fill yes)
		(layer "F.Cu")
		(net "GND")
	)
	(gr_poly
		(pts
			(arc
				(start 175.851566 -319.65011)
				(mid 175.648366 -319.65011)
				(end 175.851566 -319.65011)
			)
		)
		(stroke
			(width 0)
			(type solid)
		)
		(fill yes)
		(layer "F.Cu")
		(net "GND")
	)
	(gr_poly
		(pts
			(arc
				(start 177.751232 -272.14957)
				(mid 177.548032 -272.14957)
				(end 177.751232 -272.14957)
			)
		)
		(stroke
			(width 0)
			(type solid)
		)
		(fill yes)
		(layer "F.Cu")
		(net "GND")
	)
	(gr_poly
		(pts
			(arc
				(start 177.751486 -319.65011)
				(mid 177.548286 -319.65011)
				(end 177.751486 -319.65011)
			)
		)
		(stroke
			(width 0)
			(type solid)
		)
		(fill yes)
		(layer "F.Cu")
		(net "GND")
	)
	(gr_poly
		(pts
			(arc
				(start 179.651406 -272.14957)
				(mid 179.448206 -272.14957)
				(end 179.651406 -272.14957)
			)
		)
		(stroke
			(width 0)
			(type solid)
		)
		(fill yes)
		(layer "F.Cu")
		(net "GND")
	)
	(gr_poly
		(pts
			(arc
				(start 179.65166 -319.65011)
				(mid 179.44846 -319.65011)
				(end 179.65166 -319.65011)
			)
		)
		(stroke
			(width 0)
			(type solid)
		)
		(fill yes)
		(layer "F.Cu")
		(net "GND")
	)
	(gr_poly
		(pts
			(arc
				(start 181.551326 -272.14957)
				(mid 181.348126 -272.14957)
				(end 181.551326 -272.14957)
			)
		)
		(stroke
			(width 0)
			(type solid)
		)
		(fill yes)
		(layer "F.Cu")
		(net "GND")
	)
	(gr_poly
		(pts
			(arc
				(start 181.55158 -319.65011)
				(mid 181.34838 -319.65011)
				(end 181.55158 -319.65011)
			)
		)
		(stroke
			(width 0)
			(type solid)
		)
		(fill yes)
		(layer "F.Cu")
		(net "GND")
	)
	(gr_poly
		(pts
			(arc
				(start 183.451246 -272.14957)
				(mid 183.248046 -272.14957)
				(end 183.451246 -272.14957)
			)
		)
		(stroke
			(width 0)
			(type solid)
		)
		(fill yes)
		(layer "F.Cu")
		(net "GND")
	)
	(gr_poly
		(pts
			(arc
				(start 183.4515 -319.65011)
				(mid 183.2483 -319.65011)
				(end 183.4515 -319.65011)
			)
		)
		(stroke
			(width 0)
			(type solid)
		)
		(fill yes)
		(layer "F.Cu")
		(net "GND")
	)
	(gr_poly
		(pts
			(arc
				(start 185.35142 -272.14957)
				(mid 185.14822 -272.14957)
				(end 185.35142 -272.14957)
			)
		)
		(stroke
			(width 0)
			(type solid)
		)
		(fill yes)
		(layer "F.Cu")
		(net "GND")
	)
	(gr_poly
		(pts
			(arc
				(start 185.351674 -319.65011)
				(mid 185.148474 -319.65011)
				(end 185.351674 -319.65011)
			)
		)
		(stroke
			(width 0)
			(type solid)
		)
		(fill yes)
		(layer "F.Cu")
		(net "GND")
	)
	(gr_poly
		(pts
			(arc
				(start 187.25134 -272.14957)
				(mid 187.04814 -272.14957)
				(end 187.25134 -272.14957)
			)
		)
		(stroke
			(width 0)
			(type solid)
		)
		(fill yes)
		(layer "F.Cu")
		(net "GND")
	)
	(gr_poly
		(pts
			(arc
				(start 187.251594 -319.65011)
				(mid 187.048394 -319.65011)
				(end 187.251594 -319.65011)
			)
		)
		(stroke
			(width 0)
			(type solid)
		)
		(fill yes)
		(layer "F.Cu")
		(net "GND")
	)
	(gr_poly
		(pts
			(arc
				(start 189.15126 -272.14957)
				(mid 188.94806 -272.14957)
				(end 189.15126 -272.14957)
			)
		)
		(stroke
			(width 0)
			(type solid)
		)
		(fill yes)
		(layer "F.Cu")
		(net "GND")
	)
	(gr_poly
		(pts
			(arc
				(start 189.151514 -319.65011)
				(mid 188.948314 -319.65011)
				(end 189.151514 -319.65011)
			)
		)
		(stroke
			(width 0)
			(type solid)
		)
		(fill yes)
		(layer "F.Cu")
		(net "GND")
	)
	(gr_poly
		(pts
			(arc
				(start 191.051434 -272.14957)
				(mid 190.848234 -272.14957)
				(end 191.051434 -272.14957)
			)
		)
		(stroke
			(width 0)
			(type solid)
		)
		(fill yes)
		(layer "F.Cu")
		(net "GND")
	)
	(gr_poly
		(pts
			(arc
				(start 191.051688 -319.65011)
				(mid 190.848488 -319.65011)
				(end 191.051688 -319.65011)
			)
		)
		(stroke
			(width 0)
			(type solid)
		)
		(fill yes)
		(layer "F.Cu")
		(net "GND")
	)
	(gr_poly
		(pts
			(arc
				(start 192.951608 -319.65011)
				(mid 192.748408 -319.65011)
				(end 192.951608 -319.65011)
			)
		)
		(stroke
			(width 0)
			(type solid)
		)
		(fill yes)
		(layer "F.Cu")
		(net "GND")
	)
	(gr_poly
		(pts
			(arc
				(start 192.951608 -272.14957)
				(mid 192.748408 -272.14957)
				(end 192.951608 -272.14957)
			)
		)
		(stroke
			(width 0)
			(type solid)
		)
		(fill yes)
		(layer "F.Cu")
		(net "GND")
	)
	(gr_poly
		(pts
			(arc
				(start 194.851528 -319.65011)
				(mid 194.648328 -319.65011)
				(end 194.851528 -319.65011)
			)
		)
		(stroke
			(width 0)
			(type solid)
		)
		(fill yes)
		(layer "F.Cu")
		(net "GND")
	)
	(gr_poly
		(pts
			(arc
				(start 194.851528 -272.14957)
				(mid 194.648328 -272.14957)
				(end 194.851528 -272.14957)
			)
		)
		(stroke
			(width 0)
			(type solid)
		)
		(fill yes)
		(layer "F.Cu")
		(net "GND")
	)
	(gr_poly
		(pts
			(arc
				(start 196.751448 -319.65011)
				(mid 196.548248 -319.65011)
				(end 196.751448 -319.65011)
			)
		)
		(stroke
			(width 0)
			(type solid)
		)
		(fill yes)
		(layer "F.Cu")
		(net "GND")
	)
	(gr_poly
		(pts
			(arc
				(start 196.751448 -272.14957)
				(mid 196.548248 -272.14957)
				(end 196.751448 -272.14957)
			)
		)
		(stroke
			(width 0)
			(type solid)
		)
		(fill yes)
		(layer "F.Cu")
		(net "GND")
	)
	(gr_poly
		(pts
			(arc
				(start 199.601836 -316.799722)
				(mid 199.398636 -316.799722)
				(end 199.601836 -316.799722)
			)
		)
		(stroke
			(width 0)
			(type solid)
		)
		(fill yes)
		(layer "F.Cu")
		(net "GND")
	)
	(gr_poly
		(pts
			(arc
				(start 199.601836 -314.899548)
				(mid 199.398636 -314.899548)
				(end 199.601836 -314.899548)
			)
		)
		(stroke
			(width 0)
			(type solid)
		)
		(fill yes)
		(layer "F.Cu")
		(net "GND")
	)
	(gr_poly
		(pts
			(arc
				(start 199.601836 -312.049922)
				(mid 199.398636 -312.049922)
				(end 199.601836 -312.049922)
			)
		)
		(stroke
			(width 0)
			(type solid)
		)
		(fill yes)
		(layer "F.Cu")
		(net "GND")
	)
	(gr_poly
		(pts
			(arc
				(start 199.601836 -310.149748)
				(mid 199.398636 -310.149748)
				(end 199.601836 -310.149748)
			)
		)
		(stroke
			(width 0)
			(type solid)
		)
		(fill yes)
		(layer "F.Cu")
		(net "GND")
	)
	(gr_poly
		(pts
			(arc
				(start 199.601836 -308.249828)
				(mid 199.398636 -308.249828)
				(end 199.601836 -308.249828)
			)
		)
		(stroke
			(width 0)
			(type solid)
		)
		(fill yes)
		(layer "F.Cu")
		(net "GND")
	)
	(gr_poly
		(pts
			(arc
				(start 199.601836 -306.349908)
				(mid 199.398636 -306.349908)
				(end 199.601836 -306.349908)
			)
		)
		(stroke
			(width 0)
			(type solid)
		)
		(fill yes)
		(layer "F.Cu")
		(net "GND")
	)
	(gr_poly
		(pts
			(arc
				(start 199.601836 -304.449734)
				(mid 199.398636 -304.449734)
				(end 199.601836 -304.449734)
			)
		)
		(stroke
			(width 0)
			(type solid)
		)
		(fill yes)
		(layer "F.Cu")
		(net "GND")
	)
	(gr_poly
		(pts
			(arc
				(start 199.601836 -287.3502)
				(mid 199.398636 -287.3502)
				(end 199.601836 -287.3502)
			)
		)
		(stroke
			(width 0)
			(type solid)
		)
		(fill yes)
		(layer "F.Cu")
		(net "GND")
	)
	(gr_poly
		(pts
			(arc
				(start 199.601836 -285.450026)
				(mid 199.398636 -285.450026)
				(end 199.601836 -285.450026)
			)
		)
		(stroke
			(width 0)
			(type solid)
		)
		(fill yes)
		(layer "F.Cu")
		(net "GND")
	)
	(gr_poly
		(pts
			(arc
				(start 199.601836 -283.550106)
				(mid 199.398636 -283.550106)
				(end 199.601836 -283.550106)
			)
		)
		(stroke
			(width 0)
			(type solid)
		)
		(fill yes)
		(layer "F.Cu")
		(net "GND")
	)
	(gr_poly
		(pts
			(arc
				(start 199.601836 -281.650186)
				(mid 199.398636 -281.650186)
				(end 199.601836 -281.650186)
			)
		)
		(stroke
			(width 0)
			(type solid)
		)
		(fill yes)
		(layer "F.Cu")
		(net "GND")
	)
	(gr_poly
		(pts
			(arc
				(start 199.601836 -279.750012)
				(mid 199.398636 -279.750012)
				(end 199.601836 -279.750012)
			)
		)
		(stroke
			(width 0)
			(type solid)
		)
		(fill yes)
		(layer "F.Cu")
		(net "GND")
	)
	(gr_poly
		(pts
			(arc
				(start 199.601836 -276.900132)
				(mid 199.398636 -276.900132)
				(end 199.601836 -276.900132)
			)
		)
		(stroke
			(width 0)
			(type solid)
		)
		(fill yes)
		(layer "F.Cu")
		(net "GND")
	)
	(gr_poly
		(pts
			(arc
				(start 199.601836 -274.999958)
				(mid 199.398636 -274.999958)
				(end 199.601836 -274.999958)
			)
		)
		(stroke
			(width 0)
			(type solid)
		)
		(fill yes)
		(layer "F.Cu")
		(net "GND")
	)
	(gr_poly
		(pts
			(arc
				(start 268.041374 -299.2247)
				(mid 267.838174 -299.2247)
				(end 268.041374 -299.2247)
			)
		)
		(stroke
			(width 0)
			(type solid)
		)
		(fill yes)
		(layer "F.Cu")
		(net "GND")
	)
	(gr_poly
		(pts
			(arc
				(start 268.041374 -297.32478)
				(mid 267.838174 -297.32478)
				(end 268.041374 -297.32478)
			)
		)
		(stroke
			(width 0)
			(type solid)
		)
		(fill yes)
		(layer "F.Cu")
		(net "GND")
	)
	(gr_poly
		(pts
			(arc
				(start 268.200886 -316.799468)
				(mid 267.997686 -316.799468)
				(end 268.200886 -316.799468)
			)
		)
		(stroke
			(width 0)
			(type solid)
		)
		(fill yes)
		(layer "F.Cu")
		(net "GND")
	)
	(gr_poly
		(pts
			(arc
				(start 268.200886 -314.899548)
				(mid 267.997686 -314.899548)
				(end 268.200886 -314.899548)
			)
		)
		(stroke
			(width 0)
			(type solid)
		)
		(fill yes)
		(layer "F.Cu")
		(net "GND")
	)
	(gr_poly
		(pts
			(arc
				(start 268.20114 -312.049668)
				(mid 267.99794 -312.049668)
				(end 268.20114 -312.049668)
			)
		)
		(stroke
			(width 0)
			(type solid)
		)
		(fill yes)
		(layer "F.Cu")
		(net "GND")
	)
	(gr_poly
		(pts
			(arc
				(start 268.20114 -310.150002)
				(mid 267.99794 -310.150002)
				(end 268.20114 -310.150002)
			)
		)
		(stroke
			(width 0)
			(type solid)
		)
		(fill yes)
		(layer "F.Cu")
		(net "GND")
	)
	(gr_poly
		(pts
			(arc
				(start 268.20114 -308.250082)
				(mid 267.99794 -308.250082)
				(end 268.20114 -308.250082)
			)
		)
		(stroke
			(width 0)
			(type solid)
		)
		(fill yes)
		(layer "F.Cu")
		(net "GND")
	)
	(gr_poly
		(pts
			(arc
				(start 268.20114 -306.350162)
				(mid 267.99794 -306.350162)
				(end 268.20114 -306.350162)
			)
		)
		(stroke
			(width 0)
			(type solid)
		)
		(fill yes)
		(layer "F.Cu")
		(net "GND")
	)
	(gr_poly
		(pts
			(arc
				(start 268.20114 -304.449988)
				(mid 267.99794 -304.449988)
				(end 268.20114 -304.449988)
			)
		)
		(stroke
			(width 0)
			(type solid)
		)
		(fill yes)
		(layer "F.Cu")
		(net "GND")
	)
	(gr_poly
		(pts
			(arc
				(start 268.20114 -302.550068)
				(mid 267.99794 -302.550068)
				(end 268.20114 -302.550068)
			)
		)
		(stroke
			(width 0)
			(type solid)
		)
		(fill yes)
		(layer "F.Cu")
		(net "GND")
	)
	(gr_poly
		(pts
			(arc
				(start 271.051528 -319.65011)
				(mid 270.848328 -319.65011)
				(end 271.051528 -319.65011)
			)
		)
		(stroke
			(width 0)
			(type solid)
		)
		(fill yes)
		(layer "F.Cu")
		(net "GND")
	)
	(gr_poly
		(pts
			(arc
				(start 272.951448 -319.65011)
				(mid 272.748248 -319.65011)
				(end 272.951448 -319.65011)
			)
		)
		(stroke
			(width 0)
			(type solid)
		)
		(fill yes)
		(layer "F.Cu")
		(net "GND")
	)
	(gr_poly
		(pts
			(arc
				(start 274.851368 -319.65011)
				(mid 274.648168 -319.65011)
				(end 274.851368 -319.65011)
			)
		)
		(stroke
			(width 0)
			(type solid)
		)
		(fill yes)
		(layer "F.Cu")
		(net "GND")
	)
	(gr_poly
		(pts
			(arc
				(start 276.751034 -272.14957)
				(mid 276.547834 -272.14957)
				(end 276.751034 -272.14957)
			)
		)
		(stroke
			(width 0)
			(type solid)
		)
		(fill yes)
		(layer "F.Cu")
		(net "GND")
	)
	(gr_poly
		(pts
			(arc
				(start 276.751542 -319.65011)
				(mid 276.548342 -319.65011)
				(end 276.751542 -319.65011)
			)
		)
		(stroke
			(width 0)
			(type solid)
		)
		(fill yes)
		(layer "F.Cu")
		(net "GND")
	)
	(gr_poly
		(pts
			(arc
				(start 278.651208 -272.14957)
				(mid 278.448008 -272.14957)
				(end 278.651208 -272.14957)
			)
		)
		(stroke
			(width 0)
			(type solid)
		)
		(fill yes)
		(layer "F.Cu")
		(net "GND")
	)
	(gr_poly
		(pts
			(arc
				(start 278.651462 -319.65011)
				(mid 278.448262 -319.65011)
				(end 278.651462 -319.65011)
			)
		)
		(stroke
			(width 0)
			(type solid)
		)
		(fill yes)
		(layer "F.Cu")
		(net "GND")
	)
	(gr_poly
		(pts
			(arc
				(start 280.551128 -272.14957)
				(mid 280.347928 -272.14957)
				(end 280.551128 -272.14957)
			)
		)
		(stroke
			(width 0)
			(type solid)
		)
		(fill yes)
		(layer "F.Cu")
		(net "GND")
	)
	(gr_poly
		(pts
			(arc
				(start 280.551382 -319.65011)
				(mid 280.348182 -319.65011)
				(end 280.551382 -319.65011)
			)
		)
		(stroke
			(width 0)
			(type solid)
		)
		(fill yes)
		(layer "F.Cu")
		(net "GND")
	)
	(gr_poly
		(pts
			(arc
				(start 282.451048 -272.14957)
				(mid 282.247848 -272.14957)
				(end 282.451048 -272.14957)
			)
		)
		(stroke
			(width 0)
			(type solid)
		)
		(fill yes)
		(layer "F.Cu")
		(net "GND")
	)
	(gr_poly
		(pts
			(arc
				(start 282.451556 -319.65011)
				(mid 282.248356 -319.65011)
				(end 282.451556 -319.65011)
			)
		)
		(stroke
			(width 0)
			(type solid)
		)
		(fill yes)
		(layer "F.Cu")
		(net "GND")
	)
	(gr_poly
		(pts
			(arc
				(start 284.351222 -272.14957)
				(mid 284.148022 -272.14957)
				(end 284.351222 -272.14957)
			)
		)
		(stroke
			(width 0)
			(type solid)
		)
		(fill yes)
		(layer "F.Cu")
		(net "GND")
	)
	(gr_poly
		(pts
			(arc
				(start 284.351476 -319.65011)
				(mid 284.148276 -319.65011)
				(end 284.351476 -319.65011)
			)
		)
		(stroke
			(width 0)
			(type solid)
		)
		(fill yes)
		(layer "F.Cu")
		(net "GND")
	)
	(gr_poly
		(pts
			(arc
				(start 286.251142 -272.14957)
				(mid 286.047942 -272.14957)
				(end 286.251142 -272.14957)
			)
		)
		(stroke
			(width 0)
			(type solid)
		)
		(fill yes)
		(layer "F.Cu")
		(net "GND")
	)
	(gr_poly
		(pts
			(arc
				(start 286.251396 -319.65011)
				(mid 286.048196 -319.65011)
				(end 286.251396 -319.65011)
			)
		)
		(stroke
			(width 0)
			(type solid)
		)
		(fill yes)
		(layer "F.Cu")
		(net "GND")
	)
	(gr_poly
		(pts
			(arc
				(start 288.151062 -272.14957)
				(mid 287.947862 -272.14957)
				(end 288.151062 -272.14957)
			)
		)
		(stroke
			(width 0)
			(type solid)
		)
		(fill yes)
		(layer "F.Cu")
		(net "GND")
	)
	(gr_poly
		(pts
			(arc
				(start 288.15157 -319.65011)
				(mid 287.94837 -319.65011)
				(end 288.15157 -319.65011)
			)
		)
		(stroke
			(width 0)
			(type solid)
		)
		(fill yes)
		(layer "F.Cu")
		(net "GND")
	)
	(gr_poly
		(pts
			(arc
				(start 290.051236 -272.14957)
				(mid 289.848036 -272.14957)
				(end 290.051236 -272.14957)
			)
		)
		(stroke
			(width 0)
			(type solid)
		)
		(fill yes)
		(layer "F.Cu")
		(net "GND")
	)
	(gr_poly
		(pts
			(arc
				(start 290.051744 -319.65011)
				(mid 289.848544 -319.65011)
				(end 290.051744 -319.65011)
			)
		)
		(stroke
			(width 0)
			(type solid)
		)
		(fill yes)
		(layer "F.Cu")
		(net "GND")
	)
	(gr_poly
		(pts
			(arc
				(start 291.951156 -272.149316)
				(mid 291.747956 -272.149316)
				(end 291.951156 -272.149316)
			)
		)
		(stroke
			(width 0)
			(type solid)
		)
		(fill yes)
		(layer "F.Cu")
		(net "GND")
	)
	(gr_poly
		(pts
			(arc
				(start 291.95141 -319.65011)
				(mid 291.74821 -319.65011)
				(end 291.95141 -319.65011)
			)
		)
		(stroke
			(width 0)
			(type solid)
		)
		(fill yes)
		(layer "F.Cu")
		(net "GND")
	)
	(gr_poly
		(pts
			(arc
				(start 293.851076 -272.14957)
				(mid 293.647876 -272.14957)
				(end 293.851076 -272.14957)
			)
		)
		(stroke
			(width 0)
			(type solid)
		)
		(fill yes)
		(layer "F.Cu")
		(net "GND")
	)
	(gr_poly
		(pts
			(arc
				(start 293.85133 -319.65011)
				(mid 293.64813 -319.65011)
				(end 293.85133 -319.65011)
			)
		)
		(stroke
			(width 0)
			(type solid)
		)
		(fill yes)
		(layer "F.Cu")
		(net "GND")
	)
	(gr_poly
		(pts
			(arc
				(start 295.75125 -272.14957)
				(mid 295.54805 -272.14957)
				(end 295.75125 -272.14957)
			)
		)
		(stroke
			(width 0)
			(type solid)
		)
		(fill yes)
		(layer "F.Cu")
		(net "GND")
	)
	(gr_poly
		(pts
			(arc
				(start 295.751504 -319.65011)
				(mid 295.548304 -319.65011)
				(end 295.751504 -319.65011)
			)
		)
		(stroke
			(width 0)
			(type solid)
		)
		(fill yes)
		(layer "F.Cu")
		(net "GND")
	)
	(gr_poly
		(pts
			(arc
				(start 297.65117 -272.14957)
				(mid 297.44797 -272.14957)
				(end 297.65117 -272.14957)
			)
		)
		(stroke
			(width 0)
			(type solid)
		)
		(fill yes)
		(layer "F.Cu")
		(net "GND")
	)
	(gr_poly
		(pts
			(arc
				(start 297.651424 -319.65011)
				(mid 297.448224 -319.65011)
				(end 297.651424 -319.65011)
			)
		)
		(stroke
			(width 0)
			(type solid)
		)
		(fill yes)
		(layer "F.Cu")
		(net "GND")
	)
	(gr_poly
		(pts
			(arc
				(start 299.55109 -272.14957)
				(mid 299.34789 -272.14957)
				(end 299.55109 -272.14957)
			)
		)
		(stroke
			(width 0)
			(type solid)
		)
		(fill yes)
		(layer "F.Cu")
		(net "GND")
	)
	(gr_poly
		(pts
			(arc
				(start 299.551344 -319.65011)
				(mid 299.348144 -319.65011)
				(end 299.551344 -319.65011)
			)
		)
		(stroke
			(width 0)
			(type solid)
		)
		(fill yes)
		(layer "F.Cu")
		(net "GND")
	)
	(gr_poly
		(pts
			(arc
				(start 301.451264 -272.14957)
				(mid 301.248064 -272.14957)
				(end 301.451264 -272.14957)
			)
		)
		(stroke
			(width 0)
			(type solid)
		)
		(fill yes)
		(layer "F.Cu")
		(net "GND")
	)
	(gr_poly
		(pts
			(arc
				(start 301.451518 -319.65011)
				(mid 301.248318 -319.65011)
				(end 301.451518 -319.65011)
			)
		)
		(stroke
			(width 0)
			(type solid)
		)
		(fill yes)
		(layer "F.Cu")
		(net "GND")
	)
	(gr_poly
		(pts
			(arc
				(start 303.351184 -272.14957)
				(mid 303.147984 -272.14957)
				(end 303.351184 -272.14957)
			)
		)
		(stroke
			(width 0)
			(type solid)
		)
		(fill yes)
		(layer "F.Cu")
		(net "GND")
	)
	(gr_poly
		(pts
			(arc
				(start 303.351438 -319.65011)
				(mid 303.148238 -319.65011)
				(end 303.351438 -319.65011)
			)
		)
		(stroke
			(width 0)
			(type solid)
		)
		(fill yes)
		(layer "F.Cu")
		(net "GND")
	)
	(gr_poly
		(pts
			(arc
				(start 305.251104 -272.14957)
				(mid 305.047904 -272.14957)
				(end 305.251104 -272.14957)
			)
		)
		(stroke
			(width 0)
			(type solid)
		)
		(fill yes)
		(layer "F.Cu")
		(net "GND")
	)
	(gr_poly
		(pts
			(arc
				(start 305.251358 -319.65011)
				(mid 305.048158 -319.65011)
				(end 305.251358 -319.65011)
			)
		)
		(stroke
			(width 0)
			(type solid)
		)
		(fill yes)
		(layer "F.Cu")
		(net "GND")
	)
	(gr_poly
		(pts
			(arc
				(start 307.151278 -272.14957)
				(mid 306.948078 -272.14957)
				(end 307.151278 -272.14957)
			)
		)
		(stroke
			(width 0)
			(type solid)
		)
		(fill yes)
		(layer "F.Cu")
		(net "GND")
	)
	(gr_poly
		(pts
			(arc
				(start 307.151532 -319.65011)
				(mid 306.948332 -319.65011)
				(end 307.151532 -319.65011)
			)
		)
		(stroke
			(width 0)
			(type solid)
		)
		(fill yes)
		(layer "F.Cu")
		(net "GND")
	)
	(gr_poly
		(pts
			(arc
				(start 309.051452 -319.65011)
				(mid 308.848252 -319.65011)
				(end 309.051452 -319.65011)
			)
		)
		(stroke
			(width 0)
			(type solid)
		)
		(fill yes)
		(layer "F.Cu")
		(net "GND")
	)
	(gr_poly
		(pts
			(arc
				(start 309.051452 -272.14957)
				(mid 308.848252 -272.14957)
				(end 309.051452 -272.14957)
			)
		)
		(stroke
			(width 0)
			(type solid)
		)
		(fill yes)
		(layer "F.Cu")
		(net "GND")
	)
	(gr_poly
		(pts
			(arc
				(start 310.951372 -319.65011)
				(mid 310.748172 -319.65011)
				(end 310.951372 -319.65011)
			)
		)
		(stroke
			(width 0)
			(type solid)
		)
		(fill yes)
		(layer "F.Cu")
		(net "GND")
	)
	(gr_poly
		(pts
			(arc
				(start 310.951372 -272.14957)
				(mid 310.748172 -272.14957)
				(end 310.951372 -272.14957)
			)
		)
		(stroke
			(width 0)
			(type solid)
		)
		(fill yes)
		(layer "F.Cu")
		(net "GND")
	)
	(gr_poly
		(pts
			(arc
				(start 312.851292 -319.65011)
				(mid 312.648092 -319.65011)
				(end 312.851292 -319.65011)
			)
		)
		(stroke
			(width 0)
			(type solid)
		)
		(fill yes)
		(layer "F.Cu")
		(net "GND")
	)
	(gr_poly
		(pts
			(arc
				(start 312.851292 -272.14957)
				(mid 312.648092 -272.14957)
				(end 312.851292 -272.14957)
			)
		)
		(stroke
			(width 0)
			(type solid)
		)
		(fill yes)
		(layer "F.Cu")
		(net "GND")
	)
	(gr_poly
		(pts
			(arc
				(start 315.70168 -316.799722)
				(mid 315.49848 -316.799722)
				(end 315.70168 -316.799722)
			)
		)
		(stroke
			(width 0)
			(type solid)
		)
		(fill yes)
		(layer "F.Cu")
		(net "GND")
	)
	(gr_poly
		(pts
			(arc
				(start 315.70168 -314.899548)
				(mid 315.49848 -314.899548)
				(end 315.70168 -314.899548)
			)
		)
		(stroke
			(width 0)
			(type solid)
		)
		(fill yes)
		(layer "F.Cu")
		(net "GND")
	)
	(gr_poly
		(pts
			(arc
				(start 315.70168 -312.049922)
				(mid 315.49848 -312.049922)
				(end 315.70168 -312.049922)
			)
		)
		(stroke
			(width 0)
			(type solid)
		)
		(fill yes)
		(layer "F.Cu")
		(net "GND")
	)
	(gr_poly
		(pts
			(arc
				(start 315.70168 -310.149748)
				(mid 315.49848 -310.149748)
				(end 315.70168 -310.149748)
			)
		)
		(stroke
			(width 0)
			(type solid)
		)
		(fill yes)
		(layer "F.Cu")
		(net "GND")
	)
	(gr_poly
		(pts
			(arc
				(start 315.70168 -308.249828)
				(mid 315.49848 -308.249828)
				(end 315.70168 -308.249828)
			)
		)
		(stroke
			(width 0)
			(type solid)
		)
		(fill yes)
		(layer "F.Cu")
		(net "GND")
	)
	(gr_poly
		(pts
			(arc
				(start 315.70168 -306.349908)
				(mid 315.49848 -306.349908)
				(end 315.70168 -306.349908)
			)
		)
		(stroke
			(width 0)
			(type solid)
		)
		(fill yes)
		(layer "F.Cu")
		(net "GND")
	)
	(gr_poly
		(pts
			(arc
				(start 315.70168 -304.449734)
				(mid 315.49848 -304.449734)
				(end 315.70168 -304.449734)
			)
		)
		(stroke
			(width 0)
			(type solid)
		)
		(fill yes)
		(layer "F.Cu")
		(net "GND")
	)
	(gr_poly
		(pts
			(arc
				(start 315.70168 -287.3502)
				(mid 315.49848 -287.3502)
				(end 315.70168 -287.3502)
			)
		)
		(stroke
			(width 0)
			(type solid)
		)
		(fill yes)
		(layer "F.Cu")
		(net "GND")
	)
	(gr_poly
		(pts
			(arc
				(start 315.70168 -285.450026)
				(mid 315.49848 -285.450026)
				(end 315.70168 -285.450026)
			)
		)
		(stroke
			(width 0)
			(type solid)
		)
		(fill yes)
		(layer "F.Cu")
		(net "GND")
	)
	(gr_poly
		(pts
			(arc
				(start 315.70168 -283.550106)
				(mid 315.49848 -283.550106)
				(end 315.70168 -283.550106)
			)
		)
		(stroke
			(width 0)
			(type solid)
		)
		(fill yes)
		(layer "F.Cu")
		(net "GND")
	)
	(gr_poly
		(pts
			(arc
				(start 315.70168 -281.650186)
				(mid 315.49848 -281.650186)
				(end 315.70168 -281.650186)
			)
		)
		(stroke
			(width 0)
			(type solid)
		)
		(fill yes)
		(layer "F.Cu")
		(net "GND")
	)
	(gr_poly
		(pts
			(arc
				(start 315.70168 -279.750012)
				(mid 315.49848 -279.750012)
				(end 315.70168 -279.750012)
			)
		)
		(stroke
			(width 0)
			(type solid)
		)
		(fill yes)
		(layer "F.Cu")
		(net "GND")
	)
	(gr_poly
		(pts
			(arc
				(start 315.70168 -276.900132)
				(mid 315.49848 -276.900132)
				(end 315.70168 -276.900132)
			)
		)
		(stroke
			(width 0)
			(type solid)
		)
		(fill yes)
		(layer "F.Cu")
		(net "GND")
	)
	(gr_poly
		(pts
			(arc
				(start 315.70168 -274.999958)
				(mid 315.49848 -274.999958)
				(end 315.70168 -274.999958)
			)
		)
		(stroke
			(width 0)
			(type solid)
		)
		(fill yes)
		(layer "F.Cu")
		(net "GND")
	)
	(gr_poly
		(pts
			(arc
				(start 315.861446 -288.774886)
				(mid 315.658246 -288.774886)
				(end 315.861446 -288.774886)
			)
		)
		(stroke
			(width 0)
			(type solid)
		)
		(fill yes)
		(layer "F.Cu")
		(net "GND")
	)
	(gr_poly
		(pts
			(arc
				(start 384.141472 -299.2247)
				(mid 383.938272 -299.2247)
				(end 384.141472 -299.2247)
			)
		)
		(stroke
			(width 0)
			(type solid)
		)
		(fill yes)
		(layer "F.Cu")
		(net "GND")
	)
	(gr_poly
		(pts
			(arc
				(start 384.141472 -297.32478)
				(mid 383.938272 -297.32478)
				(end 384.141472 -297.32478)
			)
		)
		(stroke
			(width 0)
			(type solid)
		)
		(fill yes)
		(layer "F.Cu")
		(net "GND")
	)
	(gr_poly
		(pts
			(arc
				(start 384.300984 -316.799468)
				(mid 384.097784 -316.799468)
				(end 384.300984 -316.799468)
			)
		)
		(stroke
			(width 0)
			(type solid)
		)
		(fill yes)
		(layer "F.Cu")
		(net "GND")
	)
	(gr_poly
		(pts
			(arc
				(start 384.300984 -314.899802)
				(mid 384.097784 -314.899802)
				(end 384.300984 -314.899802)
			)
		)
		(stroke
			(width 0)
			(type solid)
		)
		(fill yes)
		(layer "F.Cu")
		(net "GND")
	)
	(gr_poly
		(pts
			(arc
				(start 384.301238 -312.049668)
				(mid 384.098038 -312.049668)
				(end 384.301238 -312.049668)
			)
		)
		(stroke
			(width 0)
			(type solid)
		)
		(fill yes)
		(layer "F.Cu")
		(net "GND")
	)
	(gr_poly
		(pts
			(arc
				(start 384.301238 -310.150002)
				(mid 384.098038 -310.150002)
				(end 384.301238 -310.150002)
			)
		)
		(stroke
			(width 0)
			(type solid)
		)
		(fill yes)
		(layer "F.Cu")
		(net "GND")
	)
	(gr_poly
		(pts
			(arc
				(start 384.301238 -308.250082)
				(mid 384.098038 -308.250082)
				(end 384.301238 -308.250082)
			)
		)
		(stroke
			(width 0)
			(type solid)
		)
		(fill yes)
		(layer "F.Cu")
		(net "GND")
	)
	(gr_poly
		(pts
			(arc
				(start 384.301238 -306.350162)
				(mid 384.098038 -306.350162)
				(end 384.301238 -306.350162)
			)
		)
		(stroke
			(width 0)
			(type solid)
		)
		(fill yes)
		(layer "F.Cu")
		(net "GND")
	)
	(gr_poly
		(pts
			(arc
				(start 384.301238 -304.449988)
				(mid 384.098038 -304.449988)
				(end 384.301238 -304.449988)
			)
		)
		(stroke
			(width 0)
			(type solid)
		)
		(fill yes)
		(layer "F.Cu")
		(net "GND")
	)
	(gr_poly
		(pts
			(arc
				(start 384.301238 -302.550068)
				(mid 384.098038 -302.550068)
				(end 384.301238 -302.550068)
			)
		)
		(stroke
			(width 0)
			(type solid)
		)
		(fill yes)
		(layer "F.Cu")
		(net "GND")
	)
	(gr_poly
		(pts
			(arc
				(start 387.151626 -319.65011)
				(mid 386.948426 -319.65011)
				(end 387.151626 -319.65011)
			)
		)
		(stroke
			(width 0)
			(type solid)
		)
		(fill yes)
		(layer "F.Cu")
		(net "GND")
	)
	(gr_poly
		(pts
			(arc
				(start 389.051546 -319.65011)
				(mid 388.848346 -319.65011)
				(end 389.051546 -319.65011)
			)
		)
		(stroke
			(width 0)
			(type solid)
		)
		(fill yes)
		(layer "F.Cu")
		(net "GND")
	)
	(gr_poly
		(pts
			(arc
				(start 390.951466 -319.65011)
				(mid 390.748266 -319.65011)
				(end 390.951466 -319.65011)
			)
		)
		(stroke
			(width 0)
			(type solid)
		)
		(fill yes)
		(layer "F.Cu")
		(net "GND")
	)
	(gr_poly
		(pts
			(arc
				(start 392.851132 -272.14957)
				(mid 392.647932 -272.14957)
				(end 392.851132 -272.14957)
			)
		)
		(stroke
			(width 0)
			(type solid)
		)
		(fill yes)
		(layer "F.Cu")
		(net "GND")
	)
	(gr_poly
		(pts
			(arc
				(start 392.85164 -319.65011)
				(mid 392.64844 -319.65011)
				(end 392.85164 -319.65011)
			)
		)
		(stroke
			(width 0)
			(type solid)
		)
		(fill yes)
		(layer "F.Cu")
		(net "GND")
	)
	(gr_poly
		(pts
			(arc
				(start 394.751306 -272.14957)
				(mid 394.548106 -272.14957)
				(end 394.751306 -272.14957)
			)
		)
		(stroke
			(width 0)
			(type solid)
		)
		(fill yes)
		(layer "F.Cu")
		(net "GND")
	)
	(gr_poly
		(pts
			(arc
				(start 394.75156 -319.65011)
				(mid 394.54836 -319.65011)
				(end 394.75156 -319.65011)
			)
		)
		(stroke
			(width 0)
			(type solid)
		)
		(fill yes)
		(layer "F.Cu")
		(net "GND")
	)
	(gr_poly
		(pts
			(arc
				(start 396.651226 -272.14957)
				(mid 396.448026 -272.14957)
				(end 396.651226 -272.14957)
			)
		)
		(stroke
			(width 0)
			(type solid)
		)
		(fill yes)
		(layer "F.Cu")
		(net "GND")
	)
	(gr_poly
		(pts
			(arc
				(start 396.65148 -319.65011)
				(mid 396.44828 -319.65011)
				(end 396.65148 -319.65011)
			)
		)
		(stroke
			(width 0)
			(type solid)
		)
		(fill yes)
		(layer "F.Cu")
		(net "GND")
	)
	(gr_poly
		(pts
			(arc
				(start 398.551146 -272.14957)
				(mid 398.347946 -272.14957)
				(end 398.551146 -272.14957)
			)
		)
		(stroke
			(width 0)
			(type solid)
		)
		(fill yes)
		(layer "F.Cu")
		(net "GND")
	)
	(gr_poly
		(pts
			(arc
				(start 398.551654 -319.65011)
				(mid 398.348454 -319.65011)
				(end 398.551654 -319.65011)
			)
		)
		(stroke
			(width 0)
			(type solid)
		)
		(fill yes)
		(layer "F.Cu")
		(net "GND")
	)
	(gr_poly
		(pts
			(arc
				(start 400.45132 -272.14957)
				(mid 400.24812 -272.14957)
				(end 400.45132 -272.14957)
			)
		)
		(stroke
			(width 0)
			(type solid)
		)
		(fill yes)
		(layer "F.Cu")
		(net "GND")
	)
	(gr_poly
		(pts
			(arc
				(start 400.451574 -319.65011)
				(mid 400.248374 -319.65011)
				(end 400.451574 -319.65011)
			)
		)
		(stroke
			(width 0)
			(type solid)
		)
		(fill yes)
		(layer "F.Cu")
		(net "GND")
	)
	(gr_poly
		(pts
			(arc
				(start 402.35124 -272.14957)
				(mid 402.14804 -272.14957)
				(end 402.35124 -272.14957)
			)
		)
		(stroke
			(width 0)
			(type solid)
		)
		(fill yes)
		(layer "F.Cu")
		(net "GND")
	)
	(gr_poly
		(pts
			(arc
				(start 402.351494 -319.65011)
				(mid 402.148294 -319.65011)
				(end 402.351494 -319.65011)
			)
		)
		(stroke
			(width 0)
			(type solid)
		)
		(fill yes)
		(layer "F.Cu")
		(net "GND")
	)
	(gr_poly
		(pts
			(arc
				(start 404.25116 -272.14957)
				(mid 404.04796 -272.14957)
				(end 404.25116 -272.14957)
			)
		)
		(stroke
			(width 0)
			(type solid)
		)
		(fill yes)
		(layer "F.Cu")
		(net "GND")
	)
	(gr_poly
		(pts
			(arc
				(start 404.251668 -319.65011)
				(mid 404.048468 -319.65011)
				(end 404.251668 -319.65011)
			)
		)
		(stroke
			(width 0)
			(type solid)
		)
		(fill yes)
		(layer "F.Cu")
		(net "GND")
	)
	(gr_poly
		(pts
			(arc
				(start 406.151334 -272.14957)
				(mid 405.948134 -272.14957)
				(end 406.151334 -272.14957)
			)
		)
		(stroke
			(width 0)
			(type solid)
		)
		(fill yes)
		(layer "F.Cu")
		(net "GND")
	)
	(gr_poly
		(pts
			(arc
				(start 406.151842 -319.65011)
				(mid 405.948642 -319.65011)
				(end 406.151842 -319.65011)
			)
		)
		(stroke
			(width 0)
			(type solid)
		)
		(fill yes)
		(layer "F.Cu")
		(net "GND")
	)
	(gr_poly
		(pts
			(arc
				(start 408.051254 -272.149316)
				(mid 407.848054 -272.149316)
				(end 408.051254 -272.149316)
			)
		)
		(stroke
			(width 0)
			(type solid)
		)
		(fill yes)
		(layer "F.Cu")
		(net "GND")
	)
	(gr_poly
		(pts
			(arc
				(start 408.051508 -319.65011)
				(mid 407.848308 -319.65011)
				(end 408.051508 -319.65011)
			)
		)
		(stroke
			(width 0)
			(type solid)
		)
		(fill yes)
		(layer "F.Cu")
		(net "GND")
	)
	(gr_poly
		(pts
			(arc
				(start 409.951174 -272.14957)
				(mid 409.747974 -272.14957)
				(end 409.951174 -272.14957)
			)
		)
		(stroke
			(width 0)
			(type solid)
		)
		(fill yes)
		(layer "F.Cu")
		(net "GND")
	)
	(gr_poly
		(pts
			(arc
				(start 409.951428 -319.65011)
				(mid 409.748228 -319.65011)
				(end 409.951428 -319.65011)
			)
		)
		(stroke
			(width 0)
			(type solid)
		)
		(fill yes)
		(layer "F.Cu")
		(net "GND")
	)
	(gr_poly
		(pts
			(arc
				(start 411.851348 -272.14957)
				(mid 411.648148 -272.14957)
				(end 411.851348 -272.14957)
			)
		)
		(stroke
			(width 0)
			(type solid)
		)
		(fill yes)
		(layer "F.Cu")
		(net "GND")
	)
	(gr_poly
		(pts
			(arc
				(start 411.851602 -319.65011)
				(mid 411.648402 -319.65011)
				(end 411.851602 -319.65011)
			)
		)
		(stroke
			(width 0)
			(type solid)
		)
		(fill yes)
		(layer "F.Cu")
		(net "GND")
	)
	(gr_poly
		(pts
			(arc
				(start 413.751268 -272.14957)
				(mid 413.548068 -272.14957)
				(end 413.751268 -272.14957)
			)
		)
		(stroke
			(width 0)
			(type solid)
		)
		(fill yes)
		(layer "F.Cu")
		(net "GND")
	)
	(gr_poly
		(pts
			(arc
				(start 413.751522 -319.65011)
				(mid 413.548322 -319.65011)
				(end 413.751522 -319.65011)
			)
		)
		(stroke
			(width 0)
			(type solid)
		)
		(fill yes)
		(layer "F.Cu")
		(net "GND")
	)
	(gr_poly
		(pts
			(arc
				(start 415.651188 -272.14957)
				(mid 415.447988 -272.14957)
				(end 415.651188 -272.14957)
			)
		)
		(stroke
			(width 0)
			(type solid)
		)
		(fill yes)
		(layer "F.Cu")
		(net "GND")
	)
	(gr_poly
		(pts
			(arc
				(start 415.651442 -319.65011)
				(mid 415.448242 -319.65011)
				(end 415.651442 -319.65011)
			)
		)
		(stroke
			(width 0)
			(type solid)
		)
		(fill yes)
		(layer "F.Cu")
		(net "GND")
	)
	(gr_poly
		(pts
			(arc
				(start 417.551362 -272.14957)
				(mid 417.348162 -272.14957)
				(end 417.551362 -272.14957)
			)
		)
		(stroke
			(width 0)
			(type solid)
		)
		(fill yes)
		(layer "F.Cu")
		(net "GND")
	)
	(gr_poly
		(pts
			(arc
				(start 417.551616 -319.65011)
				(mid 417.348416 -319.65011)
				(end 417.551616 -319.65011)
			)
		)
		(stroke
			(width 0)
			(type solid)
		)
		(fill yes)
		(layer "F.Cu")
		(net "GND")
	)
	(gr_poly
		(pts
			(arc
				(start 419.451282 -272.14957)
				(mid 419.248082 -272.14957)
				(end 419.451282 -272.14957)
			)
		)
		(stroke
			(width 0)
			(type solid)
		)
		(fill yes)
		(layer "F.Cu")
		(net "GND")
	)
	(gr_poly
		(pts
			(arc
				(start 419.451536 -319.65011)
				(mid 419.248336 -319.65011)
				(end 419.451536 -319.65011)
			)
		)
		(stroke
			(width 0)
			(type solid)
		)
		(fill yes)
		(layer "F.Cu")
		(net "GND")
	)
	(gr_poly
		(pts
			(arc
				(start 421.351202 -272.14957)
				(mid 421.148002 -272.14957)
				(end 421.351202 -272.14957)
			)
		)
		(stroke
			(width 0)
			(type solid)
		)
		(fill yes)
		(layer "F.Cu")
		(net "GND")
	)
	(gr_poly
		(pts
			(arc
				(start 421.351456 -319.65011)
				(mid 421.148256 -319.65011)
				(end 421.351456 -319.65011)
			)
		)
		(stroke
			(width 0)
			(type solid)
		)
		(fill yes)
		(layer "F.Cu")
		(net "GND")
	)
	(gr_poly
		(pts
			(arc
				(start 423.251376 -272.14957)
				(mid 423.048176 -272.14957)
				(end 423.251376 -272.14957)
			)
		)
		(stroke
			(width 0)
			(type solid)
		)
		(fill yes)
		(layer "F.Cu")
		(net "GND")
	)
	(gr_poly
		(pts
			(arc
				(start 423.25163 -319.65011)
				(mid 423.04843 -319.65011)
				(end 423.25163 -319.65011)
			)
		)
		(stroke
			(width 0)
			(type solid)
		)
		(fill yes)
		(layer "F.Cu")
		(net "GND")
	)
	(gr_poly
		(pts
			(arc
				(start 425.15155 -319.65011)
				(mid 424.94835 -319.65011)
				(end 425.15155 -319.65011)
			)
		)
		(stroke
			(width 0)
			(type solid)
		)
		(fill yes)
		(layer "F.Cu")
		(net "GND")
	)
	(gr_poly
		(pts
			(arc
				(start 425.15155 -272.14957)
				(mid 424.94835 -272.14957)
				(end 425.15155 -272.14957)
			)
		)
		(stroke
			(width 0)
			(type solid)
		)
		(fill yes)
		(layer "F.Cu")
		(net "GND")
	)
	(gr_poly
		(pts
			(arc
				(start 427.05147 -319.65011)
				(mid 426.84827 -319.65011)
				(end 427.05147 -319.65011)
			)
		)
		(stroke
			(width 0)
			(type solid)
		)
		(fill yes)
		(layer "F.Cu")
		(net "GND")
	)
	(gr_poly
		(pts
			(arc
				(start 427.05147 -272.14957)
				(mid 426.84827 -272.14957)
				(end 427.05147 -272.14957)
			)
		)
		(stroke
			(width 0)
			(type solid)
		)
		(fill yes)
		(layer "F.Cu")
		(net "GND")
	)
	(gr_poly
		(pts
			(arc
				(start 428.95139 -319.65011)
				(mid 428.74819 -319.65011)
				(end 428.95139 -319.65011)
			)
		)
		(stroke
			(width 0)
			(type solid)
		)
		(fill yes)
		(layer "F.Cu")
		(net "GND")
	)
	(gr_poly
		(pts
			(arc
				(start 428.95139 -272.14957)
				(mid 428.74819 -272.14957)
				(end 428.95139 -272.14957)
			)
		)
		(stroke
			(width 0)
			(type solid)
		)
		(fill yes)
		(layer "F.Cu")
		(net "GND")
	)
	(gr_poly
		(pts
			(arc
				(start 431.801778 -316.799722)
				(mid 431.598578 -316.799722)
				(end 431.801778 -316.799722)
			)
		)
		(stroke
			(width 0)
			(type solid)
		)
		(fill yes)
		(layer "F.Cu")
		(net "GND")
	)
	(gr_poly
		(pts
			(arc
				(start 431.801778 -314.899548)
				(mid 431.598578 -314.899548)
				(end 431.801778 -314.899548)
			)
		)
		(stroke
			(width 0)
			(type solid)
		)
		(fill yes)
		(layer "F.Cu")
		(net "GND")
	)
	(gr_poly
		(pts
			(arc
				(start 431.801778 -312.049922)
				(mid 431.598578 -312.049922)
				(end 431.801778 -312.049922)
			)
		)
		(stroke
			(width 0)
			(type solid)
		)
		(fill yes)
		(layer "F.Cu")
		(net "GND")
	)
	(gr_poly
		(pts
			(arc
				(start 431.801778 -310.149748)
				(mid 431.598578 -310.149748)
				(end 431.801778 -310.149748)
			)
		)
		(stroke
			(width 0)
			(type solid)
		)
		(fill yes)
		(layer "F.Cu")
		(net "GND")
	)
	(gr_poly
		(pts
			(arc
				(start 431.801778 -308.249828)
				(mid 431.598578 -308.249828)
				(end 431.801778 -308.249828)
			)
		)
		(stroke
			(width 0)
			(type solid)
		)
		(fill yes)
		(layer "F.Cu")
		(net "GND")
	)
	(gr_poly
		(pts
			(arc
				(start 431.801778 -306.349908)
				(mid 431.598578 -306.349908)
				(end 431.801778 -306.349908)
			)
		)
		(stroke
			(width 0)
			(type solid)
		)
		(fill yes)
		(layer "F.Cu")
		(net "GND")
	)
	(gr_poly
		(pts
			(arc
				(start 431.801778 -304.449734)
				(mid 431.598578 -304.449734)
				(end 431.801778 -304.449734)
			)
		)
		(stroke
			(width 0)
			(type solid)
		)
		(fill yes)
		(layer "F.Cu")
		(net "GND")
	)
	(gr_poly
		(pts
			(arc
				(start 431.801778 -287.3502)
				(mid 431.598578 -287.3502)
				(end 431.801778 -287.3502)
			)
		)
		(stroke
			(width 0)
			(type solid)
		)
		(fill yes)
		(layer "F.Cu")
		(net "GND")
	)
	(gr_poly
		(pts
			(arc
				(start 431.801778 -285.450026)
				(mid 431.598578 -285.450026)
				(end 431.801778 -285.450026)
			)
		)
		(stroke
			(width 0)
			(type solid)
		)
		(fill yes)
		(layer "F.Cu")
		(net "GND")
	)
	(gr_poly
		(pts
			(arc
				(start 431.801778 -283.550106)
				(mid 431.598578 -283.550106)
				(end 431.801778 -283.550106)
			)
		)
		(stroke
			(width 0)
			(type solid)
		)
		(fill yes)
		(layer "F.Cu")
		(net "GND")
	)
	(gr_poly
		(pts
			(arc
				(start 431.801778 -281.650186)
				(mid 431.598578 -281.650186)
				(end 431.801778 -281.650186)
			)
		)
		(stroke
			(width 0)
			(type solid)
		)
		(fill yes)
		(layer "F.Cu")
		(net "GND")
	)
	(gr_poly
		(pts
			(arc
				(start 431.801778 -279.750012)
				(mid 431.598578 -279.750012)
				(end 431.801778 -279.750012)
			)
		)
		(stroke
			(width 0)
			(type solid)
		)
		(fill yes)
		(layer "F.Cu")
		(net "GND")
	)
	(gr_poly
		(pts
			(arc
				(start 431.801778 -276.900132)
				(mid 431.598578 -276.900132)
				(end 431.801778 -276.900132)
			)
		)
		(stroke
			(width 0)
			(type solid)
		)
		(fill yes)
		(layer "F.Cu")
		(net "GND")
	)
	(gr_poly
		(pts
			(arc
				(start 431.801778 -274.999958)
				(mid 431.598578 -274.999958)
				(end 431.801778 -274.999958)
			)
		)
		(stroke
			(width 0)
			(type solid)
		)
		(fill yes)
		(layer "F.Cu")
		(net "GND")
	)
	(gr_poly
		(pts
			(arc
				(start 431.961544 -288.774886)
				(mid 431.758344 -288.774886)
				(end 431.961544 -288.774886)
			)
		)
		(stroke
			(width 0)
			(type solid)
		)
		(fill yes)
		(layer "F.Cu")
		(net "GND")
	)
	(gr_poly
		(pts
			(xy 105.79354 -108.985304) (xy 105.79354 -103.889048) (xy 106.67746 -103.005128) (xy 106.67746 -102.71379)
			(xy 106.67746 -102.027736) (xy 106.67746 -100.540312) (xy 106.467656 -100.330508) (xy 106.436414 -100.330508)
			(xy 102.832662 -100.330508) (xy 99.606862 -100.330508) (xy 99.473512 -100.463858) (xy 99.473512 -101.185472)
			(xy 99.34702 -101.311964) (xy 98.76917 -101.889814) (xy 98.76917 -106.86796) (xy 98.76917 -107.253786)
			(xy 98.76917 -107.813094) (xy 98.989134 -108.033058) (xy 103.43261 -108.033058) (xy 103.639874 -108.240322)
			(xy 103.639874 -109.056424) (xy 103.793544 -109.210094) (xy 103.981504 -109.210094) (xy 105.56875 -109.210094)
		)
		(stroke
			(width 0)
			(type solid)
		)
		(fill yes)
		(layer "F.Cu")
		(net "GND")
	)
	(gr_poly
		(pts
			(xy 231.144318 -149.624034) (xy 231.144318 -144.947894) (xy 231.301798 -144.790414) (xy 231.924098 -144.790414)
			(xy 231.959658 -144.754854) (xy 231.959658 -144.518634) (xy 231.939338 -144.498314) (xy 231.418638 -144.498314)
			(xy 231.329738 -144.587214) (xy 230.791258 -144.587214) (xy 230.735378 -144.531334) (xy 230.735378 -144.406874)
			(xy 230.735378 -143.784574) (xy 230.717598 -143.766794) (xy 230.471218 -143.766794) (xy 230.455978 -143.782034)
			(xy 230.455978 -144.434814) (xy 230.455978 -144.516094) (xy 230.389938 -144.582134) (xy 226.275138 -144.582134)
			(xy 226.043998 -144.813274) (xy 226.043998 -149.649434) (xy 226.084638 -149.690074) (xy 231.078278 -149.690074)
		)
		(stroke
			(width 0)
			(type solid)
		)
		(fill yes)
		(layer "F.Cu")
		(net "GND")
	)
	(gr_poly
		(pts
			(xy 262.226552 -86.818724) (xy 262.226552 -81.825084) (xy 262.160512 -81.759044) (xy 257.484372 -81.759044)
			(xy 257.326892 -81.601564) (xy 257.326892 -80.979264) (xy 257.291332 -80.943704) (xy 257.055112 -80.943704)
			(xy 257.034792 -80.964024) (xy 257.034792 -81.484724) (xy 257.123692 -81.573624) (xy 257.123692 -82.112104)
			(xy 257.067812 -82.167984) (xy 256.943352 -82.167984) (xy 256.321052 -82.167984) (xy 256.303272 -82.185764)
			(xy 256.303272 -82.432144) (xy 256.318512 -82.447384) (xy 256.971292 -82.447384) (xy 257.052572 -82.447384)
			(xy 257.118612 -82.513424) (xy 257.118612 -86.628224) (xy 257.349752 -86.859364) (xy 262.185912 -86.859364)
		)
		(stroke
			(width 0)
			(type solid)
		)
		(fill yes)
		(layer "F.Cu")
		(net "GND")
	)
	(gr_poly
		(pts
			(xy 337.993482 -108.985304) (xy 337.993482 -103.889048) (xy 338.877402 -103.005128) (xy 338.877402 -102.71379)
			(xy 338.877402 -102.027736) (xy 338.877402 -100.540312) (xy 338.667598 -100.330508) (xy 338.636356 -100.330508)
			(xy 335.032604 -100.330508) (xy 331.806804 -100.330508) (xy 331.673454 -100.463858) (xy 331.673454 -101.185472)
			(xy 331.546962 -101.311964) (xy 330.969112 -101.889814) (xy 330.969112 -106.86796) (xy 330.969112 -107.253786)
			(xy 330.969112 -107.813094) (xy 331.189076 -108.033058) (xy 335.632552 -108.033058) (xy 335.839816 -108.240322)
			(xy 335.839816 -109.056424) (xy 335.993486 -109.210094) (xy 336.181446 -109.210094) (xy 337.768692 -109.210094)
		)
		(stroke
			(width 0)
			(type solid)
		)
		(fill yes)
		(layer "F.Cu")
		(net "GND")
	)
	(gr_poly
		(pts
			(xy 454.09358 -108.985304) (xy 454.09358 -103.889048) (xy 454.9775 -103.005128) (xy 454.9775 -102.71379)
			(xy 454.9775 -102.027736) (xy 454.9775 -100.540312) (xy 454.767696 -100.330508) (xy 454.736454 -100.330508)
			(xy 451.132702 -100.330508) (xy 447.906902 -100.330508) (xy 447.773552 -100.463858) (xy 447.773552 -101.185472)
			(xy 447.64706 -101.311964) (xy 447.06921 -101.889814) (xy 447.06921 -106.86796) (xy 447.06921 -107.253786)
			(xy 447.06921 -107.813094) (xy 447.289174 -108.033058) (xy 451.73265 -108.033058) (xy 451.939914 -108.240322)
			(xy 451.939914 -109.056424) (xy 452.093584 -109.210094) (xy 452.281544 -109.210094) (xy 453.86879 -109.210094)
		)
		(stroke
			(width 0)
			(type solid)
		)
		(fill yes)
		(layer "F.Cu")
		(net "GND")
	)
	(gr_poly
		(pts
			(xy 454.992994 -308.282848) (xy 454.992994 -304.968148) (xy 455.278744 -304.682398) (xy 455.280014 -304.682398)
			(xy 455.619104 -304.343308) (xy 455.644504 -304.317908) (xy 457.1492 -304.317908) (xy 457.60005 -304.317908)
			(xy 457.87818 -304.596038) (xy 457.87818 -305.488086) (xy 457.91501 -305.524916) (xy 458.361542 -305.524916)
			(xy 459.011528 -304.87493) (xy 459.011528 -300.851062) (xy 458.887068 -300.726602) (xy 458.632814 -300.726602)
			(xy 453.71258 -300.726602) (xy 452.802752 -300.726602) (xy 452.720964 -300.80839) (xy 452.720964 -304.61839)
			(xy 453.538082 -305.435508) (xy 454.690734 -306.58816) (xy 454.690734 -308.310788) (xy 454.759314 -308.379368)
			(xy 454.896474 -308.379368)
		)
		(stroke
			(width 0)
			(type solid)
		)
		(fill yes)
		(layer "F.Cu")
		(net "SW_P1V25_PEX3_PH")
	)
	(gr_poly
		(pts
			(xy 5.755386 -57.27319) (xy 5.755386 -56.76519) (xy 5.829046 -56.69153) (xy 8.375396 -56.69153) (xy 8.998458 -56.69153)
			(xy 9.977374 -57.670446) (xy 12.401296 -57.670446) (xy 12.596368 -57.475374) (xy 12.596368 -54.400958)
			(xy 12.384786 -54.189376) (xy 9.847326 -54.189376) (xy 9.312402 -54.7243) (xy 8.434324 -54.7243)
			(xy 8.38835 -54.678072) (xy 5.600192 -54.678072) (xy 5.18795 -54.678072) (xy 4.962144 -54.452266)
			(xy 4.962144 -54.040024) (xy 4.76631 -53.84419) (xy 4.661662 -53.84419) (xy 4.464304 -53.84419) (xy 2.527046 -53.84419)
			(xy 2.359406 -54.01183) (xy 2.359406 -57.548526) (xy 2.53111 -57.72023) (xy 5.308346 -57.72023)
		)
		(stroke
			(width 0)
			(type solid)
		)
		(fill yes)
		(layer "F.Cu")
		(net "P3V3_AUX")
	)
	(gr_poly
		(pts
			(arc
				(start 13.132562 -309.424324)
				(mid 12.875514 -309.424324)
				(end 13.132562 -309.424324)
			)
		)
		(stroke
			(width 0)
			(type solid)
		)
		(fill yes)
		(layer "F.Cu")
		(net "GND")
	)
	(gr_poly
		(pts
			(xy 31.755334 -57.27319) (xy 31.755334 -56.76519) (xy 31.828994 -56.69153) (xy 34.375344 -56.69153)
			(xy 34.382964 -56.69915) (xy 35.023806 -56.69915) (xy 35.693604 -57.368948) (xy 37.964872 -57.368948)
			(xy 38.05174 -57.28208) (xy 38.05174 -54.134004) (xy 37.870892 -53.953156) (xy 35.986974 -53.953156)
			(xy 35.262058 -54.678072) (xy 34.388298 -54.678072) (xy 31.60014 -54.678072) (xy 31.202884 -54.678072)
			(xy 31.0896 -54.564788) (xy 31.0896 -54.167532) (xy 30.766258 -53.84419) (xy 30.66161 -53.84419)
			(xy 30.464252 -53.84419) (xy 28.526994 -53.84419) (xy 28.359354 -54.01183) (xy 28.359354 -57.548526)
			(xy 28.531058 -57.72023) (xy 31.308294 -57.72023)
		)
		(stroke
			(width 0)
			(type solid)
		)
		(fill yes)
		(layer "F.Cu")
		(net "P3V3_AUX")
	)
	(gr_poly
		(pts
			(xy 57.755282 -57.27319) (xy 57.755282 -56.76519) (xy 57.828942 -56.69153) (xy 60.375292 -56.69153)
			(xy 60.382912 -56.69915) (xy 61.023754 -56.69915) (xy 61.693552 -57.368948) (xy 63.96482 -57.368948)
			(xy 64.051688 -57.28208) (xy 64.051688 -54.134004) (xy 63.87084 -53.953156) (xy 61.986922 -53.953156)
			(xy 61.262006 -54.678072) (xy 60.388246 -54.678072) (xy 57.600088 -54.678072) (xy 57.202832 -54.678072)
			(xy 57.089548 -54.564788) (xy 57.089548 -54.167532) (xy 56.766206 -53.84419) (xy 56.661558 -53.84419)
			(xy 56.4642 -53.84419) (xy 54.526942 -53.84419) (xy 54.359302 -54.01183) (xy 54.359302 -57.548526)
			(xy 54.531006 -57.72023) (xy 57.308242 -57.72023)
		)
		(stroke
			(width 0)
			(type solid)
		)
		(fill yes)
		(layer "F.Cu")
		(net "P3V3_AUX")
	)
	(gr_poly
		(pts
			(xy 75.528424 -112.420908) (xy 84.594446 -112.420908) (xy 86.124288 -110.891066) (xy 89.850214 -110.891066)
			(xy 90.259154 -110.482126) (xy 90.259154 -109.922056) (xy 90.259154 -108.717334)
			(arc
				(start 90.259154 -104.585516)
				(mid 90.255321 -104.566159)
				(end 90.244422 -104.549702)
			)
			(arc
				(start 90.079322 -104.384602)
				(mid 90.062876 -104.373676)
				(end 90.043508 -104.36987)
			)
			(xy 89.3953 -104.36987) (xy 87.63508 -104.36987) (xy 85.179662 -104.36987) (xy 81.900776 -107.648756)
			(xy 77.132434 -107.648756) (xy 75.737974 -109.043216) (xy 72.659748 -109.043216) (xy 72.625712 -109.077252)
			(xy 72.625712 -112.386872) (xy 72.667114 -112.428274) (xy 75.521058 -112.428274)
		)
		(stroke
			(width 0)
			(type solid)
		)
		(fill yes)
		(layer "F.Cu")
		(net "P12V_NIC1")
	)
	(gr_poly
		(pts
			(xy 83.75523 -57.27319) (xy 83.75523 -56.76519) (xy 83.82889 -56.69153) (xy 86.37524 -56.69153) (xy 86.38286 -56.69915)
			(xy 87.023702 -56.69915) (xy 87.6935 -57.368948) (xy 89.964768 -57.368948) (xy 90.051636 -57.28208)
			(xy 90.051636 -54.134004) (xy 89.870788 -53.953156) (xy 87.98687 -53.953156) (xy 87.261954 -54.678072)
			(xy 86.388194 -54.678072) (xy 83.600036 -54.678072) (xy 83.20278 -54.678072) (xy 83.089496 -54.564788)
			(xy 83.089496 -54.167532) (xy 82.766154 -53.84419) (xy 82.661506 -53.84419) (xy 82.464148 -53.84419)
			(xy 80.52689 -53.84419) (xy 80.35925 -54.01183) (xy 80.35925 -57.548526) (xy 80.530954 -57.72023)
			(xy 83.30819 -57.72023)
		)
		(stroke
			(width 0)
			(type solid)
		)
		(fill yes)
		(layer "F.Cu")
		(net "P3V3_AUX")
	)
	(gr_poly
		(pts
			(xy 94.053914 -120.394222) (xy 94.031054 -120.371362) (xy 92.55887 -120.371362) (xy 92.128594 -119.941086)
			(xy 92.128594 -116.08435) (xy 92.040202 -115.995958) (xy 91.255342 -115.995958) (xy 91.214702 -116.036598)
			(xy 91.214702 -116.541804) (xy 91.194128 -116.541804) (xy 90.423746 -117.312186) (xy 87.639144 -117.312186)
			(xy 84.803742 -114.476784) (xy 74.405744 -114.476784) (xy 73.827894 -115.054634) (xy 72.671432 -115.054634)
			(xy 72.644508 -115.081558) (xy 72.644508 -115.38966) (xy 72.668638 -115.41379) (xy 74.093578 -115.41379)
			(xy 74.570844 -115.891056) (xy 75.103228 -115.891056) (xy 76.88707 -117.674898) (xy 82.93354 -117.674898)
			(xy 87.913464 -122.654822) (xy 94.053914 -122.654822)
		)
		(stroke
			(width 0)
			(type solid)
		)
		(fill yes)
		(layer "F.Cu")
		(net "P3V3_NIC1")
	)
	(gr_poly
		(pts
			(xy 108.155486 -230.54818) (xy 108.155486 -230.248714) (xy 108.155486 -226.738434) (xy 106.227626 -224.810574)
			(xy 106.227626 -223.087946) (xy 106.159046 -223.019366) (xy 106.021886 -223.019366) (xy 105.925366 -223.115886)
			(xy 105.925366 -226.430586) (xy 105.639616 -226.716336) (xy 105.638346 -226.716336) (xy 105.299256 -227.055426)
			(xy 105.273856 -227.080826) (xy 103.049832 -227.080826) (xy 103.016812 -227.047806) (xy 103.016812 -227.047552)
			(xy 102.547166 -226.577906) (xy 102.547166 -225.747326) (xy 102.544626 -225.74504) (xy 102.518718 -225.719132)
			(xy 101.65969 -225.719132) (xy 101.55809 -225.820732) (xy 101.55809 -230.142288) (xy 101.55809 -230.548688)
			(xy 101.681534 -230.672132) (xy 108.031534 -230.672132)
		)
		(stroke
			(width 0)
			(type solid)
		)
		(fill yes)
		(layer "F.Cu")
		(net "SW_P1V8_PEX_PH")
	)
	(gr_poly
		(pts
			(xy 121.855484 -57.27319) (xy 121.855484 -56.76519) (xy 121.929144 -56.69153) (xy 124.475494 -56.69153)
			(xy 124.483114 -56.69915) (xy 125.123956 -56.69915) (xy 125.793754 -57.368948) (xy 128.065022 -57.368948)
			(xy 128.15189 -57.28208) (xy 128.15189 -54.134004) (xy 127.971042 -53.953156) (xy 126.087124 -53.953156)
			(xy 125.362208 -54.678072) (xy 124.488448 -54.678072) (xy 121.70029 -54.678072) (xy 121.303034 -54.678072)
			(xy 121.18975 -54.564788) (xy 121.18975 -54.167532) (xy 120.866408 -53.84419) (xy 120.76176 -53.84419)
			(xy 120.564402 -53.84419) (xy 118.627144 -53.84419) (xy 118.459504 -54.01183) (xy 118.459504 -57.548526)
			(xy 118.631208 -57.72023) (xy 121.408444 -57.72023)
		)
		(stroke
			(width 0)
			(type solid)
		)
		(fill yes)
		(layer "F.Cu")
		(net "P3V3_AUX")
	)
	(gr_poly
		(pts
			(xy 147.855432 -57.27319) (xy 147.855432 -56.76519) (xy 147.929092 -56.69153) (xy 150.475442 -56.69153)
			(xy 150.483062 -56.69915) (xy 151.123904 -56.69915) (xy 151.793702 -57.368948) (xy 154.06497 -57.368948)
			(xy 154.151838 -57.28208) (xy 154.151838 -54.134004) (xy 153.97099 -53.953156) (xy 152.087072 -53.953156)
			(xy 151.362156 -54.678072) (xy 150.488396 -54.678072) (xy 147.700238 -54.678072) (xy 147.302982 -54.678072)
			(xy 147.189698 -54.564788) (xy 147.189698 -54.167532) (xy 146.866356 -53.84419) (xy 146.761708 -53.84419)
			(xy 146.56435 -53.84419) (xy 144.627092 -53.84419) (xy 144.459452 -54.01183) (xy 144.459452 -57.548526)
			(xy 144.631156 -57.72023) (xy 147.408392 -57.72023)
		)
		(stroke
			(width 0)
			(type solid)
		)
		(fill yes)
		(layer "F.Cu")
		(net "P3V3_AUX")
	)
	(gr_poly
		(pts
			(xy 173.85538 -57.27319) (xy 173.85538 -56.76519) (xy 173.92904 -56.69153) (xy 176.47539 -56.69153)
			(xy 176.48301 -56.69915) (xy 177.123852 -56.69915) (xy 177.79365 -57.368948) (xy 180.064918 -57.368948)
			(xy 180.151786 -57.28208) (xy 180.151786 -54.134004) (xy 179.970938 -53.953156) (xy 178.08702 -53.953156)
			(xy 177.362104 -54.678072) (xy 176.488344 -54.678072) (xy 173.700186 -54.678072) (xy 173.30293 -54.678072)
			(xy 173.189646 -54.564788) (xy 173.189646 -54.167532) (xy 172.866304 -53.84419) (xy 172.761656 -53.84419)
			(xy 172.564298 -53.84419) (xy 170.62704 -53.84419) (xy 170.4594 -54.01183) (xy 170.4594 -57.548526)
			(xy 170.631104 -57.72023) (xy 173.40834 -57.72023)
		)
		(stroke
			(width 0)
			(type solid)
		)
		(fill yes)
		(layer "F.Cu")
		(net "P3V3_AUX")
	)
	(gr_poly
		(pts
			(xy 199.855328 -57.27319) (xy 199.855328 -56.76519) (xy 199.928988 -56.69153) (xy 202.475338 -56.69153)
			(xy 202.482958 -56.69915) (xy 203.1238 -56.69915) (xy 203.793598 -57.368948) (xy 206.064866 -57.368948)
			(xy 206.151734 -57.28208) (xy 206.151734 -54.134004) (xy 205.970886 -53.953156) (xy 204.086968 -53.953156)
			(xy 203.362052 -54.678072) (xy 202.488292 -54.678072) (xy 199.700134 -54.678072) (xy 199.302878 -54.678072)
			(xy 199.189594 -54.564788) (xy 199.189594 -54.167532) (xy 198.866252 -53.84419) (xy 198.761604 -53.84419)
			(xy 198.564246 -53.84419) (xy 196.626988 -53.84419) (xy 196.459348 -54.01183) (xy 196.459348 -57.548526)
			(xy 196.631052 -57.72023) (xy 199.408288 -57.72023)
		)
		(stroke
			(width 0)
			(type solid)
		)
		(fill yes)
		(layer "F.Cu")
		(net "P3V3_AUX")
	)
	(gr_poly
		(pts
			(xy 224.371916 -308.159404) (xy 224.371916 -304.844704) (xy 224.657666 -304.558954) (xy 224.658936 -304.558954)
			(xy 224.998026 -304.219864) (xy 225.023426 -304.194464) (xy 226.528122 -304.194464) (xy 227.05949 -304.194464)
			(xy 227.174552 -304.194464) (xy 227.230686 -304.250598) (xy 227.257102 -304.277014) (xy 227.257102 -305.364642)
			(xy 227.293932 -305.401472) (xy 227.824284 -305.401472) (xy 228.219508 -305.006248) (xy 228.219508 -300.818296)
			(xy 228.00437 -300.603158) (xy 223.091502 -300.603158) (xy 222.181674 -300.603158) (xy 222.099886 -300.684946)
			(xy 222.099886 -304.494946) (xy 222.917004 -305.312064) (xy 224.069656 -306.464716) (xy 224.069656 -308.187344)
			(xy 224.138236 -308.255924) (xy 224.275396 -308.255924)
		)
		(stroke
			(width 0)
			(type solid)
		)
		(fill yes)
		(layer "F.Cu")
		(net "SW_P1V25_PEX1_PH")
	)
	(gr_poly
		(pts
			(arc
				(start 227.429822 -311.711086)
				(mid 227.172774 -311.711086)
				(end 227.429822 -311.711086)
			)
		)
		(stroke
			(width 0)
			(type solid)
		)
		(fill yes)
		(layer "F.Cu")
		(net "GND")
	)
	(gr_poly
		(pts
			(arc
				(start 242.946174 -218.535504)
				(mid 242.685062 -218.535504)
				(end 242.946174 -218.535504)
			)
		)
		(stroke
			(width 0)
			(type solid)
		)
		(fill yes)
		(layer "F.Cu")
		(net "GND")
	)
	(gr_poly
		(pts
			(arc
				(start 243.67998 -311.711086)
				(mid 243.422932 -311.711086)
				(end 243.67998 -311.711086)
			)
		)
		(stroke
			(width 0)
			(type solid)
		)
		(fill yes)
		(layer "F.Cu")
		(net "GND")
	)
	(gr_poly
		(pts
			(arc
				(start 251.17806 -330.849732)
				(mid 250.923552 -330.849732)
				(end 251.17806 -330.849732)
			)
		)
		(stroke
			(width 0)
			(type solid)
		)
		(fill yes)
		(layer "F.Cu")
		(net "GND")
	)
	(gr_poly
		(pts
			(arc
				(start 255.091184 -215.25738)
				(mid 255.110707 -215.253479)
				(end 255.127252 -215.242394)
			)
			(arc
				(start 255.150874 -215.218772)
				(mid 255.161936 -215.202355)
				(end 255.16586 -215.182958)
			)
			(xy 255.16586 -213.196424) (xy 255.171448 -213.190836) (xy 255.171448 -212.5726) (xy 255.171448 -211.883498)
			(xy 254.932434 -211.644484) (xy 253.747778 -211.644484) (xy 253.477522 -211.91474) (xy 253.477522 -212.5726)
			(xy 253.477522 -213.509098)
			(arc
				(start 253.489968 -213.521544)
				(mid 253.500894 -213.53799)
				(end 253.5047 -213.557358)
			)
			(xy 253.5047 -215.237568)
			(arc
				(start 253.50978 -215.242394)
				(mid 253.526314 -215.253505)
				(end 253.545848 -215.25738)
			)
		)
		(stroke
			(width 0)
			(type solid)
		)
		(fill yes)
		(layer "F.Cu")
		(net "GND")
	)
	(gr_poly
		(pts
			(xy 263.955276 -57.27319) (xy 263.955276 -56.76519) (xy 264.028936 -56.69153) (xy 266.575286 -56.69153)
			(xy 266.582906 -56.69915) (xy 267.223748 -56.69915) (xy 267.893546 -57.368948) (xy 270.164814 -57.368948)
			(xy 270.251682 -57.28208) (xy 270.251682 -54.134004) (xy 270.070834 -53.953156) (xy 268.186916 -53.953156)
			(xy 267.462 -54.678072) (xy 266.58824 -54.678072) (xy 263.800082 -54.678072) (xy 263.402826 -54.678072)
			(xy 263.289542 -54.564788) (xy 263.289542 -54.167532) (xy 262.9662 -53.84419) (xy 262.861552 -53.84419)
			(xy 262.664194 -53.84419) (xy 260.726936 -53.84419) (xy 260.559296 -54.01183) (xy 260.559296 -57.548526)
			(xy 260.731 -57.72023) (xy 263.508236 -57.72023)
		)
		(stroke
			(width 0)
			(type solid)
		)
		(fill yes)
		(layer "F.Cu")
		(net "P3V3_AUX")
	)
	(gr_poly
		(pts
			(xy 289.955224 -57.27319) (xy 289.955224 -56.76519) (xy 290.028884 -56.69153) (xy 292.575234 -56.69153)
			(xy 292.582854 -56.69915) (xy 293.223696 -56.69915) (xy 293.893494 -57.368948) (xy 296.164762 -57.368948)
			(xy 296.25163 -57.28208) (xy 296.25163 -54.134004) (xy 296.070782 -53.953156) (xy 294.186864 -53.953156)
			(xy 293.461948 -54.678072) (xy 292.588188 -54.678072) (xy 289.80003 -54.678072) (xy 289.402774 -54.678072)
			(xy 289.28949 -54.564788) (xy 289.28949 -54.167532) (xy 288.966148 -53.84419) (xy 288.8615 -53.84419)
			(xy 288.664142 -53.84419) (xy 286.726884 -53.84419) (xy 286.559244 -54.01183) (xy 286.559244 -57.548526)
			(xy 286.730948 -57.72023) (xy 289.508184 -57.72023)
		)
		(stroke
			(width 0)
			(type solid)
		)
		(fill yes)
		(layer "F.Cu")
		(net "P3V3_AUX")
	)
	(gr_poly
		(pts
			(xy 307.728366 -112.420908) (xy 316.794388 -112.420908) (xy 318.32423 -110.891066) (xy 322.050156 -110.891066)
			(xy 322.459096 -110.482126) (xy 322.459096 -109.922056) (xy 322.459096 -108.717334)
			(arc
				(start 322.459096 -104.585516)
				(mid 322.455263 -104.566159)
				(end 322.444364 -104.549702)
			)
			(arc
				(start 322.279264 -104.384602)
				(mid 322.262818 -104.373676)
				(end 322.24345 -104.36987)
			)
			(xy 321.595242 -104.36987) (xy 319.835022 -104.36987) (xy 317.379604 -104.36987) (xy 314.280804 -107.468416)
			(xy 309.547006 -107.468416) (xy 307.972206 -109.043216) (xy 304.85969 -109.043216) (xy 304.825654 -109.077252)
			(xy 304.825654 -112.386872) (xy 304.867056 -112.428274) (xy 307.721 -112.428274)
		)
		(stroke
			(width 0)
			(type solid)
		)
		(fill yes)
		(layer "F.Cu")
		(net "P12V_NIC5")
	)
	(gr_poly
		(pts
			(xy 315.955172 -57.27319) (xy 315.955172 -56.76519) (xy 316.028832 -56.69153) (xy 318.575182 -56.69153)
			(xy 318.582802 -56.69915) (xy 319.223644 -56.69915) (xy 319.893442 -57.368948) (xy 322.16471 -57.368948)
			(xy 322.251578 -57.28208) (xy 322.251578 -54.134004) (xy 322.07073 -53.953156) (xy 320.186812 -53.953156)
			(xy 319.461896 -54.678072) (xy 318.588136 -54.678072) (xy 315.799978 -54.678072) (xy 315.402722 -54.678072)
			(xy 315.289438 -54.564788) (xy 315.289438 -54.167532) (xy 314.966096 -53.84419) (xy 314.861448 -53.84419)
			(xy 314.66409 -53.84419) (xy 312.726832 -53.84419) (xy 312.559192 -54.01183) (xy 312.559192 -57.548526)
			(xy 312.730896 -57.72023) (xy 315.508132 -57.72023)
		)
		(stroke
			(width 0)
			(type solid)
		)
		(fill yes)
		(layer "F.Cu")
		(net "P3V3_AUX")
	)
	(gr_poly
		(pts
			(xy 326.253856 -120.394222) (xy 326.230996 -120.371362) (xy 324.758812 -120.371362) (xy 324.328536 -119.941086)
			(xy 324.328536 -116.08435) (xy 324.240144 -115.995958) (xy 323.455284 -115.995958) (xy 323.414644 -116.036598)
			(xy 323.414644 -116.541804) (xy 323.39407 -116.541804) (xy 322.623688 -117.312186) (xy 319.839086 -117.312186)
			(xy 317.003684 -114.476784) (xy 306.605686 -114.476784) (xy 306.027836 -115.054634) (xy 304.871374 -115.054634)
			(xy 304.84445 -115.081558) (xy 304.84445 -115.38966) (xy 304.86858 -115.41379) (xy 306.29352 -115.41379)
			(xy 306.770786 -115.891056) (xy 307.30317 -115.891056) (xy 309.087012 -117.674898) (xy 315.133482 -117.674898)
			(xy 320.113406 -122.654822) (xy 326.253856 -122.654822)
		)
		(stroke
			(width 0)
			(type solid)
		)
		(fill yes)
		(layer "F.Cu")
		(net "P3V3_NIC5")
	)
	(gr_poly
		(pts
			(xy 354.055426 -57.27319) (xy 354.055426 -56.76519) (xy 354.129086 -56.69153) (xy 356.675436 -56.69153)
			(xy 356.683056 -56.69915) (xy 357.323898 -56.69915) (xy 357.993696 -57.368948) (xy 360.264964 -57.368948)
			(xy 360.351832 -57.28208) (xy 360.351832 -54.134004) (xy 360.170984 -53.953156) (xy 358.287066 -53.953156)
			(xy 357.56215 -54.678072) (xy 356.68839 -54.678072) (xy 353.900232 -54.678072) (xy 353.502976 -54.678072)
			(xy 353.389692 -54.564788) (xy 353.389692 -54.167532) (xy 353.06635 -53.84419) (xy 352.961702 -53.84419)
			(xy 352.764344 -53.84419) (xy 350.827086 -53.84419) (xy 350.659446 -54.01183) (xy 350.659446 -57.548526)
			(xy 350.83115 -57.72023) (xy 353.608386 -57.72023)
		)
		(stroke
			(width 0)
			(type solid)
		)
		(fill yes)
		(layer "F.Cu")
		(net "P3V3_AUX")
	)
	(gr_poly
		(pts
			(xy 380.055374 -57.27319) (xy 380.055374 -56.76519) (xy 380.129034 -56.69153) (xy 382.675384 -56.69153)
			(xy 382.683004 -56.69915) (xy 383.323846 -56.69915) (xy 383.993644 -57.368948) (xy 386.264912 -57.368948)
			(xy 386.35178 -57.28208) (xy 386.35178 -54.134004) (xy 386.170932 -53.953156) (xy 384.287014 -53.953156)
			(xy 383.562098 -54.678072) (xy 382.688338 -54.678072) (xy 379.90018 -54.678072) (xy 379.502924 -54.678072)
			(xy 379.38964 -54.564788) (xy 379.38964 -54.167532) (xy 379.066298 -53.84419) (xy 378.96165 -53.84419)
			(xy 378.764292 -53.84419) (xy 376.827034 -53.84419) (xy 376.659394 -54.01183) (xy 376.659394 -57.548526)
			(xy 376.831098 -57.72023) (xy 379.608334 -57.72023)
		)
		(stroke
			(width 0)
			(type solid)
		)
		(fill yes)
		(layer "F.Cu")
		(net "P3V3_AUX")
	)
	(gr_poly
		(pts
			(arc
				(start 385.483862 -230.725218)
				(mid 385.229862 -230.725218)
				(end 385.483862 -230.725218)
			)
		)
		(stroke
			(width 0)
			(type solid)
		)
		(fill yes)
		(layer "F.Cu")
		(net "GND")
	)
	(gr_poly
		(pts
			(xy 406.055322 -57.27319) (xy 406.055322 -56.76519) (xy 406.128982 -56.69153) (xy 408.675332 -56.69153)
			(xy 408.682952 -56.69915) (xy 409.323794 -56.69915) (xy 409.993592 -57.368948) (xy 412.26486 -57.368948)
			(xy 412.351728 -57.28208) (xy 412.351728 -54.134004) (xy 412.17088 -53.953156) (xy 410.286962 -53.953156)
			(xy 409.562046 -54.678072) (xy 408.688286 -54.678072) (xy 405.900128 -54.678072) (xy 405.502872 -54.678072)
			(xy 405.389588 -54.564788) (xy 405.389588 -54.167532) (xy 405.066246 -53.84419) (xy 404.961598 -53.84419)
			(xy 404.76424 -53.84419) (xy 402.826982 -53.84419) (xy 402.659342 -54.01183) (xy 402.659342 -57.548526)
			(xy 402.831046 -57.72023) (xy 405.608282 -57.72023)
		)
		(stroke
			(width 0)
			(type solid)
		)
		(fill yes)
		(layer "F.Cu")
		(net "P3V3_AUX")
	)
	(gr_poly
		(pts
			(xy 423.828464 -112.420908) (xy 432.894486 -112.420908) (xy 434.424328 -110.891066) (xy 438.150254 -110.891066)
			(xy 438.559194 -110.482126) (xy 438.559194 -109.922056) (xy 438.559194 -108.717334)
			(arc
				(start 438.559194 -104.585516)
				(mid 438.555361 -104.566159)
				(end 438.544462 -104.549702)
			)
			(arc
				(start 438.379362 -104.384602)
				(mid 438.362916 -104.373676)
				(end 438.343548 -104.36987)
			)
			(xy 437.69534 -104.36987) (xy 435.93512 -104.36987) (xy 433.479702 -104.36987) (xy 430.173384 -107.676188)
			(xy 425.670472 -107.676188) (xy 424.303444 -109.043216) (xy 420.959788 -109.043216) (xy 420.925752 -109.077252)
			(xy 420.925752 -112.386872) (xy 420.967154 -112.428274) (xy 423.821098 -112.428274)
		)
		(stroke
			(width 0)
			(type solid)
		)
		(fill yes)
		(layer "F.Cu")
		(net "P12V_NIC7")
	)
	(gr_poly
		(pts
			(xy 432.05527 -57.27319) (xy 432.05527 -56.76519) (xy 432.12893 -56.69153) (xy 434.67528 -56.69153)
			(xy 434.6829 -56.69915) (xy 435.323742 -56.69915) (xy 435.99354 -57.368948) (xy 438.264808 -57.368948)
			(xy 438.351676 -57.28208) (xy 438.351676 -54.134004) (xy 438.170828 -53.953156) (xy 436.28691 -53.953156)
			(xy 435.561994 -54.678072) (xy 434.688234 -54.678072) (xy 431.900076 -54.678072) (xy 431.50282 -54.678072)
			(xy 431.389536 -54.564788) (xy 431.389536 -54.167532) (xy 431.066194 -53.84419) (xy 430.961546 -53.84419)
			(xy 430.764188 -53.84419) (xy 428.82693 -53.84419) (xy 428.65929 -54.01183) (xy 428.65929 -57.548526)
			(xy 428.830994 -57.72023) (xy 431.60823 -57.72023)
		)
		(stroke
			(width 0)
			(type solid)
		)
		(fill yes)
		(layer "F.Cu")
		(net "P3V3_AUX")
	)
	(gr_poly
		(pts
			(xy 442.353954 -120.394222) (xy 442.331094 -120.371362) (xy 440.85891 -120.371362) (xy 440.428634 -119.941086)
			(xy 440.428634 -116.08435) (xy 440.340242 -115.995958) (xy 439.555382 -115.995958) (xy 439.514742 -116.036598)
			(xy 439.514742 -116.541804) (xy 439.494168 -116.541804) (xy 438.723786 -117.312186) (xy 435.939184 -117.312186)
			(xy 433.103782 -114.476784) (xy 422.705784 -114.476784) (xy 422.127934 -115.054634) (xy 420.971472 -115.054634)
			(xy 420.944548 -115.081558) (xy 420.944548 -115.38966) (xy 420.968678 -115.41379) (xy 422.393618 -115.41379)
			(xy 422.870884 -115.891056) (xy 423.403268 -115.891056) (xy 425.18711 -117.674898) (xy 431.23358 -117.674898)
			(xy 436.213504 -122.654822) (xy 442.353954 -122.654822)
		)
		(stroke
			(width 0)
			(type solid)
		)
		(fill yes)
		(layer "F.Cu")
		(net "P3V3_NIC7")
	)
	(gr_poly
		(pts
			(arc
				(start 458.0509 -311.83453)
				(mid 457.793852 -311.83453)
				(end 458.0509 -311.83453)
			)
		)
		(stroke
			(width 0)
			(type solid)
		)
		(fill yes)
		(layer "F.Cu")
		(net "GND")
	)
	(gr_poly
		(pts
			(xy 19.537172 -170.723306) (xy 19.537172 -169.380408) (xy 19.537172 -169.296842) (xy 19.79549 -169.038524)
			(xy 19.796506 -169.038524) (xy 19.833336 -169.001694) (xy 20.396962 -169.001694) (xy 20.74164 -169.346372)
			(xy 21.596604 -169.346372) (xy 21.723096 -169.21988) (xy 21.723096 -166.535862) (xy 21.63318 -166.445946)
			(xy 20.668996 -166.445946) (xy 20.605242 -166.5097) (xy 20.605242 -167.555164) (xy 20.605242 -167.618918)
			(xy 20.169632 -168.054528) (xy 19.571462 -168.054528) (xy 19.43227 -168.19372) (xy 19.296888 -168.329102)
			(xy 19.296888 -168.71569) (xy 19.296888 -169.728896) (xy 19.296888 -169.966132) (xy 19.296888 -170.002454)
			(xy 19.296888 -170.723306) (xy 19.358356 -170.784774) (xy 19.475704 -170.784774)
		)
		(stroke
			(width 0)
			(type solid)
		)
		(fill yes)
		(layer "F.Cu")
		(net "SW_P12V_P5V_AUX_FLT")
	)
	(gr_poly
		(pts
			(arc
				(start 108.885736 -279.373838)
				(mid 108.905259 -279.369937)
				(end 108.921804 -279.358852)
			)
			(arc
				(start 108.937298 -279.343358)
				(mid 108.948409 -279.326824)
				(end 108.952284 -279.30729)
			)
			(arc
				(start 108.952284 -278.812244)
				(mid 108.937405 -278.776323)
				(end 108.901484 -278.761444)
			)
			(arc
				(start 104.563926 -278.761444)
				(mid 104.544539 -278.765394)
				(end 104.528112 -278.77643)
			)
			(arc
				(start 104.454452 -278.85009)
				(mid 104.443526 -278.866536)
				(end 104.43972 -278.885904)
			)
			(xy 104.43972 -279.357328)
			(arc
				(start 104.441244 -279.358852)
				(mid 104.457778 -279.369963)
				(end 104.477312 -279.373838)
			)
		)
		(stroke
			(width 0)
			(type solid)
		)
		(fill yes)
		(layer "F.Cu")
		(net "GND")
	)
	(gr_poly
		(pts
			(arc
				(start 125.544834 -279.373838)
				(mid 125.564357 -279.369937)
				(end 125.580902 -279.358852)
			)
			(arc
				(start 125.596396 -279.343358)
				(mid 125.607507 -279.326824)
				(end 125.611382 -279.30729)
			)
			(arc
				(start 125.611382 -278.812244)
				(mid 125.596503 -278.776323)
				(end 125.560582 -278.761444)
			)
			(arc
				(start 121.223024 -278.761444)
				(mid 121.203637 -278.765394)
				(end 121.18721 -278.77643)
			)
			(arc
				(start 121.11355 -278.85009)
				(mid 121.102488 -278.866507)
				(end 121.098564 -278.885904)
			)
			(xy 121.098564 -279.357328)
			(arc
				(start 121.100342 -279.358852)
				(mid 121.116876 -279.369963)
				(end 121.13641 -279.373838)
			)
		)
		(stroke
			(width 0)
			(type solid)
		)
		(fill yes)
		(layer "F.Cu")
		(net "GND")
	)
	(gr_poly
		(pts
			(xy 240.622074 -308.159404) (xy 240.622074 -304.844704) (xy 240.907824 -304.558954) (xy 240.909094 -304.558954)
			(xy 241.248184 -304.219864) (xy 241.273584 -304.194464) (xy 242.77828 -304.194464) (xy 243.309648 -304.194464)
			(xy 243.42471 -304.194464) (xy 243.480844 -304.250598) (xy 243.50726 -304.277014) (xy 243.50726 -305.364642)
			(xy 243.54409 -305.401472) (xy 243.984018 -305.401472) (xy 244.51056 -304.87493) (xy 244.51056 -300.743366)
			(xy 244.370352 -300.603158) (xy 244.261894 -300.603158) (xy 239.34166 -300.603158) (xy 238.431832 -300.603158)
			(xy 238.350044 -300.684946) (xy 238.350044 -304.494946) (xy 239.167162 -305.312064) (xy 240.319814 -306.464716)
			(xy 240.319814 -308.187344) (xy 240.388394 -308.255924) (xy 240.525554 -308.255924)
		)
		(stroke
			(width 0)
			(type solid)
		)
		(fill yes)
		(layer "F.Cu")
		(net "SW_P1V25_PEX2_PH")
	)
	(gr_poly
		(pts
			(arc
				(start 257.61696 7.454392)
				(mid 257.334004 7.454392)
				(end 257.61696 7.454392)
			)
		)
		(stroke
			(width 0)
			(type solid)
		)
		(fill yes)
		(layer "F.Cu")
		(net "COUPON_GND2")
	)
	(gr_poly
		(pts
			(arc
				(start 257.61696 8.713216)
				(mid 257.334004 8.713216)
				(end 257.61696 8.713216)
			)
		)
		(stroke
			(width 0)
			(type solid)
		)
		(fill yes)
		(layer "F.Cu")
		(net "COUPON_GND2")
	)
	(gr_poly
		(pts
			(arc
				(start 257.61696 9.994392)
				(mid 257.334004 9.994392)
				(end 257.61696 9.994392)
			)
		)
		(stroke
			(width 0)
			(type solid)
		)
		(fill yes)
		(layer "F.Cu")
		(net "COUPON_GND2")
	)
	(gr_poly
		(pts
			(arc
				(start 257.61696 11.253216)
				(mid 257.334004 11.253216)
				(end 257.61696 11.253216)
			)
		)
		(stroke
			(width 0)
			(type solid)
		)
		(fill yes)
		(layer "F.Cu")
		(net "COUPON_GND2")
	)
	(gr_poly
		(pts
			(arc
				(start 275.39696 17.406112)
				(mid 275.114004 17.406112)
				(end 275.39696 17.406112)
			)
		)
		(stroke
			(width 0)
			(type solid)
		)
		(fill yes)
		(layer "F.Cu")
		(net "COUPON_GND2")
	)
	(gr_poly
		(pts
			(arc
				(start 275.39696 18.664936)
				(mid 275.114004 18.664936)
				(end 275.39696 18.664936)
			)
		)
		(stroke
			(width 0)
			(type solid)
		)
		(fill yes)
		(layer "F.Cu")
		(net "COUPON_GND2")
	)
	(gr_poly
		(pts
			(arc
				(start 275.39696 19.946112)
				(mid 275.114004 19.946112)
				(end 275.39696 19.946112)
			)
		)
		(stroke
			(width 0)
			(type solid)
		)
		(fill yes)
		(layer "F.Cu")
		(net "COUPON_GND2")
	)
	(gr_poly
		(pts
			(arc
				(start 275.39696 21.204936)
				(mid 275.114004 21.204936)
				(end 275.39696 21.204936)
			)
		)
		(stroke
			(width 0)
			(type solid)
		)
		(fill yes)
		(layer "F.Cu")
		(net "COUPON_GND2")
	)
	(gr_poly
		(pts
			(arc
				(start 310.760364 17.399)
				(mid 310.477408 17.399)
				(end 310.760364 17.399)
			)
		)
		(stroke
			(width 0)
			(type solid)
		)
		(fill yes)
		(layer "F.Cu")
		(net "COUPON_GND2")
	)
	(gr_poly
		(pts
			(arc
				(start 310.760364 18.657824)
				(mid 310.477408 18.657824)
				(end 310.760364 18.657824)
			)
		)
		(stroke
			(width 0)
			(type solid)
		)
		(fill yes)
		(layer "F.Cu")
		(net "COUPON_GND2")
	)
	(gr_poly
		(pts
			(arc
				(start 310.760364 19.939)
				(mid 310.477408 19.939)
				(end 310.760364 19.939)
			)
		)
		(stroke
			(width 0)
			(type solid)
		)
		(fill yes)
		(layer "F.Cu")
		(net "COUPON_GND2")
	)
	(gr_poly
		(pts
			(arc
				(start 310.760364 21.197824)
				(mid 310.477408 21.197824)
				(end 310.760364 21.197824)
			)
		)
		(stroke
			(width 0)
			(type solid)
		)
		(fill yes)
		(layer "F.Cu")
		(net "COUPON_GND2")
	)
	(gr_poly
		(pts
			(arc
				(start 312.120788 7.4803)
				(mid 311.837832 7.4803)
				(end 312.120788 7.4803)
			)
		)
		(stroke
			(width 0)
			(type solid)
		)
		(fill yes)
		(layer "F.Cu")
		(net "COUPON_GND2")
	)
	(gr_poly
		(pts
			(arc
				(start 312.120788 8.739124)
				(mid 311.837832 8.739124)
				(end 312.120788 8.739124)
			)
		)
		(stroke
			(width 0)
			(type solid)
		)
		(fill yes)
		(layer "F.Cu")
		(net "COUPON_GND2")
	)
	(gr_poly
		(pts
			(arc
				(start 312.120788 10.0203)
				(mid 311.837832 10.0203)
				(end 312.120788 10.0203)
			)
		)
		(stroke
			(width 0)
			(type solid)
		)
		(fill yes)
		(layer "F.Cu")
		(net "COUPON_GND2")
	)
	(gr_poly
		(pts
			(arc
				(start 312.120788 11.279124)
				(mid 311.837832 11.279124)
				(end 312.120788 11.279124)
			)
		)
		(stroke
			(width 0)
			(type solid)
		)
		(fill yes)
		(layer "F.Cu")
		(net "COUPON_GND2")
	)
	(gr_poly
		(pts
			(arc
				(start 330.38796 7.487412)
				(mid 330.105004 7.487412)
				(end 330.38796 7.487412)
			)
		)
		(stroke
			(width 0)
			(type solid)
		)
		(fill yes)
		(layer "F.Cu")
		(net "COUPON_GND2")
	)
	(gr_poly
		(pts
			(arc
				(start 330.38796 8.746236)
				(mid 330.105004 8.746236)
				(end 330.38796 8.746236)
			)
		)
		(stroke
			(width 0)
			(type solid)
		)
		(fill yes)
		(layer "F.Cu")
		(net "COUPON_GND2")
	)
	(gr_poly
		(pts
			(arc
				(start 330.38796 10.027412)
				(mid 330.105004 10.027412)
				(end 330.38796 10.027412)
			)
		)
		(stroke
			(width 0)
			(type solid)
		)
		(fill yes)
		(layer "F.Cu")
		(net "COUPON_GND2")
	)
	(gr_poly
		(pts
			(arc
				(start 330.38796 11.286236)
				(mid 330.105004 11.286236)
				(end 330.38796 11.286236)
			)
		)
		(stroke
			(width 0)
			(type solid)
		)
		(fill yes)
		(layer "F.Cu")
		(net "COUPON_GND2")
	)
	(gr_poly
		(pts
			(arc
				(start 340.54796 17.406112)
				(mid 340.265004 17.406112)
				(end 340.54796 17.406112)
			)
		)
		(stroke
			(width 0)
			(type solid)
		)
		(fill yes)
		(layer "F.Cu")
		(net "COUPON_GND2")
	)
	(gr_poly
		(pts
			(arc
				(start 340.54796 18.664936)
				(mid 340.265004 18.664936)
				(end 340.54796 18.664936)
			)
		)
		(stroke
			(width 0)
			(type solid)
		)
		(fill yes)
		(layer "F.Cu")
		(net "COUPON_GND2")
	)
	(gr_poly
		(pts
			(arc
				(start 340.54796 19.946112)
				(mid 340.265004 19.946112)
				(end 340.54796 19.946112)
			)
		)
		(stroke
			(width 0)
			(type solid)
		)
		(fill yes)
		(layer "F.Cu")
		(net "COUPON_GND2")
	)
	(gr_poly
		(pts
			(arc
				(start 340.54796 21.204936)
				(mid 340.265004 21.204936)
				(end 340.54796 21.204936)
			)
		)
		(stroke
			(width 0)
			(type solid)
		)
		(fill yes)
		(layer "F.Cu")
		(net "COUPON_GND2")
	)
	(gr_poly
		(pts
			(arc
				(start 341.085932 -279.373838)
				(mid 341.105455 -279.369937)
				(end 341.122 -279.358852)
			)
			(arc
				(start 341.137494 -279.343358)
				(mid 341.148605 -279.326824)
				(end 341.15248 -279.30729)
			)
			(arc
				(start 341.15248 -278.812244)
				(mid 341.137601 -278.776323)
				(end 341.10168 -278.761444)
			)
			(arc
				(start 336.764122 -278.761444)
				(mid 336.744735 -278.765394)
				(end 336.728308 -278.77643)
			)
			(arc
				(start 336.654648 -278.85009)
				(mid 336.643722 -278.866536)
				(end 336.639916 -278.885904)
			)
			(xy 336.639916 -279.357328)
			(arc
				(start 336.64144 -279.358852)
				(mid 336.657974 -279.369963)
				(end 336.677508 -279.373838)
			)
		)
		(stroke
			(width 0)
			(type solid)
		)
		(fill yes)
		(layer "F.Cu")
		(net "GND")
	)
	(gr_poly
		(pts
			(arc
				(start 357.74503 -279.373838)
				(mid 357.764553 -279.369937)
				(end 357.781098 -279.358852)
			)
			(arc
				(start 357.796592 -279.343358)
				(mid 357.807703 -279.326824)
				(end 357.811578 -279.30729)
			)
			(arc
				(start 357.811578 -278.812244)
				(mid 357.796699 -278.776323)
				(end 357.760778 -278.761444)
			)
			(arc
				(start 353.42322 -278.761444)
				(mid 353.403833 -278.765394)
				(end 353.387406 -278.77643)
			)
			(arc
				(start 353.313746 -278.85009)
				(mid 353.302684 -278.866507)
				(end 353.29876 -278.885904)
			)
			(xy 353.29876 -279.357328)
			(arc
				(start 353.300538 -279.358852)
				(mid 353.317072 -279.369963)
				(end 353.336606 -279.373838)
			)
		)
		(stroke
			(width 0)
			(type solid)
		)
		(fill yes)
		(layer "F.Cu")
		(net "GND")
	)
	(gr_poly
		(pts
			(arc
				(start 375.911364 17.399)
				(mid 375.628408 17.399)
				(end 375.911364 17.399)
			)
		)
		(stroke
			(width 0)
			(type solid)
		)
		(fill yes)
		(layer "F.Cu")
		(net "COUPON_GND2")
	)
	(gr_poly
		(pts
			(arc
				(start 375.911364 18.657824)
				(mid 375.628408 18.657824)
				(end 375.911364 18.657824)
			)
		)
		(stroke
			(width 0)
			(type solid)
		)
		(fill yes)
		(layer "F.Cu")
		(net "COUPON_GND2")
	)
	(gr_poly
		(pts
			(arc
				(start 375.911364 19.939)
				(mid 375.628408 19.939)
				(end 375.911364 19.939)
			)
		)
		(stroke
			(width 0)
			(type solid)
		)
		(fill yes)
		(layer "F.Cu")
		(net "COUPON_GND2")
	)
	(gr_poly
		(pts
			(arc
				(start 375.911364 21.197824)
				(mid 375.628408 21.197824)
				(end 375.911364 21.197824)
			)
		)
		(stroke
			(width 0)
			(type solid)
		)
		(fill yes)
		(layer "F.Cu")
		(net "COUPON_GND2")
	)
	(gr_poly
		(pts
			(arc
				(start 384.891788 7.51332)
				(mid 384.608832 7.51332)
				(end 384.891788 7.51332)
			)
		)
		(stroke
			(width 0)
			(type solid)
		)
		(fill yes)
		(layer "F.Cu")
		(net "COUPON_GND2")
	)
	(gr_poly
		(pts
			(arc
				(start 384.891788 8.772144)
				(mid 384.608832 8.772144)
				(end 384.891788 8.772144)
			)
		)
		(stroke
			(width 0)
			(type solid)
		)
		(fill yes)
		(layer "F.Cu")
		(net "COUPON_GND2")
	)
	(gr_poly
		(pts
			(arc
				(start 384.891788 10.05332)
				(mid 384.608832 10.05332)
				(end 384.891788 10.05332)
			)
		)
		(stroke
			(width 0)
			(type solid)
		)
		(fill yes)
		(layer "F.Cu")
		(net "COUPON_GND2")
	)
	(gr_poly
		(pts
			(arc
				(start 384.891788 11.312144)
				(mid 384.608832 11.312144)
				(end 384.891788 11.312144)
			)
		)
		(stroke
			(width 0)
			(type solid)
		)
		(fill yes)
		(layer "F.Cu")
		(net "COUPON_GND2")
	)
	(gr_poly
		(pts
			(arc
				(start 402.65096 7.520432)
				(mid 402.368004 7.520432)
				(end 402.65096 7.520432)
			)
		)
		(stroke
			(width 0)
			(type solid)
		)
		(fill yes)
		(layer "F.Cu")
		(net "COUPON_GND2")
	)
	(gr_poly
		(pts
			(arc
				(start 402.65096 8.779256)
				(mid 402.368004 8.779256)
				(end 402.65096 8.779256)
			)
		)
		(stroke
			(width 0)
			(type solid)
		)
		(fill yes)
		(layer "F.Cu")
		(net "COUPON_GND2")
	)
	(gr_poly
		(pts
			(arc
				(start 402.65096 10.060432)
				(mid 402.368004 10.060432)
				(end 402.65096 10.060432)
			)
		)
		(stroke
			(width 0)
			(type solid)
		)
		(fill yes)
		(layer "F.Cu")
		(net "COUPON_GND2")
	)
	(gr_poly
		(pts
			(arc
				(start 402.65096 11.319256)
				(mid 402.368004 11.319256)
				(end 402.65096 11.319256)
			)
		)
		(stroke
			(width 0)
			(type solid)
		)
		(fill yes)
		(layer "F.Cu")
		(net "COUPON_GND2")
	)
	(gr_poly
		(pts
			(arc
				(start 405.19096 17.406112)
				(mid 404.908004 17.406112)
				(end 405.19096 17.406112)
			)
		)
		(stroke
			(width 0)
			(type solid)
		)
		(fill yes)
		(layer "F.Cu")
		(net "COUPON_GND2")
	)
	(gr_poly
		(pts
			(arc
				(start 405.19096 18.664936)
				(mid 404.908004 18.664936)
				(end 405.19096 18.664936)
			)
		)
		(stroke
			(width 0)
			(type solid)
		)
		(fill yes)
		(layer "F.Cu")
		(net "COUPON_GND2")
	)
	(gr_poly
		(pts
			(arc
				(start 405.19096 19.946112)
				(mid 404.908004 19.946112)
				(end 405.19096 19.946112)
			)
		)
		(stroke
			(width 0)
			(type solid)
		)
		(fill yes)
		(layer "F.Cu")
		(net "COUPON_GND2")
	)
	(gr_poly
		(pts
			(arc
				(start 405.19096 21.204936)
				(mid 404.908004 21.204936)
				(end 405.19096 21.204936)
			)
		)
		(stroke
			(width 0)
			(type solid)
		)
		(fill yes)
		(layer "F.Cu")
		(net "COUPON_GND2")
	)
	(gr_poly
		(pts
			(arc
				(start 440.554364 17.399)
				(mid 440.271408 17.399)
				(end 440.554364 17.399)
			)
		)
		(stroke
			(width 0)
			(type solid)
		)
		(fill yes)
		(layer "F.Cu")
		(net "COUPON_GND2")
	)
	(gr_poly
		(pts
			(arc
				(start 440.554364 18.657824)
				(mid 440.271408 18.657824)
				(end 440.554364 18.657824)
			)
		)
		(stroke
			(width 0)
			(type solid)
		)
		(fill yes)
		(layer "F.Cu")
		(net "COUPON_GND2")
	)
	(gr_poly
		(pts
			(arc
				(start 440.554364 19.939)
				(mid 440.271408 19.939)
				(end 440.554364 19.939)
			)
		)
		(stroke
			(width 0)
			(type solid)
		)
		(fill yes)
		(layer "F.Cu")
		(net "COUPON_GND2")
	)
	(gr_poly
		(pts
			(arc
				(start 440.554364 21.197824)
				(mid 440.271408 21.197824)
				(end 440.554364 21.197824)
			)
		)
		(stroke
			(width 0)
			(type solid)
		)
		(fill yes)
		(layer "F.Cu")
		(net "COUPON_GND2")
	)
	(gr_poly
		(pts
			(arc
				(start 457.154788 7.54634)
				(mid 456.871832 7.54634)
				(end 457.154788 7.54634)
			)
		)
		(stroke
			(width 0)
			(type solid)
		)
		(fill yes)
		(layer "F.Cu")
		(net "COUPON_GND2")
	)
	(gr_poly
		(pts
			(arc
				(start 457.154788 8.805164)
				(mid 456.871832 8.805164)
				(end 457.154788 8.805164)
			)
		)
		(stroke
			(width 0)
			(type solid)
		)
		(fill yes)
		(layer "F.Cu")
		(net "COUPON_GND2")
	)
	(gr_poly
		(pts
			(arc
				(start 457.154788 10.08634)
				(mid 456.871832 10.08634)
				(end 457.154788 10.08634)
			)
		)
		(stroke
			(width 0)
			(type solid)
		)
		(fill yes)
		(layer "F.Cu")
		(net "COUPON_GND2")
	)
	(gr_poly
		(pts
			(arc
				(start 457.154788 11.345164)
				(mid 456.871832 11.345164)
				(end 457.154788 11.345164)
			)
		)
		(stroke
			(width 0)
			(type solid)
		)
		(fill yes)
		(layer "F.Cu")
		(net "COUPON_GND2")
	)
	(gr_poly
		(pts
			(xy 19.492214 -173.85792) (xy 19.492214 -173.092364) (xy 19.492214 -171.832016) (xy 19.517868 -171.806362)
			(xy 19.54149 -171.78274) (xy 19.5834 -171.74083) (xy 19.594322 -171.729908) (xy 21.262594 -171.729908)
			(xy 22.381464 -171.729908) (xy 23.657052 -171.729908) (xy 23.755096 -171.632118) (xy 23.755096 -167.973248)
			(xy 23.625556 -167.843708) (xy 22.175978 -167.843708) (xy 22.075902 -167.943784) (xy 22.075902 -169.071544)
			(xy 22.075902 -169.28592) (xy 21.565108 -169.796714) (xy 21.565108 -170.752262) (xy 21.26615 -171.05122)
			(xy 20.325842 -171.05122) (xy 18.953734 -171.05122) (xy 18.345404 -171.65955) (xy 18.345404 -172.419264)
			(xy 17.961864 -172.802804) (xy 17.961864 -173.890178) (xy 18.088864 -174.017178) (xy 19.332956 -174.017178)
		)
		(stroke
			(width 0)
			(type solid)
		)
		(fill yes)
		(layer "F.Cu")
		(net "GND")
	)
	(gr_poly
		(pts
			(arc
				(start 131.923536 -169.130218)
				(mid 131.63296 -169.130218)
				(end 131.923536 -169.130218)
			)
		)
		(stroke
			(width 0)
			(type solid)
		)
		(fill yes)
		(layer "F.Cu")
		(net "GND")
	)
	(gr_poly
		(pts
			(arc
				(start 211.58454 -248.407174)
				(mid 211.291424 -248.407174)
				(end 211.58454 -248.407174)
			)
		)
		(stroke
			(width 0)
			(type solid)
		)
		(fill yes)
		(layer "F.Cu")
		(net "GND")
	)
	(gr_poly
		(pts
			(arc
				(start 215.918288 -207.01)
				(mid 215.627712 -207.01)
				(end 215.918288 -207.01)
			)
		)
		(stroke
			(width 0)
			(type solid)
		)
		(fill yes)
		(layer "F.Cu")
		(net "GND")
	)
	(gr_poly
		(pts
			(arc
				(start 215.918288 -202.438)
				(mid 215.627712 -202.438)
				(end 215.918288 -202.438)
			)
		)
		(stroke
			(width 0)
			(type solid)
		)
		(fill yes)
		(layer "F.Cu")
		(net "GND")
	)
	(gr_poly
		(pts
			(arc
				(start 215.918288 -197.866)
				(mid 215.627712 -197.866)
				(end 215.918288 -197.866)
			)
		)
		(stroke
			(width 0)
			(type solid)
		)
		(fill yes)
		(layer "F.Cu")
		(net "GND")
	)
	(gr_poly
		(pts
			(arc
				(start 215.918288 -193.294)
				(mid 215.627712 -193.294)
				(end 215.918288 -193.294)
			)
		)
		(stroke
			(width 0)
			(type solid)
		)
		(fill yes)
		(layer "F.Cu")
		(net "GND")
	)
	(gr_poly
		(pts
			(arc
				(start 229.9462 -329.539092)
				(mid 229.642924 -329.539092)
				(end 229.9462 -329.539092)
			)
		)
		(stroke
			(width 0)
			(type solid)
		)
		(fill yes)
		(layer "F.Cu")
		(net "GND")
	)
	(gr_poly
		(pts
			(arc
				(start 232.681272 -246.35079)
				(mid 232.388156 -246.35079)
				(end 232.681272 -246.35079)
			)
		)
		(stroke
			(width 0)
			(type solid)
		)
		(fill yes)
		(layer "F.Cu")
		(net "GND")
	)
	(gr_poly
		(pts
			(arc
				(start 305.52263 -257.441954)
				(mid 305.229514 -257.441954)
				(end 305.52263 -257.441954)
			)
		)
		(stroke
			(width 0)
			(type solid)
		)
		(fill yes)
		(layer "F.Cu")
		(net "GND")
	)
	(gr_poly
		(pts
			(arc
				(start 316.833758 -254.4064)
				(mid 316.540642 -254.4064)
				(end 316.833758 -254.4064)
			)
		)
		(stroke
			(width 0)
			(type solid)
		)
		(fill yes)
		(layer "F.Cu")
		(net "GND")
	)
	(gr_poly
		(pts
			(arc
				(start 317.443358 -257.556)
				(mid 317.150242 -257.556)
				(end 317.443358 -257.556)
			)
		)
		(stroke
			(width 0)
			(type solid)
		)
		(fill yes)
		(layer "F.Cu")
		(net "GND")
	)
	(gr_poly
		(pts
			(arc
				(start 362.7247 -245.267734)
				(mid 362.431584 -245.267734)
				(end 362.7247 -245.267734)
			)
		)
		(stroke
			(width 0)
			(type solid)
		)
		(fill yes)
		(layer "F.Cu")
		(net "GND")
	)
	(gr_poly
		(pts
			(arc
				(start 393.331446 -77.446124)
				(mid 393.03833 -77.446124)
				(end 393.331446 -77.446124)
			)
		)
		(stroke
			(width 0)
			(type solid)
		)
		(fill yes)
		(layer "F.Cu")
		(net "GND")
	)
	(gr_poly
		(pts
			(arc
				(start 406.0952 -89.154508)
				(mid 405.802084 -89.154508)
				(end 406.0952 -89.154508)
			)
		)
		(stroke
			(width 0)
			(type solid)
		)
		(fill yes)
		(layer "F.Cu")
		(net "GND")
	)
	(gr_poly
		(pts
			(xy 10.074656 -305.872642) (xy 10.074656 -302.557942) (xy 10.360406 -302.272192) (xy 10.361676 -302.272192)
			(xy 10.700766 -301.933102) (xy 10.726166 -301.907702) (xy 12.230862 -301.907702) (xy 12.76223 -301.907702)
			(xy 12.877292 -301.907702) (xy 12.933426 -301.963836) (xy 12.959842 -301.990252) (xy 12.959842 -303.07788)
			(xy 12.996672 -303.11471) (xy 13.488924 -303.11471) (xy 13.843 -302.760634) (xy 13.843 -302.664114)
			(xy 13.843 -298.46143) (xy 13.697966 -298.316396) (xy 8.794242 -298.316396) (xy 7.884414 -298.316396)
			(xy 7.464298 -298.316396) (xy 7.314184 -298.46651) (xy 7.314184 -302.906176) (xy 7.695692 -303.287684)
			(xy 8.882126 -303.287684) (xy 9.772396 -304.177954) (xy 9.772396 -305.900582) (xy 9.840976 -305.969162)
			(xy 9.978136 -305.969162)
		)
		(stroke
			(width 0)
			(type solid)
		)
		(fill yes)
		(layer "F.Cu")
		(net "SW_P1V25_PEX0_PH")
	)
	(gr_poly
		(pts
			(arc
				(start 98.604832 -329.35545)
				(mid 98.289364 -329.35545)
				(end 98.604832 -329.35545)
			)
		)
		(stroke
			(width 0)
			(type solid)
		)
		(fill yes)
		(layer "F.Cu")
		(net "GND")
	)
	(gr_poly
		(pts
			(arc
				(start 98.61931 -330.730606)
				(mid 98.303842 -330.730606)
				(end 98.61931 -330.730606)
			)
		)
		(stroke
			(width 0)
			(type solid)
		)
		(fill yes)
		(layer "F.Cu")
		(net "GND")
	)
	(gr_poly
		(pts
			(arc
				(start 102.768908 -343.298272)
				(mid 102.45344 -343.298272)
				(end 102.768908 -343.298272)
			)
		)
		(stroke
			(width 0)
			(type solid)
		)
		(fill yes)
		(layer "F.Cu")
		(net "GND")
	)
	(gr_poly
		(pts
			(arc
				(start 104.027732 -343.298272)
				(mid 103.712264 -343.298272)
				(end 104.027732 -343.298272)
			)
		)
		(stroke
			(width 0)
			(type solid)
		)
		(fill yes)
		(layer "F.Cu")
		(net "GND")
	)
	(gr_poly
		(pts
			(arc
				(start 108.814108 -117.862604)
				(mid 108.499148 -117.862604)
				(end 108.814108 -117.862604)
			)
		)
		(stroke
			(width 0)
			(type solid)
		)
		(fill yes)
		(layer "F.Cu")
		(net "GND")
	)
	(gr_poly
		(pts
			(xy 112.779556 -128.03251) (xy 112.779556 -125.771148) (xy 112.771174 -125.762766) (xy 112.740186 -125.762766)
			(xy 112.739932 -125.76302) (xy 112.282732 -125.76302) (xy 112.279938 -125.760226) (xy 112.09274 -125.760226)
			(xy 111.651796 -125.319282) (xy 111.651796 -125.132084) (xy 111.651796 -124.794264) (xy 112.33277 -124.11329)
			(xy 118.859808 -124.11329) (xy 119.07647 -123.896628) (xy 119.07647 -119.761) (xy 118.988078 -119.672608)
			(xy 118.203218 -119.672608) (xy 118.162578 -119.713248) (xy 118.162578 -120.588532) (xy 117.870986 -120.880124)
			(xy 110.263432 -120.880124) (xy 108.415074 -122.728482) (xy 106.625898 -122.728482) (xy 104.612694 -124.741686)
			(xy 104.584246 -124.741686) (xy 104.32415 -125.001782) (xy 104.32415 -127.62484) (xy 104.74071 -128.0414)
			(xy 112.770666 -128.0414)
		)
		(stroke
			(width 0)
			(type solid)
		)
		(fill yes)
		(layer "F.Cu")
		(net "P3V3")
	)
	(gr_poly
		(pts
			(arc
				(start 114.93754 -331.729842)
				(mid 114.622072 -331.729842)
				(end 114.93754 -331.729842)
			)
		)
		(stroke
			(width 0)
			(type solid)
		)
		(fill yes)
		(layer "F.Cu")
		(net "GND")
	)
	(gr_poly
		(pts
			(arc
				(start 114.93754 -330.471018)
				(mid 114.622072 -330.471018)
				(end 114.93754 -330.471018)
			)
		)
		(stroke
			(width 0)
			(type solid)
		)
		(fill yes)
		(layer "F.Cu")
		(net "GND")
	)
	(gr_poly
		(pts
			(arc
				(start 115.334034 -94.156276)
				(mid 115.02517 -94.156276)
				(end 115.334034 -94.156276)
			)
		)
		(stroke
			(width 0)
			(type solid)
		)
		(fill yes)
		(layer "F.Cu")
		(net "GND")
	)
	(gr_poly
		(pts
			(arc
				(start 115.685316 -247.553988)
				(mid 115.360704 -247.553988)
				(end 115.685316 -247.553988)
			)
		)
		(stroke
			(width 0)
			(type solid)
		)
		(fill yes)
		(layer "F.Cu")
		(net "GND")
	)
	(gr_poly
		(pts
			(arc
				(start 122.708416 -112.907318)
				(mid 122.393456 -112.907318)
				(end 122.708416 -112.907318)
			)
		)
		(stroke
			(width 0)
			(type solid)
		)
		(fill yes)
		(layer "F.Cu")
		(net "GND")
	)
	(gr_poly
		(pts
			(arc
				(start 125.010164 -214.174324)
				(mid 124.685552 -214.174324)
				(end 125.010164 -214.174324)
			)
		)
		(stroke
			(width 0)
			(type solid)
		)
		(fill yes)
		(layer "F.Cu")
		(net "GND")
	)
	(gr_poly
		(pts
			(arc
				(start 132.425186 -214.917782)
				(mid 132.100574 -214.917782)
				(end 132.425186 -214.917782)
			)
		)
		(stroke
			(width 0)
			(type solid)
		)
		(fill yes)
		(layer "F.Cu")
		(net "GND")
	)
	(gr_poly
		(pts
			(arc
				(start 138.652504 -215.981026)
				(mid 138.327892 -215.981026)
				(end 138.652504 -215.981026)
			)
		)
		(stroke
			(width 0)
			(type solid)
		)
		(fill yes)
		(layer "F.Cu")
		(net "GND")
	)
	(gr_poly
		(pts
			(arc
				(start 145.49374 -213.955884)
				(mid 145.169128 -213.955884)
				(end 145.49374 -213.955884)
			)
		)
		(stroke
			(width 0)
			(type solid)
		)
		(fill yes)
		(layer "F.Cu")
		(net "GND")
	)
	(gr_poly
		(pts
			(arc
				(start 220.987366 -248.412762)
				(mid 220.662754 -248.412762)
				(end 220.987366 -248.412762)
			)
		)
		(stroke
			(width 0)
			(type solid)
		)
		(fill yes)
		(layer "F.Cu")
		(net "GND")
	)
	(gr_poly
		(pts
			(xy 221.00667 -69.984112) (xy 221.00667 -65.67678) (xy 221.00667 -59.113928) (xy 218.940634 -57.047892)
			(xy 218.940634 -56.113934) (xy 218.356434 -55.529734) (xy 217.848434 -55.529734) (xy 217.774774 -55.456074)
			(xy 217.774774 -52.23764) (xy 217.625676 -52.088542) (xy 215.890348 -52.088542) (xy 215.761316 -52.217574)
			(xy 215.761316 -55.986934) (xy 214.927434 -56.820816) (xy 214.927434 -59.644534) (xy 214.969598 -59.686698)
			(xy 214.969598 -63.562484) (xy 215.773254 -64.36614) (xy 215.782398 -64.36614) (xy 216.346278 -64.93002)
			(xy 216.346278 -68.30695) (xy 215.581992 -69.071236) (xy 214.996776 -69.071236) (xy 214.865712 -69.2023)
			(xy 214.865712 -69.783452) (xy 214.922354 -69.840094) (xy 215.979502 -69.840094) (xy 216.333324 -70.193916)
			(xy 220.796866 -70.193916)
		)
		(stroke
			(width 0)
			(type solid)
		)
		(fill yes)
		(layer "F.Cu")
		(net "P12V_AUX")
	)
	(gr_poly
		(pts
			(arc
				(start 230.466646 -244.457982)
				(mid 230.142034 -244.457982)
				(end 230.466646 -244.457982)
			)
		)
		(stroke
			(width 0)
			(type solid)
		)
		(fill yes)
		(layer "F.Cu")
		(net "GND")
	)
	(gr_poly
		(pts
			(arc
				(start 233.498898 -245.038118)
				(mid 233.174286 -245.038118)
				(end 233.498898 -245.038118)
			)
		)
		(stroke
			(width 0)
			(type solid)
		)
		(fill yes)
		(layer "F.Cu")
		(net "GND")
	)
	(gr_poly
		(pts
			(xy 453.206612 -69.984112) (xy 453.206612 -65.67678) (xy 453.206612 -59.41949) (xy 451.140576 -57.353454)
			(xy 451.140576 -56.113934) (xy 450.556376 -55.529734) (xy 450.048376 -55.529734) (xy 449.974716 -55.456074)
			(xy 449.974716 -52.23764) (xy 449.825618 -52.088542) (xy 448.09029 -52.088542) (xy 447.961258 -52.217574)
			(xy 447.961258 -55.986934) (xy 447.127376 -56.820816) (xy 447.127376 -59.644534) (xy 447.16954 -59.686698)
			(xy 447.16954 -63.562484) (xy 447.973196 -64.36614) (xy 447.98234 -64.36614) (xy 448.54622 -64.93002)
			(xy 448.54622 -68.30695) (xy 447.781934 -69.071236) (xy 447.196718 -69.071236) (xy 447.065654 -69.2023)
			(xy 447.065654 -69.783452) (xy 447.122296 -69.840094) (xy 448.179444 -69.840094) (xy 448.533266 -70.193916)
			(xy 452.996808 -70.193916)
		)
		(stroke
			(width 0)
			(type solid)
		)
		(fill yes)
		(layer "F.Cu")
		(net "P12V_AUX")
	)
	(gr_poly
		(pts
			(arc
				(start 16.914622 -307.183028)
				(mid 16.582898 -307.183028)
				(end 16.914622 -307.183028)
			)
		)
		(stroke
			(width 0)
			(type solid)
		)
		(fill yes)
		(layer "F.Cu")
		(net "GND")
	)
	(gr_poly
		(pts
			(xy 52.906676 -69.984112) (xy 52.906676 -65.67678) (xy 52.546504 -65.316608) (xy 52.546504 -58.809128)
			(xy 50.84064 -57.103264) (xy 50.84064 -56.113934) (xy 50.25644 -55.529734) (xy 49.74844 -55.529734)
			(xy 49.67478 -55.456074) (xy 49.67478 -52.23764) (xy 49.525682 -52.088542) (xy 47.790354 -52.088542)
			(xy 47.661322 -52.217574) (xy 47.661322 -55.986934) (xy 46.82744 -56.820816) (xy 46.82744 -59.644534)
			(xy 46.869604 -59.686698) (xy 46.869604 -63.562484) (xy 47.67326 -64.36614) (xy 47.682404 -64.36614)
			(xy 48.246284 -64.93002) (xy 48.246284 -68.30695) (xy 47.481998 -69.071236) (xy 46.896782 -69.071236)
			(xy 46.765718 -69.2023) (xy 46.765718 -69.783452) (xy 46.82236 -69.840094) (xy 47.879508 -69.840094)
			(xy 48.23333 -70.193916) (xy 52.696872 -70.193916)
		)
		(stroke
			(width 0)
			(type solid)
		)
		(fill yes)
		(layer "F.Cu")
		(net "P12V_AUX")
	)
	(gr_poly
		(pts
			(xy 143.006826 -69.984112) (xy 143.006826 -65.67678) (xy 142.597124 -65.267078) (xy 142.597124 -58.971688)
			(xy 140.94079 -57.315354) (xy 140.94079 -56.113934) (xy 140.35659 -55.529734) (xy 139.84859 -55.529734)
			(xy 139.77493 -55.456074) (xy 139.77493 -52.23764) (xy 139.625832 -52.088542) (xy 137.890504 -52.088542)
			(xy 137.761472 -52.217574) (xy 137.761472 -55.986934) (xy 136.92759 -56.820816) (xy 136.92759 -59.644534)
			(xy 136.969754 -59.686698) (xy 136.969754 -63.562484) (xy 137.77341 -64.36614) (xy 137.782554 -64.36614)
			(xy 138.346434 -64.93002) (xy 138.346434 -68.30695) (xy 137.582148 -69.071236) (xy 136.996932 -69.071236)
			(xy 136.865868 -69.2023) (xy 136.865868 -69.783452) (xy 136.92251 -69.840094) (xy 137.979658 -69.840094)
			(xy 138.33348 -70.193916) (xy 142.797022 -70.193916)
		)
		(stroke
			(width 0)
			(type solid)
		)
		(fill yes)
		(layer "F.Cu")
		(net "P12V_AUX")
	)
	(gr_poly
		(pts
			(xy 195.006722 -69.984112) (xy 195.006722 -65.67678) (xy 194.586352 -65.25641) (xy 194.586352 -58.729118)
			(xy 192.940686 -57.083452) (xy 192.940686 -56.113934) (xy 192.356486 -55.529734) (xy 191.848486 -55.529734)
			(xy 191.774826 -55.456074) (xy 191.774826 -52.23764) (xy 191.625728 -52.088542) (xy 189.8904 -52.088542)
			(xy 189.761368 -52.217574) (xy 189.761368 -55.986934) (xy 188.927486 -56.820816) (xy 188.927486 -59.644534)
			(xy 188.96965 -59.686698) (xy 188.96965 -63.562484) (xy 189.773306 -64.36614) (xy 189.78245 -64.36614)
			(xy 190.34633 -64.93002) (xy 190.34633 -68.30695) (xy 189.582044 -69.071236) (xy 188.996828 -69.071236)
			(xy 188.865764 -69.2023) (xy 188.865764 -69.783452) (xy 188.922406 -69.840094) (xy 189.979554 -69.840094)
			(xy 190.333376 -70.193916) (xy 194.796918 -70.193916)
		)
		(stroke
			(width 0)
			(type solid)
		)
		(fill yes)
		(layer "F.Cu")
		(net "P12V_AUX")
	)
	(gr_poly
		(pts
			(arc
				(start 261.87654 -355.388164)
				(mid 261.896063 -355.384263)
				(end 261.912608 -355.373178)
			)
			(arc
				(start 262.021574 -355.264212)
				(mid 262.032685 -355.247678)
				(end 262.03656 -355.228144)
			)
			(arc
				(start 262.03656 -351.882456)
				(mid 262.032659 -351.862933)
				(end 262.021574 -351.846388)
			)
			(arc
				(start 261.861046 -351.68586)
				(mid 261.844512 -351.674749)
				(end 261.824978 -351.670874)
			)
			(arc
				(start 254.373634 -351.670874)
				(mid 254.354111 -351.674775)
				(end 254.337566 -351.68586)
			)
			(arc
				(start 254.182372 -351.841054)
				(mid 254.171261 -351.857588)
				(end 254.167386 -351.877122)
			)
			(arc
				(start 254.167386 -355.337364)
				(mid 254.182265 -355.373285)
				(end 254.218186 -355.388164)
			)
		)
		(stroke
			(width 0)
			(type solid)
		)
		(fill yes)
		(layer "F.Cu")
		(net "GND")
	)
	(gr_poly
		(pts
			(arc
				(start 304.67935 -253.620016)
				(mid 304.33391 -253.620016)
				(end 304.67935 -253.620016)
			)
		)
		(stroke
			(width 0)
			(type solid)
		)
		(fill yes)
		(layer "F.Cu")
		(net "GND")
	)
	(gr_poly
		(pts
			(xy 337.106514 -69.984112) (xy 337.106514 -65.67678) (xy 337.106514 -59.239912) (xy 335.040478 -57.173876)
			(xy 335.040478 -57.048146) (xy 335.040478 -56.113934) (xy 334.456278 -55.529734) (xy 333.948278 -55.529734)
			(xy 333.874618 -55.456074) (xy 333.874618 -52.23764) (xy 333.72552 -52.088542) (xy 331.990192 -52.088542)
			(xy 331.86116 -52.217574) (xy 331.86116 -55.986934) (xy 331.027278 -56.820816) (xy 331.027278 -59.644534)
			(xy 331.069442 -59.686698) (xy 331.069442 -63.562484) (xy 331.873098 -64.36614) (xy 331.882242 -64.36614)
			(xy 332.446122 -64.93002) (xy 332.446122 -68.30695) (xy 331.681836 -69.071236) (xy 331.09662 -69.071236)
			(xy 330.965556 -69.2023) (xy 330.965556 -69.783452) (xy 331.022198 -69.840094) (xy 332.079346 -69.840094)
			(xy 332.433168 -70.193916) (xy 336.89671 -70.193916)
		)
		(stroke
			(width 0)
			(type solid)
		)
		(fill yes)
		(layer "F.Cu")
		(net "P12V_AUX")
	)
	(gr_poly
		(pts
			(xy 401.206716 -69.984112) (xy 401.206716 -65.67678) (xy 400.659346 -65.12941) (xy 400.659346 -58.742072)
			(xy 399.14068 -57.223406) (xy 399.14068 -56.113934) (xy 398.55648 -55.529734) (xy 398.04848 -55.529734)
			(xy 397.97482 -55.456074) (xy 397.97482 -52.23764) (xy 397.825722 -52.088542) (xy 396.090394 -52.088542)
			(xy 395.961362 -52.217574) (xy 395.961362 -55.986934) (xy 395.12748 -56.820816) (xy 395.12748 -59.644534)
			(xy 395.169644 -59.686698) (xy 395.169644 -63.562484) (xy 395.9733 -64.36614) (xy 395.982444 -64.36614)
			(xy 396.546324 -64.93002) (xy 396.546324 -68.30695) (xy 395.782038 -69.071236) (xy 395.196822 -69.071236)
			(xy 395.065758 -69.2023) (xy 395.065758 -69.783452) (xy 395.1224 -69.840094) (xy 396.179548 -69.840094)
			(xy 396.53337 -70.193916) (xy 400.996912 -70.193916)
		)
		(stroke
			(width 0)
			(type solid)
		)
		(fill yes)
		(layer "F.Cu")
		(net "P12V_AUX")
	)
	(gr_poly
		(pts
			(xy 427.206664 -69.984112) (xy 427.206664 -65.67678) (xy 426.645832 -65.115948) (xy 426.645832 -58.858912)
			(xy 425.140628 -57.353708) (xy 425.140628 -56.113934) (xy 424.556428 -55.529734) (xy 424.048428 -55.529734)
			(xy 423.974768 -55.456074) (xy 423.974768 -52.23764) (xy 423.82567 -52.088542) (xy 422.090342 -52.088542)
			(xy 421.96131 -52.217574) (xy 421.96131 -55.986934) (xy 421.127428 -56.820816) (xy 421.127428 -59.644534)
			(xy 421.169592 -59.686698) (xy 421.169592 -63.562484) (xy 421.973248 -64.36614) (xy 421.982392 -64.36614)
			(xy 422.546272 -64.93002) (xy 422.546272 -68.30695) (xy 421.781986 -69.071236) (xy 421.19677 -69.071236)
			(xy 421.065706 -69.2023) (xy 421.065706 -69.783452) (xy 421.122348 -69.840094) (xy 422.179496 -69.840094)
			(xy 422.533318 -70.193916) (xy 426.99686 -70.193916)
		)
		(stroke
			(width 0)
			(type solid)
		)
		(fill yes)
		(layer "F.Cu")
		(net "P12V_AUX")
	)
	(gr_poly
		(pts
			(xy 26.906728 -69.984112) (xy 26.906728 -65.67678) (xy 26.6065 -65.376552) (xy 26.6065 -59.29122)
			(xy 24.840692 -57.525412) (xy 24.840692 -57.015634) (xy 24.840692 -56.113934) (xy 24.256492 -55.529734)
			(xy 23.748492 -55.529734) (xy 23.674832 -55.456074) (xy 23.674832 -52.23764) (xy 23.525734 -52.088542)
			(xy 21.790406 -52.088542) (xy 21.661374 -52.217574) (xy 21.661374 -55.986934) (xy 20.827492 -56.820816)
			(xy 20.827492 -59.644534) (xy 20.869656 -59.686698) (xy 20.869656 -63.562484) (xy 21.673312 -64.36614)
			(xy 21.682456 -64.36614) (xy 22.246336 -64.93002) (xy 22.246336 -68.30695) (xy 21.48205 -69.071236)
			(xy 20.896834 -69.071236) (xy 20.76577 -69.2023) (xy 20.76577 -69.783452) (xy 20.822412 -69.840094)
			(xy 21.87956 -69.840094) (xy 22.233382 -70.193916) (xy 26.696924 -70.193916)
		)
		(stroke
			(width 0)
			(type solid)
		)
		(fill yes)
		(layer "F.Cu")
		(net "P12V_AUX")
	)
	(gr_poly
		(pts
			(xy 78.906624 -69.984112) (xy 78.906624 -65.67678) (xy 78.551278 -65.321434) (xy 78.551278 -58.90133)
			(xy 76.840588 -57.19064) (xy 76.840588 -56.897778) (xy 76.840588 -56.113934) (xy 76.256388 -55.529734)
			(xy 75.748388 -55.529734) (xy 75.674728 -55.456074) (xy 75.674728 -52.23764) (xy 75.52563 -52.088542)
			(xy 73.790302 -52.088542) (xy 73.66127 -52.217574) (xy 73.66127 -55.986934) (xy 72.827388 -56.820816)
			(xy 72.827388 -59.644534) (xy 72.869552 -59.686698) (xy 72.869552 -63.562484) (xy 73.673208 -64.36614)
			(xy 73.682352 -64.36614) (xy 74.246232 -64.93002) (xy 74.246232 -68.30695) (xy 73.481946 -69.071236)
			(xy 72.89673 -69.071236) (xy 72.765666 -69.2023) (xy 72.765666 -69.783452) (xy 72.822308 -69.840094)
			(xy 73.879456 -69.840094) (xy 74.233278 -70.193916) (xy 78.69682 -70.193916)
		)
		(stroke
			(width 0)
			(type solid)
		)
		(fill yes)
		(layer "F.Cu")
		(net "P12V_AUX")
	)
	(gr_poly
		(pts
			(xy 104.906572 -69.984112) (xy 104.906572 -65.67678) (xy 104.906572 -59.26455) (xy 102.840536 -57.198514)
			(xy 102.840536 -57.047384) (xy 102.840536 -56.833008) (xy 102.840536 -56.113934) (xy 102.256336 -55.529734)
			(xy 101.748336 -55.529734) (xy 101.674676 -55.456074) (xy 101.674676 -52.23764) (xy 101.525578 -52.088542)
			(xy 99.79025 -52.088542) (xy 99.661218 -52.217574) (xy 99.661218 -55.986934) (xy 98.827336 -56.820816)
			(xy 98.827336 -59.644534) (xy 98.8695 -59.686698) (xy 98.8695 -63.562484) (xy 99.673156 -64.36614)
			(xy 99.6823 -64.36614) (xy 100.24618 -64.93002) (xy 100.24618 -68.30695) (xy 99.481894 -69.071236)
			(xy 98.896678 -69.071236) (xy 98.765614 -69.2023) (xy 98.765614 -69.783452) (xy 98.822256 -69.840094)
			(xy 99.879404 -69.840094) (xy 100.233226 -70.193916) (xy 104.696768 -70.193916)
		)
		(stroke
			(width 0)
			(type solid)
		)
		(fill yes)
		(layer "F.Cu")
		(net "P12V_AUX")
	)
	(gr_poly
		(pts
			(xy 169.006774 -69.984112) (xy 169.006774 -65.67678) (xy 168.594024 -65.264284) (xy 168.594024 -58.896758)
			(xy 166.940738 -57.243472) (xy 166.940738 -57.044844) (xy 166.940738 -56.113934) (xy 166.356538 -55.529734)
			(xy 165.848538 -55.529734) (xy 165.774878 -55.456074) (xy 165.774878 -52.23764) (xy 165.62578 -52.088542)
			(xy 163.890452 -52.088542) (xy 163.76142 -52.217574) (xy 163.76142 -55.986934) (xy 162.927538 -56.820816)
			(xy 162.927538 -59.644534) (xy 162.969702 -59.686698) (xy 162.969702 -63.562484) (xy 163.773358 -64.36614)
			(xy 163.782502 -64.36614) (xy 164.346382 -64.93002) (xy 164.346382 -68.30695) (xy 163.582096 -69.071236)
			(xy 162.99688 -69.071236) (xy 162.865816 -69.2023) (xy 162.865816 -69.783452) (xy 162.922458 -69.840094)
			(xy 163.979606 -69.840094) (xy 164.333428 -70.193916) (xy 168.79697 -70.193916)
		)
		(stroke
			(width 0)
			(type solid)
		)
		(fill yes)
		(layer "F.Cu")
		(net "P12V_AUX")
	)
	(gr_poly
		(pts
			(xy 210.153758 -119.196358) (xy 210.1342 -119.1768) (xy 208.734152 -119.1768) (xy 208.228438 -118.671086)
			(xy 208.228438 -114.56035) (xy 208.140046 -114.471958) (xy 207.355186 -114.471958) (xy 207.314546 -114.512598)
			(xy 207.314546 -115.387882) (xy 207.108552 -115.593876) (xy 203.204572 -115.593876) (xy 202.846686 -115.23599)
			(xy 194.661028 -115.23599) (xy 193.952622 -114.527584) (xy 190.41364 -114.527584) (xy 190.135764 -114.80546)
			(xy 190.135764 -114.937794) (xy 190.020194 -115.053364) (xy 189.88786 -115.053364) (xy 189.883796 -115.057428)
			(xy 188.754258 -115.057428) (xy 188.724794 -115.086892) (xy 188.724794 -115.40744) (xy 188.741304 -115.42395)
			(xy 190.097156 -115.42395) (xy 191.057276 -116.38407) (xy 191.630808 -116.38407) (xy 192.921636 -117.674898)
			(xy 199.804274 -117.674898) (xy 203.514198 -121.384822) (xy 210.153758 -121.384822)
		)
		(stroke
			(width 0)
			(type solid)
		)
		(fill yes)
		(layer "F.Cu")
		(net "P3V3_NIC3")
	)
	(gr_poly
		(pts
			(xy 259.10667 -69.984112) (xy 259.10667 -65.67678) (xy 258.786884 -65.357248) (xy 258.786884 -58.957464)
			(xy 257.040634 -57.211214) (xy 257.040634 -56.881522) (xy 257.040634 -56.113934) (xy 256.456434 -55.529734)
			(xy 255.948434 -55.529734) (xy 255.874774 -55.456074) (xy 255.874774 -52.23764) (xy 255.725676 -52.088542)
			(xy 253.990348 -52.088542) (xy 253.861316 -52.217574) (xy 253.861316 -55.986934) (xy 253.027434 -56.820816)
			(xy 253.027434 -59.644534) (xy 253.069598 -59.686698) (xy 253.069598 -63.562484) (xy 253.873254 -64.36614)
			(xy 253.882398 -64.36614) (xy 254.446278 -64.93002) (xy 254.446278 -68.30695) (xy 253.681992 -69.071236)
			(xy 253.096776 -69.071236) (xy 252.965712 -69.2023) (xy 252.965712 -69.783452) (xy 253.022354 -69.840094)
			(xy 254.079502 -69.840094) (xy 254.433324 -70.193916) (xy 258.896866 -70.193916)
		)
		(stroke
			(width 0)
			(type solid)
		)
		(fill yes)
		(layer "F.Cu")
		(net "P12V_AUX")
	)
	(gr_poly
		(pts
			(xy 285.106618 -69.984112) (xy 285.106618 -65.67678) (xy 284.580584 -65.150746) (xy 284.580584 -58.682128)
			(xy 283.040582 -57.142126) (xy 283.040582 -56.963056) (xy 283.040582 -56.113934) (xy 282.456382 -55.529734)
			(xy 281.948382 -55.529734) (xy 281.874722 -55.456074) (xy 281.874722 -52.23764) (xy 281.725624 -52.088542)
			(xy 279.990296 -52.088542) (xy 279.861264 -52.217574) (xy 279.861264 -55.986934) (xy 279.027382 -56.820816)
			(xy 279.027382 -59.644534) (xy 279.069546 -59.686698) (xy 279.069546 -63.562484) (xy 279.873202 -64.36614)
			(xy 279.882346 -64.36614) (xy 280.446226 -64.93002) (xy 280.446226 -68.30695) (xy 279.68194 -69.071236)
			(xy 279.096724 -69.071236) (xy 278.96566 -69.2023) (xy 278.96566 -69.783452) (xy 279.022302 -69.840094)
			(xy 280.07945 -69.840094) (xy 280.433272 -70.193916) (xy 284.896814 -70.193916)
		)
		(stroke
			(width 0)
			(type solid)
		)
		(fill yes)
		(layer "F.Cu")
		(net "P12V_AUX")
	)
	(gr_poly
		(pts
			(xy 311.106566 -69.984112) (xy 311.106566 -65.67678) (xy 310.691276 -65.26149) (xy 310.691276 -58.870088)
			(xy 309.04053 -57.219342) (xy 309.04053 -57.048146) (xy 309.04053 -56.113934) (xy 308.45633 -55.529734)
			(xy 307.94833 -55.529734) (xy 307.87467 -55.456074) (xy 307.87467 -52.23764) (xy 307.725572 -52.088542)
			(xy 305.990244 -52.088542) (xy 305.861212 -52.217574) (xy 305.861212 -55.986934) (xy 305.02733 -56.820816)
			(xy 305.02733 -59.644534) (xy 305.069494 -59.686698) (xy 305.069494 -63.562484) (xy 305.87315 -64.36614)
			(xy 305.882294 -64.36614) (xy 306.446174 -64.93002) (xy 306.446174 -68.30695) (xy 305.681888 -69.071236)
			(xy 305.096672 -69.071236) (xy 304.965608 -69.2023) (xy 304.965608 -69.783452) (xy 305.02225 -69.840094)
			(xy 306.079398 -69.840094) (xy 306.43322 -70.193916) (xy 310.896762 -70.193916)
		)
		(stroke
			(width 0)
			(type solid)
		)
		(fill yes)
		(layer "F.Cu")
		(net "P12V_AUX")
	)
	(gr_poly
		(pts
			(xy 375.206768 -69.984112) (xy 375.206768 -65.67678) (xy 374.68048 -65.150492) (xy 374.68048 -58.734198)
			(xy 373.140732 -57.19445) (xy 373.140732 -57.031636) (xy 373.140732 -56.113934) (xy 372.556532 -55.529734)
			(xy 372.048532 -55.529734) (xy 371.974872 -55.456074) (xy 371.974872 -52.23764) (xy 371.825774 -52.088542)
			(xy 370.090446 -52.088542) (xy 369.961414 -52.217574) (xy 369.961414 -55.986934) (xy 369.127532 -56.820816)
			(xy 369.127532 -59.644534) (xy 369.169696 -59.686698) (xy 369.169696 -63.562484) (xy 369.973352 -64.36614)
			(xy 369.982496 -64.36614) (xy 370.546376 -64.93002) (xy 370.546376 -68.30695) (xy 369.78209 -69.071236)
			(xy 369.196874 -69.071236) (xy 369.06581 -69.2023) (xy 369.06581 -69.783452) (xy 369.122452 -69.840094)
			(xy 370.1796 -69.840094) (xy 370.533422 -70.193916) (xy 374.996964 -70.193916)
		)
		(stroke
			(width 0)
			(type solid)
		)
		(fill yes)
		(layer "F.Cu")
		(net "P12V_AUX")
	)
	(gr_poly
		(pts
			(arc
				(start 28.543504 -258.360672)
				(mid 28.563027 -258.356771)
				(end 28.579572 -258.345686)
			)
			(xy 28.586176 -258.339082) (xy 28.593796 -258.32054)
			(arc
				(start 28.593796 -254.4699)
				(mid 28.589895 -254.450377)
				(end 28.57881 -254.433832)
			)
			(arc
				(start 28.527248 -254.38227)
				(mid 28.510714 -254.371159)
				(end 28.49118 -254.367284)
			)
			(xy 27.557476 -254.367284) (xy 27.557476 -254.367538)
			(arc
				(start 27.45613 -254.367538)
				(mid 27.436607 -254.371439)
				(end 27.420062 -254.382524)
			)
			(arc
				(start 27.34056 -254.462026)
				(mid 27.329634 -254.478472)
				(end 27.325828 -254.49784)
			)
			(arc
				(start 27.325828 -258.300982)
				(mid 27.329661 -258.320339)
				(end 27.34056 -258.336796)
			)
			(arc
				(start 27.34945 -258.345686)
				(mid 27.365984 -258.356797)
				(end 27.385518 -258.360672)
			)
		)
		(stroke
			(width 0)
			(type solid)
		)
		(fill yes)
		(layer "F.Cu")
		(net "GND")
	)
	(gr_poly
		(pts
			(arc
				(start 29.871416 -280.869136)
				(mid 29.890773 -280.865303)
				(end 29.90723 -280.854404)
			)
			(arc
				(start 29.91612 -280.845514)
				(mid 29.927231 -280.82898)
				(end 29.931106 -280.809446)
			)
			(arc
				(start 29.931106 -279.65146)
				(mid 29.927205 -279.631937)
				(end 29.91612 -279.615392)
			)
			(xy 29.909516 -279.608788) (xy 29.890974 -279.601168)
			(arc
				(start 26.040334 -279.601168)
				(mid 26.020811 -279.605069)
				(end 26.004266 -279.616154)
			)
			(arc
				(start 25.952704 -279.667716)
				(mid 25.941593 -279.68425)
				(end 25.937718 -279.703784)
			)
			(xy 25.937718 -280.637488) (xy 25.937972 -280.637488)
			(arc
				(start 25.937972 -280.738834)
				(mid 25.941873 -280.758357)
				(end 25.952958 -280.774902)
			)
			(arc
				(start 26.03246 -280.854404)
				(mid 26.048906 -280.86533)
				(end 26.068274 -280.869136)
			)
		)
		(stroke
			(width 0)
			(type solid)
		)
		(fill yes)
		(layer "F.Cu")
		(net "GND")
	)
	(gr_poly
		(pts
			(arc
				(start 32.8295 -257.314192)
				(mid 32.848887 -257.310242)
				(end 32.865314 -257.299206)
			)
			(arc
				(start 32.874204 -257.290316)
				(mid 32.885315 -257.273782)
				(end 32.88919 -257.254248)
			)
			(arc
				(start 32.88919 -256.096262)
				(mid 32.885289 -256.076739)
				(end 32.874204 -256.060194)
			)
			(xy 32.8676 -256.05359) (xy 32.849058 -256.04597)
			(arc
				(start 28.998418 -256.04597)
				(mid 28.978895 -256.049871)
				(end 28.96235 -256.060956)
			)
			(arc
				(start 28.910788 -256.112518)
				(mid 28.899677 -256.129052)
				(end 28.895802 -256.148586)
			)
			(xy 28.895802 -257.08229) (xy 28.896056 -257.08229)
			(arc
				(start 28.896056 -257.183636)
				(mid 28.899957 -257.203159)
				(end 28.911042 -257.219704)
			)
			(arc
				(start 28.990544 -257.299206)
				(mid 29.006961 -257.310268)
				(end 29.026358 -257.314192)
			)
		)
		(stroke
			(width 0)
			(type solid)
		)
		(fill yes)
		(layer "F.Cu")
		(net "GND")
	)
	(gr_poly
		(pts
			(arc
				(start 37.625782 -262.257032)
				(mid 37.645305 -262.253131)
				(end 37.66185 -262.242046)
			)
			(arc
				(start 37.713158 -262.190738)
				(mid 37.724269 -262.174204)
				(end 37.728144 -262.15467)
			)
			(arc
				(start 37.728144 -260.32714)
				(mid 37.724243 -260.307617)
				(end 37.713158 -260.291072)
			)
			(arc
				(start 37.586158 -260.164072)
				(mid 37.569624 -260.152961)
				(end 37.55009 -260.149086)
			)
			(arc
				(start 36.73094 -260.149086)
				(mid 36.711417 -260.152987)
				(end 36.694872 -260.164072)
			)
			(arc
				(start 36.588192 -260.270752)
				(mid 36.577266 -260.287198)
				(end 36.57346 -260.306566)
			)
			(arc
				(start 36.57346 -262.163814)
				(mid 36.577293 -262.183171)
				(end 36.588192 -262.199628)
			)
			(arc
				(start 36.63061 -262.242046)
				(mid 36.647144 -262.253157)
				(end 36.666678 -262.257032)
			)
		)
		(stroke
			(width 0)
			(type solid)
		)
		(fill yes)
		(layer "F.Cu")
		(net "GND")
	)
	(gr_poly
		(pts
			(arc
				(start 37.625782 -259.056632)
				(mid 37.645305 -259.052731)
				(end 37.66185 -259.041646)
			)
			(arc
				(start 37.713158 -258.990338)
				(mid 37.724269 -258.973804)
				(end 37.728144 -258.95427)
			)
			(arc
				(start 37.728144 -257.12674)
				(mid 37.724243 -257.107217)
				(end 37.713158 -257.090672)
			)
			(arc
				(start 37.586158 -256.963672)
				(mid 37.569624 -256.952561)
				(end 37.55009 -256.948686)
			)
			(arc
				(start 36.73094 -256.948686)
				(mid 36.711417 -256.952587)
				(end 36.694872 -256.963672)
			)
			(arc
				(start 36.588192 -257.070352)
				(mid 36.577266 -257.086798)
				(end 36.57346 -257.106166)
			)
			(arc
				(start 36.57346 -258.963414)
				(mid 36.577293 -258.982771)
				(end 36.588192 -258.999228)
			)
			(arc
				(start 36.63061 -259.041646)
				(mid 36.647144 -259.052757)
				(end 36.666678 -259.056632)
			)
		)
		(stroke
			(width 0)
			(type solid)
		)
		(fill yes)
		(layer "F.Cu")
		(net "GND")
	)
	(gr_poly
		(pts
			(xy 119.586248 -146.197828) (xy 119.586248 -137.817098) (xy 119.440198 -137.671048) (xy 105.791508 -137.671048)
			(xy 105.365296 -137.244836) (xy 105.365296 -134.00024) (xy 105.36936 -133.996176) (xy 105.36936 -133.915658)
			(xy 105.85577 -133.429248) (xy 115.421156 -133.429248) (xy 115.649502 -133.200902) (xy 115.649502 -132.96265)
			(xy 115.649502 -127.780288) (xy 115.626642 -127.757428) (xy 115.03914 -127.757428) (xy 114.9985 -127.716788)
			(xy 114.9985 -125.13945) (xy 114.951002 -125.091952) (xy 113.048288 -125.091952) (xy 112.985042 -125.155198)
			(xy 112.985042 -131.4958) (xy 112.546384 -131.934458) (xy 101.681026 -131.934458) (xy 100.932742 -132.682742)
			(xy 100.932742 -139.48156) (xy 100.932742 -140.799058) (xy 101.518466 -141.384782) (xy 103.746808 -141.384782)
			(xy 104.244902 -141.882876) (xy 104.244902 -146.132042) (xy 104.54132 -146.42846) (xy 119.355616 -146.42846)
		)
		(stroke
			(width 0)
			(type solid)
		)
		(fill yes)
		(layer "F.Cu")
		(net "P3V3_AUX")
	)
	(gr_poly
		(pts
			(arc
				(start 144.643602 -258.360672)
				(mid 144.663125 -258.356771)
				(end 144.67967 -258.345686)
			)
			(xy 144.686274 -258.339082) (xy 144.693894 -258.32054)
			(arc
				(start 144.693894 -254.4699)
				(mid 144.689993 -254.450377)
				(end 144.678908 -254.433832)
			)
			(arc
				(start 144.627346 -254.38227)
				(mid 144.610812 -254.371159)
				(end 144.591278 -254.367284)
			)
			(xy 143.657574 -254.367284) (xy 143.657574 -254.367538)
			(arc
				(start 143.556228 -254.367538)
				(mid 143.536705 -254.371439)
				(end 143.52016 -254.382524)
			)
			(arc
				(start 143.440658 -254.462026)
				(mid 143.429732 -254.478472)
				(end 143.425926 -254.49784)
			)
			(arc
				(start 143.425926 -258.300982)
				(mid 143.429759 -258.320339)
				(end 143.440658 -258.336796)
			)
			(arc
				(start 143.449548 -258.345686)
				(mid 143.466082 -258.356797)
				(end 143.485616 -258.360672)
			)
		)
		(stroke
			(width 0)
			(type solid)
		)
		(fill yes)
		(layer "F.Cu")
		(net "GND")
	)
	(gr_poly
		(pts
			(arc
				(start 145.971514 -280.869136)
				(mid 145.990871 -280.865303)
				(end 146.007328 -280.854404)
			)
			(arc
				(start 146.016218 -280.845514)
				(mid 146.027329 -280.82898)
				(end 146.031204 -280.809446)
			)
			(arc
				(start 146.031204 -279.65146)
				(mid 146.027303 -279.631937)
				(end 146.016218 -279.615392)
			)
			(xy 146.009614 -279.608788) (xy 145.991072 -279.601168)
			(arc
				(start 142.140432 -279.601168)
				(mid 142.120909 -279.605069)
				(end 142.104364 -279.616154)
			)
			(arc
				(start 142.052802 -279.667716)
				(mid 142.041691 -279.68425)
				(end 142.037816 -279.703784)
			)
			(xy 142.037816 -280.637488) (xy 142.03807 -280.637488)
			(arc
				(start 142.03807 -280.738834)
				(mid 142.041971 -280.758357)
				(end 142.053056 -280.774902)
			)
			(arc
				(start 142.132558 -280.854404)
				(mid 142.149004 -280.86533)
				(end 142.168372 -280.869136)
			)
		)
		(stroke
			(width 0)
			(type solid)
		)
		(fill yes)
		(layer "F.Cu")
		(net "GND")
	)
	(gr_poly
		(pts
			(arc
				(start 148.929598 -257.314192)
				(mid 148.948985 -257.310242)
				(end 148.965412 -257.299206)
			)
			(arc
				(start 148.974302 -257.290316)
				(mid 148.985413 -257.273782)
				(end 148.989288 -257.254248)
			)
			(arc
				(start 148.989288 -256.096262)
				(mid 148.985387 -256.076739)
				(end 148.974302 -256.060194)
			)
			(xy 148.967698 -256.05359) (xy 148.949156 -256.04597)
			(arc
				(start 145.098516 -256.04597)
				(mid 145.078993 -256.049871)
				(end 145.062448 -256.060956)
			)
			(arc
				(start 145.010886 -256.112518)
				(mid 144.999775 -256.129052)
				(end 144.9959 -256.148586)
			)
			(xy 144.9959 -257.08229) (xy 144.996154 -257.08229)
			(arc
				(start 144.996154 -257.183636)
				(mid 145.000055 -257.203159)
				(end 145.01114 -257.219704)
			)
			(arc
				(start 145.090642 -257.299206)
				(mid 145.107059 -257.310268)
				(end 145.126456 -257.314192)
			)
		)
		(stroke
			(width 0)
			(type solid)
		)
		(fill yes)
		(layer "F.Cu")
		(net "GND")
	)
	(gr_poly
		(pts
			(arc
				(start 153.72588 -262.257032)
				(mid 153.745403 -262.253131)
				(end 153.761948 -262.242046)
			)
			(arc
				(start 153.813256 -262.190738)
				(mid 153.824367 -262.174204)
				(end 153.828242 -262.15467)
			)
			(arc
				(start 153.828242 -260.32714)
				(mid 153.824341 -260.307617)
				(end 153.813256 -260.291072)
			)
			(arc
				(start 153.686256 -260.164072)
				(mid 153.669722 -260.152961)
				(end 153.650188 -260.149086)
			)
			(arc
				(start 152.831038 -260.149086)
				(mid 152.811515 -260.152987)
				(end 152.79497 -260.164072)
			)
			(arc
				(start 152.68829 -260.270752)
				(mid 152.677364 -260.287198)
				(end 152.673558 -260.306566)
			)
			(arc
				(start 152.673558 -262.163814)
				(mid 152.677391 -262.183171)
				(end 152.68829 -262.199628)
			)
			(arc
				(start 152.730708 -262.242046)
				(mid 152.747242 -262.253157)
				(end 152.766776 -262.257032)
			)
		)
		(stroke
			(width 0)
			(type solid)
		)
		(fill yes)
		(layer "F.Cu")
		(net "GND")
	)
	(gr_poly
		(pts
			(arc
				(start 153.72588 -259.056632)
				(mid 153.745403 -259.052731)
				(end 153.761948 -259.041646)
			)
			(arc
				(start 153.813256 -258.990338)
				(mid 153.824367 -258.973804)
				(end 153.828242 -258.95427)
			)
			(arc
				(start 153.828242 -257.12674)
				(mid 153.824341 -257.107217)
				(end 153.813256 -257.090672)
			)
			(arc
				(start 153.686256 -256.963672)
				(mid 153.669722 -256.952561)
				(end 153.650188 -256.948686)
			)
			(arc
				(start 152.831038 -256.948686)
				(mid 152.811515 -256.952587)
				(end 152.79497 -256.963672)
			)
			(arc
				(start 152.68829 -257.070352)
				(mid 152.677364 -257.086798)
				(end 152.673558 -257.106166)
			)
			(arc
				(start 152.673558 -258.963414)
				(mid 152.677391 -258.982771)
				(end 152.68829 -258.999228)
			)
			(arc
				(start 152.730708 -259.041646)
				(mid 152.747242 -259.052757)
				(end 152.766776 -259.056632)
			)
		)
		(stroke
			(width 0)
			(type solid)
		)
		(fill yes)
		(layer "F.Cu")
		(net "GND")
	)
	(gr_poly
		(pts
			(arc
				(start 252.431042 -397.963136)
				(mid 252.450565 -397.959235)
				(end 252.46711 -397.94815)
			)
			(arc
				(start 252.932438 -397.482822)
				(mid 252.943549 -397.466288)
				(end 252.947424 -397.446754)
			)
			(arc
				(start 252.947424 -392.961114)
				(mid 252.943523 -392.941591)
				(end 252.932438 -392.925046)
			)
			(arc
				(start 252.451362 -392.44397)
				(mid 252.434828 -392.432859)
				(end 252.415294 -392.428984)
			)
			(arc
				(start 245.508526 -392.428984)
				(mid 245.489003 -392.432885)
				(end 245.472458 -392.44397)
			)
			(arc
				(start 245.132606 -392.783822)
				(mid 245.121495 -392.800356)
				(end 245.11762 -392.81989)
			)
			(arc
				(start 245.11762 -397.640302)
				(mid 245.121521 -397.659825)
				(end 245.132606 -397.67637)
			)
			(arc
				(start 245.404386 -397.94815)
				(mid 245.42092 -397.959261)
				(end 245.440454 -397.963136)
			)
		)
		(stroke
			(width 0)
			(type solid)
		)
		(fill yes)
		(layer "F.Cu")
		(net "P12V_STBY_FUSE")
	)
	(gr_poly
		(pts
			(arc
				(start 260.743446 -258.360672)
				(mid 260.762969 -258.356771)
				(end 260.779514 -258.345686)
			)
			(xy 260.786118 -258.339082) (xy 260.793738 -258.32054)
			(arc
				(start 260.793738 -254.4699)
				(mid 260.789837 -254.450377)
				(end 260.778752 -254.433832)
			)
			(arc
				(start 260.72719 -254.38227)
				(mid 260.710656 -254.371159)
				(end 260.691122 -254.367284)
			)
			(xy 259.757418 -254.367284) (xy 259.757418 -254.367538)
			(arc
				(start 259.656072 -254.367538)
				(mid 259.636549 -254.371439)
				(end 259.620004 -254.382524)
			)
			(arc
				(start 259.540502 -254.462026)
				(mid 259.529576 -254.478472)
				(end 259.52577 -254.49784)
			)
			(arc
				(start 259.52577 -258.300982)
				(mid 259.529603 -258.320339)
				(end 259.540502 -258.336796)
			)
			(arc
				(start 259.549392 -258.345686)
				(mid 259.565926 -258.356797)
				(end 259.58546 -258.360672)
			)
		)
		(stroke
			(width 0)
			(type solid)
		)
		(fill yes)
		(layer "F.Cu")
		(net "GND")
	)
	(gr_poly
		(pts
			(arc
				(start 262.071358 -280.869136)
				(mid 262.090715 -280.865303)
				(end 262.107172 -280.854404)
			)
			(arc
				(start 262.116062 -280.845514)
				(mid 262.127173 -280.82898)
				(end 262.131048 -280.809446)
			)
			(arc
				(start 262.131048 -279.65146)
				(mid 262.127147 -279.631937)
				(end 262.116062 -279.615392)
			)
			(xy 262.109458 -279.608788) (xy 262.090916 -279.601168)
			(arc
				(start 258.240276 -279.601168)
				(mid 258.220753 -279.605069)
				(end 258.204208 -279.616154)
			)
			(arc
				(start 258.152646 -279.667716)
				(mid 258.141535 -279.68425)
				(end 258.13766 -279.703784)
			)
			(xy 258.13766 -280.637488) (xy 258.137914 -280.637488)
			(arc
				(start 258.137914 -280.738834)
				(mid 258.141815 -280.758357)
				(end 258.1529 -280.774902)
			)
			(arc
				(start 258.232402 -280.854404)
				(mid 258.248848 -280.86533)
				(end 258.268216 -280.869136)
			)
		)
		(stroke
			(width 0)
			(type solid)
		)
		(fill yes)
		(layer "F.Cu")
		(net "GND")
	)
	(gr_poly
		(pts
			(arc
				(start 265.029442 -257.314192)
				(mid 265.048829 -257.310242)
				(end 265.065256 -257.299206)
			)
			(arc
				(start 265.074146 -257.290316)
				(mid 265.085257 -257.273782)
				(end 265.089132 -257.254248)
			)
			(arc
				(start 265.089132 -256.096262)
				(mid 265.085231 -256.076739)
				(end 265.074146 -256.060194)
			)
			(xy 265.067542 -256.05359) (xy 265.049 -256.04597)
			(arc
				(start 261.19836 -256.04597)
				(mid 261.178837 -256.049871)
				(end 261.162292 -256.060956)
			)
			(arc
				(start 261.11073 -256.112518)
				(mid 261.099619 -256.129052)
				(end 261.095744 -256.148586)
			)
			(xy 261.095744 -257.08229) (xy 261.095998 -257.08229)
			(arc
				(start 261.095998 -257.183636)
				(mid 261.099899 -257.203159)
				(end 261.110984 -257.219704)
			)
			(arc
				(start 261.190486 -257.299206)
				(mid 261.206903 -257.310268)
				(end 261.2263 -257.314192)
			)
		)
		(stroke
			(width 0)
			(type solid)
		)
		(fill yes)
		(layer "F.Cu")
		(net "GND")
	)
	(gr_poly
		(pts
			(arc
				(start 269.825724 -262.257032)
				(mid 269.845247 -262.253131)
				(end 269.861792 -262.242046)
			)
			(arc
				(start 269.9131 -262.190738)
				(mid 269.924211 -262.174204)
				(end 269.928086 -262.15467)
			)
			(arc
				(start 269.928086 -260.32714)
				(mid 269.924185 -260.307617)
				(end 269.9131 -260.291072)
			)
			(arc
				(start 269.7861 -260.164072)
				(mid 269.769566 -260.152961)
				(end 269.750032 -260.149086)
			)
			(arc
				(start 268.930882 -260.149086)
				(mid 268.911359 -260.152987)
				(end 268.894814 -260.164072)
			)
			(arc
				(start 268.788134 -260.270752)
				(mid 268.777208 -260.287198)
				(end 268.773402 -260.306566)
			)
			(arc
				(start 268.773402 -262.163814)
				(mid 268.777235 -262.183171)
				(end 268.788134 -262.199628)
			)
			(arc
				(start 268.830552 -262.242046)
				(mid 268.847086 -262.253157)
				(end 268.86662 -262.257032)
			)
		)
		(stroke
			(width 0)
			(type solid)
		)
		(fill yes)
		(layer "F.Cu")
		(net "GND")
	)
	(gr_poly
		(pts
			(arc
				(start 269.825724 -259.056632)
				(mid 269.845247 -259.052731)
				(end 269.861792 -259.041646)
			)
			(arc
				(start 269.9131 -258.990338)
				(mid 269.924211 -258.973804)
				(end 269.928086 -258.95427)
			)
			(arc
				(start 269.928086 -257.12674)
				(mid 269.924185 -257.107217)
				(end 269.9131 -257.090672)
			)
			(arc
				(start 269.7861 -256.963672)
				(mid 269.769566 -256.952561)
				(end 269.750032 -256.948686)
			)
			(arc
				(start 268.930882 -256.948686)
				(mid 268.911359 -256.952587)
				(end 268.894814 -256.963672)
			)
			(arc
				(start 268.788134 -257.070352)
				(mid 268.777208 -257.086798)
				(end 268.773402 -257.106166)
			)
			(arc
				(start 268.773402 -258.963414)
				(mid 268.777235 -258.982771)
				(end 268.788134 -258.999228)
			)
			(arc
				(start 268.830552 -259.041646)
				(mid 268.847086 -259.052757)
				(end 268.86662 -259.056632)
			)
		)
		(stroke
			(width 0)
			(type solid)
		)
		(fill yes)
		(layer "F.Cu")
		(net "GND")
	)
	(gr_poly
		(pts
			(arc
				(start 340.10727 -88.85301)
				(mid 340.126793 -88.849109)
				(end 340.143338 -88.838024)
			)
			(arc
				(start 340.183978 -88.797384)
				(mid 340.195089 -88.78085)
				(end 340.198964 -88.761316)
			)
			(arc
				(start 340.198964 -84.75599)
				(mid 340.195063 -84.736467)
				(end 340.183978 -84.719922)
			)
			(arc
				(start 340.144862 -84.680806)
				(mid 340.128328 -84.669695)
				(end 340.108794 -84.66582)
			)
			(arc
				(start 336.12328 -84.66582)
				(mid 336.103757 -84.669721)
				(end 336.087212 -84.680806)
			)
			(arc
				(start 336.015838 -84.75218)
				(mid 336.004727 -84.768714)
				(end 336.000852 -84.788248)
			)
			(arc
				(start 336.000852 -88.749124)
				(mid 336.004753 -88.768647)
				(end 336.015838 -88.785192)
			)
			(arc
				(start 336.06867 -88.838024)
				(mid 336.085204 -88.849135)
				(end 336.104738 -88.85301)
			)
		)
		(stroke
			(width 0)
			(type solid)
		)
		(fill yes)
		(layer "F.Cu")
		(net "GND")
	)
	(gr_poly
		(pts
			(arc
				(start 350.113854 -92.142056)
				(mid 350.133377 -92.138155)
				(end 350.149922 -92.12707)
			)
			(arc
				(start 350.200976 -92.076016)
				(mid 350.212087 -92.059482)
				(end 350.215962 -92.039948)
			)
			(arc
				(start 350.215962 -81.197196)
				(mid 350.212061 -81.177673)
				(end 350.200976 -81.161128)
			)
			(arc
				(start 350.1771 -81.137252)
				(mid 350.160566 -81.126141)
				(end 350.141032 -81.122266)
			)
			(arc
				(start 349.138748 -81.122266)
				(mid 349.119225 -81.126167)
				(end 349.10268 -81.137252)
			)
			(arc
				(start 348.961456 -81.278476)
				(mid 348.950345 -81.29501)
				(end 348.94647 -81.314544)
			)
			(arc
				(start 348.94647 -92.01277)
				(mid 348.950371 -92.032293)
				(end 348.961456 -92.048838)
			)
			(arc
				(start 349.039688 -92.12707)
				(mid 349.056222 -92.138181)
				(end 349.075756 -92.142056)
			)
		)
		(stroke
			(width 0)
			(type solid)
		)
		(fill yes)
		(layer "F.Cu")
		(net "P3V3_AUX")
	)
	(gr_poly
		(pts
			(arc
				(start 378.171456 -280.869136)
				(mid 378.190813 -280.865303)
				(end 378.20727 -280.854404)
			)
			(arc
				(start 378.21616 -280.845514)
				(mid 378.227271 -280.82898)
				(end 378.231146 -280.809446)
			)
			(arc
				(start 378.231146 -279.65146)
				(mid 378.227245 -279.631937)
				(end 378.21616 -279.615392)
			)
			(xy 378.209556 -279.608788) (xy 378.191014 -279.601168)
			(arc
				(start 374.340374 -279.601168)
				(mid 374.320851 -279.605069)
				(end 374.304306 -279.616154)
			)
			(arc
				(start 374.252744 -279.667716)
				(mid 374.241633 -279.68425)
				(end 374.237758 -279.703784)
			)
			(xy 374.237758 -280.637488) (xy 374.238012 -280.637488)
			(arc
				(start 374.238012 -280.738834)
				(mid 374.241913 -280.758357)
				(end 374.252998 -280.774902)
			)
			(arc
				(start 374.3325 -280.854404)
				(mid 374.348946 -280.86533)
				(end 374.368314 -280.869136)
			)
		)
		(stroke
			(width 0)
			(type solid)
		)
		(fill yes)
		(layer "F.Cu")
		(net "GND")
	)
	(gr_poly
		(pts
			(xy 189.555882 -55.681118) (xy 189.555882 -53.564282) (xy 189.5348 -53.5432) (xy 189.099952 -53.5432)
			(xy 189.096396 -53.539644) (xy 188.847984 -53.539644) (xy 188.774324 -53.465984) (xy 188.774324 -53.217572)
			(xy 188.774324 -52.019708) (xy 186.115198 -49.360582) (xy 186.115198 -48.054514) (xy 187.038996 -47.130716)
			(xy 188.249306 -47.130716) (xy 188.388498 -46.991524) (xy 188.388498 -46.65726) (xy 188.641228 -46.40453)
			(xy 189.132464 -46.40453) (xy 189.230762 -46.306232) (xy 189.793118 -46.306232) (xy 189.83833 -46.26102)
			(xy 189.83833 -46.155356) (xy 189.758828 -46.075854) (xy 188.943488 -46.075854) (xy 188.841634 -45.974)
			(xy 188.830204 -45.974) (xy 188.501782 -45.645578) (xy 182.009796 -45.645578) (xy 181.676548 -45.978826)
			(xy 181.676548 -55.041292) (xy 181.90591 -55.270654) (xy 188.529214 -55.270654) (xy 189.039246 -55.780686)
			(xy 189.456314 -55.780686)
		)
		(stroke
			(width 0)
			(type solid)
		)
		(fill yes)
		(layer "F.Cu")
		(net "P12V_SSD6_R")
	)
	(gr_poly
		(pts
			(xy 29.726636 -262.209026) (xy 30.817312 -262.209026) (xy 30.823408 -262.215376)
			(arc
				(start 32.80537 -262.215376)
				(mid 32.824893 -262.211475)
				(end 32.841438 -262.20039)
			)
			(arc
				(start 32.845756 -262.196072)
				(mid 32.856867 -262.179538)
				(end 32.860742 -262.160004)
			)
			(arc
				(start 32.860742 -260.857238)
				(mid 32.856841 -260.837715)
				(end 32.845756 -260.82117)
			)
			(arc
				(start 32.808418 -260.783832)
				(mid 32.791884 -260.772721)
				(end 32.77235 -260.768846)
			)
			(arc
				(start 29.107384 -260.768846)
				(mid 29.087861 -260.772747)
				(end 29.071316 -260.783832)
			)
			(arc
				(start 28.92298 -260.932168)
				(mid 28.911869 -260.948702)
				(end 28.907994 -260.968236)
			)
			(xy 28.907994 -261.303516) (xy 28.673552 -261.537958) (xy 25.774904 -261.537958) (xy 25.651206 -261.661656)
			(xy 25.651206 -262.291576) (xy 25.914604 -262.554974) (xy 29.380688 -262.554974)
		)
		(stroke
			(width 0)
			(type solid)
		)
		(fill yes)
		(layer "F.Cu")
		(net "P1V8_PLL0_PEX0")
	)
	(gr_poly
		(pts
			(arc
				(start 29.847286 -301.772574)
				(mid 29.866809 -301.768673)
				(end 29.883354 -301.757588)
			)
			(arc
				(start 29.887672 -301.75327)
				(mid 29.898783 -301.736736)
				(end 29.902658 -301.717202)
			)
			(arc
				(start 29.902658 -300.414436)
				(mid 29.898757 -300.394913)
				(end 29.887672 -300.378368)
			)
			(arc
				(start 29.850334 -300.34103)
				(mid 29.8338 -300.329919)
				(end 29.814266 -300.326044)
			)
			(arc
				(start 26.1493 -300.326044)
				(mid 26.129777 -300.329945)
				(end 26.113232 -300.34103)
			)
			(arc
				(start 25.964896 -300.489366)
				(mid 25.953785 -300.5059)
				(end 25.94991 -300.525434)
			)
			(arc
				(start 25.94991 -301.432468)
				(mid 25.953811 -301.451991)
				(end 25.964896 -301.468536)
			)
			(arc
				(start 26.247598 -301.751238)
				(mid 26.264132 -301.762349)
				(end 26.283666 -301.766224)
			)
			(xy 27.859228 -301.766224) (xy 27.865324 -301.772574)
		)
		(stroke
			(width 0)
			(type solid)
		)
		(fill yes)
		(layer "F.Cu")
		(net "P1V8_PLL0_PEX0")
	)
	(gr_poly
		(pts
			(arc
				(start 29.847286 -298.572174)
				(mid 29.866809 -298.568273)
				(end 29.883354 -298.557188)
			)
			(arc
				(start 29.887672 -298.55287)
				(mid 29.898783 -298.536336)
				(end 29.902658 -298.516802)
			)
			(arc
				(start 29.902658 -297.214036)
				(mid 29.898757 -297.194513)
				(end 29.887672 -297.177968)
			)
			(arc
				(start 29.850334 -297.14063)
				(mid 29.8338 -297.129519)
				(end 29.814266 -297.125644)
			)
			(arc
				(start 26.1493 -297.125644)
				(mid 26.129777 -297.129545)
				(end 26.113232 -297.14063)
			)
			(arc
				(start 25.964896 -297.288966)
				(mid 25.953785 -297.3055)
				(end 25.94991 -297.325034)
			)
			(arc
				(start 25.94991 -298.232068)
				(mid 25.953811 -298.251591)
				(end 25.964896 -298.268136)
			)
			(arc
				(start 26.247598 -298.550838)
				(mid 26.264132 -298.561949)
				(end 26.283666 -298.565824)
			)
			(xy 27.859228 -298.565824) (xy 27.865324 -298.572174)
		)
		(stroke
			(width 0)
			(type solid)
		)
		(fill yes)
		(layer "F.Cu")
		(net "P1V8_PLL0_PEX0")
	)
	(gr_poly
		(pts
			(arc
				(start 29.847286 -292.171374)
				(mid 29.866809 -292.167473)
				(end 29.883354 -292.156388)
			)
			(arc
				(start 29.887672 -292.15207)
				(mid 29.898783 -292.135536)
				(end 29.902658 -292.116002)
			)
			(arc
				(start 29.902658 -290.813236)
				(mid 29.898757 -290.793713)
				(end 29.887672 -290.777168)
			)
			(arc
				(start 29.850334 -290.73983)
				(mid 29.8338 -290.728719)
				(end 29.814266 -290.724844)
			)
			(arc
				(start 26.1493 -290.724844)
				(mid 26.129777 -290.728745)
				(end 26.113232 -290.73983)
			)
			(arc
				(start 25.964896 -290.888166)
				(mid 25.953785 -290.9047)
				(end 25.94991 -290.924234)
			)
			(arc
				(start 25.94991 -291.831268)
				(mid 25.953811 -291.850791)
				(end 25.964896 -291.867336)
			)
			(arc
				(start 26.247598 -292.150038)
				(mid 26.264132 -292.161149)
				(end 26.283666 -292.165024)
			)
			(xy 27.859228 -292.165024) (xy 27.865324 -292.171374)
		)
		(stroke
			(width 0)
			(type solid)
		)
		(fill yes)
		(layer "F.Cu")
		(net "P1V8_PLL0_PEX0")
	)
	(gr_poly
		(pts
			(arc
				(start 29.847286 -288.970974)
				(mid 29.866809 -288.967073)
				(end 29.883354 -288.955988)
			)
			(arc
				(start 29.887672 -288.95167)
				(mid 29.898783 -288.935136)
				(end 29.902658 -288.915602)
			)
			(arc
				(start 29.902658 -287.612836)
				(mid 29.898757 -287.593313)
				(end 29.887672 -287.576768)
			)
			(arc
				(start 29.850334 -287.53943)
				(mid 29.8338 -287.528319)
				(end 29.814266 -287.524444)
			)
			(arc
				(start 26.1493 -287.524444)
				(mid 26.129777 -287.528345)
				(end 26.113232 -287.53943)
			)
			(arc
				(start 25.964896 -287.687766)
				(mid 25.953785 -287.7043)
				(end 25.94991 -287.723834)
			)
			(arc
				(start 25.94991 -288.630868)
				(mid 25.953811 -288.650391)
				(end 25.964896 -288.666936)
			)
			(arc
				(start 26.247598 -288.949638)
				(mid 26.264132 -288.960749)
				(end 26.283666 -288.964624)
			)
			(xy 27.859228 -288.964624) (xy 27.865324 -288.970974)
		)
		(stroke
			(width 0)
			(type solid)
		)
		(fill yes)
		(layer "F.Cu")
		(net "P1V8_PLL0_PEX0")
	)
	(gr_poly
		(pts
			(arc
				(start 29.847286 -282.570174)
				(mid 29.866809 -282.566273)
				(end 29.883354 -282.555188)
			)
			(arc
				(start 29.887672 -282.55087)
				(mid 29.898783 -282.534336)
				(end 29.902658 -282.514802)
			)
			(arc
				(start 29.902658 -281.212036)
				(mid 29.898757 -281.192513)
				(end 29.887672 -281.175968)
			)
			(arc
				(start 29.850334 -281.13863)
				(mid 29.8338 -281.127519)
				(end 29.814266 -281.123644)
			)
			(arc
				(start 26.1493 -281.123644)
				(mid 26.129777 -281.127545)
				(end 26.113232 -281.13863)
			)
			(arc
				(start 25.964896 -281.286966)
				(mid 25.953785 -281.3035)
				(end 25.94991 -281.323034)
			)
			(arc
				(start 25.94991 -282.230068)
				(mid 25.953811 -282.249591)
				(end 25.964896 -282.266136)
			)
			(arc
				(start 26.247598 -282.548838)
				(mid 26.264132 -282.559949)
				(end 26.283666 -282.563824)
			)
			(xy 27.859228 -282.563824) (xy 27.865324 -282.570174)
		)
		(stroke
			(width 0)
			(type solid)
		)
		(fill yes)
		(layer "F.Cu")
		(net "P1V8_PLL0_PEX0")
	)
	(gr_poly
		(pts
			(arc
				(start 29.871416 -300.071536)
				(mid 29.890773 -300.067703)
				(end 29.90723 -300.056804)
			)
			(arc
				(start 29.91612 -300.047914)
				(mid 29.927231 -300.03138)
				(end 29.931106 -300.011846)
			)
			(xy 29.931106 -298.832778) (xy 29.924756 -298.826428) (xy 27.756866 -298.826428) (xy 27.75077 -298.820332)
			(arc
				(start 26.178256 -298.820332)
				(mid 26.158869 -298.816382)
				(end 26.142442 -298.805346)
			)
			(xy 26.140664 -298.803568)
			(arc
				(start 26.040334 -298.803568)
				(mid 26.020811 -298.807469)
				(end 26.004266 -298.818554)
			)
			(arc
				(start 25.952704 -298.870116)
				(mid 25.941593 -298.88665)
				(end 25.937718 -298.906184)
			)
			(xy 25.937718 -299.839888) (xy 25.937972 -299.839888)
			(arc
				(start 25.937972 -299.941234)
				(mid 25.941873 -299.960757)
				(end 25.952958 -299.977302)
			)
			(xy 25.977596 -300.00194) (xy 26.536904 -300.00194) (xy 26.6065 -300.071536)
		)
		(stroke
			(width 0)
			(type solid)
		)
		(fill yes)
		(layer "F.Cu")
		(net "GND")
	)
	(gr_poly
		(pts
			(arc
				(start 32.80537 -259.014976)
				(mid 32.824893 -259.011075)
				(end 32.841438 -258.99999)
			)
			(arc
				(start 32.845756 -258.995672)
				(mid 32.856867 -258.979138)
				(end 32.860742 -258.959604)
			)
			(arc
				(start 32.860742 -257.656838)
				(mid 32.856841 -257.637315)
				(end 32.845756 -257.62077)
			)
			(arc
				(start 32.808418 -257.583432)
				(mid 32.791884 -257.572321)
				(end 32.77235 -257.568446)
			)
			(arc
				(start 29.107384 -257.568446)
				(mid 29.087861 -257.572347)
				(end 29.071316 -257.583432)
			)
			(arc
				(start 28.92298 -257.731768)
				(mid 28.911869 -257.748302)
				(end 28.907994 -257.767836)
			)
			(arc
				(start 28.907994 -258.67487)
				(mid 28.911895 -258.694393)
				(end 28.92298 -258.710938)
			)
			(arc
				(start 29.205682 -258.99364)
				(mid 29.222216 -259.004751)
				(end 29.24175 -259.008626)
			)
			(xy 30.817312 -259.008626) (xy 30.823408 -259.014976)
		)
		(stroke
			(width 0)
			(type solid)
		)
		(fill yes)
		(layer "F.Cu")
		(net "P1V8_PLL0_PEX0")
	)
	(gr_poly
		(pts
			(xy 73.455784 -55.681118) (xy 73.455784 -53.54193) (xy 73.402952 -53.489098) (xy 73.071736 -53.489098)
			(xy 73.058528 -53.502306) (xy 72.95896 -53.502306) (xy 72.752966 -53.502306) (xy 72.674226 -53.423566)
			(xy 72.674226 -53.217572) (xy 72.674226 -52.019708) (xy 70.0151 -49.360582) (xy 70.0151 -48.054514)
			(xy 70.938898 -47.130716) (xy 72.149208 -47.130716) (xy 72.2884 -46.991524) (xy 72.2884 -46.65726)
			(xy 72.54113 -46.40453) (xy 73.032366 -46.40453) (xy 73.130664 -46.306232) (xy 73.69302 -46.306232)
			(xy 73.738232 -46.26102) (xy 73.738232 -46.155356) (xy 73.65873 -46.075854) (xy 72.84339 -46.075854)
			(xy 72.741536 -45.974) (xy 72.730106 -45.974) (xy 72.401684 -45.645578) (xy 65.909698 -45.645578)
			(xy 65.57645 -45.978826) (xy 65.57645 -55.041292) (xy 65.805812 -55.270654) (xy 72.429116 -55.270654)
			(xy 72.939148 -55.780686) (xy 73.356216 -55.780686)
		)
		(stroke
			(width 0)
			(type solid)
		)
		(fill yes)
		(layer "F.Cu")
		(net "P12V_SSD2_R")
	)
	(gr_poly
		(pts
			(xy 137.555986 -55.681118) (xy 137.555986 -53.54193) (xy 137.503154 -53.489098) (xy 137.171938 -53.489098)
			(xy 137.15873 -53.502306) (xy 137.059162 -53.502306) (xy 136.85393 -53.502306) (xy 136.774428 -53.422804)
			(xy 136.774428 -53.217572) (xy 136.774428 -52.019708) (xy 134.115302 -49.360582) (xy 134.115302 -48.054514)
			(xy 135.0391 -47.130716) (xy 136.24941 -47.130716) (xy 136.388602 -46.991524) (xy 136.388602 -46.65726)
			(xy 136.641332 -46.40453) (xy 137.132568 -46.40453) (xy 137.230866 -46.306232) (xy 137.793222 -46.306232)
			(xy 137.838434 -46.26102) (xy 137.838434 -46.155356) (xy 137.758932 -46.075854) (xy 136.943592 -46.075854)
			(xy 136.841738 -45.974) (xy 136.830308 -45.974) (xy 136.501886 -45.645578) (xy 130.0099 -45.645578)
			(xy 129.676652 -45.978826) (xy 129.676652 -55.041292) (xy 129.906014 -55.270654) (xy 136.529318 -55.270654)
			(xy 137.03935 -55.780686) (xy 137.456418 -55.780686)
		)
		(stroke
			(width 0)
			(type solid)
		)
		(fill yes)
		(layer "F.Cu")
		(net "P12V_SSD4_R")
	)
	(gr_poly
		(pts
			(arc
				(start 145.947384 -301.772574)
				(mid 145.966907 -301.768673)
				(end 145.983452 -301.757588)
			)
			(arc
				(start 145.98777 -301.75327)
				(mid 145.998881 -301.736736)
				(end 146.002756 -301.717202)
			)
			(arc
				(start 146.002756 -300.414436)
				(mid 145.998855 -300.394913)
				(end 145.98777 -300.378368)
			)
			(arc
				(start 145.950432 -300.34103)
				(mid 145.933898 -300.329919)
				(end 145.914364 -300.326044)
			)
			(arc
				(start 142.249398 -300.326044)
				(mid 142.229875 -300.329945)
				(end 142.21333 -300.34103)
			)
			(arc
				(start 142.064994 -300.489366)
				(mid 142.053883 -300.5059)
				(end 142.050008 -300.525434)
			)
			(arc
				(start 142.050008 -301.432468)
				(mid 142.053909 -301.451991)
				(end 142.064994 -301.468536)
			)
			(arc
				(start 142.347696 -301.751238)
				(mid 142.36423 -301.762349)
				(end 142.383764 -301.766224)
			)
			(xy 143.959326 -301.766224) (xy 143.965422 -301.772574)
		)
		(stroke
			(width 0)
			(type solid)
		)
		(fill yes)
		(layer "F.Cu")
		(net "P1V8_PLL0_PEX1")
	)
	(gr_poly
		(pts
			(arc
				(start 145.947384 -298.572174)
				(mid 145.966907 -298.568273)
				(end 145.983452 -298.557188)
			)
			(arc
				(start 145.98777 -298.55287)
				(mid 145.998881 -298.536336)
				(end 146.002756 -298.516802)
			)
			(arc
				(start 146.002756 -297.214036)
				(mid 145.998855 -297.194513)
				(end 145.98777 -297.177968)
			)
			(arc
				(start 145.950432 -297.14063)
				(mid 145.933898 -297.129519)
				(end 145.914364 -297.125644)
			)
			(arc
				(start 142.249398 -297.125644)
				(mid 142.229875 -297.129545)
				(end 142.21333 -297.14063)
			)
			(arc
				(start 142.064994 -297.288966)
				(mid 142.053883 -297.3055)
				(end 142.050008 -297.325034)
			)
			(arc
				(start 142.050008 -298.232068)
				(mid 142.053909 -298.251591)
				(end 142.064994 -298.268136)
			)
			(arc
				(start 142.347696 -298.550838)
				(mid 142.36423 -298.561949)
				(end 142.383764 -298.565824)
			)
			(xy 143.959326 -298.565824) (xy 143.965422 -298.572174)
		)
		(stroke
			(width 0)
			(type solid)
		)
		(fill yes)
		(layer "F.Cu")
		(net "P1V8_PLL0_PEX1")
	)
	(gr_poly
		(pts
			(arc
				(start 145.947384 -295.371774)
				(mid 145.966907 -295.367873)
				(end 145.983452 -295.356788)
			)
			(arc
				(start 145.98777 -295.35247)
				(mid 145.998881 -295.335936)
				(end 146.002756 -295.316402)
			)
			(arc
				(start 146.002756 -294.013636)
				(mid 145.998855 -293.994113)
				(end 145.98777 -293.977568)
			)
			(arc
				(start 145.950432 -293.94023)
				(mid 145.933898 -293.929119)
				(end 145.914364 -293.925244)
			)
			(arc
				(start 142.249398 -293.925244)
				(mid 142.229875 -293.929145)
				(end 142.21333 -293.94023)
			)
			(arc
				(start 142.064994 -294.088566)
				(mid 142.053883 -294.1051)
				(end 142.050008 -294.124634)
			)
			(arc
				(start 142.050008 -295.031668)
				(mid 142.053909 -295.051191)
				(end 142.064994 -295.067736)
			)
			(arc
				(start 142.347696 -295.350438)
				(mid 142.36423 -295.361549)
				(end 142.383764 -295.365424)
			)
			(xy 143.959326 -295.365424) (xy 143.965422 -295.371774)
		)
		(stroke
			(width 0)
			(type solid)
		)
		(fill yes)
		(layer "F.Cu")
		(net "P1V8_PLL0_PEX1")
	)
	(gr_poly
		(pts
			(arc
				(start 145.947384 -292.171374)
				(mid 145.966907 -292.167473)
				(end 145.983452 -292.156388)
			)
			(arc
				(start 145.98777 -292.15207)
				(mid 145.998881 -292.135536)
				(end 146.002756 -292.116002)
			)
			(arc
				(start 146.002756 -290.813236)
				(mid 145.998855 -290.793713)
				(end 145.98777 -290.777168)
			)
			(arc
				(start 145.950432 -290.73983)
				(mid 145.933898 -290.728719)
				(end 145.914364 -290.724844)
			)
			(arc
				(start 142.249398 -290.724844)
				(mid 142.229875 -290.728745)
				(end 142.21333 -290.73983)
			)
			(arc
				(start 142.064994 -290.888166)
				(mid 142.053883 -290.9047)
				(end 142.050008 -290.924234)
			)
			(arc
				(start 142.050008 -291.831268)
				(mid 142.053909 -291.850791)
				(end 142.064994 -291.867336)
			)
			(arc
				(start 142.347696 -292.150038)
				(mid 142.36423 -292.161149)
				(end 142.383764 -292.165024)
			)
			(xy 143.959326 -292.165024) (xy 143.965422 -292.171374)
		)
		(stroke
			(width 0)
			(type solid)
		)
		(fill yes)
		(layer "F.Cu")
		(net "P1V8_PLL0_PEX1")
	)
	(gr_poly
		(pts
			(arc
				(start 145.947384 -288.970974)
				(mid 145.966907 -288.967073)
				(end 145.983452 -288.955988)
			)
			(arc
				(start 145.98777 -288.95167)
				(mid 145.998881 -288.935136)
				(end 146.002756 -288.915602)
			)
			(arc
				(start 146.002756 -287.612836)
				(mid 145.998855 -287.593313)
				(end 145.98777 -287.576768)
			)
			(arc
				(start 145.950432 -287.53943)
				(mid 145.933898 -287.528319)
				(end 145.914364 -287.524444)
			)
			(arc
				(start 142.249398 -287.524444)
				(mid 142.229875 -287.528345)
				(end 142.21333 -287.53943)
			)
			(arc
				(start 142.064994 -287.687766)
				(mid 142.053883 -287.7043)
				(end 142.050008 -287.723834)
			)
			(arc
				(start 142.050008 -288.630868)
				(mid 142.053909 -288.650391)
				(end 142.064994 -288.666936)
			)
			(arc
				(start 142.347696 -288.949638)
				(mid 142.36423 -288.960749)
				(end 142.383764 -288.964624)
			)
			(xy 143.959326 -288.964624) (xy 143.965422 -288.970974)
		)
		(stroke
			(width 0)
			(type solid)
		)
		(fill yes)
		(layer "F.Cu")
		(net "P1V8_PLL0_PEX1")
	)
	(gr_poly
		(pts
			(arc
				(start 145.947384 -285.770574)
				(mid 145.966907 -285.766673)
				(end 145.983452 -285.755588)
			)
			(arc
				(start 145.98777 -285.75127)
				(mid 145.998881 -285.734736)
				(end 146.002756 -285.715202)
			)
			(arc
				(start 146.002756 -284.412436)
				(mid 145.998855 -284.392913)
				(end 145.98777 -284.376368)
			)
			(arc
				(start 145.950432 -284.33903)
				(mid 145.933898 -284.327919)
				(end 145.914364 -284.324044)
			)
			(arc
				(start 142.249398 -284.324044)
				(mid 142.229875 -284.327945)
				(end 142.21333 -284.33903)
			)
			(arc
				(start 142.064994 -284.487366)
				(mid 142.053883 -284.5039)
				(end 142.050008 -284.523434)
			)
			(arc
				(start 142.050008 -285.430468)
				(mid 142.053909 -285.449991)
				(end 142.064994 -285.466536)
			)
			(arc
				(start 142.347696 -285.749238)
				(mid 142.36423 -285.760349)
				(end 142.383764 -285.764224)
			)
			(xy 143.959326 -285.764224) (xy 143.965422 -285.770574)
		)
		(stroke
			(width 0)
			(type solid)
		)
		(fill yes)
		(layer "F.Cu")
		(net "P1V8_PLL0_PEX1")
	)
	(gr_poly
		(pts
			(arc
				(start 145.947384 -282.570174)
				(mid 145.966907 -282.566273)
				(end 145.983452 -282.555188)
			)
			(arc
				(start 145.98777 -282.55087)
				(mid 145.998881 -282.534336)
				(end 146.002756 -282.514802)
			)
			(arc
				(start 146.002756 -281.212036)
				(mid 145.998855 -281.192513)
				(end 145.98777 -281.175968)
			)
			(arc
				(start 145.950432 -281.13863)
				(mid 145.933898 -281.127519)
				(end 145.914364 -281.123644)
			)
			(arc
				(start 142.249398 -281.123644)
				(mid 142.229875 -281.127545)
				(end 142.21333 -281.13863)
			)
			(arc
				(start 142.064994 -281.286966)
				(mid 142.053883 -281.3035)
				(end 142.050008 -281.323034)
			)
			(arc
				(start 142.050008 -282.230068)
				(mid 142.053909 -282.249591)
				(end 142.064994 -282.266136)
			)
			(arc
				(start 142.347696 -282.548838)
				(mid 142.36423 -282.559949)
				(end 142.383764 -282.563824)
			)
			(xy 143.959326 -282.563824) (xy 143.965422 -282.570174)
		)
		(stroke
			(width 0)
			(type solid)
		)
		(fill yes)
		(layer "F.Cu")
		(net "P1V8_PLL0_PEX1")
	)
	(gr_poly
		(pts
			(arc
				(start 148.905468 -259.014976)
				(mid 148.924991 -259.011075)
				(end 148.941536 -258.99999)
			)
			(arc
				(start 148.945854 -258.995672)
				(mid 148.956965 -258.979138)
				(end 148.96084 -258.959604)
			)
			(arc
				(start 148.96084 -257.656838)
				(mid 148.956939 -257.637315)
				(end 148.945854 -257.62077)
			)
			(arc
				(start 148.908516 -257.583432)
				(mid 148.891982 -257.572321)
				(end 148.872448 -257.568446)
			)
			(arc
				(start 145.207482 -257.568446)
				(mid 145.187959 -257.572347)
				(end 145.171414 -257.583432)
			)
			(arc
				(start 145.023078 -257.731768)
				(mid 145.011967 -257.748302)
				(end 145.008092 -257.767836)
			)
			(arc
				(start 145.008092 -258.67487)
				(mid 145.011993 -258.694393)
				(end 145.023078 -258.710938)
			)
			(arc
				(start 145.30578 -258.99364)
				(mid 145.322314 -259.004751)
				(end 145.341848 -259.008626)
			)
			(xy 146.91741 -259.008626) (xy 146.923506 -259.014976)
		)
		(stroke
			(width 0)
			(type solid)
		)
		(fill yes)
		(layer "F.Cu")
		(net "P1V8_PLL0_PEX1")
	)
	(gr_poly
		(pts
			(xy 215.55583 -55.681118) (xy 215.55583 -53.54193) (xy 215.502998 -53.489098) (xy 215.171782 -53.489098)
			(xy 215.158574 -53.502306) (xy 215.059006 -53.502306) (xy 214.865204 -53.502306) (xy 214.774272 -53.411374)
			(xy 214.774272 -53.217572) (xy 214.774272 -52.019708) (xy 212.115146 -49.360582) (xy 212.115146 -48.054514)
			(xy 213.038944 -47.130716) (xy 214.249254 -47.130716) (xy 214.388446 -46.991524) (xy 214.388446 -46.65726)
			(xy 214.641176 -46.40453) (xy 215.132412 -46.40453) (xy 215.23071 -46.306232) (xy 215.793066 -46.306232)
			(xy 215.838278 -46.26102) (xy 215.838278 -46.155356) (xy 215.758776 -46.075854) (xy 214.943436 -46.075854)
			(xy 214.841582 -45.974) (xy 214.830152 -45.974) (xy 214.50173 -45.645578) (xy 208.009744 -45.645578)
			(xy 207.676496 -45.978826) (xy 207.676496 -55.041292) (xy 207.905858 -55.270654) (xy 214.529162 -55.270654)
			(xy 215.039194 -55.780686) (xy 215.456262 -55.780686)
		)
		(stroke
			(width 0)
			(type solid)
		)
		(fill yes)
		(layer "F.Cu")
		(net "P12V_SSD7_R")
	)
	(gr_poly
		(pts
			(xy 253.65583 -55.681118) (xy 253.65583 -53.54193) (xy 253.602998 -53.489098) (xy 253.271782 -53.489098)
			(xy 253.258574 -53.502306) (xy 253.159006 -53.502306) (xy 252.981206 -53.502306) (xy 252.874272 -53.395372)
			(xy 252.874272 -53.217572) (xy 252.874272 -52.019708) (xy 250.215146 -49.360582) (xy 250.215146 -48.054514)
			(xy 251.138944 -47.130716) (xy 252.349254 -47.130716) (xy 252.488446 -46.991524) (xy 252.488446 -46.65726)
			(xy 252.741176 -46.40453) (xy 253.232412 -46.40453) (xy 253.33071 -46.306232) (xy 253.893066 -46.306232)
			(xy 253.938278 -46.26102) (xy 253.938278 -46.155356) (xy 253.858776 -46.075854) (xy 253.043436 -46.075854)
			(xy 252.941582 -45.974) (xy 252.930152 -45.974) (xy 252.60173 -45.645578) (xy 246.109744 -45.645578)
			(xy 245.776496 -45.978826) (xy 245.776496 -55.041292) (xy 246.005858 -55.270654) (xy 252.629162 -55.270654)
			(xy 253.139194 -55.780686) (xy 253.556262 -55.780686)
		)
		(stroke
			(width 0)
			(type solid)
		)
		(fill yes)
		(layer "F.Cu")
		(net "P12V_SSD8_R")
	)
	(gr_poly
		(pts
			(arc
				(start 262.047228 -301.772574)
				(mid 262.066751 -301.768673)
				(end 262.083296 -301.757588)
			)
			(arc
				(start 262.087614 -301.75327)
				(mid 262.098725 -301.736736)
				(end 262.1026 -301.717202)
			)
			(arc
				(start 262.1026 -300.414436)
				(mid 262.098699 -300.394913)
				(end 262.087614 -300.378368)
			)
			(arc
				(start 262.050276 -300.34103)
				(mid 262.033742 -300.329919)
				(end 262.014208 -300.326044)
			)
			(arc
				(start 258.349242 -300.326044)
				(mid 258.329719 -300.329945)
				(end 258.313174 -300.34103)
			)
			(arc
				(start 258.164838 -300.489366)
				(mid 258.153727 -300.5059)
				(end 258.149852 -300.525434)
			)
			(arc
				(start 258.149852 -301.432468)
				(mid 258.153753 -301.451991)
				(end 258.164838 -301.468536)
			)
			(arc
				(start 258.44754 -301.751238)
				(mid 258.464074 -301.762349)
				(end 258.483608 -301.766224)
			)
			(xy 260.05917 -301.766224) (xy 260.065266 -301.772574)
		)
		(stroke
			(width 0)
			(type solid)
		)
		(fill yes)
		(layer "F.Cu")
		(net "P1V8_PLL0_PEX2")
	)
	(gr_poly
		(pts
			(arc
				(start 262.047228 -298.572174)
				(mid 262.066751 -298.568273)
				(end 262.083296 -298.557188)
			)
			(arc
				(start 262.087614 -298.55287)
				(mid 262.098725 -298.536336)
				(end 262.1026 -298.516802)
			)
			(arc
				(start 262.1026 -297.214036)
				(mid 262.098699 -297.194513)
				(end 262.087614 -297.177968)
			)
			(arc
				(start 262.050276 -297.14063)
				(mid 262.033742 -297.129519)
				(end 262.014208 -297.125644)
			)
			(arc
				(start 258.349242 -297.125644)
				(mid 258.329719 -297.129545)
				(end 258.313174 -297.14063)
			)
			(arc
				(start 258.164838 -297.288966)
				(mid 258.153727 -297.3055)
				(end 258.149852 -297.325034)
			)
			(arc
				(start 258.149852 -298.232068)
				(mid 258.153753 -298.251591)
				(end 258.164838 -298.268136)
			)
			(arc
				(start 258.44754 -298.550838)
				(mid 258.464074 -298.561949)
				(end 258.483608 -298.565824)
			)
			(xy 260.05917 -298.565824) (xy 260.065266 -298.572174)
		)
		(stroke
			(width 0)
			(type solid)
		)
		(fill yes)
		(layer "F.Cu")
		(net "P1V8_PLL0_PEX2")
	)
	(gr_poly
		(pts
			(arc
				(start 262.047228 -295.371774)
				(mid 262.066751 -295.367873)
				(end 262.083296 -295.356788)
			)
			(arc
				(start 262.087614 -295.35247)
				(mid 262.098725 -295.335936)
				(end 262.1026 -295.316402)
			)
			(arc
				(start 262.1026 -294.013636)
				(mid 262.098699 -293.994113)
				(end 262.087614 -293.977568)
			)
			(arc
				(start 262.050276 -293.94023)
				(mid 262.033742 -293.929119)
				(end 262.014208 -293.925244)
			)
			(arc
				(start 258.349242 -293.925244)
				(mid 258.329719 -293.929145)
				(end 258.313174 -293.94023)
			)
			(arc
				(start 258.164838 -294.088566)
				(mid 258.153727 -294.1051)
				(end 258.149852 -294.124634)
			)
			(arc
				(start 258.149852 -295.031668)
				(mid 258.153753 -295.051191)
				(end 258.164838 -295.067736)
			)
			(arc
				(start 258.44754 -295.350438)
				(mid 258.464074 -295.361549)
				(end 258.483608 -295.365424)
			)
			(xy 260.05917 -295.365424) (xy 260.065266 -295.371774)
		)
		(stroke
			(width 0)
			(type solid)
		)
		(fill yes)
		(layer "F.Cu")
		(net "P1V8_PLL0_PEX2")
	)
	(gr_poly
		(pts
			(arc
				(start 262.047228 -292.171374)
				(mid 262.066751 -292.167473)
				(end 262.083296 -292.156388)
			)
			(arc
				(start 262.087614 -292.15207)
				(mid 262.098725 -292.135536)
				(end 262.1026 -292.116002)
			)
			(arc
				(start 262.1026 -290.813236)
				(mid 262.098699 -290.793713)
				(end 262.087614 -290.777168)
			)
			(arc
				(start 262.050276 -290.73983)
				(mid 262.033742 -290.728719)
				(end 262.014208 -290.724844)
			)
			(arc
				(start 258.349242 -290.724844)
				(mid 258.329719 -290.728745)
				(end 258.313174 -290.73983)
			)
			(arc
				(start 258.164838 -290.888166)
				(mid 258.153727 -290.9047)
				(end 258.149852 -290.924234)
			)
			(arc
				(start 258.149852 -291.831268)
				(mid 258.153753 -291.850791)
				(end 258.164838 -291.867336)
			)
			(arc
				(start 258.44754 -292.150038)
				(mid 258.464074 -292.161149)
				(end 258.483608 -292.165024)
			)
			(xy 260.05917 -292.165024) (xy 260.065266 -292.171374)
		)
		(stroke
			(width 0)
			(type solid)
		)
		(fill yes)
		(layer "F.Cu")
		(net "P1V8_PLL0_PEX2")
	)
	(gr_poly
		(pts
			(arc
				(start 262.047228 -288.970974)
				(mid 262.066751 -288.967073)
				(end 262.083296 -288.955988)
			)
			(arc
				(start 262.087614 -288.95167)
				(mid 262.098725 -288.935136)
				(end 262.1026 -288.915602)
			)
			(arc
				(start 262.1026 -287.612836)
				(mid 262.098699 -287.593313)
				(end 262.087614 -287.576768)
			)
			(arc
				(start 262.050276 -287.53943)
				(mid 262.033742 -287.528319)
				(end 262.014208 -287.524444)
			)
			(arc
				(start 258.349242 -287.524444)
				(mid 258.329719 -287.528345)
				(end 258.313174 -287.53943)
			)
			(arc
				(start 258.164838 -287.687766)
				(mid 258.153727 -287.7043)
				(end 258.149852 -287.723834)
			)
			(arc
				(start 258.149852 -288.630868)
				(mid 258.153753 -288.650391)
				(end 258.164838 -288.666936)
			)
			(arc
				(start 258.44754 -288.949638)
				(mid 258.464074 -288.960749)
				(end 258.483608 -288.964624)
			)
			(xy 260.05917 -288.964624) (xy 260.065266 -288.970974)
		)
		(stroke
			(width 0)
			(type solid)
		)
		(fill yes)
		(layer "F.Cu")
		(net "P1V8_PLL0_PEX2")
	)
	(gr_poly
		(pts
			(arc
				(start 262.047228 -285.770574)
				(mid 262.066751 -285.766673)
				(end 262.083296 -285.755588)
			)
			(arc
				(start 262.087614 -285.75127)
				(mid 262.098725 -285.734736)
				(end 262.1026 -285.715202)
			)
			(arc
				(start 262.1026 -284.412436)
				(mid 262.098699 -284.392913)
				(end 262.087614 -284.376368)
			)
			(arc
				(start 262.050276 -284.33903)
				(mid 262.033742 -284.327919)
				(end 262.014208 -284.324044)
			)
			(arc
				(start 258.349242 -284.324044)
				(mid 258.329719 -284.327945)
				(end 258.313174 -284.33903)
			)
			(arc
				(start 258.164838 -284.487366)
				(mid 258.153727 -284.5039)
				(end 258.149852 -284.523434)
			)
			(arc
				(start 258.149852 -285.430468)
				(mid 258.153753 -285.449991)
				(end 258.164838 -285.466536)
			)
			(arc
				(start 258.44754 -285.749238)
				(mid 258.464074 -285.760349)
				(end 258.483608 -285.764224)
			)
			(xy 260.05917 -285.764224) (xy 260.065266 -285.770574)
		)
		(stroke
			(width 0)
			(type solid)
		)
		(fill yes)
		(layer "F.Cu")
		(net "P1V8_PLL0_PEX2")
	)
	(gr_poly
		(pts
			(arc
				(start 262.047228 -282.570174)
				(mid 262.066751 -282.566273)
				(end 262.083296 -282.555188)
			)
			(arc
				(start 262.087614 -282.55087)
				(mid 262.098725 -282.534336)
				(end 262.1026 -282.514802)
			)
			(arc
				(start 262.1026 -281.212036)
				(mid 262.098699 -281.192513)
				(end 262.087614 -281.175968)
			)
			(arc
				(start 262.050276 -281.13863)
				(mid 262.033742 -281.127519)
				(end 262.014208 -281.123644)
			)
			(arc
				(start 258.349242 -281.123644)
				(mid 258.329719 -281.127545)
				(end 258.313174 -281.13863)
			)
			(arc
				(start 258.164838 -281.286966)
				(mid 258.153727 -281.3035)
				(end 258.149852 -281.323034)
			)
			(arc
				(start 258.149852 -282.230068)
				(mid 258.153753 -282.249591)
				(end 258.164838 -282.266136)
			)
			(arc
				(start 258.44754 -282.548838)
				(mid 258.464074 -282.559949)
				(end 258.483608 -282.563824)
			)
			(xy 260.05917 -282.563824) (xy 260.065266 -282.570174)
		)
		(stroke
			(width 0)
			(type solid)
		)
		(fill yes)
		(layer "F.Cu")
		(net "P1V8_PLL0_PEX2")
	)
	(gr_poly
		(pts
			(arc
				(start 265.005312 -259.014976)
				(mid 265.024835 -259.011075)
				(end 265.04138 -258.99999)
			)
			(arc
				(start 265.045698 -258.995672)
				(mid 265.056809 -258.979138)
				(end 265.060684 -258.959604)
			)
			(arc
				(start 265.060684 -257.656838)
				(mid 265.056783 -257.637315)
				(end 265.045698 -257.62077)
			)
			(arc
				(start 265.00836 -257.583432)
				(mid 264.991826 -257.572321)
				(end 264.972292 -257.568446)
			)
			(arc
				(start 261.307326 -257.568446)
				(mid 261.287803 -257.572347)
				(end 261.271258 -257.583432)
			)
			(arc
				(start 261.122922 -257.731768)
				(mid 261.111811 -257.748302)
				(end 261.107936 -257.767836)
			)
			(arc
				(start 261.107936 -258.67487)
				(mid 261.111837 -258.694393)
				(end 261.122922 -258.710938)
			)
			(arc
				(start 261.405624 -258.99364)
				(mid 261.422158 -259.004751)
				(end 261.441692 -259.008626)
			)
			(xy 263.017254 -259.008626) (xy 263.02335 -259.014976)
		)
		(stroke
			(width 0)
			(type solid)
		)
		(fill yes)
		(layer "F.Cu")
		(net "P1V8_PLL0_PEX2")
	)
	(gr_poly
		(pts
			(arc
				(start 375.282968 -258.332224)
				(mid 375.302491 -258.328323)
				(end 375.319036 -258.317238)
			)
			(arc
				(start 375.356374 -258.2799)
				(mid 375.367485 -258.263366)
				(end 375.37136 -258.243832)
			)
			(arc
				(start 375.37136 -254.578866)
				(mid 375.367459 -254.559343)
				(end 375.356374 -254.542798)
			)
			(arc
				(start 375.208038 -254.394462)
				(mid 375.191504 -254.383351)
				(end 375.17197 -254.379476)
			)
			(arc
				(start 374.264936 -254.379476)
				(mid 374.245413 -254.383377)
				(end 374.228868 -254.394462)
			)
			(arc
				(start 373.946166 -254.677164)
				(mid 373.935055 -254.693698)
				(end 373.93118 -254.713232)
			)
			(xy 373.93118 -256.288794) (xy 373.92483 -256.29489)
			(arc
				(start 373.92483 -258.276852)
				(mid 373.928731 -258.296375)
				(end 373.939816 -258.31292)
			)
			(arc
				(start 373.944134 -258.317238)
				(mid 373.960668 -258.328349)
				(end 373.980202 -258.332224)
			)
		)
		(stroke
			(width 0)
			(type solid)
		)
		(fill yes)
		(layer "F.Cu")
		(net "P1V8_PLL0_PEX3")
	)
	(gr_poly
		(pts
			(arc
				(start 378.147326 -301.772574)
				(mid 378.166849 -301.768673)
				(end 378.183394 -301.757588)
			)
			(arc
				(start 378.187712 -301.75327)
				(mid 378.198823 -301.736736)
				(end 378.202698 -301.717202)
			)
			(arc
				(start 378.202698 -300.414436)
				(mid 378.198797 -300.394913)
				(end 378.187712 -300.378368)
			)
			(arc
				(start 378.150374 -300.34103)
				(mid 378.13384 -300.329919)
				(end 378.114306 -300.326044)
			)
			(arc
				(start 374.44934 -300.326044)
				(mid 374.429817 -300.329945)
				(end 374.413272 -300.34103)
			)
			(arc
				(start 374.264936 -300.489366)
				(mid 374.253825 -300.5059)
				(end 374.24995 -300.525434)
			)
			(arc
				(start 374.24995 -301.432468)
				(mid 374.253851 -301.451991)
				(end 374.264936 -301.468536)
			)
			(arc
				(start 374.547638 -301.751238)
				(mid 374.564172 -301.762349)
				(end 374.583706 -301.766224)
			)
			(xy 376.159268 -301.766224) (xy 376.165364 -301.772574)
		)
		(stroke
			(width 0)
			(type solid)
		)
		(fill yes)
		(layer "F.Cu")
		(net "P1V8_PLL0_PEX3")
	)
	(gr_poly
		(pts
			(arc
				(start 378.147326 -298.572174)
				(mid 378.166849 -298.568273)
				(end 378.183394 -298.557188)
			)
			(arc
				(start 378.187712 -298.55287)
				(mid 378.198823 -298.536336)
				(end 378.202698 -298.516802)
			)
			(arc
				(start 378.202698 -297.214036)
				(mid 378.198797 -297.194513)
				(end 378.187712 -297.177968)
			)
			(arc
				(start 378.150374 -297.14063)
				(mid 378.13384 -297.129519)
				(end 378.114306 -297.125644)
			)
			(arc
				(start 374.44934 -297.125644)
				(mid 374.429817 -297.129545)
				(end 374.413272 -297.14063)
			)
			(arc
				(start 374.264936 -297.288966)
				(mid 374.253825 -297.3055)
				(end 374.24995 -297.325034)
			)
			(arc
				(start 374.24995 -298.232068)
				(mid 374.253851 -298.251591)
				(end 374.264936 -298.268136)
			)
			(arc
				(start 374.547638 -298.550838)
				(mid 374.564172 -298.561949)
				(end 374.583706 -298.565824)
			)
			(xy 376.159268 -298.565824) (xy 376.165364 -298.572174)
		)
		(stroke
			(width 0)
			(type solid)
		)
		(fill yes)
		(layer "F.Cu")
		(net "P1V8_PLL0_PEX3")
	)
	(gr_poly
		(pts
			(arc
				(start 378.147326 -295.371774)
				(mid 378.166849 -295.367873)
				(end 378.183394 -295.356788)
			)
			(arc
				(start 378.187712 -295.35247)
				(mid 378.198823 -295.335936)
				(end 378.202698 -295.316402)
			)
			(arc
				(start 378.202698 -294.013636)
				(mid 378.198797 -293.994113)
				(end 378.187712 -293.977568)
			)
			(arc
				(start 378.150374 -293.94023)
				(mid 378.13384 -293.929119)
				(end 378.114306 -293.925244)
			)
			(arc
				(start 374.44934 -293.925244)
				(mid 374.429817 -293.929145)
				(end 374.413272 -293.94023)
			)
			(arc
				(start 374.264936 -294.088566)
				(mid 374.253825 -294.1051)
				(end 374.24995 -294.124634)
			)
			(arc
				(start 374.24995 -295.031668)
				(mid 374.253851 -295.051191)
				(end 374.264936 -295.067736)
			)
			(arc
				(start 374.547638 -295.350438)
				(mid 374.564172 -295.361549)
				(end 374.583706 -295.365424)
			)
			(xy 376.159268 -295.365424) (xy 376.165364 -295.371774)
		)
		(stroke
			(width 0)
			(type solid)
		)
		(fill yes)
		(layer "F.Cu")
		(net "P1V8_PLL0_PEX3")
	)
	(gr_poly
		(pts
			(arc
				(start 378.147326 -292.171374)
				(mid 378.166849 -292.167473)
				(end 378.183394 -292.156388)
			)
			(arc
				(start 378.187712 -292.15207)
				(mid 378.198823 -292.135536)
				(end 378.202698 -292.116002)
			)
			(arc
				(start 378.202698 -290.813236)
				(mid 378.198797 -290.793713)
				(end 378.187712 -290.777168)
			)
			(arc
				(start 378.150374 -290.73983)
				(mid 378.13384 -290.728719)
				(end 378.114306 -290.724844)
			)
			(arc
				(start 374.44934 -290.724844)
				(mid 374.429817 -290.728745)
				(end 374.413272 -290.73983)
			)
			(arc
				(start 374.264936 -290.888166)
				(mid 374.253825 -290.9047)
				(end 374.24995 -290.924234)
			)
			(arc
				(start 374.24995 -291.831268)
				(mid 374.253851 -291.850791)
				(end 374.264936 -291.867336)
			)
			(arc
				(start 374.547638 -292.150038)
				(mid 374.564172 -292.161149)
				(end 374.583706 -292.165024)
			)
			(xy 376.159268 -292.165024) (xy 376.165364 -292.171374)
		)
		(stroke
			(width 0)
			(type solid)
		)
		(fill yes)
		(layer "F.Cu")
		(net "P1V8_PLL0_PEX3")
	)
	(gr_poly
		(pts
			(arc
				(start 378.147326 -288.970974)
				(mid 378.166849 -288.967073)
				(end 378.183394 -288.955988)
			)
			(arc
				(start 378.187712 -288.95167)
				(mid 378.198823 -288.935136)
				(end 378.202698 -288.915602)
			)
			(arc
				(start 378.202698 -287.612836)
				(mid 378.198797 -287.593313)
				(end 378.187712 -287.576768)
			)
			(arc
				(start 378.150374 -287.53943)
				(mid 378.13384 -287.528319)
				(end 378.114306 -287.524444)
			)
			(arc
				(start 374.44934 -287.524444)
				(mid 374.429817 -287.528345)
				(end 374.413272 -287.53943)
			)
			(arc
				(start 374.264936 -287.687766)
				(mid 374.253825 -287.7043)
				(end 374.24995 -287.723834)
			)
			(arc
				(start 374.24995 -288.630868)
				(mid 374.253851 -288.650391)
				(end 374.264936 -288.666936)
			)
			(arc
				(start 374.547638 -288.949638)
				(mid 374.564172 -288.960749)
				(end 374.583706 -288.964624)
			)
			(xy 376.159268 -288.964624) (xy 376.165364 -288.970974)
		)
		(stroke
			(width 0)
			(type solid)
		)
		(fill yes)
		(layer "F.Cu")
		(net "P1V8_PLL0_PEX3")
	)
	(gr_poly
		(pts
			(arc
				(start 378.147326 -285.770574)
				(mid 378.166849 -285.766673)
				(end 378.183394 -285.755588)
			)
			(arc
				(start 378.187712 -285.75127)
				(mid 378.198823 -285.734736)
				(end 378.202698 -285.715202)
			)
			(arc
				(start 378.202698 -284.412436)
				(mid 378.198797 -284.392913)
				(end 378.187712 -284.376368)
			)
			(arc
				(start 378.150374 -284.33903)
				(mid 378.13384 -284.327919)
				(end 378.114306 -284.324044)
			)
			(arc
				(start 374.44934 -284.324044)
				(mid 374.429817 -284.327945)
				(end 374.413272 -284.33903)
			)
			(arc
				(start 374.264936 -284.487366)
				(mid 374.253825 -284.5039)
				(end 374.24995 -284.523434)
			)
			(arc
				(start 374.24995 -285.430468)
				(mid 374.253851 -285.449991)
				(end 374.264936 -285.466536)
			)
			(arc
				(start 374.547638 -285.749238)
				(mid 374.564172 -285.760349)
				(end 374.583706 -285.764224)
			)
			(xy 376.159268 -285.764224) (xy 376.165364 -285.770574)
		)
		(stroke
			(width 0)
			(type solid)
		)
		(fill yes)
		(layer "F.Cu")
		(net "P1V8_PLL0_PEX3")
	)
	(gr_poly
		(pts
			(arc
				(start 378.147326 -282.570174)
				(mid 378.166849 -282.566273)
				(end 378.183394 -282.555188)
			)
			(arc
				(start 378.187712 -282.55087)
				(mid 378.198823 -282.534336)
				(end 378.202698 -282.514802)
			)
			(arc
				(start 378.202698 -281.212036)
				(mid 378.198797 -281.192513)
				(end 378.187712 -281.175968)
			)
			(arc
				(start 378.150374 -281.13863)
				(mid 378.13384 -281.127519)
				(end 378.114306 -281.123644)
			)
			(arc
				(start 374.44934 -281.123644)
				(mid 374.429817 -281.127545)
				(end 374.413272 -281.13863)
			)
			(arc
				(start 374.264936 -281.286966)
				(mid 374.253825 -281.3035)
				(end 374.24995 -281.323034)
			)
			(arc
				(start 374.24995 -282.230068)
				(mid 374.253851 -282.249591)
				(end 374.264936 -282.266136)
			)
			(arc
				(start 374.547638 -282.548838)
				(mid 374.564172 -282.559949)
				(end 374.583706 -282.563824)
			)
			(xy 376.159268 -282.563824) (xy 376.165364 -282.570174)
		)
		(stroke
			(width 0)
			(type solid)
		)
		(fill yes)
		(layer "F.Cu")
		(net "P1V8_PLL0_PEX3")
	)
	(gr_poly
		(pts
			(arc
				(start 381.10541 -259.014976)
				(mid 381.124933 -259.011075)
				(end 381.141478 -258.99999)
			)
			(arc
				(start 381.145796 -258.995672)
				(mid 381.156907 -258.979138)
				(end 381.160782 -258.959604)
			)
			(arc
				(start 381.160782 -257.656838)
				(mid 381.156881 -257.637315)
				(end 381.145796 -257.62077)
			)
			(arc
				(start 381.108458 -257.583432)
				(mid 381.091924 -257.572321)
				(end 381.07239 -257.568446)
			)
			(arc
				(start 377.407424 -257.568446)
				(mid 377.387901 -257.572347)
				(end 377.371356 -257.583432)
			)
			(arc
				(start 377.22302 -257.731768)
				(mid 377.211909 -257.748302)
				(end 377.208034 -257.767836)
			)
			(arc
				(start 377.208034 -258.67487)
				(mid 377.211935 -258.694393)
				(end 377.22302 -258.710938)
			)
			(arc
				(start 377.505722 -258.99364)
				(mid 377.522256 -259.004751)
				(end 377.54179 -259.008626)
			)
			(xy 379.117352 -259.008626) (xy 379.123448 -259.014976)
		)
		(stroke
			(width 0)
			(type solid)
		)
		(fill yes)
		(layer "F.Cu")
		(net "P1V8_PLL0_PEX3")
	)
	(gr_poly
		(pts
			(arc
				(start 29.871416 -296.871136)
				(mid 29.890773 -296.867303)
				(end 29.90723 -296.856404)
			)
			(arc
				(start 29.91612 -296.847514)
				(mid 29.927231 -296.83098)
				(end 29.931106 -296.811446)
			)
			(xy 29.931106 -295.632378) (xy 29.924756 -295.626028) (xy 27.756866 -295.626028) (xy 27.75077 -295.619932)
			(arc
				(start 26.178256 -295.619932)
				(mid 26.158869 -295.615982)
				(end 26.142442 -295.604946)
			)
			(xy 26.140664 -295.603168)
			(arc
				(start 26.040334 -295.603168)
				(mid 26.020811 -295.607069)
				(end 26.004266 -295.618154)
			)
			(arc
				(start 25.952704 -295.669716)
				(mid 25.941593 -295.68625)
				(end 25.937718 -295.705784)
			)
			(xy 25.937718 -296.639488) (xy 25.937972 -296.639488)
			(arc
				(start 25.937972 -296.740834)
				(mid 25.941873 -296.760357)
				(end 25.952958 -296.776902)
			)
			(arc
				(start 26.03246 -296.856404)
				(mid 26.048906 -296.86733)
				(end 26.068274 -296.871136)
			)
		)
		(stroke
			(width 0)
			(type solid)
		)
		(fill yes)
		(layer "F.Cu")
		(net "GND")
	)
	(gr_poly
		(pts
			(arc
				(start 29.871416 -293.670736)
				(mid 29.890773 -293.666903)
				(end 29.90723 -293.656004)
			)
			(arc
				(start 29.91612 -293.647114)
				(mid 29.927231 -293.63058)
				(end 29.931106 -293.611046)
			)
			(xy 29.931106 -292.431978) (xy 29.924756 -292.425628) (xy 27.756866 -292.425628) (xy 27.75077 -292.419532)
			(arc
				(start 26.178256 -292.419532)
				(mid 26.158869 -292.415582)
				(end 26.142442 -292.404546)
			)
			(xy 26.140664 -292.402768)
			(arc
				(start 26.040334 -292.402768)
				(mid 26.020811 -292.406669)
				(end 26.004266 -292.417754)
			)
			(arc
				(start 25.952704 -292.469316)
				(mid 25.941593 -292.48585)
				(end 25.937718 -292.505384)
			)
			(xy 25.937718 -293.439088) (xy 25.937972 -293.439088)
			(arc
				(start 25.937972 -293.540434)
				(mid 25.941873 -293.559957)
				(end 25.952958 -293.576502)
			)
			(arc
				(start 26.03246 -293.656004)
				(mid 26.048906 -293.66693)
				(end 26.068274 -293.670736)
			)
		)
		(stroke
			(width 0)
			(type solid)
		)
		(fill yes)
		(layer "F.Cu")
		(net "GND")
	)
	(gr_poly
		(pts
			(arc
				(start 29.871416 -290.470336)
				(mid 29.890773 -290.466503)
				(end 29.90723 -290.455604)
			)
			(arc
				(start 29.91612 -290.446714)
				(mid 29.927231 -290.43018)
				(end 29.931106 -290.410646)
			)
			(xy 29.931106 -289.231578) (xy 29.924756 -289.225228) (xy 27.756866 -289.225228) (xy 27.75077 -289.219132)
			(arc
				(start 26.178256 -289.219132)
				(mid 26.158869 -289.215182)
				(end 26.142442 -289.204146)
			)
			(xy 26.140664 -289.202368)
			(arc
				(start 26.040334 -289.202368)
				(mid 26.020811 -289.206269)
				(end 26.004266 -289.217354)
			)
			(arc
				(start 25.952704 -289.268916)
				(mid 25.941593 -289.28545)
				(end 25.937718 -289.304984)
			)
			(xy 25.937718 -290.238688) (xy 25.937972 -290.238688)
			(arc
				(start 25.937972 -290.340034)
				(mid 25.941873 -290.359557)
				(end 25.952958 -290.376102)
			)
			(arc
				(start 26.03246 -290.455604)
				(mid 26.048906 -290.46653)
				(end 26.068274 -290.470336)
			)
		)
		(stroke
			(width 0)
			(type solid)
		)
		(fill yes)
		(layer "F.Cu")
		(net "GND")
	)
	(gr_poly
		(pts
			(arc
				(start 29.871416 -287.269936)
				(mid 29.890773 -287.266103)
				(end 29.90723 -287.255204)
			)
			(arc
				(start 29.91612 -287.246314)
				(mid 29.927231 -287.22978)
				(end 29.931106 -287.210246)
			)
			(xy 29.931106 -286.031178) (xy 29.924756 -286.024828) (xy 27.756866 -286.024828) (xy 27.75077 -286.018732)
			(arc
				(start 26.178256 -286.018732)
				(mid 26.158869 -286.014782)
				(end 26.142442 -286.003746)
			)
			(xy 26.140664 -286.001968)
			(arc
				(start 26.040334 -286.001968)
				(mid 26.020811 -286.005869)
				(end 26.004266 -286.016954)
			)
			(arc
				(start 25.952704 -286.068516)
				(mid 25.941593 -286.08505)
				(end 25.937718 -286.104584)
			)
			(xy 25.937718 -287.038288) (xy 25.937972 -287.038288)
			(arc
				(start 25.937972 -287.139634)
				(mid 25.941873 -287.159157)
				(end 25.952958 -287.175702)
			)
			(arc
				(start 26.03246 -287.255204)
				(mid 26.048906 -287.26613)
				(end 26.068274 -287.269936)
			)
		)
		(stroke
			(width 0)
			(type solid)
		)
		(fill yes)
		(layer "F.Cu")
		(net "GND")
	)
	(gr_poly
		(pts
			(arc
				(start 32.8295 -260.514592)
				(mid 32.848887 -260.510642)
				(end 32.865314 -260.499606)
			)
			(arc
				(start 32.874204 -260.490716)
				(mid 32.885315 -260.474182)
				(end 32.88919 -260.454648)
			)
			(xy 32.88919 -259.27558) (xy 32.88284 -259.269484) (xy 30.71495 -259.269484) (xy 30.708854 -259.26288)
			(arc
				(start 29.13634 -259.26288)
				(mid 29.116983 -259.259047)
				(end 29.100526 -259.248148)
			)
			(xy 29.098748 -259.24637)
			(arc
				(start 28.998418 -259.24637)
				(mid 28.978895 -259.250271)
				(end 28.96235 -259.261356)
			)
			(arc
				(start 28.910788 -259.312918)
				(mid 28.899677 -259.329452)
				(end 28.895802 -259.348986)
			)
			(xy 28.895802 -260.28269) (xy 28.896056 -260.28269)
			(arc
				(start 28.896056 -260.384036)
				(mid 28.899957 -260.403559)
				(end 28.911042 -260.420104)
			)
			(arc
				(start 28.990544 -260.499606)
				(mid 29.006961 -260.510668)
				(end 29.026358 -260.514592)
			)
		)
		(stroke
			(width 0)
			(type solid)
		)
		(fill yes)
		(layer "F.Cu")
		(net "GND")
	)
	(gr_poly
		(pts
			(xy 47.455836 -55.681118) (xy 47.455836 -53.54193) (xy 47.403004 -53.489098) (xy 47.071788 -53.489098)
			(xy 47.05858 -53.502306) (xy 46.959012 -53.502306) (xy 46.956472 -53.499766) (xy 46.743874 -53.499766)
			(xy 46.674278 -53.43017) (xy 46.674278 -53.217572) (xy 46.674278 -52.019708) (xy 44.015152 -49.360582)
			(xy 44.015152 -48.054514) (xy 44.93895 -47.130716) (xy 46.14926 -47.130716) (xy 46.288452 -46.991524)
			(xy 46.288452 -46.65726) (xy 46.541182 -46.40453) (xy 47.032418 -46.40453) (xy 47.130716 -46.306232)
			(xy 47.693072 -46.306232) (xy 47.738284 -46.26102) (xy 47.738284 -46.155356) (xy 47.658782 -46.075854)
			(xy 46.843442 -46.075854) (xy 46.741588 -45.974) (xy 46.730158 -45.974) (xy 46.401736 -45.645578)
			(xy 39.90975 -45.645578) (xy 39.576502 -45.978826) (xy 39.576502 -55.041292) (xy 39.805864 -55.270654)
			(xy 46.429168 -55.270654) (xy 46.9392 -55.780686) (xy 47.356268 -55.780686)
		)
		(stroke
			(width 0)
			(type solid)
		)
		(fill yes)
		(layer "F.Cu")
		(net "P12V_SSD1_R")
	)
	(gr_poly
		(pts
			(xy 99.455732 -55.681118) (xy 99.455732 -53.54193) (xy 99.4029 -53.489098) (xy 99.071684 -53.489098)
			(xy 99.058476 -53.502306) (xy 98.958908 -53.502306) (xy 98.953828 -53.497226) (xy 98.73488 -53.497226)
			(xy 98.674174 -53.43652) (xy 98.674174 -53.217572) (xy 98.674174 -52.019708) (xy 96.015048 -49.360582)
			(xy 96.015048 -48.054514) (xy 96.938846 -47.130716) (xy 98.149156 -47.130716) (xy 98.288348 -46.991524)
			(xy 98.288348 -46.65726) (xy 98.541078 -46.40453) (xy 99.032314 -46.40453) (xy 99.130612 -46.306232)
			(xy 99.692968 -46.306232) (xy 99.73818 -46.26102) (xy 99.73818 -46.155356) (xy 99.658678 -46.075854)
			(xy 98.843338 -46.075854) (xy 98.741484 -45.974) (xy 98.730054 -45.974) (xy 98.401632 -45.645578)
			(xy 91.909646 -45.645578) (xy 91.576398 -45.978826) (xy 91.576398 -55.041292) (xy 91.80576 -55.270654)
			(xy 98.429064 -55.270654) (xy 98.939096 -55.780686) (xy 99.356164 -55.780686)
		)
		(stroke
			(width 0)
			(type solid)
		)
		(fill yes)
		(layer "F.Cu")
		(net "P12V_SSD3_R")
	)
	(gr_poly
		(pts
			(arc
				(start 145.971514 -300.071536)
				(mid 145.990871 -300.067703)
				(end 146.007328 -300.056804)
			)
			(arc
				(start 146.016218 -300.047914)
				(mid 146.027329 -300.03138)
				(end 146.031204 -300.011846)
			)
			(xy 146.031204 -298.832778) (xy 146.024854 -298.826428) (xy 143.856964 -298.826428) (xy 143.850868 -298.820332)
			(arc
				(start 142.278354 -298.820332)
				(mid 142.258967 -298.816382)
				(end 142.24254 -298.805346)
			)
			(xy 142.240762 -298.803568)
			(arc
				(start 142.140432 -298.803568)
				(mid 142.120909 -298.807469)
				(end 142.104364 -298.818554)
			)
			(arc
				(start 142.052802 -298.870116)
				(mid 142.041691 -298.88665)
				(end 142.037816 -298.906184)
			)
			(xy 142.037816 -299.839888) (xy 142.03807 -299.839888)
			(arc
				(start 142.03807 -299.941234)
				(mid 142.041971 -299.960757)
				(end 142.053056 -299.977302)
			)
			(arc
				(start 142.132558 -300.056804)
				(mid 142.149004 -300.06773)
				(end 142.168372 -300.071536)
			)
		)
		(stroke
			(width 0)
			(type solid)
		)
		(fill yes)
		(layer "F.Cu")
		(net "GND")
	)
	(gr_poly
		(pts
			(arc
				(start 145.971514 -296.871136)
				(mid 145.990871 -296.867303)
				(end 146.007328 -296.856404)
			)
			(arc
				(start 146.016218 -296.847514)
				(mid 146.027329 -296.83098)
				(end 146.031204 -296.811446)
			)
			(xy 146.031204 -295.632378) (xy 146.024854 -295.626028) (xy 143.856964 -295.626028) (xy 143.850868 -295.619932)
			(arc
				(start 142.278354 -295.619932)
				(mid 142.258967 -295.615982)
				(end 142.24254 -295.604946)
			)
			(xy 142.240762 -295.603168)
			(arc
				(start 142.140432 -295.603168)
				(mid 142.120909 -295.607069)
				(end 142.104364 -295.618154)
			)
			(arc
				(start 142.052802 -295.669716)
				(mid 142.041691 -295.68625)
				(end 142.037816 -295.705784)
			)
			(xy 142.037816 -296.639488) (xy 142.03807 -296.639488)
			(arc
				(start 142.03807 -296.740834)
				(mid 142.041971 -296.760357)
				(end 142.053056 -296.776902)
			)
			(arc
				(start 142.132558 -296.856404)
				(mid 142.149004 -296.86733)
				(end 142.168372 -296.871136)
			)
		)
		(stroke
			(width 0)
			(type solid)
		)
		(fill yes)
		(layer "F.Cu")
		(net "GND")
	)
	(gr_poly
		(pts
			(arc
				(start 145.971514 -293.670736)
				(mid 145.990871 -293.666903)
				(end 146.007328 -293.656004)
			)
			(arc
				(start 146.016218 -293.647114)
				(mid 146.027329 -293.63058)
				(end 146.031204 -293.611046)
			)
			(xy 146.031204 -292.431978) (xy 146.024854 -292.425628) (xy 143.856964 -292.425628) (xy 143.850868 -292.419532)
			(arc
				(start 142.278354 -292.419532)
				(mid 142.258967 -292.415582)
				(end 142.24254 -292.404546)
			)
			(xy 142.240762 -292.402768)
			(arc
				(start 142.140432 -292.402768)
				(mid 142.120909 -292.406669)
				(end 142.104364 -292.417754)
			)
			(arc
				(start 142.052802 -292.469316)
				(mid 142.041691 -292.48585)
				(end 142.037816 -292.505384)
			)
			(xy 142.037816 -293.439088) (xy 142.03807 -293.439088)
			(arc
				(start 142.03807 -293.540434)
				(mid 142.041971 -293.559957)
				(end 142.053056 -293.576502)
			)
			(arc
				(start 142.132558 -293.656004)
				(mid 142.149004 -293.66693)
				(end 142.168372 -293.670736)
			)
		)
		(stroke
			(width 0)
			(type solid)
		)
		(fill yes)
		(layer "F.Cu")
		(net "GND")
	)
	(gr_poly
		(pts
			(arc
				(start 145.971514 -290.470336)
				(mid 145.990871 -290.466503)
				(end 146.007328 -290.455604)
			)
			(arc
				(start 146.016218 -290.446714)
				(mid 146.027329 -290.43018)
				(end 146.031204 -290.410646)
			)
			(xy 146.031204 -289.231578) (xy 146.024854 -289.225228) (xy 143.856964 -289.225228) (xy 143.850868 -289.219132)
			(arc
				(start 142.278354 -289.219132)
				(mid 142.258967 -289.215182)
				(end 142.24254 -289.204146)
			)
			(xy 142.240762 -289.202368)
			(arc
				(start 142.140432 -289.202368)
				(mid 142.120909 -289.206269)
				(end 142.104364 -289.217354)
			)
			(arc
				(start 142.052802 -289.268916)
				(mid 142.041691 -289.28545)
				(end 142.037816 -289.304984)
			)
			(xy 142.037816 -290.238688) (xy 142.03807 -290.238688)
			(arc
				(start 142.03807 -290.340034)
				(mid 142.041971 -290.359557)
				(end 142.053056 -290.376102)
			)
			(arc
				(start 142.132558 -290.455604)
				(mid 142.149004 -290.46653)
				(end 142.168372 -290.470336)
			)
		)
		(stroke
			(width 0)
			(type solid)
		)
		(fill yes)
		(layer "F.Cu")
		(net "GND")
	)
	(gr_poly
		(pts
			(arc
				(start 145.971514 -287.269936)
				(mid 145.990871 -287.266103)
				(end 146.007328 -287.255204)
			)
			(arc
				(start 146.016218 -287.246314)
				(mid 146.027329 -287.22978)
				(end 146.031204 -287.210246)
			)
			(xy 146.031204 -286.031178) (xy 146.024854 -286.024828) (xy 143.856964 -286.024828) (xy 143.850868 -286.018732)
			(arc
				(start 142.278354 -286.018732)
				(mid 142.258967 -286.014782)
				(end 142.24254 -286.003746)
			)
			(xy 142.240762 -286.001968)
			(arc
				(start 142.140432 -286.001968)
				(mid 142.120909 -286.005869)
				(end 142.104364 -286.016954)
			)
			(arc
				(start 142.052802 -286.068516)
				(mid 142.041691 -286.08505)
				(end 142.037816 -286.104584)
			)
			(xy 142.037816 -287.038288) (xy 142.03807 -287.038288)
			(arc
				(start 142.03807 -287.139634)
				(mid 142.041971 -287.159157)
				(end 142.053056 -287.175702)
			)
			(arc
				(start 142.132558 -287.255204)
				(mid 142.149004 -287.26613)
				(end 142.168372 -287.269936)
			)
		)
		(stroke
			(width 0)
			(type solid)
		)
		(fill yes)
		(layer "F.Cu")
		(net "GND")
	)
	(gr_poly
		(pts
			(arc
				(start 148.929598 -260.514592)
				(mid 148.948985 -260.510642)
				(end 148.965412 -260.499606)
			)
			(arc
				(start 148.974302 -260.490716)
				(mid 148.985413 -260.474182)
				(end 148.989288 -260.454648)
			)
			(xy 148.989288 -259.27558) (xy 148.982938 -259.269484) (xy 146.815048 -259.269484) (xy 146.808952 -259.26288)
			(arc
				(start 145.236438 -259.26288)
				(mid 145.217081 -259.259047)
				(end 145.200624 -259.248148)
			)
			(xy 145.198846 -259.24637)
			(arc
				(start 145.098516 -259.24637)
				(mid 145.078993 -259.250271)
				(end 145.062448 -259.261356)
			)
			(arc
				(start 145.010886 -259.312918)
				(mid 144.999775 -259.329452)
				(end 144.9959 -259.348986)
			)
			(xy 144.9959 -260.28269) (xy 144.996154 -260.28269)
			(arc
				(start 144.996154 -260.384036)
				(mid 145.000055 -260.403559)
				(end 145.01114 -260.420104)
			)
			(arc
				(start 145.090642 -260.499606)
				(mid 145.107059 -260.510668)
				(end 145.126456 -260.514592)
			)
		)
		(stroke
			(width 0)
			(type solid)
		)
		(fill yes)
		(layer "F.Cu")
		(net "GND")
	)
	(gr_poly
		(pts
			(xy 163.555934 -55.681118) (xy 163.555934 -53.54193) (xy 163.503102 -53.489098) (xy 163.171886 -53.489098)
			(xy 163.158678 -53.502306) (xy 163.05911 -53.502306) (xy 163.057332 -53.500528) (xy 162.85337 -53.500528)
			(xy 162.774376 -53.421534) (xy 162.774376 -53.217572) (xy 162.774376 -52.019708) (xy 160.11525 -49.360582)
			(xy 160.11525 -48.054514) (xy 161.039048 -47.130716) (xy 162.249358 -47.130716) (xy 162.38855 -46.991524)
			(xy 162.38855 -46.65726) (xy 162.64128 -46.40453) (xy 163.132516 -46.40453) (xy 163.230814 -46.306232)
			(xy 163.79317 -46.306232) (xy 163.838382 -46.26102) (xy 163.838382 -46.155356) (xy 163.75888 -46.075854)
			(xy 162.94354 -46.075854) (xy 162.841686 -45.974) (xy 162.830256 -45.974) (xy 162.501834 -45.645578)
			(xy 156.009848 -45.645578) (xy 155.6766 -45.978826) (xy 155.6766 -55.041292) (xy 155.905962 -55.270654)
			(xy 162.529266 -55.270654) (xy 163.039298 -55.780686) (xy 163.456366 -55.780686)
		)
		(stroke
			(width 0)
			(type solid)
		)
		(fill yes)
		(layer "F.Cu")
		(net "P12V_SSD5_R")
	)
	(gr_poly
		(pts
			(arc
				(start 262.071358 -300.071536)
				(mid 262.090715 -300.067703)
				(end 262.107172 -300.056804)
			)
			(arc
				(start 262.116062 -300.047914)
				(mid 262.127173 -300.03138)
				(end 262.131048 -300.011846)
			)
			(xy 262.131048 -298.832778) (xy 262.124698 -298.826428) (xy 259.956808 -298.826428) (xy 259.950712 -298.820332)
			(arc
				(start 258.378198 -298.820332)
				(mid 258.358811 -298.816382)
				(end 258.342384 -298.805346)
			)
			(xy 258.340606 -298.803568)
			(arc
				(start 258.240276 -298.803568)
				(mid 258.220753 -298.807469)
				(end 258.204208 -298.818554)
			)
			(arc
				(start 258.152646 -298.870116)
				(mid 258.141535 -298.88665)
				(end 258.13766 -298.906184)
			)
			(xy 258.13766 -299.839888) (xy 258.137914 -299.839888)
			(arc
				(start 258.137914 -299.941234)
				(mid 258.141815 -299.960757)
				(end 258.1529 -299.977302)
			)
			(arc
				(start 258.232402 -300.056804)
				(mid 258.248848 -300.06773)
				(end 258.268216 -300.071536)
			)
		)
		(stroke
			(width 0)
			(type solid)
		)
		(fill yes)
		(layer "F.Cu")
		(net "GND")
	)
	(gr_poly
		(pts
			(arc
				(start 262.071358 -296.871136)
				(mid 262.090715 -296.867303)
				(end 262.107172 -296.856404)
			)
			(arc
				(start 262.116062 -296.847514)
				(mid 262.127173 -296.83098)
				(end 262.131048 -296.811446)
			)
			(xy 262.131048 -295.632378) (xy 262.124698 -295.626028) (xy 259.956808 -295.626028) (xy 259.950712 -295.619932)
			(arc
				(start 258.378198 -295.619932)
				(mid 258.358811 -295.615982)
				(end 258.342384 -295.604946)
			)
			(xy 258.340606 -295.603168)
			(arc
				(start 258.240276 -295.603168)
				(mid 258.220753 -295.607069)
				(end 258.204208 -295.618154)
			)
			(arc
				(start 258.152646 -295.669716)
				(mid 258.141535 -295.68625)
				(end 258.13766 -295.705784)
			)
			(xy 258.13766 -296.639488) (xy 258.137914 -296.639488)
			(arc
				(start 258.137914 -296.740834)
				(mid 258.141815 -296.760357)
				(end 258.1529 -296.776902)
			)
			(arc
				(start 258.232402 -296.856404)
				(mid 258.248848 -296.86733)
				(end 258.268216 -296.871136)
			)
		)
		(stroke
			(width 0)
			(type solid)
		)
		(fill yes)
		(layer "F.Cu")
		(net "GND")
	)
	(gr_poly
		(pts
			(arc
				(start 262.071358 -293.670736)
				(mid 262.090715 -293.666903)
				(end 262.107172 -293.656004)
			)
			(arc
				(start 262.116062 -293.647114)
				(mid 262.127173 -293.63058)
				(end 262.131048 -293.611046)
			)
			(xy 262.131048 -292.431978) (xy 262.124698 -292.425628) (xy 259.956808 -292.425628) (xy 259.950712 -292.419532)
			(arc
				(start 258.378198 -292.419532)
				(mid 258.358811 -292.415582)
				(end 258.342384 -292.404546)
			)
			(xy 258.340606 -292.402768)
			(arc
				(start 258.240276 -292.402768)
				(mid 258.220753 -292.406669)
				(end 258.204208 -292.417754)
			)
			(arc
				(start 258.152646 -292.469316)
				(mid 258.141535 -292.48585)
				(end 258.13766 -292.505384)
			)
			(xy 258.13766 -293.439088) (xy 258.137914 -293.439088)
			(arc
				(start 258.137914 -293.540434)
				(mid 258.141815 -293.559957)
				(end 258.1529 -293.576502)
			)
			(arc
				(start 258.232402 -293.656004)
				(mid 258.248848 -293.66693)
				(end 258.268216 -293.670736)
			)
		)
		(stroke
			(width 0)
			(type solid)
		)
		(fill yes)
		(layer "F.Cu")
		(net "GND")
	)
	(gr_poly
		(pts
			(arc
				(start 262.071358 -290.470336)
				(mid 262.090715 -290.466503)
				(end 262.107172 -290.455604)
			)
			(arc
				(start 262.116062 -290.446714)
				(mid 262.127173 -290.43018)
				(end 262.131048 -290.410646)
			)
			(xy 262.131048 -289.231578) (xy 262.124698 -289.225228) (xy 259.956808 -289.225228) (xy 259.950712 -289.219132)
			(arc
				(start 258.378198 -289.219132)
				(mid 258.358811 -289.215182)
				(end 258.342384 -289.204146)
			)
			(xy 258.340606 -289.202368)
			(arc
				(start 258.240276 -289.202368)
				(mid 258.220753 -289.206269)
				(end 258.204208 -289.217354)
			)
			(arc
				(start 258.152646 -289.268916)
				(mid 258.141535 -289.28545)
				(end 258.13766 -289.304984)
			)
			(xy 258.13766 -290.238688) (xy 258.137914 -290.238688)
			(arc
				(start 258.137914 -290.340034)
				(mid 258.141815 -290.359557)
				(end 258.1529 -290.376102)
			)
			(arc
				(start 258.232402 -290.455604)
				(mid 258.248848 -290.46653)
				(end 258.268216 -290.470336)
			)
		)
		(stroke
			(width 0)
			(type solid)
		)
		(fill yes)
		(layer "F.Cu")
		(net "GND")
	)
	(gr_poly
		(pts
			(arc
				(start 262.071358 -287.269936)
				(mid 262.090715 -287.266103)
				(end 262.107172 -287.255204)
			)
			(arc
				(start 262.116062 -287.246314)
				(mid 262.127173 -287.22978)
				(end 262.131048 -287.210246)
			)
			(xy 262.131048 -286.031178) (xy 262.124698 -286.024828) (xy 259.956808 -286.024828) (xy 259.950712 -286.018732)
			(arc
				(start 258.378198 -286.018732)
				(mid 258.358811 -286.014782)
				(end 258.342384 -286.003746)
			)
			(xy 258.340606 -286.001968)
			(arc
				(start 258.240276 -286.001968)
				(mid 258.220753 -286.005869)
				(end 258.204208 -286.016954)
			)
			(arc
				(start 258.152646 -286.068516)
				(mid 258.141535 -286.08505)
				(end 258.13766 -286.104584)
			)
			(xy 258.13766 -287.038288) (xy 258.137914 -287.038288)
			(arc
				(start 258.137914 -287.139634)
				(mid 258.141815 -287.159157)
				(end 258.1529 -287.175702)
			)
			(arc
				(start 258.232402 -287.255204)
				(mid 258.248848 -287.26613)
				(end 258.268216 -287.269936)
			)
		)
		(stroke
			(width 0)
			(type solid)
		)
		(fill yes)
		(layer "F.Cu")
		(net "GND")
	)
	(gr_poly
		(pts
			(arc
				(start 265.029442 -260.514592)
				(mid 265.048829 -260.510642)
				(end 265.065256 -260.499606)
			)
			(arc
				(start 265.074146 -260.490716)
				(mid 265.085257 -260.474182)
				(end 265.089132 -260.454648)
			)
			(xy 265.089132 -259.27558) (xy 265.082782 -259.269484) (xy 262.914892 -259.269484) (xy 262.908796 -259.26288)
			(arc
				(start 261.336282 -259.26288)
				(mid 261.316925 -259.259047)
				(end 261.300468 -259.248148)
			)
			(xy 261.29869 -259.24637)
			(arc
				(start 261.19836 -259.24637)
				(mid 261.178837 -259.250271)
				(end 261.162292 -259.261356)
			)
			(arc
				(start 261.11073 -259.312918)
				(mid 261.099619 -259.329452)
				(end 261.095744 -259.348986)
			)
			(xy 261.095744 -260.28269) (xy 261.095998 -260.28269)
			(arc
				(start 261.095998 -260.384036)
				(mid 261.099899 -260.403559)
				(end 261.110984 -260.420104)
			)
			(arc
				(start 261.190486 -260.499606)
				(mid 261.206903 -260.510668)
				(end 261.2263 -260.514592)
			)
		)
		(stroke
			(width 0)
			(type solid)
		)
		(fill yes)
		(layer "F.Cu")
		(net "GND")
	)
	(gr_poly
		(pts
			(xy 279.655778 -55.681118) (xy 279.655778 -53.54193) (xy 279.602946 -53.489098) (xy 279.27173 -53.489098)
			(xy 279.258522 -53.502306) (xy 279.158954 -53.502306) (xy 279.155144 -53.498496) (xy 278.98217 -53.498496)
			(xy 278.87422 -53.390546) (xy 278.87422 -53.217572) (xy 278.87422 -52.019708) (xy 276.215094 -49.360582)
			(xy 276.215094 -48.054514) (xy 277.138892 -47.130716) (xy 278.349202 -47.130716) (xy 278.488394 -46.991524)
			(xy 278.488394 -46.65726) (xy 278.741124 -46.40453) (xy 279.23236 -46.40453) (xy 279.330658 -46.306232)
			(xy 279.893014 -46.306232) (xy 279.938226 -46.26102) (xy 279.938226 -46.155356) (xy 279.858724 -46.075854)
			(xy 279.043384 -46.075854) (xy 278.94153 -45.974) (xy 278.9301 -45.974) (xy 278.601678 -45.645578)
			(xy 272.109692 -45.645578) (xy 271.776444 -45.978826) (xy 271.776444 -55.041292) (xy 272.005806 -55.270654)
			(xy 278.62911 -55.270654) (xy 279.139142 -55.780686) (xy 279.55621 -55.780686)
		)
		(stroke
			(width 0)
			(type solid)
		)
		(fill yes)
		(layer "F.Cu")
		(net "P12V_SSD9_R")
	)
	(gr_poly
		(pts
			(xy 305.655726 -55.681118) (xy 305.655726 -53.54193) (xy 305.602894 -53.489098) (xy 305.271678 -53.489098)
			(xy 305.25847 -53.502306) (xy 305.158902 -53.502306) (xy 305.155092 -53.498496) (xy 304.934112 -53.498496)
			(xy 304.874168 -53.438552) (xy 304.874168 -53.217572) (xy 304.874168 -52.019708) (xy 302.215042 -49.360582)
			(xy 302.215042 -48.054514) (xy 303.13884 -47.130716) (xy 304.34915 -47.130716) (xy 304.488342 -46.991524)
			(xy 304.488342 -46.65726) (xy 304.741072 -46.40453) (xy 305.232308 -46.40453) (xy 305.330606 -46.306232)
			(xy 305.892962 -46.306232) (xy 305.938174 -46.26102) (xy 305.938174 -46.155356) (xy 305.858672 -46.075854)
			(xy 305.043332 -46.075854) (xy 304.941478 -45.974) (xy 304.930048 -45.974) (xy 304.601626 -45.645578)
			(xy 298.10964 -45.645578) (xy 297.776392 -45.978826) (xy 297.776392 -55.041292) (xy 298.005754 -55.270654)
			(xy 304.629058 -55.270654) (xy 305.13909 -55.780686) (xy 305.556158 -55.780686)
		)
		(stroke
			(width 0)
			(type solid)
		)
		(fill yes)
		(layer "F.Cu")
		(net "P12V_SSD10_R")
	)
	(gr_poly
		(pts
			(xy 331.655674 -55.681118) (xy 331.655674 -53.54193) (xy 331.602842 -53.489098) (xy 331.271626 -53.489098)
			(xy 331.258418 -53.502306) (xy 331.15885 -53.502306) (xy 331.157326 -53.500782) (xy 331.008482 -53.500782)
			(xy 330.874116 -53.366416) (xy 330.874116 -53.217572) (xy 330.874116 -52.019708) (xy 328.21499 -49.360582)
			(xy 328.21499 -48.054514) (xy 329.138788 -47.130716) (xy 330.349098 -47.130716) (xy 330.48829 -46.991524)
			(xy 330.48829 -46.65726) (xy 330.74102 -46.40453) (xy 331.232256 -46.40453) (xy 331.330554 -46.306232)
			(xy 331.89291 -46.306232) (xy 331.938122 -46.26102) (xy 331.938122 -46.155356) (xy 331.85862 -46.075854)
			(xy 331.04328 -46.075854) (xy 330.941426 -45.974) (xy 330.929996 -45.974) (xy 330.601574 -45.645578)
			(xy 324.109588 -45.645578) (xy 323.77634 -45.978826) (xy 323.77634 -55.041292) (xy 324.005702 -55.270654)
			(xy 330.629006 -55.270654) (xy 331.139038 -55.780686) (xy 331.556106 -55.780686)
		)
		(stroke
			(width 0)
			(type solid)
		)
		(fill yes)
		(layer "F.Cu")
		(net "P12V_SSD11_R")
	)
	(gr_poly
		(pts
			(xy 369.755928 -55.681118) (xy 369.755928 -53.54193) (xy 369.703096 -53.489098) (xy 369.37188 -53.489098)
			(xy 369.358672 -53.502306) (xy 369.259104 -53.502306) (xy 369.258596 -53.502052) (xy 369.069366 -53.502052)
			(xy 368.97437 -53.407056) (xy 368.97437 -53.217572) (xy 368.97437 -52.019708) (xy 366.315244 -49.360582)
			(xy 366.315244 -48.054514) (xy 367.239042 -47.130716) (xy 368.449352 -47.130716) (xy 368.588544 -46.991524)
			(xy 368.588544 -46.65726) (xy 368.841274 -46.40453) (xy 369.33251 -46.40453) (xy 369.430808 -46.306232)
			(xy 369.993164 -46.306232) (xy 370.038376 -46.26102) (xy 370.038376 -46.155356) (xy 369.958874 -46.075854)
			(xy 369.143534 -46.075854) (xy 369.04168 -45.974) (xy 369.03025 -45.974) (xy 368.701828 -45.645578)
			(xy 362.209842 -45.645578) (xy 361.876594 -45.978826) (xy 361.876594 -55.041292) (xy 362.105956 -55.270654)
			(xy 368.72926 -55.270654) (xy 369.239292 -55.780686) (xy 369.65636 -55.780686)
		)
		(stroke
			(width 0)
			(type solid)
		)
		(fill yes)
		(layer "F.Cu")
		(net "P12V_SSD12_R")
	)
	(gr_poly
		(pts
			(arc
				(start 378.171456 -300.071536)
				(mid 378.190813 -300.067703)
				(end 378.20727 -300.056804)
			)
			(arc
				(start 378.21616 -300.047914)
				(mid 378.227271 -300.03138)
				(end 378.231146 -300.011846)
			)
			(xy 378.231146 -298.832778) (xy 378.224796 -298.826428) (xy 376.056906 -298.826428) (xy 376.05081 -298.820332)
			(arc
				(start 374.478296 -298.820332)
				(mid 374.458909 -298.816382)
				(end 374.442482 -298.805346)
			)
			(xy 374.440704 -298.803568)
			(arc
				(start 374.340374 -298.803568)
				(mid 374.320851 -298.807469)
				(end 374.304306 -298.818554)
			)
			(arc
				(start 374.252744 -298.870116)
				(mid 374.241633 -298.88665)
				(end 374.237758 -298.906184)
			)
			(xy 374.237758 -299.839888) (xy 374.238012 -299.839888)
			(arc
				(start 374.238012 -299.941234)
				(mid 374.241913 -299.960757)
				(end 374.252998 -299.977302)
			)
			(arc
				(start 374.3325 -300.056804)
				(mid 374.348946 -300.06773)
				(end 374.368314 -300.071536)
			)
		)
		(stroke
			(width 0)
			(type solid)
		)
		(fill yes)
		(layer "F.Cu")
		(net "GND")
	)
	(gr_poly
		(pts
			(arc
				(start 378.171456 -296.871136)
				(mid 378.190813 -296.867303)
				(end 378.20727 -296.856404)
			)
			(arc
				(start 378.21616 -296.847514)
				(mid 378.227271 -296.83098)
				(end 378.231146 -296.811446)
			)
			(xy 378.231146 -295.632378) (xy 378.224796 -295.626028) (xy 376.056906 -295.626028) (xy 376.05081 -295.619932)
			(arc
				(start 374.478296 -295.619932)
				(mid 374.458909 -295.615982)
				(end 374.442482 -295.604946)
			)
			(xy 374.440704 -295.603168)
			(arc
				(start 374.340374 -295.603168)
				(mid 374.320851 -295.607069)
				(end 374.304306 -295.618154)
			)
			(arc
				(start 374.252744 -295.669716)
				(mid 374.241633 -295.68625)
				(end 374.237758 -295.705784)
			)
			(xy 374.237758 -296.639488) (xy 374.238012 -296.639488)
			(arc
				(start 374.238012 -296.740834)
				(mid 374.241913 -296.760357)
				(end 374.252998 -296.776902)
			)
			(arc
				(start 374.3325 -296.856404)
				(mid 374.348946 -296.86733)
				(end 374.368314 -296.871136)
			)
		)
		(stroke
			(width 0)
			(type solid)
		)
		(fill yes)
		(layer "F.Cu")
		(net "GND")
	)
	(gr_poly
		(pts
			(arc
				(start 378.171456 -293.670736)
				(mid 378.190813 -293.666903)
				(end 378.20727 -293.656004)
			)
			(arc
				(start 378.21616 -293.647114)
				(mid 378.227271 -293.63058)
				(end 378.231146 -293.611046)
			)
			(xy 378.231146 -292.431978) (xy 378.224796 -292.425628) (xy 376.056906 -292.425628) (xy 376.05081 -292.419532)
			(arc
				(start 374.478296 -292.419532)
				(mid 374.458909 -292.415582)
				(end 374.442482 -292.404546)
			)
			(xy 374.440704 -292.402768)
			(arc
				(start 374.340374 -292.402768)
				(mid 374.320851 -292.406669)
				(end 374.304306 -292.417754)
			)
			(arc
				(start 374.252744 -292.469316)
				(mid 374.241633 -292.48585)
				(end 374.237758 -292.505384)
			)
			(xy 374.237758 -293.439088) (xy 374.238012 -293.439088)
			(arc
				(start 374.238012 -293.540434)
				(mid 374.241913 -293.559957)
				(end 374.252998 -293.576502)
			)
			(arc
				(start 374.3325 -293.656004)
				(mid 374.348946 -293.66693)
				(end 374.368314 -293.670736)
			)
		)
		(stroke
			(width 0)
			(type solid)
		)
		(fill yes)
		(layer "F.Cu")
		(net "GND")
	)
	(gr_poly
		(pts
			(arc
				(start 378.171456 -290.470336)
				(mid 378.190813 -290.466503)
				(end 378.20727 -290.455604)
			)
			(arc
				(start 378.21616 -290.446714)
				(mid 378.227271 -290.43018)
				(end 378.231146 -290.410646)
			)
			(xy 378.231146 -289.231578) (xy 378.224796 -289.225228) (xy 376.056906 -289.225228) (xy 376.05081 -289.219132)
			(arc
				(start 374.478296 -289.219132)
				(mid 374.458909 -289.215182)
				(end 374.442482 -289.204146)
			)
			(xy 374.440704 -289.202368)
			(arc
				(start 374.340374 -289.202368)
				(mid 374.320851 -289.206269)
				(end 374.304306 -289.217354)
			)
			(arc
				(start 374.252744 -289.268916)
				(mid 374.241633 -289.28545)
				(end 374.237758 -289.304984)
			)
			(xy 374.237758 -290.238688) (xy 374.238012 -290.238688)
			(arc
				(start 374.238012 -290.340034)
				(mid 374.241913 -290.359557)
				(end 374.252998 -290.376102)
			)
			(arc
				(start 374.3325 -290.455604)
				(mid 374.348946 -290.46653)
				(end 374.368314 -290.470336)
			)
		)
		(stroke
			(width 0)
			(type solid)
		)
		(fill yes)
		(layer "F.Cu")
		(net "GND")
	)
	(gr_poly
		(pts
			(arc
				(start 378.171456 -287.269936)
				(mid 378.190813 -287.266103)
				(end 378.20727 -287.255204)
			)
			(arc
				(start 378.21616 -287.246314)
				(mid 378.227271 -287.22978)
				(end 378.231146 -287.210246)
			)
			(xy 378.231146 -286.031178) (xy 378.224796 -286.024828) (xy 376.056906 -286.024828) (xy 376.05081 -286.018732)
			(arc
				(start 374.478296 -286.018732)
				(mid 374.458909 -286.014782)
				(end 374.442482 -286.003746)
			)
			(xy 374.440704 -286.001968)
			(arc
				(start 374.340374 -286.001968)
				(mid 374.320851 -286.005869)
				(end 374.304306 -286.016954)
			)
			(arc
				(start 374.252744 -286.068516)
				(mid 374.241633 -286.08505)
				(end 374.237758 -286.104584)
			)
			(xy 374.237758 -287.038288) (xy 374.238012 -287.038288)
			(arc
				(start 374.238012 -287.139634)
				(mid 374.241913 -287.159157)
				(end 374.252998 -287.175702)
			)
			(arc
				(start 374.3325 -287.255204)
				(mid 374.348946 -287.26613)
				(end 374.368314 -287.269936)
			)
		)
		(stroke
			(width 0)
			(type solid)
		)
		(fill yes)
		(layer "F.Cu")
		(net "GND")
	)
	(gr_poly
		(pts
			(arc
				(start 381.12954 -260.514592)
				(mid 381.148927 -260.510642)
				(end 381.165354 -260.499606)
			)
			(arc
				(start 381.174244 -260.490716)
				(mid 381.185355 -260.474182)
				(end 381.18923 -260.454648)
			)
			(xy 381.18923 -259.27558) (xy 381.18288 -259.269484) (xy 379.01499 -259.269484) (xy 379.008894 -259.26288)
			(arc
				(start 377.43638 -259.26288)
				(mid 377.417023 -259.259047)
				(end 377.400566 -259.248148)
			)
			(xy 377.398788 -259.24637)
			(arc
				(start 377.298458 -259.24637)
				(mid 377.278935 -259.250271)
				(end 377.26239 -259.261356)
			)
			(arc
				(start 377.210828 -259.312918)
				(mid 377.199717 -259.329452)
				(end 377.195842 -259.348986)
			)
			(xy 377.195842 -260.28269) (xy 377.196096 -260.28269)
			(arc
				(start 377.196096 -260.384036)
				(mid 377.199997 -260.403559)
				(end 377.211082 -260.420104)
			)
			(arc
				(start 377.290584 -260.499606)
				(mid 377.307001 -260.510668)
				(end 377.326398 -260.514592)
			)
		)
		(stroke
			(width 0)
			(type solid)
		)
		(fill yes)
		(layer "F.Cu")
		(net "GND")
	)
	(gr_poly
		(pts
			(xy 395.755876 -55.681118) (xy 395.755876 -53.54193) (xy 395.703044 -53.489098) (xy 395.371828 -53.489098)
			(xy 395.35862 -53.502306) (xy 395.259052 -53.502306) (xy 395.256258 -53.499512) (xy 395.064234 -53.499512)
			(xy 394.974318 -53.409596) (xy 394.974318 -53.217572) (xy 394.974318 -52.019708) (xy 392.315192 -49.360582)
			(xy 392.315192 -48.054514) (xy 393.23899 -47.130716) (xy 394.4493 -47.130716) (xy 394.588492 -46.991524)
			(xy 394.588492 -46.65726) (xy 394.841222 -46.40453) (xy 395.332458 -46.40453) (xy 395.430756 -46.306232)
			(xy 395.993112 -46.306232) (xy 396.038324 -46.26102) (xy 396.038324 -46.155356) (xy 395.958822 -46.075854)
			(xy 395.143482 -46.075854) (xy 395.041628 -45.974) (xy 395.030198 -45.974) (xy 394.701776 -45.645578)
			(xy 388.20979 -45.645578) (xy 387.876542 -45.978826) (xy 387.876542 -55.041292) (xy 388.105904 -55.270654)
			(xy 394.729208 -55.270654) (xy 395.23924 -55.780686) (xy 395.656308 -55.780686)
		)
		(stroke
			(width 0)
			(type solid)
		)
		(fill yes)
		(layer "F.Cu")
		(net "P12V_SSD13_R")
	)
	(gr_poly
		(pts
			(xy 421.755824 -55.681118) (xy 421.755824 -53.54193) (xy 421.702992 -53.489098) (xy 421.371776 -53.489098)
			(xy 421.358568 -53.502306) (xy 421.259 -53.502306) (xy 421.259 -53.501036) (xy 421.040052 -53.501036)
			(xy 420.974266 -53.43525) (xy 420.974266 -53.216048) (xy 420.974266 -52.019708) (xy 418.31514 -49.360582)
			(xy 418.31514 -48.054514) (xy 419.238938 -47.130716) (xy 420.449248 -47.130716) (xy 420.58844 -46.991524)
			(xy 420.58844 -46.65726) (xy 420.84117 -46.40453) (xy 421.332406 -46.40453) (xy 421.430704 -46.306232)
			(xy 421.99306 -46.306232) (xy 422.038272 -46.26102) (xy 422.038272 -46.155356) (xy 421.95877 -46.075854)
			(xy 421.14343 -46.075854) (xy 421.041576 -45.974) (xy 421.030146 -45.974) (xy 420.701724 -45.645578)
			(xy 414.209738 -45.645578) (xy 413.87649 -45.978826) (xy 413.87649 -55.041292) (xy 414.105852 -55.270654)
			(xy 420.729156 -55.270654) (xy 421.239188 -55.780686) (xy 421.656256 -55.780686)
		)
		(stroke
			(width 0)
			(type solid)
		)
		(fill yes)
		(layer "F.Cu")
		(net "P12V_SSD14_R")
	)
	(gr_poly
		(pts
			(xy 447.755772 -55.681118) (xy 447.755772 -53.54193) (xy 447.70294 -53.489098) (xy 447.371724 -53.489098)
			(xy 447.358516 -53.502306) (xy 447.258948 -53.502306) (xy 447.256154 -53.499512) (xy 447.06667 -53.499512)
			(xy 446.974214 -53.407056) (xy 446.974214 -53.217572) (xy 446.974214 -52.019708) (xy 444.315088 -49.360582)
			(xy 444.315088 -48.054514) (xy 445.238886 -47.130716) (xy 446.449196 -47.130716) (xy 446.588388 -46.991524)
			(xy 446.588388 -46.65726) (xy 446.841118 -46.40453) (xy 447.332354 -46.40453) (xy 447.430652 -46.306232)
			(xy 447.993008 -46.306232) (xy 448.03822 -46.26102) (xy 448.03822 -46.155356) (xy 447.958718 -46.075854)
			(xy 447.143378 -46.075854) (xy 447.041524 -45.974) (xy 447.030094 -45.974) (xy 446.701672 -45.645578)
			(xy 440.209686 -45.645578) (xy 439.876438 -45.978826) (xy 439.876438 -55.041292) (xy 440.1058 -55.270654)
			(xy 446.729104 -55.270654) (xy 447.239136 -55.780686) (xy 447.656204 -55.780686)
		)
		(stroke
			(width 0)
			(type solid)
		)
		(fill yes)
		(layer "F.Cu")
		(net "P12V_SSD15_R")
	)
	(gr_poly
		(pts
			(xy 456.55992 -113.483644) (xy 456.55992 -109.307122) (xy 457.035662 -108.83138) (xy 459.332076 -108.83138)
			(xy 459.50251 -108.660946) (xy 459.50251 -96.162368) (xy 458.484478 -95.144336) (xy 451.202552 -95.144336)
			(xy 449.815204 -96.531684) (xy 449.00342 -96.531684) (xy 448.23761 -97.297494) (xy 447.079624 -97.297494)
			(xy 447.03365 -97.343468) (xy 447.03365 -97.870518) (xy 446.895728 -98.00844) (xy 444.42126 -98.00844)
			(xy 444.369952 -98.059748) (xy 444.369952 -99.868482) (xy 444.42634 -99.92487) (xy 448.258946 -99.92487)
			(arc
				(start 448.344798 -100.010722)
				(mid 448.361332 -100.021833)
				(end 448.380866 -100.025708)
			)
			(xy 451.157848 -100.025708) (xy 451.158356 -100.0252) (xy 455.111104 -100.0252) (xy 455.313796 -100.227892)
			(xy 455.313796 -103.17734) (xy 454.407778 -104.083358) (xy 454.407778 -108.363512) (xy 455.225912 -109.181646)
			(xy 455.257916 -109.213396) (xy 455.257916 -113.504218) (xy 456.539346 -113.504218)
		)
		(stroke
			(width 0)
			(type solid)
		)
		(fill yes)
		(layer "F.Cu")
		(net "P12V_AUX")
	)
	(gr_poly
		(pts
			(xy 115.013994 -176.258982) (xy 115.013994 -176.119536) (xy 115.013994 -173.784006) (xy 115.013994 -172.387006)
			(xy 115.013994 -170.097196) (xy 112.206024 -167.289226) (xy 112.206024 -164.831268) (xy 112.206024 -164.644578)
			(xy 112.206024 -164.231828) (xy 111.814102 -163.839906) (xy 111.401352 -163.839906) (xy 111.19612 -163.634674)
			(xy 110.653068 -163.091622) (xy 110.329472 -162.768026) (xy 110.329472 -162.392868) (xy 110.328964 -162.39236)
			(xy 110.328964 -158.44266) (xy 110.328964 -158.15945) (xy 110.32998 -158.158688) (xy 110.32998 -158.095696)
			(xy 110.661704 -157.763972) (xy 110.661704 -157.385766) (xy 110.607094 -157.331156) (xy 110.097824 -157.331156)
			(xy 110.019084 -157.409896) (xy 110.019084 -160.70072) (xy 109.651546 -161.068258) (xy 109.180376 -161.539428)
			(xy 109.180376 -163.397946) (xy 108.324904 -164.253418) (xy 108.324904 -167.98671) (xy 106.462068 -169.849546)
			(xy 106.462068 -172.43298) (xy 106.462068 -174.864268) (xy 106.462068 -176.194974) (xy 106.904028 -176.636934)
			(xy 114.636042 -176.636934)
		)
		(stroke
			(width 0)
			(type solid)
		)
		(fill yes)
		(layer "F.Cu")
		(net "SW_P12V_P3V3_AUX_FLT")
	)
	(gr_poly
		(pts
			(xy 261.435342 -262.215376) (xy 263.02335 -262.215376)
			(arc
				(start 265.005312 -262.215376)
				(mid 265.024835 -262.211475)
				(end 265.04138 -262.20039)
			)
			(arc
				(start 265.045698 -262.196072)
				(mid 265.056809 -262.179538)
				(end 265.060684 -262.160004)
			)
			(arc
				(start 265.060684 -260.857238)
				(mid 265.056783 -260.837715)
				(end 265.045698 -260.82117)
			)
			(arc
				(start 265.00836 -260.783832)
				(mid 264.991826 -260.772721)
				(end 264.972292 -260.768846)
			)
			(arc
				(start 261.307326 -260.768846)
				(mid 261.287803 -260.772747)
				(end 261.271258 -260.783832)
			)
			(arc
				(start 261.122922 -260.932168)
				(mid 261.111811 -260.948702)
				(end 261.107936 -260.968236)
			)
			(xy 261.107936 -261.300468) (xy 260.964172 -261.444232) (xy 260.31063 -261.444232) (xy 260.155436 -261.599426)
			(xy 260.155436 -262.039862) (xy 259.938774 -262.256524) (xy 258.998974 -262.256524) (xy 258.934204 -262.321294)
			(xy 258.934204 -262.515604) (xy 258.956556 -262.537956) (xy 261.112762 -262.537956)
		)
		(stroke
			(width 0)
			(type solid)
		)
		(fill yes)
		(layer "F.Cu")
		(net "P1V8_PLL0_PEX2")
	)
	(gr_poly
		(pts
			(arc
				(start 3.054604 -41.48582)
				(mid 3.074127 -41.481919)
				(end 3.090672 -41.470834)
			)
			(arc
				(start 3.502406 -41.0591)
				(mid 3.51894 -41.047989)
				(end 3.538474 -41.044114)
			)
			(arc
				(start 3.923284 -41.044114)
				(mid 3.942807 -41.040213)
				(end 3.959352 -41.029128)
			)
			(arc
				(start 4.079494 -40.908986)
				(mid 4.090605 -40.892452)
				(end 4.09448 -40.872918)
			)
			(arc
				(start 4.09448 -40.261286)
				(mid 4.090696 -40.241792)
				(end 4.079748 -40.225218)
			)
			(arc
				(start 4.053078 -40.198548)
				(mid 4.036544 -40.187437)
				(end 4.01701 -40.183562)
			)
			(xy 1.65354 -40.183562) (xy 1.634998 -40.191182)
			(arc
				(start 1.631188 -40.194992)
				(mid 1.620077 -40.211526)
				(end 1.616202 -40.23106)
			)
			(arc
				(start 1.616202 -41.423336)
				(mid 1.620103 -41.442859)
				(end 1.631188 -41.459404)
			)
			(arc
				(start 1.642618 -41.470834)
				(mid 1.659152 -41.481945)
				(end 1.678686 -41.48582)
			)
		)
		(stroke
			(width 0)
			(type solid)
		)
		(fill yes)
		(layer "F.Cu")
		(net "P3V3_AUX")
	)
	(gr_poly
		(pts
			(arc
				(start 29.871416 -284.069536)
				(mid 29.890939 -284.065635)
				(end 29.907484 -284.05455)
			)
			(xy 29.91612 -284.045914)
			(arc
				(start 29.916628 -284.045406)
				(mid 29.92737 -284.029049)
				(end 29.931106 -284.009846)
			)
			(arc
				(start 29.931106 -282.85186)
				(mid 29.929132 -282.837581)
				(end 29.923232 -282.824428)
			)
			(xy 27.756866 -282.824428) (xy 27.75077 -282.818332)
			(arc
				(start 26.178256 -282.818332)
				(mid 26.158869 -282.814382)
				(end 26.142442 -282.803346)
			)
			(xy 26.140664 -282.801568)
			(arc
				(start 26.040334 -282.801568)
				(mid 26.020811 -282.805469)
				(end 26.004266 -282.816554)
			)
			(xy 25.952704 -282.868116) (xy 25.945338 -282.875228) (xy 25.937718 -282.894024) (xy 25.937718 -283.837888)
			(xy 25.937972 -283.837888)
			(arc
				(start 25.937972 -283.939234)
				(mid 25.941737 -283.958425)
				(end 25.95245 -283.974794)
			)
			(xy 25.952704 -283.975048)
			(arc
				(start 26.032206 -284.05455)
				(mid 26.04874 -284.065661)
				(end 26.068274 -284.069536)
			)
		)
		(stroke
			(width 0)
			(type solid)
		)
		(fill yes)
		(layer "F.Cu")
		(net "GND")
	)
	(gr_poly
		(pts
			(xy 108.25988 -113.512854) (xy 108.25988 -109.307122) (xy 108.735622 -108.83138) (xy 111.032036 -108.83138)
			(xy 111.20247 -108.660946) (xy 111.20247 -96.162368) (xy 110.708948 -95.668846) (xy 107.330748 -95.668846)
			(xy 106.806238 -95.144336) (xy 102.902512 -95.144336) (xy 101.515164 -96.531684) (xy 100.70338 -96.531684)
			(xy 99.93757 -97.297494) (xy 98.779584 -97.297494) (xy 98.73361 -97.343468) (xy 98.73361 -97.870518)
			(xy 98.595688 -98.00844) (xy 96.12122 -98.00844) (xy 96.069912 -98.059748) (xy 96.069912 -99.868482)
			(xy 96.14408 -99.94265) (xy 99.976686 -99.94265)
			(arc
				(start 100.044758 -100.010722)
				(mid 100.061292 -100.021833)
				(end 100.080826 -100.025708)
			)
			(xy 102.857808 -100.025708) (xy 102.858316 -100.0252) (xy 106.811064 -100.0252) (xy 107.013756 -100.227892)
			(xy 107.013756 -103.17734) (xy 106.107738 -104.083358) (xy 106.107738 -108.363512) (xy 106.925872 -109.181646)
			(xy 106.957876 -109.213396) (xy 106.957876 -113.504218) (xy 106.979466 -113.525808) (xy 108.246926 -113.525808)
		)
		(stroke
			(width 0)
			(type solid)
		)
		(fill yes)
		(layer "F.Cu")
		(net "P12V_AUX")
	)
	(gr_poly
		(pts
			(arc
				(start 145.971514 -284.069536)
				(mid 145.991037 -284.065635)
				(end 146.007582 -284.05455)
			)
			(xy 146.016218 -284.045914)
			(arc
				(start 146.016726 -284.045406)
				(mid 146.027468 -284.029049)
				(end 146.031204 -284.009846)
			)
			(arc
				(start 146.031204 -282.85186)
				(mid 146.02923 -282.837581)
				(end 146.02333 -282.824428)
			)
			(xy 143.856964 -282.824428) (xy 143.850868 -282.818332)
			(arc
				(start 142.278354 -282.818332)
				(mid 142.258967 -282.814382)
				(end 142.24254 -282.803346)
			)
			(xy 142.240762 -282.801568)
			(arc
				(start 142.140432 -282.801568)
				(mid 142.120909 -282.805469)
				(end 142.104364 -282.816554)
			)
			(xy 142.052802 -282.868116) (xy 142.045436 -282.875228) (xy 142.037816 -282.894024) (xy 142.037816 -283.837888)
			(xy 142.03807 -283.837888)
			(arc
				(start 142.03807 -283.939234)
				(mid 142.041835 -283.958425)
				(end 142.052548 -283.974794)
			)
			(xy 142.052802 -283.975048)
			(arc
				(start 142.132304 -284.05455)
				(mid 142.148838 -284.065661)
				(end 142.168372 -284.069536)
			)
		)
		(stroke
			(width 0)
			(type solid)
		)
		(fill yes)
		(layer "F.Cu")
		(net "GND")
	)
	(gr_poly
		(pts
			(arc
				(start 262.071358 -284.069536)
				(mid 262.090881 -284.065635)
				(end 262.107426 -284.05455)
			)
			(xy 262.116062 -284.045914)
			(arc
				(start 262.11657 -284.045406)
				(mid 262.127312 -284.029049)
				(end 262.131048 -284.009846)
			)
			(arc
				(start 262.131048 -282.85186)
				(mid 262.129074 -282.837581)
				(end 262.123174 -282.824428)
			)
			(xy 259.956808 -282.824428) (xy 259.950712 -282.818332)
			(arc
				(start 258.378198 -282.818332)
				(mid 258.358811 -282.814382)
				(end 258.342384 -282.803346)
			)
			(xy 258.340606 -282.801568)
			(arc
				(start 258.240276 -282.801568)
				(mid 258.220753 -282.805469)
				(end 258.204208 -282.816554)
			)
			(xy 258.152646 -282.868116) (xy 258.14528 -282.875228) (xy 258.13766 -282.894024) (xy 258.13766 -283.837888)
			(xy 258.137914 -283.837888)
			(arc
				(start 258.137914 -283.939234)
				(mid 258.141679 -283.958425)
				(end 258.152392 -283.974794)
			)
			(xy 258.152646 -283.975048)
			(arc
				(start 258.232148 -284.05455)
				(mid 258.248682 -284.065661)
				(end 258.268216 -284.069536)
			)
		)
		(stroke
			(width 0)
			(type solid)
		)
		(fill yes)
		(layer "F.Cu")
		(net "GND")
	)
	(gr_poly
		(pts
			(xy 340.459822 -113.512854) (xy 340.459822 -109.307122) (xy 340.935564 -108.83138) (xy 343.231978 -108.83138)
			(xy 343.402412 -108.660946) (xy 343.402412 -96.162368) (xy 342.84158 -95.601536) (xy 339.24494 -95.601536)
			(xy 339.21827 -95.574866) (xy 334.671924 -95.574866) (xy 333.715106 -96.531684) (xy 332.903322 -96.531684)
			(xy 332.137512 -97.297494) (xy 330.979526 -97.297494) (xy 330.933552 -97.343468) (xy 330.933552 -97.870518)
			(xy 330.79563 -98.00844) (xy 328.321162 -98.00844) (xy 328.269854 -98.059748) (xy 328.269854 -99.868482)
			(xy 328.344022 -99.94265) (xy 332.176628 -99.94265)
			(arc
				(start 332.2447 -100.010722)
				(mid 332.261234 -100.021833)
				(end 332.280768 -100.025708)
			)
			(xy 335.05775 -100.025708) (xy 335.058258 -100.0252) (xy 339.011006 -100.0252) (xy 339.213698 -100.227892)
			(xy 339.213698 -103.17734) (xy 338.30768 -104.083358) (xy 338.30768 -108.363512) (xy 339.125814 -109.181646)
			(xy 339.157818 -109.213396) (xy 339.157818 -113.504218) (xy 339.179408 -113.525808) (xy 340.446868 -113.525808)
		)
		(stroke
			(width 0)
			(type solid)
		)
		(fill yes)
		(layer "F.Cu")
		(net "P12V_AUX")
	)
	(gr_poly
		(pts
			(arc
				(start 378.171456 -284.069536)
				(mid 378.190979 -284.065635)
				(end 378.207524 -284.05455)
			)
			(xy 378.21616 -284.045914)
			(arc
				(start 378.216668 -284.045406)
				(mid 378.22741 -284.029049)
				(end 378.231146 -284.009846)
			)
			(arc
				(start 378.231146 -282.85186)
				(mid 378.229172 -282.837581)
				(end 378.223272 -282.824428)
			)
			(xy 376.056906 -282.824428) (xy 376.05081 -282.818332)
			(arc
				(start 374.478296 -282.818332)
				(mid 374.458909 -282.814382)
				(end 374.442482 -282.803346)
			)
			(xy 374.440704 -282.801568)
			(arc
				(start 374.340374 -282.801568)
				(mid 374.320851 -282.805469)
				(end 374.304306 -282.816554)
			)
			(xy 374.252744 -282.868116) (xy 374.245378 -282.875228) (xy 374.237758 -282.894024) (xy 374.237758 -283.837888)
			(xy 374.238012 -283.837888)
			(arc
				(start 374.238012 -283.939234)
				(mid 374.241777 -283.958425)
				(end 374.25249 -283.974794)
			)
			(xy 374.252744 -283.975048)
			(arc
				(start 374.332246 -284.05455)
				(mid 374.34878 -284.065661)
				(end 374.368314 -284.069536)
			)
		)
		(stroke
			(width 0)
			(type solid)
		)
		(fill yes)
		(layer "F.Cu")
		(net "GND")
	)
	(gr_poly
		(pts
			(xy 102.858316 -284.647386) (xy 105.57256 -284.647386) (xy 105.576624 -284.643322) (xy 105.576624 -282.607004)
			(xy 105.561638 -282.592018) (xy 104.069134 -282.592018) (xy 104.024938 -282.547822) (xy 104.024938 -281.256486)
			(xy 103.89489 -281.126438) (xy 103.89489 -279.795732) (xy 104.185212 -279.50541) (xy 104.185212 -278.720042)
			(xy 104.398064 -278.50719) (xy 109.06506 -278.50719) (xy 110.191042 -279.633172) (xy 110.191042 -284.606238)
			(xy 110.284006 -284.699202) (xy 110.967012 -284.699202) (xy 111.018828 -284.647386) (xy 113.733072 -284.647386)
			(xy 113.737136 -284.643322) (xy 113.737136 -282.607004) (xy 113.72215 -282.592018) (xy 112.229646 -282.592018)
			(xy 112.18545 -282.547822) (xy 112.18545 -281.229054) (xy 112.053624 -281.097228) (xy 112.053624 -279.72766)
			(xy 112.338612 -279.442672) (xy 112.338612 -272.590514) (xy 112.197896 -272.449798) (xy 102.241858 -272.449798)
			(xy 102.03053 -272.661126) (xy 102.03053 -280.632408) (xy 102.031038 -280.643584) (xy 102.03053 -280.65476)
			(xy 102.03053 -284.606238) (xy 102.123494 -284.699202) (xy 102.8065 -284.699202)
		)
		(stroke
			(width 0)
			(type solid)
		)
		(fill yes)
		(layer "F.Cu")
		(net "SW_P12V_P0V8_PEX0_FLT")
	)
	(gr_poly
		(pts
			(xy 119.517414 -284.647386) (xy 122.231658 -284.647386) (xy 122.235722 -284.643322) (xy 122.235722 -282.607004)
			(xy 122.220736 -282.592018) (xy 120.728232 -282.592018) (xy 120.684036 -282.547822) (xy 120.684036 -281.256486)
			(xy 120.553988 -281.126438) (xy 120.553988 -279.795732) (xy 120.84431 -279.50541) (xy 120.84431 -278.720042)
			(xy 121.057162 -278.50719) (xy 125.724158 -278.50719) (xy 126.85014 -279.633172) (xy 126.85014 -284.606238)
			(xy 126.943104 -284.699202) (xy 127.62611 -284.699202) (xy 127.677926 -284.647386) (xy 130.39217 -284.647386)
			(xy 130.396234 -284.643322) (xy 130.396234 -282.607004) (xy 130.381248 -282.592018) (xy 128.888744 -282.592018)
			(xy 128.844548 -282.547822) (xy 128.844548 -281.229054) (xy 128.712722 -281.097228) (xy 128.712722 -279.72766)
			(xy 128.99771 -279.442672) (xy 128.99771 -272.590514) (xy 128.856994 -272.449798) (xy 118.900956 -272.449798)
			(xy 118.689628 -272.661126) (xy 118.689628 -280.632408) (xy 118.690136 -280.643584) (xy 118.689628 -280.65476)
			(xy 118.689628 -284.606238) (xy 118.782592 -284.699202) (xy 119.465598 -284.699202)
		)
		(stroke
			(width 0)
			(type solid)
		)
		(fill yes)
		(layer "F.Cu")
		(net "SW_P12V_P0V8_PEX1_FLT")
	)
	(gr_poly
		(pts
			(xy 335.058512 -284.647386) (xy 337.772756 -284.647386) (xy 337.77682 -284.643322) (xy 337.77682 -282.607004)
			(xy 337.761834 -282.592018) (xy 336.26933 -282.592018) (xy 336.225134 -282.547822) (xy 336.225134 -281.256486)
			(xy 336.095086 -281.126438) (xy 336.095086 -279.795732) (xy 336.385408 -279.50541) (xy 336.385408 -278.720042)
			(xy 336.59826 -278.50719) (xy 341.265256 -278.50719) (xy 342.391238 -279.633172) (xy 342.391238 -284.606238)
			(xy 342.484202 -284.699202) (xy 343.167208 -284.699202) (xy 343.219024 -284.647386) (xy 345.933268 -284.647386)
			(xy 345.937332 -284.643322) (xy 345.937332 -282.607004) (xy 345.922346 -282.592018) (xy 344.429842 -282.592018)
			(xy 344.385646 -282.547822) (xy 344.385646 -281.229054) (xy 344.25382 -281.097228) (xy 344.25382 -279.72766)
			(xy 344.538808 -279.442672) (xy 344.538808 -272.590514) (xy 344.398092 -272.449798) (xy 334.442054 -272.449798)
			(xy 334.230726 -272.661126) (xy 334.230726 -280.632408) (xy 334.231234 -280.643584) (xy 334.230726 -280.65476)
			(xy 334.230726 -284.606238) (xy 334.32369 -284.699202) (xy 335.006696 -284.699202)
		)
		(stroke
			(width 0)
			(type solid)
		)
		(fill yes)
		(layer "F.Cu")
		(net "SW_P12V_P0V8_PEX2_FLT")
	)
	(gr_poly
		(pts
			(xy 351.71761 -284.647386) (xy 354.431854 -284.647386) (xy 354.435918 -284.643322) (xy 354.435918 -282.607004)
			(xy 354.420932 -282.592018) (xy 352.928428 -282.592018) (xy 352.884232 -282.547822) (xy 352.884232 -281.256486)
			(xy 352.754184 -281.126438) (xy 352.754184 -279.795732) (xy 353.044506 -279.50541) (xy 353.044506 -278.720042)
			(xy 353.257358 -278.50719) (xy 357.924354 -278.50719) (xy 359.050336 -279.633172) (xy 359.050336 -284.606238)
			(xy 359.1433 -284.699202) (xy 359.826306 -284.699202) (xy 359.878122 -284.647386) (xy 362.592366 -284.647386)
			(xy 362.59643 -284.643322) (xy 362.59643 -282.607004) (xy 362.581444 -282.592018) (xy 361.08894 -282.592018)
			(xy 361.044744 -282.547822) (xy 361.044744 -281.229054) (xy 360.912918 -281.097228) (xy 360.912918 -279.72766)
			(xy 361.197906 -279.442672) (xy 361.197906 -272.590514) (xy 361.05719 -272.449798) (xy 351.101152 -272.449798)
			(xy 350.889824 -272.661126) (xy 350.889824 -280.632408) (xy 350.890332 -280.643584) (xy 350.889824 -280.65476)
			(xy 350.889824 -284.606238) (xy 350.982788 -284.699202) (xy 351.665794 -284.699202)
		)
		(stroke
			(width 0)
			(type solid)
		)
		(fill yes)
		(layer "F.Cu")
		(net "SW_P12V_P0V8_PEX3_FLT")
	)
	(gr_poly
		(pts
			(arc
				(start 28.36545 -261.171436)
				(mid 28.384973 -261.167535)
				(end 28.401518 -261.15645)
			)
			(arc
				(start 28.468066 -261.089648)
				(mid 28.479128 -261.073231)
				(end 28.483052 -261.053834)
			)
			(arc
				(start 28.483052 -258.94157)
				(mid 28.479151 -258.922047)
				(end 28.468066 -258.905502)
			)
			(arc
				(start 28.329128 -258.766564)
				(mid 28.312594 -258.755453)
				(end 28.29306 -258.751578)
			)
			(arc
				(start 27.659838 -258.751578)
				(mid 27.640315 -258.755479)
				(end 27.62377 -258.766564)
			)
			(arc
				(start 27.572208 -258.818126)
				(mid 27.561097 -258.83466)
				(end 27.557222 -258.854194)
			)
			(arc
				(start 27.557222 -260.20649)
				(mid 27.561123 -260.226013)
				(end 27.572208 -260.242558)
			)
			(arc
				(start 27.897328 -260.567678)
				(mid 27.908439 -260.584212)
				(end 27.912314 -260.603746)
			)
			(arc
				(start 27.912314 -260.997954)
				(mid 27.916264 -261.017341)
				(end 27.9273 -261.033768)
			)
			(arc
				(start 28.049728 -261.15645)
				(mid 28.066262 -261.167561)
				(end 28.085796 -261.171436)
			)
		)
		(stroke
			(width 0)
			(type solid)
		)
		(fill yes)
		(layer "F.Cu")
		(net "P1V8_VDDA_PEX0_R")
	)
	(gr_poly
		(pts
			(xy 143.341598 -262.464042) (xy 144.138396 -262.464042) (xy 144.393412 -262.209026) (xy 145.341848 -262.209026)
			(xy 146.91741 -262.209026) (xy 146.923506 -262.215376)
			(arc
				(start 148.905468 -262.215376)
				(mid 148.924991 -262.211475)
				(end 148.941536 -262.20039)
			)
			(arc
				(start 148.945854 -262.196072)
				(mid 148.956965 -262.179538)
				(end 148.96084 -262.160004)
			)
			(arc
				(start 148.96084 -260.857238)
				(mid 148.956939 -260.837715)
				(end 148.945854 -260.82117)
			)
			(arc
				(start 148.908516 -260.783832)
				(mid 148.891982 -260.772721)
				(end 148.872448 -260.768846)
			)
			(xy 145.278602 -260.768846) (xy 144.591786 -261.455662) (xy 143.354298 -261.455662) (xy 143.34998 -261.45998)
			(xy 143.263112 -261.546594) (xy 143.263112 -261.968234) (xy 143.263112 -262.168132) (xy 143.20266 -262.228584)
			(xy 143.10233 -262.228584) (xy 143.100298 -262.226552) (xy 142.868904 -262.226552) (xy 142.86103 -262.234426)
			(xy 142.8369 -262.258556) (xy 142.8369 -262.486394) (xy 142.8369 -262.537194) (xy 142.853918 -262.554212)
			(xy 142.904718 -262.554212) (xy 143.251428 -262.554212)
		)
		(stroke
			(width 0)
			(type solid)
		)
		(fill yes)
		(layer "F.Cu")
		(net "P1V8_PLL0_PEX1")
	)
	(gr_poly
		(pts
			(arc
				(start 144.465548 -261.171436)
				(mid 144.485071 -261.167535)
				(end 144.501616 -261.15645)
			)
			(arc
				(start 144.568164 -261.089648)
				(mid 144.579226 -261.073231)
				(end 144.58315 -261.053834)
			)
			(arc
				(start 144.58315 -258.94157)
				(mid 144.579249 -258.922047)
				(end 144.568164 -258.905502)
			)
			(arc
				(start 144.429226 -258.766564)
				(mid 144.412692 -258.755453)
				(end 144.393158 -258.751578)
			)
			(arc
				(start 143.759936 -258.751578)
				(mid 143.740413 -258.755479)
				(end 143.723868 -258.766564)
			)
			(arc
				(start 143.672306 -258.818126)
				(mid 143.661195 -258.83466)
				(end 143.65732 -258.854194)
			)
			(arc
				(start 143.65732 -260.20649)
				(mid 143.661221 -260.226013)
				(end 143.672306 -260.242558)
			)
			(arc
				(start 143.997426 -260.567678)
				(mid 144.008537 -260.584212)
				(end 144.012412 -260.603746)
			)
			(arc
				(start 144.012412 -260.997954)
				(mid 144.016362 -261.017341)
				(end 144.027398 -261.033768)
			)
			(arc
				(start 144.149826 -261.15645)
				(mid 144.16636 -261.167561)
				(end 144.185894 -261.171436)
			)
		)
		(stroke
			(width 0)
			(type solid)
		)
		(fill yes)
		(layer "F.Cu")
		(net "P1V8_VDDA_PEX1_R")
	)
	(gr_poly
		(pts
			(arc
				(start 208.066132 -114.10823)
				(mid 208.094319 -114.099693)
				(end 208.113122 -114.076988)
			)
			(xy 208.118964 -114.06251) (xy 208.113122 -114.032538) (xy 208.111852 -114.031522)
			(arc
				(start 208.111852 -113.657634)
				(mid 208.132857 -113.546601)
				(end 208.192878 -113.450878)
			)
			(arc
				(start 208.192878 -113.450878)
				(mid 208.202904 -113.434883)
				(end 208.20634 -113.416334)
			)
			(xy 208.20634 -111.891064) (xy 208.055464 -111.740188) (xy 206.367634 -111.740188) (xy 206.331058 -111.776764)
			(xy 206.331058 -112.362234) (xy 206.904082 -112.935258)
			(arc
				(start 206.904082 -113.068354)
				(mid 206.907983 -113.087877)
				(end 206.919068 -113.104422)
			)
			(arc
				(start 207.330802 -113.516156)
				(mid 207.341913 -113.53269)
				(end 207.345788 -113.552224)
			)
			(arc
				(start 207.345788 -113.937034)
				(mid 207.349689 -113.956557)
				(end 207.360774 -113.973102)
			)
			(arc
				(start 207.480916 -114.093244)
				(mid 207.49745 -114.104355)
				(end 207.516984 -114.10823)
			)
		)
		(stroke
			(width 0)
			(type solid)
		)
		(fill yes)
		(layer "F.Cu")
		(net "P3V3_AUX")
	)
	(gr_poly
		(pts
			(arc
				(start 260.565392 -261.171436)
				(mid 260.584915 -261.167535)
				(end 260.60146 -261.15645)
			)
			(arc
				(start 260.668008 -261.089648)
				(mid 260.67907 -261.073231)
				(end 260.682994 -261.053834)
			)
			(arc
				(start 260.682994 -258.94157)
				(mid 260.679093 -258.922047)
				(end 260.668008 -258.905502)
			)
			(arc
				(start 260.52907 -258.766564)
				(mid 260.512536 -258.755453)
				(end 260.493002 -258.751578)
			)
			(arc
				(start 259.85978 -258.751578)
				(mid 259.840257 -258.755479)
				(end 259.823712 -258.766564)
			)
			(arc
				(start 259.77215 -258.818126)
				(mid 259.761039 -258.83466)
				(end 259.757164 -258.854194)
			)
			(arc
				(start 259.757164 -260.20649)
				(mid 259.761065 -260.226013)
				(end 259.77215 -260.242558)
			)
			(arc
				(start 260.09727 -260.567678)
				(mid 260.108381 -260.584212)
				(end 260.112256 -260.603746)
			)
			(arc
				(start 260.112256 -260.997954)
				(mid 260.116206 -261.017341)
				(end 260.127242 -261.033768)
			)
			(arc
				(start 260.24967 -261.15645)
				(mid 260.266204 -261.167561)
				(end 260.285738 -261.171436)
			)
		)
		(stroke
			(width 0)
			(type solid)
		)
		(fill yes)
		(layer "F.Cu")
		(net "P1V8_VDDA_PEX2_R")
	)
	(gr_poly
		(pts
			(arc
				(start 376.66549 -261.171436)
				(mid 376.685013 -261.167535)
				(end 376.701558 -261.15645)
			)
			(arc
				(start 376.768106 -261.089648)
				(mid 376.779168 -261.073231)
				(end 376.783092 -261.053834)
			)
			(arc
				(start 376.783092 -258.94157)
				(mid 376.779191 -258.922047)
				(end 376.768106 -258.905502)
			)
			(arc
				(start 376.629168 -258.766564)
				(mid 376.612634 -258.755453)
				(end 376.5931 -258.751578)
			)
			(arc
				(start 375.959878 -258.751578)
				(mid 375.940355 -258.755479)
				(end 375.92381 -258.766564)
			)
			(arc
				(start 375.872248 -258.818126)
				(mid 375.861137 -258.83466)
				(end 375.857262 -258.854194)
			)
			(arc
				(start 375.857262 -260.20649)
				(mid 375.861163 -260.226013)
				(end 375.872248 -260.242558)
			)
			(arc
				(start 376.197368 -260.567678)
				(mid 376.208479 -260.584212)
				(end 376.212354 -260.603746)
			)
			(arc
				(start 376.212354 -260.997954)
				(mid 376.216304 -261.017341)
				(end 376.22734 -261.033768)
			)
			(arc
				(start 376.349768 -261.15645)
				(mid 376.366302 -261.167561)
				(end 376.385836 -261.171436)
			)
		)
		(stroke
			(width 0)
			(type solid)
		)
		(fill yes)
		(layer "F.Cu")
		(net "P1V8_VDDA_PEX3_R")
	)
	(gr_poly
		(pts
			(xy 9.212326 -274.647406)
			(arc
				(start 9.212326 -274.272502)
				(mid 9.223252 -274.256056)
				(end 9.227058 -274.236688)
			)
			(arc
				(start 9.227058 -273.58848)
				(mid 9.228075 -273.578364)
				(end 9.231122 -273.568668)
			)
			(xy 9.23925 -273.549364)
			(arc
				(start 9.239758 -273.540728)
				(mid 9.244257 -273.523083)
				(end 9.254744 -273.508216)
			)
			(arc
				(start 11.62177 -271.14119)
				(mid 11.632881 -271.124656)
				(end 11.636756 -271.105122)
			)
			(arc
				(start 11.636756 -259.614162)
				(mid 11.632855 -259.594639)
				(end 11.62177 -259.578094)
			)
			(xy 11.468608 -259.424932) (xy 11.461496 -259.417566) (xy 11.4427 -259.409946)
			(arc
				(start 5.236718 -259.409946)
				(mid 5.217195 -259.413847)
				(end 5.20065 -259.424932)
			)
			(xy 4.922774 -259.702808) (xy 4.915408 -259.70992) (xy 4.907788 -259.728716) (xy 4.907788 -269.813024)
			(xy 4.907788 -269.855188) (xy 4.907788 -269.937484) (xy 4.83997 -270.005302) (xy 2.742438 -270.005302)
			(xy 2.182368 -270.565372) (xy 2.182368 -274.928076) (xy 2.529586 -275.275294) (xy 8.584438 -275.275294)
		)
		(stroke
			(width 0)
			(type solid)
		)
		(fill yes)
		(layer "F.Cu")
		(net "P1V25_PEX0")
	)
	(gr_poly
		(pts
			(xy 12.21994 -138.467338) (xy 12.21994 -135.504936) (xy 13.053822 -134.671054) (xy 13.053822 -134.569962)
			(arc
				(start 13.053822 -131.788408)
				(mid 13.049921 -131.768885)
				(end 13.038836 -131.75234)
			)
			(arc
				(start 13.026644 -131.740148)
				(mid 13.015533 -131.723614)
				(end 13.011658 -131.70408)
			)
			(arc
				(start 13.011658 -128.176528)
				(mid 13.007757 -128.157005)
				(end 12.996672 -128.14046)
			)
			(arc
				(start 12.722606 -127.866394)
				(mid 12.706072 -127.855283)
				(end 12.686538 -127.851408)
			)
			(arc
				(start 9.26084 -127.851408)
				(mid 9.241317 -127.855309)
				(end 9.224772 -127.866394)
			)
			(arc
				(start 9.055608 -128.035558)
				(mid 9.044497 -128.052092)
				(end 9.040622 -128.071626)
			)
			(xy 9.040622 -135.170164) (xy 9.575292 -135.704834) (xy 9.575292 -135.836152) (xy 9.575292 -135.905494)
			(xy 9.582404 -135.912606) (xy 10.177018 -135.912606) (xy 10.206482 -135.94207) (xy 10.206482 -135.955786)
			(xy 10.206482 -138.385296) (xy 10.206482 -138.518138) (xy 10.292588 -138.604244) (xy 10.42543 -138.604244)
			(xy 12.083034 -138.604244)
		)
		(stroke
			(width 0)
			(type solid)
		)
		(fill yes)
		(layer "F.Cu")
		(net "P12V_AUX")
	)
	(gr_poly
		(pts
			(xy 101.308916 -391.269982) (xy 101.315012 -391.26414)
			(arc
				(start 101.315012 -390.284208)
				(mid 101.318845 -390.264851)
				(end 101.329744 -390.248394)
			)
			(xy 101.331522 -390.246616) (xy 101.339142 -390.228074) (xy 101.339142 -390.20369) (xy 101.333554 -390.187434)
			(arc
				(start 101.327966 -390.18083)
				(mid 101.213726 -389.974463)
				(end 101.174296 -389.741918)
			)
			(arc
				(start 101.174296 -389.653018)
				(mid 101.159417 -389.617097)
				(end 101.123496 -389.602218)
			)
			(arc
				(start 100.114862 -389.602218)
				(mid 100.095339 -389.606119)
				(end 100.078794 -389.617204)
			)
			(arc
				(start 99.95027 -389.745728)
				(mid 99.939159 -389.762262)
				(end 99.935284 -389.781796)
			)
			(arc
				(start 99.935284 -390.656572)
				(mid 99.939185 -390.676095)
				(end 99.95027 -390.69264)
			)
			(arc
				(start 100.520246 -391.262616)
				(mid 100.53678 -391.273727)
				(end 100.556314 -391.277602)
			)
			(xy 101.290374 -391.277602)
		)
		(stroke
			(width 0)
			(type solid)
		)
		(fill yes)
		(layer "F.Cu")
		(net "P3V3_BIC_USB_HUB")
	)
	(gr_poly
		(pts
			(arc
				(start 118.914164 -119.30888)
				(mid 118.942351 -119.300343)
				(end 118.961154 -119.277638)
			)
			(xy 118.966996 -119.26316) (xy 118.961154 -119.233188) (xy 118.959884 -119.232172)
			(arc
				(start 118.959884 -118.858284)
				(mid 118.980889 -118.747251)
				(end 119.04091 -118.651528)
			)
			(arc
				(start 119.04091 -118.651528)
				(mid 119.050936 -118.635533)
				(end 119.054372 -118.616984)
			)
			(xy 119.054372 -116.986812) (xy 119.054372 -116.004594) (xy 118.897908 -115.84813) (xy 117.035834 -115.84813)
			(xy 116.840508 -116.043456) (xy 116.840508 -117.06733) (xy 117.752114 -117.978936)
			(arc
				(start 117.752114 -118.269004)
				(mid 117.756015 -118.288527)
				(end 117.7671 -118.305072)
			)
			(arc
				(start 118.178834 -118.716806)
				(mid 118.189945 -118.73334)
				(end 118.19382 -118.752874)
			)
			(arc
				(start 118.19382 -119.137684)
				(mid 118.197721 -119.157207)
				(end 118.208806 -119.173752)
			)
			(arc
				(start 118.328948 -119.293894)
				(mid 118.345482 -119.305005)
				(end 118.365016 -119.30888)
			)
		)
		(stroke
			(width 0)
			(type solid)
		)
		(fill yes)
		(layer "F.Cu")
		(net "P3V3_AUX")
	)
	(gr_poly
		(pts
			(xy 128.319784 -138.467338) (xy 128.319784 -135.504936) (xy 129.153666 -134.671054) (xy 129.153666 -134.569962)
			(arc
				(start 129.153666 -131.788408)
				(mid 129.149765 -131.768885)
				(end 129.13868 -131.75234)
			)
			(arc
				(start 129.126488 -131.740148)
				(mid 129.115377 -131.723614)
				(end 129.111502 -131.70408)
			)
			(arc
				(start 129.111502 -128.176528)
				(mid 129.107601 -128.157005)
				(end 129.096516 -128.14046)
			)
			(arc
				(start 128.82245 -127.866394)
				(mid 128.805916 -127.855283)
				(end 128.786382 -127.851408)
			)
			(arc
				(start 125.360684 -127.851408)
				(mid 125.341161 -127.855309)
				(end 125.324616 -127.866394)
			)
			(arc
				(start 125.155452 -128.035558)
				(mid 125.144341 -128.052092)
				(end 125.140466 -128.071626)
			)
			(xy 125.140466 -135.170164) (xy 125.675136 -135.704834) (xy 125.675136 -135.836152) (xy 125.675136 -135.905494)
			(xy 125.682248 -135.912606) (xy 126.276862 -135.912606) (xy 126.306326 -135.94207) (xy 126.306326 -135.955786)
			(xy 126.306326 -138.385296) (xy 126.306326 -138.518138) (xy 126.392432 -138.604244) (xy 126.525274 -138.604244)
			(xy 128.182878 -138.604244)
		)
		(stroke
			(width 0)
			(type solid)
		)
		(fill yes)
		(layer "F.Cu")
		(net "P12V_AUX")
	)
	(gr_poly
		(pts
			(xy 244.419882 -138.467338) (xy 244.419882 -135.504936) (xy 245.253764 -134.671054) (xy 245.253764 -134.569962)
			(arc
				(start 245.253764 -131.788408)
				(mid 245.249863 -131.768885)
				(end 245.238778 -131.75234)
			)
			(arc
				(start 245.226586 -131.740148)
				(mid 245.215475 -131.723614)
				(end 245.2116 -131.70408)
			)
			(arc
				(start 245.2116 -128.176528)
				(mid 245.207699 -128.157005)
				(end 245.196614 -128.14046)
			)
			(arc
				(start 244.922548 -127.866394)
				(mid 244.906014 -127.855283)
				(end 244.88648 -127.851408)
			)
			(arc
				(start 241.460782 -127.851408)
				(mid 241.441259 -127.855309)
				(end 241.424714 -127.866394)
			)
			(arc
				(start 241.25555 -128.035558)
				(mid 241.244439 -128.052092)
				(end 241.240564 -128.071626)
			)
			(xy 241.240564 -135.170164) (xy 241.775234 -135.704834) (xy 241.775234 -135.836152) (xy 241.775234 -135.905494)
			(xy 241.782346 -135.912606) (xy 242.37696 -135.912606) (xy 242.406424 -135.94207) (xy 242.406424 -135.955786)
			(xy 242.406424 -138.385296) (xy 242.406424 -138.518138) (xy 242.49253 -138.604244) (xy 242.625372 -138.604244)
			(xy 244.282976 -138.604244)
		)
		(stroke
			(width 0)
			(type solid)
		)
		(fill yes)
		(layer "F.Cu")
		(net "P12V_AUX")
	)
	(gr_poly
		(pts
			(xy 360.51998 -138.467338) (xy 360.51998 -135.504936) (xy 361.353862 -134.671054) (xy 361.353862 -134.569962)
			(arc
				(start 361.353862 -131.788408)
				(mid 361.349961 -131.768885)
				(end 361.338876 -131.75234)
			)
			(arc
				(start 361.326684 -131.740148)
				(mid 361.315573 -131.723614)
				(end 361.311698 -131.70408)
			)
			(arc
				(start 361.311698 -128.176528)
				(mid 361.307797 -128.157005)
				(end 361.296712 -128.14046)
			)
			(arc
				(start 361.022646 -127.866394)
				(mid 361.006112 -127.855283)
				(end 360.986578 -127.851408)
			)
			(arc
				(start 357.56088 -127.851408)
				(mid 357.541357 -127.855309)
				(end 357.524812 -127.866394)
			)
			(arc
				(start 357.355648 -128.035558)
				(mid 357.344537 -128.052092)
				(end 357.340662 -128.071626)
			)
			(xy 357.340662 -135.170164) (xy 357.875332 -135.704834) (xy 357.875332 -135.836152) (xy 357.875332 -135.905494)
			(xy 357.882444 -135.912606) (xy 358.477058 -135.912606) (xy 358.506522 -135.94207) (xy 358.506522 -135.955786)
			(xy 358.506522 -138.385296) (xy 358.506522 -138.518138) (xy 358.592628 -138.604244) (xy 358.72547 -138.604244)
			(xy 360.383074 -138.604244)
		)
		(stroke
			(width 0)
			(type solid)
		)
		(fill yes)
		(layer "F.Cu")
		(net "P12V_AUX")
	)
	(gr_poly
		(pts
			(arc
				(start 29.847286 -295.371774)
				(mid 29.866809 -295.367873)
				(end 29.883354 -295.356788)
			)
			(arc
				(start 29.887672 -295.35247)
				(mid 29.898783 -295.335936)
				(end 29.902658 -295.316402)
			)
			(arc
				(start 29.902658 -294.013636)
				(mid 29.898757 -293.994113)
				(end 29.887672 -293.977568)
			)
			(arc
				(start 29.850334 -293.94023)
				(mid 29.8338 -293.929119)
				(end 29.814266 -293.925244)
			)
			(xy 28.481782 -293.925244) (xy 28.435046 -293.97198) (xy 28.435046 -294.23487) (xy 28.308046 -294.36187)
			(xy 27.795728 -294.36187) (xy 27.674062 -294.240204) (xy 27.674062 -293.97198) (xy 27.627326 -293.925244)
			(arc
				(start 26.1493 -293.925244)
				(mid 26.129777 -293.929145)
				(end 26.113232 -293.94023)
			)
			(arc
				(start 25.964896 -294.088566)
				(mid 25.953785 -294.1051)
				(end 25.94991 -294.124634)
			)
			(arc
				(start 25.94991 -295.031668)
				(mid 25.953811 -295.051191)
				(end 25.964896 -295.067736)
			)
			(arc
				(start 26.247598 -295.350438)
				(mid 26.264132 -295.361549)
				(end 26.283666 -295.365424)
			)
			(xy 27.859228 -295.365424) (xy 27.865324 -295.371774)
		)
		(stroke
			(width 0)
			(type solid)
		)
		(fill yes)
		(layer "F.Cu")
		(net "P1V8_PLL0_PEX0")
	)
	(gr_poly
		(pts
			(xy 229.475792 -322.445126) (xy 229.475792 -312.125868) (xy 229.36073 -312.010806) (xy 227.739448 -312.010806)
			(xy 227.65385 -312.096404) (xy 227.65385 -321.057778) (xy 227.062284 -321.649344) (xy 224.70618 -321.649344)
			(xy 223.543876 -320.48704) (xy 223.543876 -307.313076) (xy 223.505776 -307.274976) (xy 220.386656 -307.274976)
			(xy 220.245686 -307.415946)
			(arc
				(start 220.245686 -309.790846)
				(mid 220.457932 -310.471046)
				(end 220.529658 -311.179972)
			)
			(arc
				(start 220.529658 -311.179972)
				(mid 220.39878 -312.133572)
				(end 220.015816 -313.016646)
			)
			(xy 220.015816 -319.058798) (xy 220.010736 -319.063878) (xy 220.010736 -320.157602) (xy 220.012768 -320.159634)
			(xy 220.012768 -322.64858) (xy 220.444314 -323.080126) (xy 228.840792 -323.080126)
		)
		(stroke
			(width 0)
			(type solid)
		)
		(fill yes)
		(layer "F.Cu")
		(net "GND")
	)
	(gr_poly
		(pts
			(arc
				(start 29.847286 -285.770574)
				(mid 29.866809 -285.766673)
				(end 29.883354 -285.755588)
			)
			(arc
				(start 29.887672 -285.75127)
				(mid 29.898783 -285.734736)
				(end 29.902658 -285.715202)
			)
			(arc
				(start 29.902658 -284.412436)
				(mid 29.898757 -284.392913)
				(end 29.887672 -284.376368)
			)
			(arc
				(start 29.850334 -284.33903)
				(mid 29.8338 -284.327919)
				(end 29.814266 -284.324044)
			)
			(xy 28.446476 -284.324044) (xy 28.446476 -284.639004) (xy 28.331668 -284.753812) (xy 27.755596 -284.753812)
			(xy 27.634184 -284.6324) (xy 27.634184 -284.359858) (xy 27.6098 -284.335474) (xy 27.599894 -284.325568)
			(xy 27.599894 -284.324044)
			(arc
				(start 26.1493 -284.324044)
				(mid 26.129777 -284.327945)
				(end 26.113232 -284.33903)
			)
			(arc
				(start 25.964896 -284.487366)
				(mid 25.953785 -284.5039)
				(end 25.94991 -284.523434)
			)
			(arc
				(start 25.94991 -285.430468)
				(mid 25.953811 -285.449991)
				(end 25.964896 -285.466536)
			)
			(arc
				(start 26.247598 -285.749238)
				(mid 26.264132 -285.760349)
				(end 26.283666 -285.764224)
			)
			(xy 27.859228 -285.764224) (xy 27.865324 -285.770574)
		)
		(stroke
			(width 0)
			(type solid)
		)
		(fill yes)
		(layer "F.Cu")
		(net "P1V8_PLL0_PEX0")
	)
	(gr_poly
		(pts
			(xy 107.649264 -249.560588)
			(arc
				(start 107.649264 -248.155968)
				(mid 107.660375 -248.139434)
				(end 107.66425 -248.1199)
			)
			(arc
				(start 107.66425 -244.228112)
				(mid 107.660349 -244.208589)
				(end 107.649264 -244.192044)
			)
			(arc
				(start 107.499658 -244.042438)
				(mid 107.483124 -244.031327)
				(end 107.46359 -244.027452)
			)
			(arc
				(start 103.737156 -244.027452)
				(mid 103.717633 -244.031353)
				(end 103.701088 -244.042438)
			)
			(arc
				(start 103.321104 -244.422422)
				(mid 103.309993 -244.438956)
				(end 103.306118 -244.45849)
			)
			(arc
				(start 103.306118 -245.261892)
				(mid 103.302217 -245.281415)
				(end 103.291132 -245.29796)
			)
			(arc
				(start 103.185214 -245.403878)
				(mid 103.16868 -245.414989)
				(end 103.149146 -245.418864)
			)
			(arc
				(start 102.40391 -245.418864)
				(mid 102.384387 -245.422765)
				(end 102.367842 -245.43385)
			)
			(arc
				(start 102.2223 -245.579392)
				(mid 102.211189 -245.595926)
				(end 102.207314 -245.61546)
			)
			(xy 102.207314 -247.48617) (xy 102.210362 -247.489218) (xy 102.210362 -248.368566) (xy 102.21214 -248.370344)
			(xy 102.21214 -249.741436) (xy 102.430326 -249.959622) (xy 107.25023 -249.959622)
		)
		(stroke
			(width 0)
			(type solid)
		)
		(fill yes)
		(layer "F.Cu")
		(net "P1V8_PEX")
	)
	(gr_poly
		(pts
			(xy 239.657382 -277.403306) (xy 239.657382 -277.402544)
			(arc
				(start 240.32083 -276.739096)
				(mid 240.340187 -276.735263)
				(end 240.356644 -276.724364)
			)
			(arc
				(start 240.521744 -276.559264)
				(mid 240.53267 -276.542818)
				(end 240.536476 -276.52345)
			)
			(arc
				(start 240.536476 -275.875242)
				(mid 240.537493 -275.865126)
				(end 240.54054 -275.85543)
			)
			(xy 240.548668 -275.836126)
			(arc
				(start 240.549176 -275.82749)
				(mid 240.553675 -275.809845)
				(end 240.564162 -275.794978)
			)
			(arc
				(start 242.931188 -273.427952)
				(mid 242.942299 -273.411418)
				(end 242.946174 -273.391884)
			)
			(arc
				(start 242.946174 -261.900924)
				(mid 242.942273 -261.881401)
				(end 242.931188 -261.864856)
			)
			(xy 242.778026 -261.711694) (xy 242.770914 -261.704328) (xy 242.752118 -261.696708)
			(arc
				(start 236.546136 -261.696708)
				(mid 236.526613 -261.700609)
				(end 236.510068 -261.711694)
			)
			(xy 236.232192 -261.98957) (xy 236.224826 -261.996682) (xy 236.217206 -262.015478) (xy 236.217206 -272.245836)
			(xy 236.022388 -272.440654) (xy 234.234736 -272.440654) (xy 233.898948 -272.776442) (xy 233.898948 -276.9743)
			(xy 234.373166 -277.448518) (xy 239.61217 -277.448518)
		)
		(stroke
			(width 0)
			(type solid)
		)
		(fill yes)
		(layer "F.Cu")
		(net "P1V25_PEX2")
	)
	(gr_poly
		(pts
			(xy 454.201784 -277.373588) (xy 454.727564 -276.847808)
			(arc
				(start 454.892664 -276.682708)
				(mid 454.90359 -276.666262)
				(end 454.907396 -276.646894)
			)
			(arc
				(start 454.907396 -275.998686)
				(mid 454.908413 -275.98857)
				(end 454.91146 -275.978874)
			)
			(xy 454.919588 -275.95957)
			(arc
				(start 454.920096 -275.950934)
				(mid 454.924595 -275.933289)
				(end 454.935082 -275.918422)
			)
			(xy 456.947778 -273.905726) (xy 458.030072 -273.905726) (xy 458.336142 -273.599656) (xy 458.336142 -272.803874)
			(xy 458.219556 -272.687288) (xy 457.625958 -272.687288) (xy 457.317094 -272.378424)
			(arc
				(start 457.317094 -262.024368)
				(mid 457.313193 -262.004845)
				(end 457.302108 -261.9883)
			)
			(xy 457.148946 -261.835138) (xy 457.141834 -261.827772) (xy 457.123038 -261.820152)
			(arc
				(start 450.917056 -261.820152)
				(mid 450.897533 -261.824053)
				(end 450.880988 -261.835138)
			)
			(xy 450.603112 -262.113014) (xy 450.595746 -262.120126) (xy 450.588126 -262.138922) (xy 450.588126 -272.222976)
			(xy 450.432678 -272.378424) (xy 448.027298 -272.378424) (xy 447.799968 -272.605754) (xy 447.799968 -277.185882)
			(xy 447.799968 -277.474934) (xy 448.066922 -277.741888) (xy 453.833484 -277.741888)
		)
		(stroke
			(width 0)
			(type solid)
		)
		(fill yes)
		(layer "F.Cu")
		(net "P1V25_PEX3")
	)
	(gr_poly
		(pts
			(xy 26.17724 -263.344152) (xy 26.294842 -263.22655) (xy 26.369264 -263.152128) (xy 27.364182 -263.152128)
			(xy 27.48534 -263.03097) (xy 27.48534 -262.866124) (xy 27.403298 -262.784082) (xy 25.552908 -262.784082)
			(arc
				(start 25.357836 -262.58901)
				(mid 25.34691 -262.572564)
				(end 25.343104 -262.553196)
			)
			(arc
				(start 25.343104 -262.543544)
				(mid 25.339154 -262.524157)
				(end 25.328118 -262.50773)
			)
			(arc
				(start 25.015698 -262.19531)
				(mid 25.004587 -262.178776)
				(end 25.000712 -262.159242)
			)
			(arc
				(start 25.000712 -260.711188)
				(mid 24.996811 -260.691665)
				(end 24.985726 -260.67512)
			)
			(arc
				(start 24.948896 -260.63829)
				(mid 24.932362 -260.627179)
				(end 24.912828 -260.623304)
			)
			(arc
				(start 23.683468 -260.623304)
				(mid 23.663945 -260.627205)
				(end 23.6474 -260.63829)
			)
			(arc
				(start 23.640288 -260.645402)
				(mid 23.629177 -260.661936)
				(end 23.625302 -260.68147)
			)
			(arc
				(start 23.625302 -262.427212)
				(mid 23.629203 -262.446735)
				(end 23.640288 -262.46328)
			)
			(arc
				(start 24.666194 -263.489186)
				(mid 24.682728 -263.500297)
				(end 24.702262 -263.504172)
			)
			(xy 26.01722 -263.504172)
		)
		(stroke
			(width 0)
			(type solid)
		)
		(fill yes)
		(layer "F.Cu")
		(net "GND")
	)
	(gr_poly
		(pts
			(arc
				(start 91.966288 -115.63223)
				(mid 91.994475 -115.623693)
				(end 92.013278 -115.600988)
			)
			(xy 92.01912 -115.58651) (xy 92.013278 -115.556538) (xy 92.012008 -115.555522)
			(arc
				(start 92.012008 -115.181634)
				(mid 92.033013 -115.070601)
				(end 92.093034 -114.974878)
			)
			(arc
				(start 92.093034 -114.974878)
				(mid 92.10306 -114.958883)
				(end 92.106496 -114.940334)
			)
			(arc
				(start 92.106496 -113.20145)
				(mid 92.102595 -113.181927)
				(end 92.09151 -113.165382)
			)
			(xy 92.0877 -113.161572) (xy 92.069158 -113.153952) (xy 90.961464 -113.153952) (xy 90.954352 -113.161064)
			(xy 90.413078 -113.161064) (xy 90.283284 -113.290858) (xy 90.283284 -114.0714)
			(arc
				(start 90.804238 -114.592354)
				(mid 90.808139 -114.611877)
				(end 90.819224 -114.628422)
			)
			(arc
				(start 91.230958 -115.040156)
				(mid 91.242069 -115.05669)
				(end 91.245944 -115.076224)
			)
			(arc
				(start 91.245944 -115.461034)
				(mid 91.249845 -115.480557)
				(end 91.26093 -115.497102)
			)
			(arc
				(start 91.381072 -115.617244)
				(mid 91.397606 -115.628355)
				(end 91.41714 -115.63223)
			)
		)
		(stroke
			(width 0)
			(type solid)
		)
		(fill yes)
		(layer "F.Cu")
		(net "P3V3_AUX")
	)
	(gr_poly
		(pts
			(arc
				(start 136.579356 -318.761872)
				(mid 137.771323 -315.898778)
				(end 139.828778 -313.57824)
			)
			(arc
				(start 139.828778 -294.41394)
				(mid 139.824877 -294.394417)
				(end 139.813792 -294.377872)
			)
			(arc
				(start 139.39393 -293.95801)
				(mid 139.377396 -293.946899)
				(end 139.357862 -293.943024)
			)
			(xy 118.763034 -293.943024) (xy 118.683786 -294.022272) (xy 118.683786 -302.475646) (xy 119.480838 -303.272698)
			(xy 134.67969 -303.272698) (xy 134.859268 -303.452276) (xy 134.859268 -308.394862) (xy 134.599934 -308.654196)
			(xy 123.716288 -308.654196) (xy 123.465336 -308.905148) (xy 123.465336 -318.57442) (xy 123.652788 -318.761872)
		)
		(stroke
			(width 0)
			(type solid)
		)
		(fill yes)
		(layer "F.Cu")
		(net "P0V8_PEX1")
	)
	(gr_poly
		(pts
			(arc
				(start 440.266328 -115.63223)
				(mid 440.294515 -115.623693)
				(end 440.313318 -115.600988)
			)
			(xy 440.31916 -115.58651) (xy 440.313318 -115.556538) (xy 440.312048 -115.555522)
			(arc
				(start 440.312048 -115.181634)
				(mid 440.333053 -115.070601)
				(end 440.393074 -114.974878)
			)
			(arc
				(start 440.393074 -114.974878)
				(mid 440.4031 -114.958883)
				(end 440.406536 -114.940334)
			)
			(arc
				(start 440.406536 -113.20145)
				(mid 440.402635 -113.181927)
				(end 440.39155 -113.165382)
			)
			(xy 440.38774 -113.161572) (xy 440.369198 -113.153952) (xy 439.239914 -113.153952) (xy 438.582308 -113.153952)
			(xy 438.491376 -113.244884) (xy 438.491376 -113.774728) (xy 439.104278 -114.38763)
			(arc
				(start 439.104278 -114.592354)
				(mid 439.108179 -114.611877)
				(end 439.119264 -114.628422)
			)
			(arc
				(start 439.530998 -115.040156)
				(mid 439.542109 -115.05669)
				(end 439.545984 -115.076224)
			)
			(arc
				(start 439.545984 -115.461034)
				(mid 439.549885 -115.480557)
				(end 439.56097 -115.497102)
			)
			(arc
				(start 439.681112 -115.617244)
				(mid 439.697646 -115.628355)
				(end 439.71718 -115.63223)
			)
		)
		(stroke
			(width 0)
			(type solid)
		)
		(fill yes)
		(layer "F.Cu")
		(net "P3V3_AUX")
	)
	(gr_poly
		(pts
			(xy 460.09687 -322.56857) (xy 460.09687 -313.803284) (xy 460.09687 -312.42381) (xy 459.774544 -312.101484)
			(xy 458.380592 -312.101484) (xy 458.274928 -312.207148) (xy 458.274928 -313.795918) (xy 458.274928 -321.181222)
			(xy 457.712826 -321.743324) (xy 455.297794 -321.743324) (xy 454.164954 -320.610484) (xy 454.164954 -307.41874)
			(xy 454.139554 -307.39334)
			(arc
				(start 451.295516 -307.39334)
				(mid 451.436183 -307.994457)
				(end 451.483476 -308.61)
			)
			(arc
				(start 451.483476 -308.61)
				(mid 451.265971 -309.916683)
				(end 450.636894 -311.082436)
			)
			(xy 450.636894 -319.182242) (xy 450.631814 -319.187322) (xy 450.631814 -320.281046) (xy 450.633846 -320.283078)
			(xy 450.633846 -322.772024) (xy 451.065392 -323.20357) (xy 459.46187 -323.20357)
		)
		(stroke
			(width 0)
			(type solid)
		)
		(fill yes)
		(layer "F.Cu")
		(net "GND")
	)
	(gr_poly
		(pts
			(arc
				(start 253.075948 -216.01176)
				(mid 253.095471 -216.007859)
				(end 253.112016 -215.996774)
			)
			(arc
				(start 253.23546 -215.87333)
				(mid 253.246571 -215.856796)
				(end 253.250446 -215.837262)
			)
			(arc
				(start 253.250446 -213.841584)
				(mid 253.235567 -213.805663)
				(end 253.199646 -213.790784)
			)
			(arc
				(start 250.823222 -213.790784)
				(mid 250.803699 -213.786883)
				(end 250.787154 -213.775798)
			)
			(arc
				(start 250.409964 -213.398608)
				(mid 250.39343 -213.387497)
				(end 250.373896 -213.383622)
			)
			(arc
				(start 249.363484 -213.383622)
				(mid 249.343961 -213.387523)
				(end 249.327416 -213.398608)
			)
			(arc
				(start 249.320558 -213.405466)
				(mid 249.309447 -213.422)
				(end 249.305572 -213.441534)
			)
			(arc
				(start 249.305572 -215.096598)
				(mid 249.309522 -215.115985)
				(end 249.320558 -215.132412)
			)
			(arc
				(start 249.360436 -215.172544)
				(mid 249.371362 -215.18899)
				(end 249.375168 -215.208358)
			)
			(arc
				(start 249.375168 -215.82253)
				(mid 249.379118 -215.841917)
				(end 249.390154 -215.858344)
			)
			(arc
				(start 249.528584 -215.996774)
				(mid 249.545118 -216.007885)
				(end 249.564652 -216.01176)
			)
		)
		(stroke
			(width 0)
			(type solid)
		)
		(fill yes)
		(layer "F.Cu")
		(net "P1V2_AUX")
	)
	(gr_poly
		(pts
			(arc
				(start 27.539696 -30.696154)
				(mid 27.559219 -30.692253)
				(end 27.575764 -30.681168)
			)
			(arc
				(start 27.987498 -30.269434)
				(mid 28.004032 -30.258323)
				(end 28.023566 -30.254448)
			)
			(arc
				(start 28.408376 -30.254448)
				(mid 28.427899 -30.250547)
				(end 28.444444 -30.239462)
			)
			(arc
				(start 28.564586 -30.11932)
				(mid 28.575697 -30.102786)
				(end 28.579572 -30.083252)
			)
			(arc
				(start 28.579572 -29.534104)
				(mid 28.571035 -29.505917)
				(end 28.54833 -29.487114)
			)
			(xy 28.533852 -29.481272) (xy 28.50388 -29.487114) (xy 28.502864 -29.488384)
			(arc
				(start 28.128976 -29.488384)
				(mid 28.017943 -29.467379)
				(end 27.92222 -29.407358)
			)
			(arc
				(start 27.92222 -29.407358)
				(mid 27.906225 -29.397332)
				(end 27.887676 -29.393896)
			)
			(arc
				(start 26.148792 -29.393896)
				(mid 26.129269 -29.397797)
				(end 26.112724 -29.408882)
			)
			(xy 26.108914 -29.412692) (xy 26.101294 -29.431234)
			(arc
				(start 26.101294 -30.63367)
				(mid 26.105195 -30.653193)
				(end 26.11628 -30.669738)
			)
			(arc
				(start 26.12771 -30.681168)
				(mid 26.144244 -30.692279)
				(end 26.163778 -30.696154)
			)
		)
		(stroke
			(width 0)
			(type solid)
		)
		(fill yes)
		(layer "F.Cu")
		(net "P3V3_AUX")
	)
	(gr_poly
		(pts
			(arc
				(start 31.133542 -299.840142)
				(mid 31.153036 -299.836358)
				(end 31.16961 -299.82541)
			)
			(arc
				(start 31.233618 -299.761402)
				(mid 31.244729 -299.744868)
				(end 31.248604 -299.725334)
			)
			(arc
				(start 31.248604 -299.582586)
				(mid 31.252505 -299.563063)
				(end 31.26359 -299.546518)
			)
			(arc
				(start 31.310072 -299.500036)
				(mid 31.326606 -299.488925)
				(end 31.34614 -299.48505)
			)
			(arc
				(start 32.668464 -299.48505)
				(mid 32.687987 -299.481149)
				(end 32.704532 -299.470064)
			)
			(arc
				(start 32.728916 -299.44568)
				(mid 32.740027 -299.429146)
				(end 32.743902 -299.409612)
			)
			(arc
				(start 32.743902 -298.99356)
				(mid 32.740001 -298.974037)
				(end 32.728916 -298.957492)
			)
			(arc
				(start 32.700722 -298.929298)
				(mid 32.684188 -298.918187)
				(end 32.664654 -298.914312)
			)
			(arc
				(start 30.512004 -298.914312)
				(mid 30.492481 -298.918213)
				(end 30.475936 -298.929298)
			)
			(arc
				(start 30.336998 -299.068236)
				(mid 30.325887 -299.08477)
				(end 30.322012 -299.104304)
			)
			(arc
				(start 30.322012 -299.737526)
				(mid 30.325913 -299.757049)
				(end 30.336998 -299.773594)
			)
			(arc
				(start 30.38856 -299.825156)
				(mid 30.405094 -299.836267)
				(end 30.424628 -299.840142)
			)
		)
		(stroke
			(width 0)
			(type solid)
		)
		(fill yes)
		(layer "F.Cu")
		(net "PCEPLL1_VDDA18_PEX0_R")
	)
	(gr_poly
		(pts
			(arc
				(start 31.133542 -293.439342)
				(mid 31.153036 -293.435558)
				(end 31.16961 -293.42461)
			)
			(arc
				(start 31.233618 -293.360602)
				(mid 31.244729 -293.344068)
				(end 31.248604 -293.324534)
			)
			(arc
				(start 31.248604 -293.181786)
				(mid 31.252505 -293.162263)
				(end 31.26359 -293.145718)
			)
			(arc
				(start 31.310072 -293.099236)
				(mid 31.326606 -293.088125)
				(end 31.34614 -293.08425)
			)
			(arc
				(start 32.668464 -293.08425)
				(mid 32.687987 -293.080349)
				(end 32.704532 -293.069264)
			)
			(arc
				(start 32.728916 -293.04488)
				(mid 32.740027 -293.028346)
				(end 32.743902 -293.008812)
			)
			(arc
				(start 32.743902 -292.59276)
				(mid 32.740001 -292.573237)
				(end 32.728916 -292.556692)
			)
			(arc
				(start 32.700722 -292.528498)
				(mid 32.684188 -292.517387)
				(end 32.664654 -292.513512)
			)
			(arc
				(start 30.512004 -292.513512)
				(mid 30.492481 -292.517413)
				(end 30.475936 -292.528498)
			)
			(arc
				(start 30.336998 -292.667436)
				(mid 30.325887 -292.68397)
				(end 30.322012 -292.703504)
			)
			(arc
				(start 30.322012 -293.336726)
				(mid 30.325913 -293.356249)
				(end 30.336998 -293.372794)
			)
			(arc
				(start 30.38856 -293.424356)
				(mid 30.405094 -293.435467)
				(end 30.424628 -293.439342)
			)
		)
		(stroke
			(width 0)
			(type solid)
		)
		(fill yes)
		(layer "F.Cu")
		(net "PCEPLL2_VDDA18_PEX0_R")
	)
	(gr_poly
		(pts
			(arc
				(start 31.133542 -290.238942)
				(mid 31.153036 -290.235158)
				(end 31.16961 -290.22421)
			)
			(arc
				(start 31.233618 -290.160202)
				(mid 31.244729 -290.143668)
				(end 31.248604 -290.124134)
			)
			(arc
				(start 31.248604 -289.981386)
				(mid 31.252505 -289.961863)
				(end 31.26359 -289.945318)
			)
			(arc
				(start 31.310072 -289.898836)
				(mid 31.326606 -289.887725)
				(end 31.34614 -289.88385)
			)
			(arc
				(start 32.668464 -289.88385)
				(mid 32.687987 -289.879949)
				(end 32.704532 -289.868864)
			)
			(arc
				(start 32.728916 -289.84448)
				(mid 32.740027 -289.827946)
				(end 32.743902 -289.808412)
			)
			(arc
				(start 32.743902 -289.39236)
				(mid 32.740001 -289.372837)
				(end 32.728916 -289.356292)
			)
			(arc
				(start 32.700722 -289.328098)
				(mid 32.684188 -289.316987)
				(end 32.664654 -289.313112)
			)
			(arc
				(start 30.512004 -289.313112)
				(mid 30.492481 -289.317013)
				(end 30.475936 -289.328098)
			)
			(arc
				(start 30.336998 -289.467036)
				(mid 30.325887 -289.48357)
				(end 30.322012 -289.503104)
			)
			(arc
				(start 30.322012 -290.136326)
				(mid 30.325913 -290.155849)
				(end 30.336998 -290.172394)
			)
			(arc
				(start 30.38856 -290.223956)
				(mid 30.405094 -290.235067)
				(end 30.424628 -290.238942)
			)
		)
		(stroke
			(width 0)
			(type solid)
		)
		(fill yes)
		(layer "F.Cu")
		(net "PCEPLL4_VDDA18_PEX0_R")
	)
	(gr_poly
		(pts
			(arc
				(start 31.133542 -287.038542)
				(mid 31.153036 -287.034758)
				(end 31.16961 -287.02381)
			)
			(arc
				(start 31.233618 -286.959802)
				(mid 31.244729 -286.943268)
				(end 31.248604 -286.923734)
			)
			(arc
				(start 31.248604 -286.780986)
				(mid 31.252505 -286.761463)
				(end 31.26359 -286.744918)
			)
			(arc
				(start 31.310072 -286.698436)
				(mid 31.326606 -286.687325)
				(end 31.34614 -286.68345)
			)
			(arc
				(start 32.668464 -286.68345)
				(mid 32.687987 -286.679549)
				(end 32.704532 -286.668464)
			)
			(arc
				(start 32.728916 -286.64408)
				(mid 32.740027 -286.627546)
				(end 32.743902 -286.608012)
			)
			(arc
				(start 32.743902 -286.19196)
				(mid 32.740001 -286.172437)
				(end 32.728916 -286.155892)
			)
			(arc
				(start 32.700722 -286.127698)
				(mid 32.684188 -286.116587)
				(end 32.664654 -286.112712)
			)
			(arc
				(start 30.512004 -286.112712)
				(mid 30.492481 -286.116613)
				(end 30.475936 -286.127698)
			)
			(arc
				(start 30.336998 -286.266636)
				(mid 30.325887 -286.28317)
				(end 30.322012 -286.302704)
			)
			(arc
				(start 30.322012 -286.935926)
				(mid 30.325913 -286.955449)
				(end 30.336998 -286.971994)
			)
			(arc
				(start 30.38856 -287.023556)
				(mid 30.405094 -287.034667)
				(end 30.424628 -287.038542)
			)
		)
		(stroke
			(width 0)
			(type solid)
		)
		(fill yes)
		(layer "F.Cu")
		(net "PCEPLL6_VDDA18_PEX0_R")
	)
	(gr_poly
		(pts
			(arc
				(start 31.133542 -283.838142)
				(mid 31.153036 -283.834358)
				(end 31.16961 -283.82341)
			)
			(arc
				(start 31.233618 -283.759402)
				(mid 31.244729 -283.742868)
				(end 31.248604 -283.723334)
			)
			(arc
				(start 31.248604 -283.580586)
				(mid 31.252505 -283.561063)
				(end 31.26359 -283.544518)
			)
			(arc
				(start 31.310072 -283.498036)
				(mid 31.326606 -283.486925)
				(end 31.34614 -283.48305)
			)
			(arc
				(start 32.668464 -283.48305)
				(mid 32.687987 -283.479149)
				(end 32.704532 -283.468064)
			)
			(arc
				(start 32.728916 -283.44368)
				(mid 32.740027 -283.427146)
				(end 32.743902 -283.407612)
			)
			(arc
				(start 32.743902 -282.99156)
				(mid 32.740001 -282.972037)
				(end 32.728916 -282.955492)
			)
			(arc
				(start 32.700722 -282.927298)
				(mid 32.684188 -282.916187)
				(end 32.664654 -282.912312)
			)
			(arc
				(start 30.512004 -282.912312)
				(mid 30.492481 -282.916213)
				(end 30.475936 -282.927298)
			)
			(arc
				(start 30.336998 -283.066236)
				(mid 30.325887 -283.08277)
				(end 30.322012 -283.102304)
			)
			(arc
				(start 30.322012 -283.735526)
				(mid 30.325913 -283.755049)
				(end 30.336998 -283.771594)
			)
			(arc
				(start 30.38856 -283.823156)
				(mid 30.405094 -283.834267)
				(end 30.424628 -283.838142)
			)
		)
		(stroke
			(width 0)
			(type solid)
		)
		(fill yes)
		(layer "F.Cu")
		(net "PCEPLL7_VDDA18_PEX0_R")
	)
	(gr_poly
		(pts
			(arc
				(start 33.185862 -282.597606)
				(mid 33.205385 -282.593705)
				(end 33.22193 -282.58262)
			)
			(arc
				(start 33.345882 -282.458668)
				(mid 33.356993 -282.442134)
				(end 33.360868 -282.4226)
			)
			(arc
				(start 33.360868 -280.646886)
				(mid 33.356967 -280.627363)
				(end 33.345882 -280.610818)
			)
			(arc
				(start 33.209738 -280.474674)
				(mid 33.193204 -280.463563)
				(end 33.17367 -280.459688)
			)
			(arc
				(start 31.617666 -280.459688)
				(mid 31.598143 -280.463589)
				(end 31.581598 -280.474674)
			)
			(arc
				(start 31.525972 -280.5303)
				(mid 31.514861 -280.546834)
				(end 31.510986 -280.566368)
			)
			(arc
				(start 31.510986 -280.960322)
				(mid 31.507085 -280.979845)
				(end 31.496 -280.99639)
			)
			(arc
				(start 31.4706 -281.02179)
				(mid 31.454066 -281.032901)
				(end 31.434532 -281.036776)
			)
			(arc
				(start 30.625796 -281.036776)
				(mid 30.606273 -281.040677)
				(end 30.589728 -281.051762)
			)
			(arc
				(start 30.500574 -281.140916)
				(mid 30.489463 -281.15745)
				(end 30.485588 -281.176984)
			)
			(arc
				(start 30.485588 -282.46705)
				(mid 30.489489 -282.486573)
				(end 30.500574 -282.503118)
			)
			(arc
				(start 30.58033 -282.582874)
				(mid 30.596893 -282.593848)
				(end 30.616398 -282.597606)
			)
		)
		(stroke
			(width 0)
			(type solid)
		)
		(fill yes)
		(layer "F.Cu")
		(net "SYSPLL_VDDA18_PEX0")
	)
	(gr_poly
		(pts
			(arc
				(start 36.143946 -262.242808)
				(mid 36.163469 -262.238907)
				(end 36.180014 -262.227822)
			)
			(arc
				(start 36.303966 -262.10387)
				(mid 36.315077 -262.087336)
				(end 36.318952 -262.067802)
			)
			(arc
				(start 36.318952 -260.292088)
				(mid 36.315051 -260.272565)
				(end 36.303966 -260.25602)
			)
			(arc
				(start 36.167822 -260.119876)
				(mid 36.151288 -260.108765)
				(end 36.131754 -260.10489)
			)
			(arc
				(start 34.57575 -260.10489)
				(mid 34.556227 -260.108791)
				(end 34.539682 -260.119876)
			)
			(arc
				(start 34.484056 -260.175502)
				(mid 34.472945 -260.192036)
				(end 34.46907 -260.21157)
			)
			(arc
				(start 34.46907 -260.605524)
				(mid 34.465169 -260.625047)
				(end 34.454084 -260.641592)
			)
			(arc
				(start 34.428684 -260.666992)
				(mid 34.41215 -260.678103)
				(end 34.392616 -260.681978)
			)
			(arc
				(start 33.58388 -260.681978)
				(mid 33.564357 -260.685879)
				(end 33.547812 -260.696964)
			)
			(arc
				(start 33.458658 -260.786118)
				(mid 33.447547 -260.802652)
				(end 33.443672 -260.822186)
			)
			(arc
				(start 33.443672 -262.112252)
				(mid 33.447573 -262.131775)
				(end 33.458658 -262.14832)
			)
			(arc
				(start 33.538414 -262.228076)
				(mid 33.554977 -262.23905)
				(end 33.574482 -262.242808)
			)
		)
		(stroke
			(width 0)
			(type solid)
		)
		(fill yes)
		(layer "F.Cu")
		(net "PCEPLL3_VDDA18_PEX0")
	)
	(gr_poly
		(pts
			(arc
				(start 36.143946 -259.042408)
				(mid 36.163469 -259.038507)
				(end 36.180014 -259.027422)
			)
			(arc
				(start 36.303966 -258.90347)
				(mid 36.315077 -258.886936)
				(end 36.318952 -258.867402)
			)
			(arc
				(start 36.318952 -257.091688)
				(mid 36.315051 -257.072165)
				(end 36.303966 -257.05562)
			)
			(arc
				(start 36.167822 -256.919476)
				(mid 36.151288 -256.908365)
				(end 36.131754 -256.90449)
			)
			(arc
				(start 34.57575 -256.90449)
				(mid 34.556227 -256.908391)
				(end 34.539682 -256.919476)
			)
			(arc
				(start 34.484056 -256.975102)
				(mid 34.472945 -256.991636)
				(end 34.46907 -257.01117)
			)
			(arc
				(start 34.46907 -257.405124)
				(mid 34.465169 -257.424647)
				(end 34.454084 -257.441192)
			)
			(arc
				(start 34.428684 -257.466592)
				(mid 34.41215 -257.477703)
				(end 34.392616 -257.481578)
			)
			(arc
				(start 33.58388 -257.481578)
				(mid 33.564357 -257.485479)
				(end 33.547812 -257.496564)
			)
			(arc
				(start 33.458658 -257.585718)
				(mid 33.447547 -257.602252)
				(end 33.443672 -257.621786)
			)
			(arc
				(start 33.443672 -258.911852)
				(mid 33.447573 -258.931375)
				(end 33.458658 -258.94792)
			)
			(arc
				(start 33.538414 -259.027676)
				(mid 33.554977 -259.03865)
				(end 33.574482 -259.042408)
			)
		)
		(stroke
			(width 0)
			(type solid)
		)
		(fill yes)
		(layer "F.Cu")
		(net "PCEPLL5_VDDA18_PEX0")
	)
	(gr_poly
		(pts
			(arc
				(start 53.539644 -30.696154)
				(mid 53.559167 -30.692253)
				(end 53.575712 -30.681168)
			)
			(arc
				(start 53.987446 -30.269434)
				(mid 54.00398 -30.258323)
				(end 54.023514 -30.254448)
			)
			(arc
				(start 54.408324 -30.254448)
				(mid 54.427847 -30.250547)
				(end 54.444392 -30.239462)
			)
			(arc
				(start 54.564534 -30.11932)
				(mid 54.575645 -30.102786)
				(end 54.57952 -30.083252)
			)
			(arc
				(start 54.57952 -29.534104)
				(mid 54.570983 -29.505917)
				(end 54.548278 -29.487114)
			)
			(xy 54.5338 -29.481272) (xy 54.503828 -29.487114) (xy 54.502812 -29.488384)
			(arc
				(start 54.128924 -29.488384)
				(mid 54.017891 -29.467379)
				(end 53.922168 -29.407358)
			)
			(arc
				(start 53.922168 -29.407358)
				(mid 53.906173 -29.397332)
				(end 53.887624 -29.393896)
			)
			(arc
				(start 52.14874 -29.393896)
				(mid 52.129217 -29.397797)
				(end 52.112672 -29.408882)
			)
			(xy 52.108862 -29.412692) (xy 52.101242 -29.431234)
			(arc
				(start 52.101242 -30.63367)
				(mid 52.105143 -30.653193)
				(end 52.116228 -30.669738)
			)
			(arc
				(start 52.127658 -30.681168)
				(mid 52.144192 -30.692279)
				(end 52.163726 -30.696154)
			)
		)
		(stroke
			(width 0)
			(type solid)
		)
		(fill yes)
		(layer "F.Cu")
		(net "P3V3_AUX")
	)
	(gr_poly
		(pts
			(arc
				(start 79.539592 -30.696154)
				(mid 79.559115 -30.692253)
				(end 79.57566 -30.681168)
			)
			(arc
				(start 79.987394 -30.269434)
				(mid 80.003928 -30.258323)
				(end 80.023462 -30.254448)
			)
			(arc
				(start 80.408272 -30.254448)
				(mid 80.427795 -30.250547)
				(end 80.44434 -30.239462)
			)
			(arc
				(start 80.564482 -30.11932)
				(mid 80.575593 -30.102786)
				(end 80.579468 -30.083252)
			)
			(arc
				(start 80.579468 -29.534104)
				(mid 80.570931 -29.505917)
				(end 80.548226 -29.487114)
			)
			(xy 80.533748 -29.481272) (xy 80.503776 -29.487114) (xy 80.50276 -29.488384)
			(arc
				(start 80.128872 -29.488384)
				(mid 80.017839 -29.467379)
				(end 79.922116 -29.407358)
			)
			(arc
				(start 79.922116 -29.407358)
				(mid 79.906121 -29.397332)
				(end 79.887572 -29.393896)
			)
			(arc
				(start 78.148688 -29.393896)
				(mid 78.129165 -29.397797)
				(end 78.11262 -29.408882)
			)
			(xy 78.10881 -29.412692) (xy 78.10119 -29.431234)
			(arc
				(start 78.10119 -30.63367)
				(mid 78.105091 -30.653193)
				(end 78.116176 -30.669738)
			)
			(arc
				(start 78.127606 -30.681168)
				(mid 78.14414 -30.692279)
				(end 78.163674 -30.696154)
			)
		)
		(stroke
			(width 0)
			(type solid)
		)
		(fill yes)
		(layer "F.Cu")
		(net "P3V3_AUX")
	)
	(gr_poly
		(pts
			(arc
				(start 117.639846 -30.696154)
				(mid 117.659369 -30.692253)
				(end 117.675914 -30.681168)
			)
			(arc
				(start 118.087648 -30.269434)
				(mid 118.104182 -30.258323)
				(end 118.123716 -30.254448)
			)
			(arc
				(start 118.508526 -30.254448)
				(mid 118.528049 -30.250547)
				(end 118.544594 -30.239462)
			)
			(arc
				(start 118.664736 -30.11932)
				(mid 118.675847 -30.102786)
				(end 118.679722 -30.083252)
			)
			(arc
				(start 118.679722 -29.534104)
				(mid 118.671185 -29.505917)
				(end 118.64848 -29.487114)
			)
			(xy 118.634002 -29.481272) (xy 118.60403 -29.487114) (xy 118.603014 -29.488384)
			(arc
				(start 118.229126 -29.488384)
				(mid 118.118093 -29.467379)
				(end 118.02237 -29.407358)
			)
			(arc
				(start 118.02237 -29.407358)
				(mid 118.006375 -29.397332)
				(end 117.987826 -29.393896)
			)
			(arc
				(start 116.248942 -29.393896)
				(mid 116.229419 -29.397797)
				(end 116.212874 -29.408882)
			)
			(xy 116.209064 -29.412692) (xy 116.201444 -29.431234)
			(arc
				(start 116.201444 -30.63367)
				(mid 116.205345 -30.653193)
				(end 116.21643 -30.669738)
			)
			(arc
				(start 116.22786 -30.681168)
				(mid 116.244394 -30.692279)
				(end 116.263928 -30.696154)
			)
		)
		(stroke
			(width 0)
			(type solid)
		)
		(fill yes)
		(layer "F.Cu")
		(net "P3V3_AUX")
	)
	(gr_poly
		(pts
			(arc
				(start 143.639794 -30.696154)
				(mid 143.659317 -30.692253)
				(end 143.675862 -30.681168)
			)
			(arc
				(start 144.087596 -30.269434)
				(mid 144.10413 -30.258323)
				(end 144.123664 -30.254448)
			)
			(arc
				(start 144.508474 -30.254448)
				(mid 144.527997 -30.250547)
				(end 144.544542 -30.239462)
			)
			(arc
				(start 144.664684 -30.11932)
				(mid 144.675795 -30.102786)
				(end 144.67967 -30.083252)
			)
			(arc
				(start 144.67967 -29.534104)
				(mid 144.671133 -29.505917)
				(end 144.648428 -29.487114)
			)
			(xy 144.63395 -29.481272) (xy 144.603978 -29.487114) (xy 144.602962 -29.488384)
			(arc
				(start 144.229074 -29.488384)
				(mid 144.118041 -29.467379)
				(end 144.022318 -29.407358)
			)
			(arc
				(start 144.022318 -29.407358)
				(mid 144.006323 -29.397332)
				(end 143.987774 -29.393896)
			)
			(arc
				(start 142.24889 -29.393896)
				(mid 142.229367 -29.397797)
				(end 142.212822 -29.408882)
			)
			(xy 142.209012 -29.412692) (xy 142.201392 -29.431234)
			(arc
				(start 142.201392 -30.63367)
				(mid 142.205293 -30.653193)
				(end 142.216378 -30.669738)
			)
			(arc
				(start 142.227808 -30.681168)
				(mid 142.244342 -30.692279)
				(end 142.263876 -30.696154)
			)
		)
		(stroke
			(width 0)
			(type solid)
		)
		(fill yes)
		(layer "F.Cu")
		(net "P3V3_AUX")
	)
	(gr_poly
		(pts
			(arc
				(start 147.23364 -299.840142)
				(mid 147.253134 -299.836358)
				(end 147.269708 -299.82541)
			)
			(arc
				(start 147.333716 -299.761402)
				(mid 147.344827 -299.744868)
				(end 147.348702 -299.725334)
			)
			(arc
				(start 147.348702 -299.582586)
				(mid 147.352603 -299.563063)
				(end 147.363688 -299.546518)
			)
			(arc
				(start 147.41017 -299.500036)
				(mid 147.426704 -299.488925)
				(end 147.446238 -299.48505)
			)
			(arc
				(start 148.768562 -299.48505)
				(mid 148.788085 -299.481149)
				(end 148.80463 -299.470064)
			)
			(arc
				(start 148.829014 -299.44568)
				(mid 148.840125 -299.429146)
				(end 148.844 -299.409612)
			)
			(arc
				(start 148.844 -298.99356)
				(mid 148.840099 -298.974037)
				(end 148.829014 -298.957492)
			)
			(arc
				(start 148.80082 -298.929298)
				(mid 148.784286 -298.918187)
				(end 148.764752 -298.914312)
			)
			(arc
				(start 146.612102 -298.914312)
				(mid 146.592579 -298.918213)
				(end 146.576034 -298.929298)
			)
			(arc
				(start 146.437096 -299.068236)
				(mid 146.425985 -299.08477)
				(end 146.42211 -299.104304)
			)
			(arc
				(start 146.42211 -299.737526)
				(mid 146.426011 -299.757049)
				(end 146.437096 -299.773594)
			)
			(arc
				(start 146.488658 -299.825156)
				(mid 146.505192 -299.836267)
				(end 146.524726 -299.840142)
			)
		)
		(stroke
			(width 0)
			(type solid)
		)
		(fill yes)
		(layer "F.Cu")
		(net "PCEPLL1_VDDA18_PEX1_R")
	)
	(gr_poly
		(pts
			(arc
				(start 147.23364 -293.439342)
				(mid 147.253134 -293.435558)
				(end 147.269708 -293.42461)
			)
			(arc
				(start 147.333716 -293.360602)
				(mid 147.344827 -293.344068)
				(end 147.348702 -293.324534)
			)
			(arc
				(start 147.348702 -293.181786)
				(mid 147.352603 -293.162263)
				(end 147.363688 -293.145718)
			)
			(arc
				(start 147.41017 -293.099236)
				(mid 147.426704 -293.088125)
				(end 147.446238 -293.08425)
			)
			(arc
				(start 148.768562 -293.08425)
				(mid 148.788085 -293.080349)
				(end 148.80463 -293.069264)
			)
			(arc
				(start 148.829014 -293.04488)
				(mid 148.840125 -293.028346)
				(end 148.844 -293.008812)
			)
			(arc
				(start 148.844 -292.59276)
				(mid 148.840099 -292.573237)
				(end 148.829014 -292.556692)
			)
			(arc
				(start 148.80082 -292.528498)
				(mid 148.784286 -292.517387)
				(end 148.764752 -292.513512)
			)
			(arc
				(start 146.612102 -292.513512)
				(mid 146.592579 -292.517413)
				(end 146.576034 -292.528498)
			)
			(arc
				(start 146.437096 -292.667436)
				(mid 146.425985 -292.68397)
				(end 146.42211 -292.703504)
			)
			(arc
				(start 146.42211 -293.336726)
				(mid 146.426011 -293.356249)
				(end 146.437096 -293.372794)
			)
			(arc
				(start 146.488658 -293.424356)
				(mid 146.505192 -293.435467)
				(end 146.524726 -293.439342)
			)
		)
		(stroke
			(width 0)
			(type solid)
		)
		(fill yes)
		(layer "F.Cu")
		(net "PCEPLL2_VDDA18_PEX1_R")
	)
	(gr_poly
		(pts
			(arc
				(start 147.23364 -290.238942)
				(mid 147.253134 -290.235158)
				(end 147.269708 -290.22421)
			)
			(arc
				(start 147.333716 -290.160202)
				(mid 147.344827 -290.143668)
				(end 147.348702 -290.124134)
			)
			(arc
				(start 147.348702 -289.981386)
				(mid 147.352603 -289.961863)
				(end 147.363688 -289.945318)
			)
			(arc
				(start 147.41017 -289.898836)
				(mid 147.426704 -289.887725)
				(end 147.446238 -289.88385)
			)
			(arc
				(start 148.768562 -289.88385)
				(mid 148.788085 -289.879949)
				(end 148.80463 -289.868864)
			)
			(arc
				(start 148.829014 -289.84448)
				(mid 148.840125 -289.827946)
				(end 148.844 -289.808412)
			)
			(arc
				(start 148.844 -289.39236)
				(mid 148.840099 -289.372837)
				(end 148.829014 -289.356292)
			)
			(arc
				(start 148.80082 -289.328098)
				(mid 148.784286 -289.316987)
				(end 148.764752 -289.313112)
			)
			(arc
				(start 146.612102 -289.313112)
				(mid 146.592579 -289.317013)
				(end 146.576034 -289.328098)
			)
			(arc
				(start 146.437096 -289.467036)
				(mid 146.425985 -289.48357)
				(end 146.42211 -289.503104)
			)
			(arc
				(start 146.42211 -290.136326)
				(mid 146.426011 -290.155849)
				(end 146.437096 -290.172394)
			)
			(arc
				(start 146.488658 -290.223956)
				(mid 146.505192 -290.235067)
				(end 146.524726 -290.238942)
			)
		)
		(stroke
			(width 0)
			(type solid)
		)
		(fill yes)
		(layer "F.Cu")
		(net "PCEPLL4_VDDA18_PEX1_R")
	)
	(gr_poly
		(pts
			(arc
				(start 147.23364 -287.038542)
				(mid 147.253134 -287.034758)
				(end 147.269708 -287.02381)
			)
			(arc
				(start 147.333716 -286.959802)
				(mid 147.344827 -286.943268)
				(end 147.348702 -286.923734)
			)
			(arc
				(start 147.348702 -286.780986)
				(mid 147.352603 -286.761463)
				(end 147.363688 -286.744918)
			)
			(arc
				(start 147.41017 -286.698436)
				(mid 147.426704 -286.687325)
				(end 147.446238 -286.68345)
			)
			(arc
				(start 148.768562 -286.68345)
				(mid 148.788085 -286.679549)
				(end 148.80463 -286.668464)
			)
			(arc
				(start 148.829014 -286.64408)
				(mid 148.840125 -286.627546)
				(end 148.844 -286.608012)
			)
			(arc
				(start 148.844 -286.19196)
				(mid 148.840099 -286.172437)
				(end 148.829014 -286.155892)
			)
			(arc
				(start 148.80082 -286.127698)
				(mid 148.784286 -286.116587)
				(end 148.764752 -286.112712)
			)
			(arc
				(start 146.612102 -286.112712)
				(mid 146.592579 -286.116613)
				(end 146.576034 -286.127698)
			)
			(arc
				(start 146.437096 -286.266636)
				(mid 146.425985 -286.28317)
				(end 146.42211 -286.302704)
			)
			(arc
				(start 146.42211 -286.935926)
				(mid 146.426011 -286.955449)
				(end 146.437096 -286.971994)
			)
			(arc
				(start 146.488658 -287.023556)
				(mid 146.505192 -287.034667)
				(end 146.524726 -287.038542)
			)
		)
		(stroke
			(width 0)
			(type solid)
		)
		(fill yes)
		(layer "F.Cu")
		(net "PCEPLL6_VDDA18_PEX1_R")
	)
	(gr_poly
		(pts
			(arc
				(start 147.23364 -283.838142)
				(mid 147.253134 -283.834358)
				(end 147.269708 -283.82341)
			)
			(arc
				(start 147.333716 -283.759402)
				(mid 147.344827 -283.742868)
				(end 147.348702 -283.723334)
			)
			(arc
				(start 147.348702 -283.580586)
				(mid 147.352603 -283.561063)
				(end 147.363688 -283.544518)
			)
			(arc
				(start 147.41017 -283.498036)
				(mid 147.426704 -283.486925)
				(end 147.446238 -283.48305)
			)
			(arc
				(start 148.768562 -283.48305)
				(mid 148.788085 -283.479149)
				(end 148.80463 -283.468064)
			)
			(arc
				(start 148.829014 -283.44368)
				(mid 148.840125 -283.427146)
				(end 148.844 -283.407612)
			)
			(arc
				(start 148.844 -282.99156)
				(mid 148.840099 -282.972037)
				(end 148.829014 -282.955492)
			)
			(arc
				(start 148.80082 -282.927298)
				(mid 148.784286 -282.916187)
				(end 148.764752 -282.912312)
			)
			(arc
				(start 146.612102 -282.912312)
				(mid 146.592579 -282.916213)
				(end 146.576034 -282.927298)
			)
			(arc
				(start 146.437096 -283.066236)
				(mid 146.425985 -283.08277)
				(end 146.42211 -283.102304)
			)
			(arc
				(start 146.42211 -283.735526)
				(mid 146.426011 -283.755049)
				(end 146.437096 -283.771594)
			)
			(arc
				(start 146.488658 -283.823156)
				(mid 146.505192 -283.834267)
				(end 146.524726 -283.838142)
			)
		)
		(stroke
			(width 0)
			(type solid)
		)
		(fill yes)
		(layer "F.Cu")
		(net "PCEPLL7_VDDA18_PEX1_R")
	)
	(gr_poly
		(pts
			(arc
				(start 149.28596 -282.597606)
				(mid 149.305483 -282.593705)
				(end 149.322028 -282.58262)
			)
			(arc
				(start 149.44598 -282.458668)
				(mid 149.457091 -282.442134)
				(end 149.460966 -282.4226)
			)
			(arc
				(start 149.460966 -280.646886)
				(mid 149.457065 -280.627363)
				(end 149.44598 -280.610818)
			)
			(arc
				(start 149.309836 -280.474674)
				(mid 149.293302 -280.463563)
				(end 149.273768 -280.459688)
			)
			(arc
				(start 147.717764 -280.459688)
				(mid 147.698241 -280.463589)
				(end 147.681696 -280.474674)
			)
			(arc
				(start 147.62607 -280.5303)
				(mid 147.614959 -280.546834)
				(end 147.611084 -280.566368)
			)
			(arc
				(start 147.611084 -280.960322)
				(mid 147.607183 -280.979845)
				(end 147.596098 -280.99639)
			)
			(arc
				(start 147.570698 -281.02179)
				(mid 147.554164 -281.032901)
				(end 147.53463 -281.036776)
			)
			(arc
				(start 146.725894 -281.036776)
				(mid 146.706371 -281.040677)
				(end 146.689826 -281.051762)
			)
			(arc
				(start 146.600672 -281.140916)
				(mid 146.589561 -281.15745)
				(end 146.585686 -281.176984)
			)
			(arc
				(start 146.585686 -282.46705)
				(mid 146.589587 -282.486573)
				(end 146.600672 -282.503118)
			)
			(arc
				(start 146.680428 -282.582874)
				(mid 146.696991 -282.593848)
				(end 146.716496 -282.597606)
			)
		)
		(stroke
			(width 0)
			(type solid)
		)
		(fill yes)
		(layer "F.Cu")
		(net "SYSPLL_VDDA18_PEX1")
	)
	(gr_poly
		(pts
			(arc
				(start 152.244044 -262.242808)
				(mid 152.263567 -262.238907)
				(end 152.280112 -262.227822)
			)
			(arc
				(start 152.404064 -262.10387)
				(mid 152.415175 -262.087336)
				(end 152.41905 -262.067802)
			)
			(arc
				(start 152.41905 -260.292088)
				(mid 152.415149 -260.272565)
				(end 152.404064 -260.25602)
			)
			(arc
				(start 152.26792 -260.119876)
				(mid 152.251386 -260.108765)
				(end 152.231852 -260.10489)
			)
			(arc
				(start 150.675848 -260.10489)
				(mid 150.656325 -260.108791)
				(end 150.63978 -260.119876)
			)
			(arc
				(start 150.584154 -260.175502)
				(mid 150.573043 -260.192036)
				(end 150.569168 -260.21157)
			)
			(arc
				(start 150.569168 -260.605524)
				(mid 150.565267 -260.625047)
				(end 150.554182 -260.641592)
			)
			(arc
				(start 150.528782 -260.666992)
				(mid 150.512248 -260.678103)
				(end 150.492714 -260.681978)
			)
			(arc
				(start 149.683978 -260.681978)
				(mid 149.664455 -260.685879)
				(end 149.64791 -260.696964)
			)
			(arc
				(start 149.558756 -260.786118)
				(mid 149.547645 -260.802652)
				(end 149.54377 -260.822186)
			)
			(arc
				(start 149.54377 -262.112252)
				(mid 149.547671 -262.131775)
				(end 149.558756 -262.14832)
			)
			(arc
				(start 149.638512 -262.228076)
				(mid 149.655075 -262.23905)
				(end 149.67458 -262.242808)
			)
		)
		(stroke
			(width 0)
			(type solid)
		)
		(fill yes)
		(layer "F.Cu")
		(net "PCEPLL3_VDDA18_PEX1")
	)
	(gr_poly
		(pts
			(arc
				(start 152.244044 -259.042408)
				(mid 152.263567 -259.038507)
				(end 152.280112 -259.027422)
			)
			(arc
				(start 152.404064 -258.90347)
				(mid 152.415175 -258.886936)
				(end 152.41905 -258.867402)
			)
			(arc
				(start 152.41905 -257.091688)
				(mid 152.415149 -257.072165)
				(end 152.404064 -257.05562)
			)
			(arc
				(start 152.26792 -256.919476)
				(mid 152.251386 -256.908365)
				(end 152.231852 -256.90449)
			)
			(arc
				(start 150.675848 -256.90449)
				(mid 150.656325 -256.908391)
				(end 150.63978 -256.919476)
			)
			(arc
				(start 150.584154 -256.975102)
				(mid 150.573043 -256.991636)
				(end 150.569168 -257.01117)
			)
			(arc
				(start 150.569168 -257.405124)
				(mid 150.565267 -257.424647)
				(end 150.554182 -257.441192)
			)
			(arc
				(start 150.528782 -257.466592)
				(mid 150.512248 -257.477703)
				(end 150.492714 -257.481578)
			)
			(arc
				(start 149.683978 -257.481578)
				(mid 149.664455 -257.485479)
				(end 149.64791 -257.496564)
			)
			(arc
				(start 149.558756 -257.585718)
				(mid 149.547645 -257.602252)
				(end 149.54377 -257.621786)
			)
			(arc
				(start 149.54377 -258.911852)
				(mid 149.547671 -258.931375)
				(end 149.558756 -258.94792)
			)
			(arc
				(start 149.638512 -259.027676)
				(mid 149.655075 -259.03865)
				(end 149.67458 -259.042408)
			)
		)
		(stroke
			(width 0)
			(type solid)
		)
		(fill yes)
		(layer "F.Cu")
		(net "PCEPLL5_VDDA18_PEX1")
	)
	(gr_poly
		(pts
			(arc
				(start 169.639742 -30.696154)
				(mid 169.659265 -30.692253)
				(end 169.67581 -30.681168)
			)
			(arc
				(start 170.087544 -30.269434)
				(mid 170.104078 -30.258323)
				(end 170.123612 -30.254448)
			)
			(arc
				(start 170.508422 -30.254448)
				(mid 170.527945 -30.250547)
				(end 170.54449 -30.239462)
			)
			(arc
				(start 170.664632 -30.11932)
				(mid 170.675743 -30.102786)
				(end 170.679618 -30.083252)
			)
			(arc
				(start 170.679618 -29.534104)
				(mid 170.671081 -29.505917)
				(end 170.648376 -29.487114)
			)
			(xy 170.633898 -29.481272) (xy 170.603926 -29.487114) (xy 170.60291 -29.488384)
			(arc
				(start 170.229022 -29.488384)
				(mid 170.117989 -29.467379)
				(end 170.022266 -29.407358)
			)
			(arc
				(start 170.022266 -29.407358)
				(mid 170.006271 -29.397332)
				(end 169.987722 -29.393896)
			)
			(arc
				(start 168.248838 -29.393896)
				(mid 168.229315 -29.397797)
				(end 168.21277 -29.408882)
			)
			(xy 168.20896 -29.412692) (xy 168.20134 -29.431234)
			(arc
				(start 168.20134 -30.63367)
				(mid 168.205241 -30.653193)
				(end 168.216326 -30.669738)
			)
			(arc
				(start 168.227756 -30.681168)
				(mid 168.24429 -30.692279)
				(end 168.263824 -30.696154)
			)
		)
		(stroke
			(width 0)
			(type solid)
		)
		(fill yes)
		(layer "F.Cu")
		(net "P3V3_AUX")
	)
	(gr_poly
		(pts
			(arc
				(start 195.63969 -30.696154)
				(mid 195.659213 -30.692253)
				(end 195.675758 -30.681168)
			)
			(arc
				(start 196.087492 -30.269434)
				(mid 196.104026 -30.258323)
				(end 196.12356 -30.254448)
			)
			(arc
				(start 196.50837 -30.254448)
				(mid 196.527893 -30.250547)
				(end 196.544438 -30.239462)
			)
			(arc
				(start 196.66458 -30.11932)
				(mid 196.675691 -30.102786)
				(end 196.679566 -30.083252)
			)
			(arc
				(start 196.679566 -29.534104)
				(mid 196.671029 -29.505917)
				(end 196.648324 -29.487114)
			)
			(xy 196.633846 -29.481272) (xy 196.603874 -29.487114) (xy 196.602858 -29.488384)
			(arc
				(start 196.22897 -29.488384)
				(mid 196.117937 -29.467379)
				(end 196.022214 -29.407358)
			)
			(arc
				(start 196.022214 -29.407358)
				(mid 196.006219 -29.397332)
				(end 195.98767 -29.393896)
			)
			(arc
				(start 194.248786 -29.393896)
				(mid 194.229263 -29.397797)
				(end 194.212718 -29.408882)
			)
			(xy 194.208908 -29.412692) (xy 194.201288 -29.431234)
			(arc
				(start 194.201288 -30.63367)
				(mid 194.205189 -30.653193)
				(end 194.216274 -30.669738)
			)
			(arc
				(start 194.227704 -30.681168)
				(mid 194.244238 -30.692279)
				(end 194.263772 -30.696154)
			)
		)
		(stroke
			(width 0)
			(type solid)
		)
		(fill yes)
		(layer "F.Cu")
		(net "P3V3_AUX")
	)
	(gr_poly
		(pts
			(arc
				(start 233.73969 -30.696154)
				(mid 233.759213 -30.692253)
				(end 233.775758 -30.681168)
			)
			(arc
				(start 234.187492 -30.269434)
				(mid 234.204026 -30.258323)
				(end 234.22356 -30.254448)
			)
			(arc
				(start 234.60837 -30.254448)
				(mid 234.627893 -30.250547)
				(end 234.644438 -30.239462)
			)
			(arc
				(start 234.76458 -30.11932)
				(mid 234.775691 -30.102786)
				(end 234.779566 -30.083252)
			)
			(arc
				(start 234.779566 -29.534104)
				(mid 234.771029 -29.505917)
				(end 234.748324 -29.487114)
			)
			(xy 234.733846 -29.481272) (xy 234.703874 -29.487114) (xy 234.702858 -29.488384)
			(arc
				(start 234.32897 -29.488384)
				(mid 234.217937 -29.467379)
				(end 234.122214 -29.407358)
			)
			(arc
				(start 234.122214 -29.407358)
				(mid 234.106219 -29.397332)
				(end 234.08767 -29.393896)
			)
			(arc
				(start 232.348786 -29.393896)
				(mid 232.329263 -29.397797)
				(end 232.312718 -29.408882)
			)
			(xy 232.308908 -29.412692) (xy 232.301288 -29.431234)
			(arc
				(start 232.301288 -30.63367)
				(mid 232.305189 -30.653193)
				(end 232.316274 -30.669738)
			)
			(arc
				(start 232.327704 -30.681168)
				(mid 232.344238 -30.692279)
				(end 232.363772 -30.696154)
			)
		)
		(stroke
			(width 0)
			(type solid)
		)
		(fill yes)
		(layer "F.Cu")
		(net "P3V3_AUX")
	)
	(gr_poly
		(pts
			(xy 248.08307 -272.430494) (xy 248.08307 -272.064988) (xy 248.08307 -262.10895) (xy 248.08307 -258.375658)
			(xy 247.941084 -258.233672) (xy 242.881404 -258.233672) (xy 242.729512 -258.08178) (xy 232.178098 -258.08178)
			(xy 232.040938 -258.21894) (xy 232.040938 -271.160748) (xy 232.860596 -271.980406) (xy 233.642916 -271.980406)
			(arc
				(start 235.890816 -271.980406)
				(mid 235.910339 -271.976505)
				(end 235.926884 -271.96542)
			)
			(arc
				(start 235.947966 -271.944338)
				(mid 235.959028 -271.927921)
				(end 235.962952 -271.908524)
			)
			(arc
				(start 235.962952 -261.920228)
				(mid 235.966785 -261.900871)
				(end 235.977684 -261.884414)
			)
			(arc
				(start 235.980224 -261.88162)
				(mid 235.991286 -261.865203)
				(end 235.99521 -261.845806)
			)
			(arc
				(start 235.99521 -261.456932)
				(mid 235.999111 -261.437409)
				(end 236.010196 -261.420864)
			)
			(arc
				(start 236.299502 -261.131558)
				(mid 236.316036 -261.120447)
				(end 236.33557 -261.116572)
			)
			(arc
				(start 242.772692 -261.116572)
				(mid 242.792215 -261.120473)
				(end 242.80876 -261.131558)
			)
			(arc
				(start 243.305838 -261.628636)
				(mid 243.316949 -261.64517)
				(end 243.320824 -261.664704)
			)
			(xy 243.320824 -271.630648) (xy 243.320824 -272.666206) (xy 243.440712 -272.786094) (xy 247.72747 -272.786094)
		)
		(stroke
			(width 0)
			(type solid)
		)
		(fill yes)
		(layer "F.Cu")
		(net "P1V25_SERDES_VDDPLL_PEX2")
	)
	(gr_poly
		(pts
			(arc
				(start 259.739638 -30.696154)
				(mid 259.759161 -30.692253)
				(end 259.775706 -30.681168)
			)
			(arc
				(start 260.18744 -30.269434)
				(mid 260.203974 -30.258323)
				(end 260.223508 -30.254448)
			)
			(arc
				(start 260.608318 -30.254448)
				(mid 260.627841 -30.250547)
				(end 260.644386 -30.239462)
			)
			(arc
				(start 260.764528 -30.11932)
				(mid 260.775639 -30.102786)
				(end 260.779514 -30.083252)
			)
			(arc
				(start 260.779514 -29.534104)
				(mid 260.770977 -29.505917)
				(end 260.748272 -29.487114)
			)
			(xy 260.733794 -29.481272) (xy 260.703822 -29.487114) (xy 260.702806 -29.488384)
			(arc
				(start 260.328918 -29.488384)
				(mid 260.217885 -29.467379)
				(end 260.122162 -29.407358)
			)
			(arc
				(start 260.122162 -29.407358)
				(mid 260.106167 -29.397332)
				(end 260.087618 -29.393896)
			)
			(arc
				(start 258.348734 -29.393896)
				(mid 258.329211 -29.397797)
				(end 258.312666 -29.408882)
			)
			(xy 258.308856 -29.412692) (xy 258.301236 -29.431234)
			(arc
				(start 258.301236 -30.63367)
				(mid 258.305137 -30.653193)
				(end 258.316222 -30.669738)
			)
			(arc
				(start 258.327652 -30.681168)
				(mid 258.344186 -30.692279)
				(end 258.36372 -30.696154)
			)
		)
		(stroke
			(width 0)
			(type solid)
		)
		(fill yes)
		(layer "F.Cu")
		(net "P3V3_AUX")
	)
	(gr_poly
		(pts
			(arc
				(start 263.333484 -299.840142)
				(mid 263.352978 -299.836358)
				(end 263.369552 -299.82541)
			)
			(arc
				(start 263.43356 -299.761402)
				(mid 263.444671 -299.744868)
				(end 263.448546 -299.725334)
			)
			(arc
				(start 263.448546 -299.582586)
				(mid 263.452447 -299.563063)
				(end 263.463532 -299.546518)
			)
			(arc
				(start 263.510014 -299.500036)
				(mid 263.526548 -299.488925)
				(end 263.546082 -299.48505)
			)
			(arc
				(start 264.868406 -299.48505)
				(mid 264.887929 -299.481149)
				(end 264.904474 -299.470064)
			)
			(arc
				(start 264.928858 -299.44568)
				(mid 264.939969 -299.429146)
				(end 264.943844 -299.409612)
			)
			(arc
				(start 264.943844 -298.99356)
				(mid 264.939943 -298.974037)
				(end 264.928858 -298.957492)
			)
			(arc
				(start 264.900664 -298.929298)
				(mid 264.88413 -298.918187)
				(end 264.864596 -298.914312)
			)
			(arc
				(start 262.711946 -298.914312)
				(mid 262.692423 -298.918213)
				(end 262.675878 -298.929298)
			)
			(arc
				(start 262.53694 -299.068236)
				(mid 262.525829 -299.08477)
				(end 262.521954 -299.104304)
			)
			(arc
				(start 262.521954 -299.737526)
				(mid 262.525855 -299.757049)
				(end 262.53694 -299.773594)
			)
			(arc
				(start 262.588502 -299.825156)
				(mid 262.605036 -299.836267)
				(end 262.62457 -299.840142)
			)
		)
		(stroke
			(width 0)
			(type solid)
		)
		(fill yes)
		(layer "F.Cu")
		(net "PCEPLL1_VDDA18_PEX2_R")
	)
	(gr_poly
		(pts
			(arc
				(start 263.333484 -293.439342)
				(mid 263.352978 -293.435558)
				(end 263.369552 -293.42461)
			)
			(arc
				(start 263.43356 -293.360602)
				(mid 263.444671 -293.344068)
				(end 263.448546 -293.324534)
			)
			(arc
				(start 263.448546 -293.181786)
				(mid 263.452447 -293.162263)
				(end 263.463532 -293.145718)
			)
			(arc
				(start 263.510014 -293.099236)
				(mid 263.526548 -293.088125)
				(end 263.546082 -293.08425)
			)
			(arc
				(start 264.868406 -293.08425)
				(mid 264.887929 -293.080349)
				(end 264.904474 -293.069264)
			)
			(arc
				(start 264.928858 -293.04488)
				(mid 264.939969 -293.028346)
				(end 264.943844 -293.008812)
			)
			(arc
				(start 264.943844 -292.59276)
				(mid 264.939943 -292.573237)
				(end 264.928858 -292.556692)
			)
			(arc
				(start 264.900664 -292.528498)
				(mid 264.88413 -292.517387)
				(end 264.864596 -292.513512)
			)
			(arc
				(start 262.711946 -292.513512)
				(mid 262.692423 -292.517413)
				(end 262.675878 -292.528498)
			)
			(arc
				(start 262.53694 -292.667436)
				(mid 262.525829 -292.68397)
				(end 262.521954 -292.703504)
			)
			(arc
				(start 262.521954 -293.336726)
				(mid 262.525855 -293.356249)
				(end 262.53694 -293.372794)
			)
			(arc
				(start 262.588502 -293.424356)
				(mid 262.605036 -293.435467)
				(end 262.62457 -293.439342)
			)
		)
		(stroke
			(width 0)
			(type solid)
		)
		(fill yes)
		(layer "F.Cu")
		(net "PCEPLL2_VDDA18_PEX2_R")
	)
	(gr_poly
		(pts
			(arc
				(start 263.333484 -290.238942)
				(mid 263.352978 -290.235158)
				(end 263.369552 -290.22421)
			)
			(arc
				(start 263.43356 -290.160202)
				(mid 263.444671 -290.143668)
				(end 263.448546 -290.124134)
			)
			(arc
				(start 263.448546 -289.981386)
				(mid 263.452447 -289.961863)
				(end 263.463532 -289.945318)
			)
			(arc
				(start 263.510014 -289.898836)
				(mid 263.526548 -289.887725)
				(end 263.546082 -289.88385)
			)
			(arc
				(start 264.868406 -289.88385)
				(mid 264.887929 -289.879949)
				(end 264.904474 -289.868864)
			)
			(arc
				(start 264.928858 -289.84448)
				(mid 264.939969 -289.827946)
				(end 264.943844 -289.808412)
			)
			(arc
				(start 264.943844 -289.39236)
				(mid 264.939943 -289.372837)
				(end 264.928858 -289.356292)
			)
			(arc
				(start 264.900664 -289.328098)
				(mid 264.88413 -289.316987)
				(end 264.864596 -289.313112)
			)
			(arc
				(start 262.711946 -289.313112)
				(mid 262.692423 -289.317013)
				(end 262.675878 -289.328098)
			)
			(arc
				(start 262.53694 -289.467036)
				(mid 262.525829 -289.48357)
				(end 262.521954 -289.503104)
			)
			(arc
				(start 262.521954 -290.136326)
				(mid 262.525855 -290.155849)
				(end 262.53694 -290.172394)
			)
			(arc
				(start 262.588502 -290.223956)
				(mid 262.605036 -290.235067)
				(end 262.62457 -290.238942)
			)
		)
		(stroke
			(width 0)
			(type solid)
		)
		(fill yes)
		(layer "F.Cu")
		(net "PCEPLL4_VDDA18_PEX2_R")
	)
	(gr_poly
		(pts
			(arc
				(start 263.333484 -287.038542)
				(mid 263.352978 -287.034758)
				(end 263.369552 -287.02381)
			)
			(arc
				(start 263.43356 -286.959802)
				(mid 263.444671 -286.943268)
				(end 263.448546 -286.923734)
			)
			(arc
				(start 263.448546 -286.780986)
				(mid 263.452447 -286.761463)
				(end 263.463532 -286.744918)
			)
			(arc
				(start 263.510014 -286.698436)
				(mid 263.526548 -286.687325)
				(end 263.546082 -286.68345)
			)
			(arc
				(start 264.868406 -286.68345)
				(mid 264.887929 -286.679549)
				(end 264.904474 -286.668464)
			)
			(arc
				(start 264.928858 -286.64408)
				(mid 264.939969 -286.627546)
				(end 264.943844 -286.608012)
			)
			(arc
				(start 264.943844 -286.19196)
				(mid 264.939943 -286.172437)
				(end 264.928858 -286.155892)
			)
			(arc
				(start 264.900664 -286.127698)
				(mid 264.88413 -286.116587)
				(end 264.864596 -286.112712)
			)
			(arc
				(start 262.711946 -286.112712)
				(mid 262.692423 -286.116613)
				(end 262.675878 -286.127698)
			)
			(arc
				(start 262.53694 -286.266636)
				(mid 262.525829 -286.28317)
				(end 262.521954 -286.302704)
			)
			(arc
				(start 262.521954 -286.935926)
				(mid 262.525855 -286.955449)
				(end 262.53694 -286.971994)
			)
			(arc
				(start 262.588502 -287.023556)
				(mid 262.605036 -287.034667)
				(end 262.62457 -287.038542)
			)
		)
		(stroke
			(width 0)
			(type solid)
		)
		(fill yes)
		(layer "F.Cu")
		(net "PCEPLL6_VDDA18_PEX2_R")
	)
	(gr_poly
		(pts
			(arc
				(start 263.333484 -283.838142)
				(mid 263.352978 -283.834358)
				(end 263.369552 -283.82341)
			)
			(arc
				(start 263.43356 -283.759402)
				(mid 263.444671 -283.742868)
				(end 263.448546 -283.723334)
			)
			(arc
				(start 263.448546 -283.580586)
				(mid 263.452447 -283.561063)
				(end 263.463532 -283.544518)
			)
			(arc
				(start 263.510014 -283.498036)
				(mid 263.526548 -283.486925)
				(end 263.546082 -283.48305)
			)
			(arc
				(start 264.868406 -283.48305)
				(mid 264.887929 -283.479149)
				(end 264.904474 -283.468064)
			)
			(arc
				(start 264.928858 -283.44368)
				(mid 264.939969 -283.427146)
				(end 264.943844 -283.407612)
			)
			(arc
				(start 264.943844 -282.99156)
				(mid 264.939943 -282.972037)
				(end 264.928858 -282.955492)
			)
			(arc
				(start 264.900664 -282.927298)
				(mid 264.88413 -282.916187)
				(end 264.864596 -282.912312)
			)
			(arc
				(start 262.711946 -282.912312)
				(mid 262.692423 -282.916213)
				(end 262.675878 -282.927298)
			)
			(arc
				(start 262.53694 -283.066236)
				(mid 262.525829 -283.08277)
				(end 262.521954 -283.102304)
			)
			(arc
				(start 262.521954 -283.735526)
				(mid 262.525855 -283.755049)
				(end 262.53694 -283.771594)
			)
			(arc
				(start 262.588502 -283.823156)
				(mid 262.605036 -283.834267)
				(end 262.62457 -283.838142)
			)
		)
		(stroke
			(width 0)
			(type solid)
		)
		(fill yes)
		(layer "F.Cu")
		(net "PCEPLL7_VDDA18_PEX2_R")
	)
	(gr_poly
		(pts
			(arc
				(start 265.385804 -282.597606)
				(mid 265.405327 -282.593705)
				(end 265.421872 -282.58262)
			)
			(arc
				(start 265.545824 -282.458668)
				(mid 265.556935 -282.442134)
				(end 265.56081 -282.4226)
			)
			(arc
				(start 265.56081 -280.646886)
				(mid 265.556909 -280.627363)
				(end 265.545824 -280.610818)
			)
			(arc
				(start 265.40968 -280.474674)
				(mid 265.393146 -280.463563)
				(end 265.373612 -280.459688)
			)
			(arc
				(start 263.817608 -280.459688)
				(mid 263.798085 -280.463589)
				(end 263.78154 -280.474674)
			)
			(arc
				(start 263.725914 -280.5303)
				(mid 263.714803 -280.546834)
				(end 263.710928 -280.566368)
			)
			(arc
				(start 263.710928 -280.960322)
				(mid 263.707027 -280.979845)
				(end 263.695942 -280.99639)
			)
			(arc
				(start 263.670542 -281.02179)
				(mid 263.654008 -281.032901)
				(end 263.634474 -281.036776)
			)
			(arc
				(start 262.825738 -281.036776)
				(mid 262.806215 -281.040677)
				(end 262.78967 -281.051762)
			)
			(arc
				(start 262.700516 -281.140916)
				(mid 262.689405 -281.15745)
				(end 262.68553 -281.176984)
			)
			(arc
				(start 262.68553 -282.46705)
				(mid 262.689431 -282.486573)
				(end 262.700516 -282.503118)
			)
			(arc
				(start 262.780272 -282.582874)
				(mid 262.796835 -282.593848)
				(end 262.81634 -282.597606)
			)
		)
		(stroke
			(width 0)
			(type solid)
		)
		(fill yes)
		(layer "F.Cu")
		(net "SYSPLL_VDDA18_PEX2")
	)
	(gr_poly
		(pts
			(arc
				(start 268.343888 -262.242808)
				(mid 268.363411 -262.238907)
				(end 268.379956 -262.227822)
			)
			(arc
				(start 268.503908 -262.10387)
				(mid 268.515019 -262.087336)
				(end 268.518894 -262.067802)
			)
			(arc
				(start 268.518894 -260.292088)
				(mid 268.514993 -260.272565)
				(end 268.503908 -260.25602)
			)
			(arc
				(start 268.367764 -260.119876)
				(mid 268.35123 -260.108765)
				(end 268.331696 -260.10489)
			)
			(arc
				(start 266.775692 -260.10489)
				(mid 266.756169 -260.108791)
				(end 266.739624 -260.119876)
			)
			(arc
				(start 266.683998 -260.175502)
				(mid 266.672887 -260.192036)
				(end 266.669012 -260.21157)
			)
			(arc
				(start 266.669012 -260.605524)
				(mid 266.665111 -260.625047)
				(end 266.654026 -260.641592)
			)
			(arc
				(start 266.628626 -260.666992)
				(mid 266.612092 -260.678103)
				(end 266.592558 -260.681978)
			)
			(arc
				(start 265.783822 -260.681978)
				(mid 265.764299 -260.685879)
				(end 265.747754 -260.696964)
			)
			(arc
				(start 265.6586 -260.786118)
				(mid 265.647489 -260.802652)
				(end 265.643614 -260.822186)
			)
			(arc
				(start 265.643614 -262.112252)
				(mid 265.647515 -262.131775)
				(end 265.6586 -262.14832)
			)
			(arc
				(start 265.738356 -262.228076)
				(mid 265.754919 -262.23905)
				(end 265.774424 -262.242808)
			)
		)
		(stroke
			(width 0)
			(type solid)
		)
		(fill yes)
		(layer "F.Cu")
		(net "PCEPLL3_VDDA18_PEX2")
	)
	(gr_poly
		(pts
			(arc
				(start 268.343888 -259.042408)
				(mid 268.363411 -259.038507)
				(end 268.379956 -259.027422)
			)
			(arc
				(start 268.503908 -258.90347)
				(mid 268.515019 -258.886936)
				(end 268.518894 -258.867402)
			)
			(arc
				(start 268.518894 -257.091688)
				(mid 268.514993 -257.072165)
				(end 268.503908 -257.05562)
			)
			(arc
				(start 268.367764 -256.919476)
				(mid 268.35123 -256.908365)
				(end 268.331696 -256.90449)
			)
			(arc
				(start 266.775692 -256.90449)
				(mid 266.756169 -256.908391)
				(end 266.739624 -256.919476)
			)
			(arc
				(start 266.683998 -256.975102)
				(mid 266.672887 -256.991636)
				(end 266.669012 -257.01117)
			)
			(arc
				(start 266.669012 -257.405124)
				(mid 266.665111 -257.424647)
				(end 266.654026 -257.441192)
			)
			(arc
				(start 266.628626 -257.466592)
				(mid 266.612092 -257.477703)
				(end 266.592558 -257.481578)
			)
			(arc
				(start 265.783822 -257.481578)
				(mid 265.764299 -257.485479)
				(end 265.747754 -257.496564)
			)
			(arc
				(start 265.6586 -257.585718)
				(mid 265.647489 -257.602252)
				(end 265.643614 -257.621786)
			)
			(arc
				(start 265.643614 -258.911852)
				(mid 265.647515 -258.931375)
				(end 265.6586 -258.94792)
			)
			(arc
				(start 265.738356 -259.027676)
				(mid 265.754919 -259.03865)
				(end 265.774424 -259.042408)
			)
		)
		(stroke
			(width 0)
			(type solid)
		)
		(fill yes)
		(layer "F.Cu")
		(net "PCEPLL5_VDDA18_PEX2")
	)
	(gr_poly
		(pts
			(arc
				(start 285.739586 -30.696154)
				(mid 285.759109 -30.692253)
				(end 285.775654 -30.681168)
			)
			(arc
				(start 286.187388 -30.269434)
				(mid 286.203922 -30.258323)
				(end 286.223456 -30.254448)
			)
			(arc
				(start 286.608266 -30.254448)
				(mid 286.627789 -30.250547)
				(end 286.644334 -30.239462)
			)
			(arc
				(start 286.764476 -30.11932)
				(mid 286.775587 -30.102786)
				(end 286.779462 -30.083252)
			)
			(arc
				(start 286.779462 -29.534104)
				(mid 286.770925 -29.505917)
				(end 286.74822 -29.487114)
			)
			(xy 286.733742 -29.481272) (xy 286.70377 -29.487114) (xy 286.702754 -29.488384)
			(arc
				(start 286.328866 -29.488384)
				(mid 286.217833 -29.467379)
				(end 286.12211 -29.407358)
			)
			(arc
				(start 286.12211 -29.407358)
				(mid 286.106115 -29.397332)
				(end 286.087566 -29.393896)
			)
			(arc
				(start 284.348682 -29.393896)
				(mid 284.329159 -29.397797)
				(end 284.312614 -29.408882)
			)
			(xy 284.308804 -29.412692) (xy 284.301184 -29.431234)
			(arc
				(start 284.301184 -30.63367)
				(mid 284.305085 -30.653193)
				(end 284.31617 -30.669738)
			)
			(arc
				(start 284.3276 -30.681168)
				(mid 284.344134 -30.692279)
				(end 284.363668 -30.696154)
			)
		)
		(stroke
			(width 0)
			(type solid)
		)
		(fill yes)
		(layer "F.Cu")
		(net "P3V3_AUX")
	)
	(gr_poly
		(pts
			(arc
				(start 311.739534 -30.696154)
				(mid 311.759057 -30.692253)
				(end 311.775602 -30.681168)
			)
			(arc
				(start 312.187336 -30.269434)
				(mid 312.20387 -30.258323)
				(end 312.223404 -30.254448)
			)
			(arc
				(start 312.608214 -30.254448)
				(mid 312.627737 -30.250547)
				(end 312.644282 -30.239462)
			)
			(arc
				(start 312.764424 -30.11932)
				(mid 312.775535 -30.102786)
				(end 312.77941 -30.083252)
			)
			(arc
				(start 312.77941 -29.534104)
				(mid 312.770873 -29.505917)
				(end 312.748168 -29.487114)
			)
			(xy 312.73369 -29.481272) (xy 312.703718 -29.487114) (xy 312.702702 -29.488384)
			(arc
				(start 312.328814 -29.488384)
				(mid 312.217781 -29.467379)
				(end 312.122058 -29.407358)
			)
			(arc
				(start 312.122058 -29.407358)
				(mid 312.106063 -29.397332)
				(end 312.087514 -29.393896)
			)
			(arc
				(start 310.34863 -29.393896)
				(mid 310.329107 -29.397797)
				(end 310.312562 -29.408882)
			)
			(xy 310.308752 -29.412692) (xy 310.301132 -29.431234)
			(arc
				(start 310.301132 -30.63367)
				(mid 310.305033 -30.653193)
				(end 310.316118 -30.669738)
			)
			(arc
				(start 310.327548 -30.681168)
				(mid 310.344082 -30.692279)
				(end 310.363616 -30.696154)
			)
		)
		(stroke
			(width 0)
			(type solid)
		)
		(fill yes)
		(layer "F.Cu")
		(net "P3V3_AUX")
	)
	(gr_poly
		(pts
			(arc
				(start 324.16623 -115.63223)
				(mid 324.194417 -115.623693)
				(end 324.21322 -115.600988)
			)
			(xy 324.219062 -115.58651) (xy 324.21322 -115.556538) (xy 324.21195 -115.555522)
			(arc
				(start 324.21195 -115.181634)
				(mid 324.232955 -115.070601)
				(end 324.292976 -114.974878)
			)
			(arc
				(start 324.292976 -114.974878)
				(mid 324.303002 -114.958883)
				(end 324.306438 -114.940334)
			)
			(arc
				(start 324.306438 -113.20145)
				(mid 324.302537 -113.181927)
				(end 324.291452 -113.165382)
			)
			(xy 324.287642 -113.161572) (xy 324.2691 -113.153952) (xy 323.18452 -113.153952) (xy 323.180964 -113.157508)
			(xy 322.623688 -113.157508) (xy 322.52793 -113.157508) (xy 322.424552 -113.260886) (xy 322.424552 -113.85677)
			(xy 322.507864 -113.940082) (xy 323.00418 -114.436398)
			(arc
				(start 323.00418 -114.592354)
				(mid 323.008081 -114.611877)
				(end 323.019166 -114.628422)
			)
			(arc
				(start 323.4309 -115.040156)
				(mid 323.442011 -115.05669)
				(end 323.445886 -115.076224)
			)
			(arc
				(start 323.445886 -115.461034)
				(mid 323.449787 -115.480557)
				(end 323.460872 -115.497102)
			)
			(arc
				(start 323.581014 -115.617244)
				(mid 323.597548 -115.628355)
				(end 323.617082 -115.63223)
			)
		)
		(stroke
			(width 0)
			(type solid)
		)
		(fill yes)
		(layer "F.Cu")
		(net "P3V3_AUX")
	)
	(gr_poly
		(pts
			(arc
				(start 349.839788 -30.696154)
				(mid 349.859311 -30.692253)
				(end 349.875856 -30.681168)
			)
			(arc
				(start 350.28759 -30.269434)
				(mid 350.304124 -30.258323)
				(end 350.323658 -30.254448)
			)
			(arc
				(start 350.708468 -30.254448)
				(mid 350.727991 -30.250547)
				(end 350.744536 -30.239462)
			)
			(arc
				(start 350.864678 -30.11932)
				(mid 350.875789 -30.102786)
				(end 350.879664 -30.083252)
			)
			(arc
				(start 350.879664 -29.534104)
				(mid 350.871127 -29.505917)
				(end 350.848422 -29.487114)
			)
			(xy 350.833944 -29.481272) (xy 350.803972 -29.487114) (xy 350.802956 -29.488384)
			(arc
				(start 350.429068 -29.488384)
				(mid 350.318035 -29.467379)
				(end 350.222312 -29.407358)
			)
			(arc
				(start 350.222312 -29.407358)
				(mid 350.206317 -29.397332)
				(end 350.187768 -29.393896)
			)
			(arc
				(start 348.448884 -29.393896)
				(mid 348.429361 -29.397797)
				(end 348.412816 -29.408882)
			)
			(xy 348.409006 -29.412692) (xy 348.401386 -29.431234)
			(arc
				(start 348.401386 -30.63367)
				(mid 348.405287 -30.653193)
				(end 348.416372 -30.669738)
			)
			(arc
				(start 348.427802 -30.681168)
				(mid 348.444336 -30.692279)
				(end 348.46387 -30.696154)
			)
		)
		(stroke
			(width 0)
			(type solid)
		)
		(fill yes)
		(layer "F.Cu")
		(net "P3V3_AUX")
	)
	(gr_poly
		(pts
			(arc
				(start 368.113056 -318.761872)
				(mid 369.518658 -315.400143)
				(end 372.028974 -312.75909)
			)
			(arc
				(start 372.028974 -294.41394)
				(mid 372.025073 -294.394417)
				(end 372.013988 -294.377872)
			)
			(arc
				(start 371.594126 -293.95801)
				(mid 371.577592 -293.946899)
				(end 371.558058 -293.943024)
			)
			(xy 350.96323 -293.943024) (xy 350.883982 -294.022272) (xy 350.883982 -302.475646) (xy 351.681034 -303.272698)
			(xy 366.879886 -303.272698) (xy 367.059464 -303.452276) (xy 367.059464 -308.394862) (xy 366.80013 -308.654196)
			(xy 355.916484 -308.654196) (xy 355.665532 -308.905148) (xy 355.665532 -318.57442) (xy 355.852984 -318.761872)
		)
		(stroke
			(width 0)
			(type solid)
		)
		(fill yes)
		(layer "F.Cu")
		(net "P0V8_PEX3")
	)
	(gr_poly
		(pts
			(arc
				(start 375.839736 -30.696154)
				(mid 375.859259 -30.692253)
				(end 375.875804 -30.681168)
			)
			(arc
				(start 376.287538 -30.269434)
				(mid 376.304072 -30.258323)
				(end 376.323606 -30.254448)
			)
			(arc
				(start 376.708416 -30.254448)
				(mid 376.727939 -30.250547)
				(end 376.744484 -30.239462)
			)
			(arc
				(start 376.864626 -30.11932)
				(mid 376.875737 -30.102786)
				(end 376.879612 -30.083252)
			)
			(arc
				(start 376.879612 -29.534104)
				(mid 376.871075 -29.505917)
				(end 376.84837 -29.487114)
			)
			(xy 376.833892 -29.481272) (xy 376.80392 -29.487114) (xy 376.802904 -29.488384)
			(arc
				(start 376.429016 -29.488384)
				(mid 376.317983 -29.467379)
				(end 376.22226 -29.407358)
			)
			(arc
				(start 376.22226 -29.407358)
				(mid 376.206265 -29.397332)
				(end 376.187716 -29.393896)
			)
			(arc
				(start 374.448832 -29.393896)
				(mid 374.429309 -29.397797)
				(end 374.412764 -29.408882)
			)
			(xy 374.408954 -29.412692) (xy 374.401334 -29.431234)
			(arc
				(start 374.401334 -30.63367)
				(mid 374.405235 -30.653193)
				(end 374.41632 -30.669738)
			)
			(arc
				(start 374.42775 -30.681168)
				(mid 374.444284 -30.692279)
				(end 374.463818 -30.696154)
			)
		)
		(stroke
			(width 0)
			(type solid)
		)
		(fill yes)
		(layer "F.Cu")
		(net "P3V3_AUX")
	)
	(gr_poly
		(pts
			(arc
				(start 379.433582 -299.840142)
				(mid 379.453076 -299.836358)
				(end 379.46965 -299.82541)
			)
			(arc
				(start 379.533658 -299.761402)
				(mid 379.544769 -299.744868)
				(end 379.548644 -299.725334)
			)
			(arc
				(start 379.548644 -299.582586)
				(mid 379.552545 -299.563063)
				(end 379.56363 -299.546518)
			)
			(arc
				(start 379.610112 -299.500036)
				(mid 379.626646 -299.488925)
				(end 379.64618 -299.48505)
			)
			(arc
				(start 380.968504 -299.48505)
				(mid 380.988027 -299.481149)
				(end 381.004572 -299.470064)
			)
			(arc
				(start 381.028956 -299.44568)
				(mid 381.040067 -299.429146)
				(end 381.043942 -299.409612)
			)
			(arc
				(start 381.043942 -298.99356)
				(mid 381.040041 -298.974037)
				(end 381.028956 -298.957492)
			)
			(arc
				(start 381.000762 -298.929298)
				(mid 380.984228 -298.918187)
				(end 380.964694 -298.914312)
			)
			(arc
				(start 378.812044 -298.914312)
				(mid 378.792521 -298.918213)
				(end 378.775976 -298.929298)
			)
			(arc
				(start 378.637038 -299.068236)
				(mid 378.625927 -299.08477)
				(end 378.622052 -299.104304)
			)
			(arc
				(start 378.622052 -299.737526)
				(mid 378.625953 -299.757049)
				(end 378.637038 -299.773594)
			)
			(arc
				(start 378.6886 -299.825156)
				(mid 378.705134 -299.836267)
				(end 378.724668 -299.840142)
			)
		)
		(stroke
			(width 0)
			(type solid)
		)
		(fill yes)
		(layer "F.Cu")
		(net "PCEPLL1_VDDA18_PEX3_R")
	)
	(gr_poly
		(pts
			(arc
				(start 379.433582 -293.439342)
				(mid 379.453076 -293.435558)
				(end 379.46965 -293.42461)
			)
			(arc
				(start 379.533658 -293.360602)
				(mid 379.544769 -293.344068)
				(end 379.548644 -293.324534)
			)
			(arc
				(start 379.548644 -293.181786)
				(mid 379.552545 -293.162263)
				(end 379.56363 -293.145718)
			)
			(arc
				(start 379.610112 -293.099236)
				(mid 379.626646 -293.088125)
				(end 379.64618 -293.08425)
			)
			(arc
				(start 380.968504 -293.08425)
				(mid 380.988027 -293.080349)
				(end 381.004572 -293.069264)
			)
			(arc
				(start 381.028956 -293.04488)
				(mid 381.040067 -293.028346)
				(end 381.043942 -293.008812)
			)
			(arc
				(start 381.043942 -292.59276)
				(mid 381.040041 -292.573237)
				(end 381.028956 -292.556692)
			)
			(arc
				(start 381.000762 -292.528498)
				(mid 380.984228 -292.517387)
				(end 380.964694 -292.513512)
			)
			(arc
				(start 378.812044 -292.513512)
				(mid 378.792521 -292.517413)
				(end 378.775976 -292.528498)
			)
			(arc
				(start 378.637038 -292.667436)
				(mid 378.625927 -292.68397)
				(end 378.622052 -292.703504)
			)
			(arc
				(start 378.622052 -293.336726)
				(mid 378.625953 -293.356249)
				(end 378.637038 -293.372794)
			)
			(arc
				(start 378.6886 -293.424356)
				(mid 378.705134 -293.435467)
				(end 378.724668 -293.439342)
			)
		)
		(stroke
			(width 0)
			(type solid)
		)
		(fill yes)
		(layer "F.Cu")
		(net "PCEPLL2_VDDA18_PEX3_R")
	)
	(gr_poly
		(pts
			(arc
				(start 379.433582 -290.238942)
				(mid 379.453076 -290.235158)
				(end 379.46965 -290.22421)
			)
			(arc
				(start 379.533658 -290.160202)
				(mid 379.544769 -290.143668)
				(end 379.548644 -290.124134)
			)
			(arc
				(start 379.548644 -289.981386)
				(mid 379.552545 -289.961863)
				(end 379.56363 -289.945318)
			)
			(arc
				(start 379.610112 -289.898836)
				(mid 379.626646 -289.887725)
				(end 379.64618 -289.88385)
			)
			(arc
				(start 380.968504 -289.88385)
				(mid 380.988027 -289.879949)
				(end 381.004572 -289.868864)
			)
			(arc
				(start 381.028956 -289.84448)
				(mid 381.040067 -289.827946)
				(end 381.043942 -289.808412)
			)
			(arc
				(start 381.043942 -289.39236)
				(mid 381.040041 -289.372837)
				(end 381.028956 -289.356292)
			)
			(arc
				(start 381.000762 -289.328098)
				(mid 380.984228 -289.316987)
				(end 380.964694 -289.313112)
			)
			(arc
				(start 378.812044 -289.313112)
				(mid 378.792521 -289.317013)
				(end 378.775976 -289.328098)
			)
			(arc
				(start 378.637038 -289.467036)
				(mid 378.625927 -289.48357)
				(end 378.622052 -289.503104)
			)
			(arc
				(start 378.622052 -290.136326)
				(mid 378.625953 -290.155849)
				(end 378.637038 -290.172394)
			)
			(arc
				(start 378.6886 -290.223956)
				(mid 378.705134 -290.235067)
				(end 378.724668 -290.238942)
			)
		)
		(stroke
			(width 0)
			(type solid)
		)
		(fill yes)
		(layer "F.Cu")
		(net "PCEPLL4_VDDA18_PEX3_R")
	)
	(gr_poly
		(pts
			(arc
				(start 379.433582 -287.038542)
				(mid 379.453076 -287.034758)
				(end 379.46965 -287.02381)
			)
			(arc
				(start 379.533658 -286.959802)
				(mid 379.544769 -286.943268)
				(end 379.548644 -286.923734)
			)
			(arc
				(start 379.548644 -286.780986)
				(mid 379.552545 -286.761463)
				(end 379.56363 -286.744918)
			)
			(arc
				(start 379.610112 -286.698436)
				(mid 379.626646 -286.687325)
				(end 379.64618 -286.68345)
			)
			(arc
				(start 380.968504 -286.68345)
				(mid 380.988027 -286.679549)
				(end 381.004572 -286.668464)
			)
			(arc
				(start 381.028956 -286.64408)
				(mid 381.040067 -286.627546)
				(end 381.043942 -286.608012)
			)
			(arc
				(start 381.043942 -286.19196)
				(mid 381.040041 -286.172437)
				(end 381.028956 -286.155892)
			)
			(arc
				(start 381.000762 -286.127698)
				(mid 380.984228 -286.116587)
				(end 380.964694 -286.112712)
			)
			(arc
				(start 378.812044 -286.112712)
				(mid 378.792521 -286.116613)
				(end 378.775976 -286.127698)
			)
			(arc
				(start 378.637038 -286.266636)
				(mid 378.625927 -286.28317)
				(end 378.622052 -286.302704)
			)
			(arc
				(start 378.622052 -286.935926)
				(mid 378.625953 -286.955449)
				(end 378.637038 -286.971994)
			)
			(arc
				(start 378.6886 -287.023556)
				(mid 378.705134 -287.034667)
				(end 378.724668 -287.038542)
			)
		)
		(stroke
			(width 0)
			(type solid)
		)
		(fill yes)
		(layer "F.Cu")
		(net "PCEPLL6_VDDA18_PEX3_R")
	)
	(gr_poly
		(pts
			(arc
				(start 379.433582 -283.838142)
				(mid 379.453076 -283.834358)
				(end 379.46965 -283.82341)
			)
			(arc
				(start 379.533658 -283.759402)
				(mid 379.544769 -283.742868)
				(end 379.548644 -283.723334)
			)
			(arc
				(start 379.548644 -283.580586)
				(mid 379.552545 -283.561063)
				(end 379.56363 -283.544518)
			)
			(arc
				(start 379.610112 -283.498036)
				(mid 379.626646 -283.486925)
				(end 379.64618 -283.48305)
			)
			(arc
				(start 380.968504 -283.48305)
				(mid 380.988027 -283.479149)
				(end 381.004572 -283.468064)
			)
			(arc
				(start 381.028956 -283.44368)
				(mid 381.040067 -283.427146)
				(end 381.043942 -283.407612)
			)
			(arc
				(start 381.043942 -282.99156)
				(mid 381.040041 -282.972037)
				(end 381.028956 -282.955492)
			)
			(arc
				(start 381.000762 -282.927298)
				(mid 380.984228 -282.916187)
				(end 380.964694 -282.912312)
			)
			(arc
				(start 378.812044 -282.912312)
				(mid 378.792521 -282.916213)
				(end 378.775976 -282.927298)
			)
			(arc
				(start 378.637038 -283.066236)
				(mid 378.625927 -283.08277)
				(end 378.622052 -283.102304)
			)
			(arc
				(start 378.622052 -283.735526)
				(mid 378.625953 -283.755049)
				(end 378.637038 -283.771594)
			)
			(arc
				(start 378.6886 -283.823156)
				(mid 378.705134 -283.834267)
				(end 378.724668 -283.838142)
			)
		)
		(stroke
			(width 0)
			(type solid)
		)
		(fill yes)
		(layer "F.Cu")
		(net "PCEPLL7_VDDA18_PEX3_R")
	)
	(gr_poly
		(pts
			(arc
				(start 381.485902 -282.597606)
				(mid 381.505425 -282.593705)
				(end 381.52197 -282.58262)
			)
			(arc
				(start 381.645922 -282.458668)
				(mid 381.657033 -282.442134)
				(end 381.660908 -282.4226)
			)
			(arc
				(start 381.660908 -280.646886)
				(mid 381.657007 -280.627363)
				(end 381.645922 -280.610818)
			)
			(arc
				(start 381.509778 -280.474674)
				(mid 381.493244 -280.463563)
				(end 381.47371 -280.459688)
			)
			(arc
				(start 379.917706 -280.459688)
				(mid 379.898183 -280.463589)
				(end 379.881638 -280.474674)
			)
			(arc
				(start 379.826012 -280.5303)
				(mid 379.814901 -280.546834)
				(end 379.811026 -280.566368)
			)
			(arc
				(start 379.811026 -280.960322)
				(mid 379.807125 -280.979845)
				(end 379.79604 -280.99639)
			)
			(arc
				(start 379.77064 -281.02179)
				(mid 379.754106 -281.032901)
				(end 379.734572 -281.036776)
			)
			(arc
				(start 378.925836 -281.036776)
				(mid 378.906313 -281.040677)
				(end 378.889768 -281.051762)
			)
			(arc
				(start 378.800614 -281.140916)
				(mid 378.789503 -281.15745)
				(end 378.785628 -281.176984)
			)
			(arc
				(start 378.785628 -282.46705)
				(mid 378.789529 -282.486573)
				(end 378.800614 -282.503118)
			)
			(arc
				(start 378.88037 -282.582874)
				(mid 378.896933 -282.593848)
				(end 378.916438 -282.597606)
			)
		)
		(stroke
			(width 0)
			(type solid)
		)
		(fill yes)
		(layer "F.Cu")
		(net "SYSPLL_VDDA18_PEX3")
	)
	(gr_poly
		(pts
			(arc
				(start 384.443986 -262.242808)
				(mid 384.463509 -262.238907)
				(end 384.480054 -262.227822)
			)
			(arc
				(start 384.604006 -262.10387)
				(mid 384.615117 -262.087336)
				(end 384.618992 -262.067802)
			)
			(arc
				(start 384.618992 -260.292088)
				(mid 384.615091 -260.272565)
				(end 384.604006 -260.25602)
			)
			(arc
				(start 384.467862 -260.119876)
				(mid 384.451328 -260.108765)
				(end 384.431794 -260.10489)
			)
			(arc
				(start 382.87579 -260.10489)
				(mid 382.856267 -260.108791)
				(end 382.839722 -260.119876)
			)
			(arc
				(start 382.784096 -260.175502)
				(mid 382.772985 -260.192036)
				(end 382.76911 -260.21157)
			)
			(arc
				(start 382.76911 -260.605524)
				(mid 382.765209 -260.625047)
				(end 382.754124 -260.641592)
			)
			(arc
				(start 382.728724 -260.666992)
				(mid 382.71219 -260.678103)
				(end 382.692656 -260.681978)
			)
			(arc
				(start 381.88392 -260.681978)
				(mid 381.864397 -260.685879)
				(end 381.847852 -260.696964)
			)
			(arc
				(start 381.758698 -260.786118)
				(mid 381.747587 -260.802652)
				(end 381.743712 -260.822186)
			)
			(arc
				(start 381.743712 -262.112252)
				(mid 381.747613 -262.131775)
				(end 381.758698 -262.14832)
			)
			(arc
				(start 381.838454 -262.228076)
				(mid 381.855017 -262.23905)
				(end 381.874522 -262.242808)
			)
		)
		(stroke
			(width 0)
			(type solid)
		)
		(fill yes)
		(layer "F.Cu")
		(net "PCEPLL3_VDDA18_PEX3")
	)
	(gr_poly
		(pts
			(arc
				(start 384.443986 -259.042408)
				(mid 384.463509 -259.038507)
				(end 384.480054 -259.027422)
			)
			(arc
				(start 384.604006 -258.90347)
				(mid 384.615117 -258.886936)
				(end 384.618992 -258.867402)
			)
			(arc
				(start 384.618992 -257.091688)
				(mid 384.615091 -257.072165)
				(end 384.604006 -257.05562)
			)
			(arc
				(start 384.467862 -256.919476)
				(mid 384.451328 -256.908365)
				(end 384.431794 -256.90449)
			)
			(arc
				(start 382.87579 -256.90449)
				(mid 382.856267 -256.908391)
				(end 382.839722 -256.919476)
			)
			(arc
				(start 382.784096 -256.975102)
				(mid 382.772985 -256.991636)
				(end 382.76911 -257.01117)
			)
			(arc
				(start 382.76911 -257.405124)
				(mid 382.765209 -257.424647)
				(end 382.754124 -257.441192)
			)
			(arc
				(start 382.728724 -257.466592)
				(mid 382.71219 -257.477703)
				(end 382.692656 -257.481578)
			)
			(arc
				(start 381.88392 -257.481578)
				(mid 381.864397 -257.485479)
				(end 381.847852 -257.496564)
			)
			(arc
				(start 381.758698 -257.585718)
				(mid 381.747587 -257.602252)
				(end 381.743712 -257.621786)
			)
			(arc
				(start 381.743712 -258.911852)
				(mid 381.747613 -258.931375)
				(end 381.758698 -258.94792)
			)
			(arc
				(start 381.838454 -259.027676)
				(mid 381.855017 -259.03865)
				(end 381.874522 -259.042408)
			)
		)
		(stroke
			(width 0)
			(type solid)
		)
		(fill yes)
		(layer "F.Cu")
		(net "PCEPLL5_VDDA18_PEX3")
	)
	(gr_poly
		(pts
			(arc
				(start 401.839684 -30.696154)
				(mid 401.859207 -30.692253)
				(end 401.875752 -30.681168)
			)
			(arc
				(start 402.287486 -30.269434)
				(mid 402.30402 -30.258323)
				(end 402.323554 -30.254448)
			)
			(arc
				(start 402.708364 -30.254448)
				(mid 402.727887 -30.250547)
				(end 402.744432 -30.239462)
			)
			(arc
				(start 402.864574 -30.11932)
				(mid 402.875685 -30.102786)
				(end 402.87956 -30.083252)
			)
			(arc
				(start 402.87956 -29.534104)
				(mid 402.871023 -29.505917)
				(end 402.848318 -29.487114)
			)
			(xy 402.83384 -29.481272) (xy 402.803868 -29.487114) (xy 402.802852 -29.488384)
			(arc
				(start 402.428964 -29.488384)
				(mid 402.317931 -29.467379)
				(end 402.222208 -29.407358)
			)
			(arc
				(start 402.222208 -29.407358)
				(mid 402.206213 -29.397332)
				(end 402.187664 -29.393896)
			)
			(arc
				(start 400.44878 -29.393896)
				(mid 400.429257 -29.397797)
				(end 400.412712 -29.408882)
			)
			(xy 400.408902 -29.412692) (xy 400.401282 -29.431234)
			(arc
				(start 400.401282 -30.63367)
				(mid 400.405183 -30.653193)
				(end 400.416268 -30.669738)
			)
			(arc
				(start 400.427698 -30.681168)
				(mid 400.444232 -30.692279)
				(end 400.463766 -30.696154)
			)
		)
		(stroke
			(width 0)
			(type solid)
		)
		(fill yes)
		(layer "F.Cu")
		(net "P3V3_AUX")
	)
	(gr_poly
		(pts
			(arc
				(start 427.839632 -30.696154)
				(mid 427.859155 -30.692253)
				(end 427.8757 -30.681168)
			)
			(arc
				(start 428.287434 -30.269434)
				(mid 428.303968 -30.258323)
				(end 428.323502 -30.254448)
			)
			(arc
				(start 428.708312 -30.254448)
				(mid 428.727835 -30.250547)
				(end 428.74438 -30.239462)
			)
			(arc
				(start 428.864522 -30.11932)
				(mid 428.875633 -30.102786)
				(end 428.879508 -30.083252)
			)
			(arc
				(start 428.879508 -29.534104)
				(mid 428.870971 -29.505917)
				(end 428.848266 -29.487114)
			)
			(xy 428.833788 -29.481272) (xy 428.803816 -29.487114) (xy 428.8028 -29.488384)
			(arc
				(start 428.428912 -29.488384)
				(mid 428.317879 -29.467379)
				(end 428.222156 -29.407358)
			)
			(arc
				(start 428.222156 -29.407358)
				(mid 428.206161 -29.397332)
				(end 428.187612 -29.393896)
			)
			(arc
				(start 426.448728 -29.393896)
				(mid 426.429205 -29.397797)
				(end 426.41266 -29.408882)
			)
			(xy 426.40885 -29.412692) (xy 426.40123 -29.431234)
			(arc
				(start 426.40123 -30.63367)
				(mid 426.405131 -30.653193)
				(end 426.416216 -30.669738)
			)
			(arc
				(start 426.427646 -30.681168)
				(mid 426.44418 -30.692279)
				(end 426.463714 -30.696154)
			)
		)
		(stroke
			(width 0)
			(type solid)
		)
		(fill yes)
		(layer "F.Cu")
		(net "P3V3_AUX")
	)
	(gr_poly
		(pts
			(xy 17.08912 -270.336518) (xy 17.207484 -270.218154) (xy 17.207484 -269.595854) (xy 17.207484 -255.431544)
			(xy 16.91386 -255.13792) (xy 2.513584 -255.13792) (xy 1.63068 -255.13792) (xy 1.52654 -255.24206)
			(xy 1.52654 -256.140712) (xy 1.927606 -256.541778) (xy 1.927606 -269.287752) (xy 2.333498 -269.693644)
			(arc
				(start 4.581398 -269.693644)
				(mid 4.600921 -269.689743)
				(end 4.617466 -269.678658)
			)
			(arc
				(start 4.638548 -269.657576)
				(mid 4.64961 -269.641159)
				(end 4.653534 -269.621762)
			)
			(arc
				(start 4.653534 -259.633466)
				(mid 4.657367 -259.614109)
				(end 4.668266 -259.597652)
			)
			(arc
				(start 4.670806 -259.594858)
				(mid 4.681868 -259.578441)
				(end 4.685792 -259.559044)
			)
			(arc
				(start 4.685792 -259.17017)
				(mid 4.689693 -259.150647)
				(end 4.700778 -259.134102)
			)
			(arc
				(start 4.990084 -258.844796)
				(mid 5.006618 -258.833685)
				(end 5.026152 -258.82981)
			)
			(arc
				(start 11.463274 -258.82981)
				(mid 11.482797 -258.833711)
				(end 11.499342 -258.844796)
			)
			(arc
				(start 11.99642 -259.341874)
				(mid 12.007531 -259.358408)
				(end 12.011406 -259.377942)
			)
			(xy 12.011406 -269.506954) (xy 12.01166 -269.507208) (xy 12.01166 -270.29664) (xy 12.1158 -270.40078)
			(xy 17.024858 -270.40078)
		)
		(stroke
			(width 0)
			(type solid)
		)
		(fill yes)
		(layer "F.Cu")
		(net "P1V25_SERDES_VDDPLL_PEX0")
	)
	(gr_poly
		(pts
			(arc
				(start 17.745202 -44.904406)
				(mid 17.764725 -44.900505)
				(end 17.78127 -44.88942)
			)
			(arc
				(start 17.9451 -44.72559)
				(mid 17.956211 -44.709056)
				(end 17.960086 -44.689522)
			)
			(arc
				(start 17.960086 -44.419012)
				(mid 17.963987 -44.399489)
				(end 17.975072 -44.382944)
			)
			(arc
				(start 18.138902 -44.219114)
				(mid 18.155436 -44.208003)
				(end 18.17497 -44.204128)
			)
			(arc
				(start 18.922238 -44.204128)
				(mid 18.941761 -44.200227)
				(end 18.958306 -44.189142)
			)
			(arc
				(start 19.077432 -44.070016)
				(mid 19.088543 -44.053482)
				(end 19.092418 -44.033948)
			)
			(arc
				(start 19.092418 -41.022524)
				(mid 19.088517 -41.003001)
				(end 19.077432 -40.986456)
			)
			(arc
				(start 18.928588 -40.837612)
				(mid 18.912054 -40.826501)
				(end 18.89252 -40.822626)
			)
			(xy 14.265656 -40.822626) (xy 14.265656 -40.82288)
			(arc
				(start 13.779754 -40.82288)
				(mid 13.760231 -40.826781)
				(end 13.743686 -40.837866)
			)
			(arc
				(start 13.580364 -41.001188)
				(mid 13.569253 -41.017722)
				(end 13.565378 -41.037256)
			)
			(arc
				(start 13.565378 -44.73448)
				(mid 13.569279 -44.754003)
				(end 13.580364 -44.770548)
			)
			(arc
				(start 13.699236 -44.88942)
				(mid 13.71577 -44.900531)
				(end 13.735304 -44.904406)
			)
		)
		(stroke
			(width 0)
			(type solid)
		)
		(fill yes)
		(layer "F.Cu")
		(net "P12V_SSD0")
	)
	(gr_poly
		(pts
			(arc
				(start 43.74515 -44.904406)
				(mid 43.764673 -44.900505)
				(end 43.781218 -44.88942)
			)
			(arc
				(start 43.945048 -44.72559)
				(mid 43.956159 -44.709056)
				(end 43.960034 -44.689522)
			)
			(arc
				(start 43.960034 -44.419012)
				(mid 43.963935 -44.399489)
				(end 43.97502 -44.382944)
			)
			(arc
				(start 44.13885 -44.219114)
				(mid 44.155384 -44.208003)
				(end 44.174918 -44.204128)
			)
			(arc
				(start 44.922186 -44.204128)
				(mid 44.941709 -44.200227)
				(end 44.958254 -44.189142)
			)
			(arc
				(start 45.07738 -44.070016)
				(mid 45.088491 -44.053482)
				(end 45.092366 -44.033948)
			)
			(arc
				(start 45.092366 -41.022524)
				(mid 45.088465 -41.003001)
				(end 45.07738 -40.986456)
			)
			(arc
				(start 44.928536 -40.837612)
				(mid 44.912002 -40.826501)
				(end 44.892468 -40.822626)
			)
			(xy 40.265604 -40.822626) (xy 40.265604 -40.82288)
			(arc
				(start 39.779702 -40.82288)
				(mid 39.760179 -40.826781)
				(end 39.743634 -40.837866)
			)
			(arc
				(start 39.580312 -41.001188)
				(mid 39.569201 -41.017722)
				(end 39.565326 -41.037256)
			)
			(arc
				(start 39.565326 -44.73448)
				(mid 39.569227 -44.754003)
				(end 39.580312 -44.770548)
			)
			(arc
				(start 39.699184 -44.88942)
				(mid 39.715718 -44.900531)
				(end 39.735252 -44.904406)
			)
		)
		(stroke
			(width 0)
			(type solid)
		)
		(fill yes)
		(layer "F.Cu")
		(net "P12V_SSD1")
	)
	(gr_poly
		(pts
			(xy 230.441754 -272.825718) (xy 231.054148 -272.213324) (xy 231.054148 -271.808448) (xy 231.054148 -261.271004)
			(xy 230.331264 -260.54812) (xy 230.331264 -258.56692) (xy 230.258366 -258.494022) (xy 228.91115 -258.494022)
			(xy 228.533452 -258.116324) (xy 226.682808 -258.116324) (xy 216.309702 -258.116324) (xy 215.79078 -258.635246)
			(xy 215.79078 -271.160748) (xy 216.610438 -271.980406) (xy 217.392758 -271.980406)
			(arc
				(start 219.640658 -271.980406)
				(mid 219.660181 -271.976505)
				(end 219.676726 -271.96542)
			)
			(arc
				(start 219.697808 -271.944338)
				(mid 219.70887 -271.927921)
				(end 219.712794 -271.908524)
			)
			(arc
				(start 219.712794 -261.920228)
				(mid 219.716627 -261.900871)
				(end 219.727526 -261.884414)
			)
			(arc
				(start 219.730066 -261.88162)
				(mid 219.741128 -261.865203)
				(end 219.745052 -261.845806)
			)
			(arc
				(start 219.745052 -261.456932)
				(mid 219.748953 -261.437409)
				(end 219.760038 -261.420864)
			)
			(arc
				(start 220.049344 -261.131558)
				(mid 220.065878 -261.120447)
				(end 220.085412 -261.116572)
			)
			(arc
				(start 226.522534 -261.116572)
				(mid 226.542057 -261.120473)
				(end 226.558602 -261.131558)
			)
			(arc
				(start 227.05568 -261.628636)
				(mid 227.066791 -261.64517)
				(end 227.070666 -261.664704)
			)
			(xy 227.070666 -271.959324) (xy 227.070666 -272.47723) (xy 227.547678 -272.954242) (xy 230.31323 -272.954242)
		)
		(stroke
			(width 0)
			(type solid)
		)
		(fill yes)
		(layer "F.Cu")
		(net "P1V25_SERDES_VDDPLL_PEX1")
	)
	(gr_poly
		(pts
			(arc
				(start 230.517446 -274.086574)
				(mid 230.536969 -274.082673)
				(end 230.553514 -274.071588)
			)
			(arc
				(start 230.646986 -273.978116)
				(mid 230.658097 -273.961582)
				(end 230.661972 -273.942048)
			)
			(arc
				(start 230.661972 -273.318732)
				(mid 230.658071 -273.299209)
				(end 230.646986 -273.282664)
			)
			(arc
				(start 230.560372 -273.19605)
				(mid 230.543838 -273.184939)
				(end 230.524304 -273.181064)
			)
			(arc
				(start 230.467154 -273.181064)
				(mid 230.447767 -273.185014)
				(end 230.43134 -273.19605)
			)
			(xy 230.42626 -273.200876) (xy 230.407718 -273.208496)
			(arc
				(start 227.46335 -273.208496)
				(mid 227.443993 -273.204663)
				(end 227.427536 -273.193764)
			)
			(xy 227.422456 -273.188684) (xy 227.403914 -273.181064)
			(arc
				(start 227.252784 -273.181064)
				(mid 227.233261 -273.184965)
				(end 227.216716 -273.19605)
			)
			(arc
				(start 227.143818 -273.268948)
				(mid 227.132707 -273.285482)
				(end 227.128832 -273.305016)
			)
			(arc
				(start 227.128832 -273.832066)
				(mid 227.132733 -273.851589)
				(end 227.143818 -273.868134)
			)
			(arc
				(start 227.288344 -274.01266)
				(mid 227.30479 -274.023586)
				(end 227.324158 -274.027392)
			)
			(arc
				(start 228.037136 -274.027392)
				(mid 228.056523 -274.031342)
				(end 228.07295 -274.042378)
			)
			(arc
				(start 228.102414 -274.071588)
				(mid 228.118831 -274.08265)
				(end 228.138228 -274.086574)
			)
		)
		(stroke
			(width 0)
			(type solid)
		)
		(fill yes)
		(layer "F.Cu")
		(net "GND")
	)
	(gr_poly
		(pts
			(arc
				(start 31.133542 -280.637742)
				(mid 31.153036 -280.633958)
				(end 31.16961 -280.62301)
			)
			(arc
				(start 31.233618 -280.559002)
				(mid 31.244729 -280.542468)
				(end 31.248604 -280.522934)
			)
			(arc
				(start 31.248604 -280.380186)
				(mid 31.252505 -280.360663)
				(end 31.26359 -280.344118)
			)
			(arc
				(start 31.310072 -280.297636)
				(mid 31.326606 -280.286525)
				(end 31.34614 -280.28265)
			)
			(arc
				(start 31.392876 -280.28265)
				(mid 31.412263 -280.2787)
				(end 31.42869 -280.267664)
			)
			(arc
				(start 31.476442 -280.220166)
				(mid 31.492859 -280.209104)
				(end 31.512256 -280.20518)
			)
			(arc
				(start 32.693102 -280.20518)
				(mid 32.729023 -280.190301)
				(end 32.743902 -280.15438)
			)
			(arc
				(start 32.743902 -279.79116)
				(mid 32.740001 -279.771637)
				(end 32.728916 -279.755092)
			)
			(arc
				(start 32.700722 -279.726898)
				(mid 32.684188 -279.715787)
				(end 32.664654 -279.711912)
			)
			(arc
				(start 30.512004 -279.711912)
				(mid 30.492481 -279.715813)
				(end 30.475936 -279.726898)
			)
			(arc
				(start 30.336998 -279.865836)
				(mid 30.325887 -279.88237)
				(end 30.322012 -279.901904)
			)
			(arc
				(start 30.322012 -280.535126)
				(mid 30.325913 -280.554649)
				(end 30.336998 -280.571194)
			)
			(arc
				(start 30.38856 -280.622756)
				(mid 30.405094 -280.633867)
				(end 30.424628 -280.637742)
			)
		)
		(stroke
			(width 0)
			(type solid)
		)
		(fill yes)
		(layer "F.Cu")
		(net "SYSPLL_VDDA18_PEX0_R")
	)
	(gr_poly
		(pts
			(arc
				(start 33.185862 -301.800006)
				(mid 33.205385 -301.796105)
				(end 33.22193 -301.78502)
			)
			(arc
				(start 33.336738 -301.670212)
				(mid 33.3478 -301.653795)
				(end 33.351724 -301.634398)
			)
			(xy 33.351724 -300.200314) (xy 33.393126 -300.158912) (xy 33.393126 -299.636942) (xy 33.296098 -299.539914)
			(xy 33.03905 -299.539914) (xy 32.902144 -299.67682) (xy 32.90189 -299.677074)
			(arc
				(start 32.794448 -299.784516)
				(mid 32.777914 -299.795627)
				(end 32.75838 -299.799502)
			)
			(arc
				(start 32.01797 -299.799502)
				(mid 31.998447 -299.795601)
				(end 31.981902 -299.784516)
			)
			(arc
				(start 31.951676 -299.75429)
				(mid 31.935259 -299.743228)
				(end 31.915862 -299.739304)
			)
			(xy 31.530036 -299.739304) (xy 31.511494 -299.747178) (xy 31.510986 -299.747686)
			(arc
				(start 31.510986 -300.162722)
				(mid 31.507085 -300.182245)
				(end 31.496 -300.19879)
			)
			(arc
				(start 31.4706 -300.22419)
				(mid 31.454066 -300.235301)
				(end 31.434532 -300.239176)
			)
			(arc
				(start 30.625796 -300.239176)
				(mid 30.606273 -300.243077)
				(end 30.589728 -300.254162)
			)
			(arc
				(start 30.500574 -300.343316)
				(mid 30.489463 -300.35985)
				(end 30.485588 -300.379384)
			)
			(arc
				(start 30.485588 -301.66945)
				(mid 30.489489 -301.688973)
				(end 30.500574 -301.705518)
			)
			(arc
				(start 30.58033 -301.785274)
				(mid 30.596893 -301.796248)
				(end 30.616398 -301.800006)
			)
		)
		(stroke
			(width 0)
			(type solid)
		)
		(fill yes)
		(layer "F.Cu")
		(net "PCEPLL1_VDDA18_PEX0")
	)
	(gr_poly
		(pts
			(arc
				(start 34.091626 -260.282944)
				(mid 34.11112 -260.27916)
				(end 34.127694 -260.268212)
			)
			(arc
				(start 34.191702 -260.204204)
				(mid 34.202813 -260.18767)
				(end 34.206688 -260.168136)
			)
			(arc
				(start 34.206688 -260.025388)
				(mid 34.210589 -260.005865)
				(end 34.221674 -259.98932)
			)
			(arc
				(start 34.268156 -259.942838)
				(mid 34.28469 -259.931727)
				(end 34.304224 -259.927852)
			)
			(arc
				(start 34.35096 -259.927852)
				(mid 34.370347 -259.923902)
				(end 34.386774 -259.912866)
			)
			(arc
				(start 34.434526 -259.865368)
				(mid 34.450972 -259.854442)
				(end 34.47034 -259.850636)
			)
			(arc
				(start 35.651186 -259.850636)
				(mid 35.687107 -259.835757)
				(end 35.701986 -259.799836)
			)
			(arc
				(start 35.701986 -259.436362)
				(mid 35.698085 -259.416839)
				(end 35.687 -259.400294)
			)
			(arc
				(start 35.658806 -259.3721)
				(mid 35.642272 -259.360989)
				(end 35.622738 -259.357114)
			)
			(arc
				(start 33.470088 -259.357114)
				(mid 33.450565 -259.361015)
				(end 33.43402 -259.3721)
			)
			(arc
				(start 33.295082 -259.511038)
				(mid 33.283971 -259.527572)
				(end 33.280096 -259.547106)
			)
			(arc
				(start 33.280096 -260.180328)
				(mid 33.283997 -260.199851)
				(end 33.295082 -260.216396)
			)
			(arc
				(start 33.346644 -260.267958)
				(mid 33.363178 -260.279069)
				(end 33.382712 -260.282944)
			)
		)
		(stroke
			(width 0)
			(type solid)
		)
		(fill yes)
		(layer "F.Cu")
		(net "PCEPLL3_VDDA18_PEX0_R")
	)
	(gr_poly
		(pts
			(arc
				(start 34.091626 -257.082544)
				(mid 34.11112 -257.07876)
				(end 34.127694 -257.067812)
			)
			(arc
				(start 34.191702 -257.003804)
				(mid 34.202813 -256.98727)
				(end 34.206688 -256.967736)
			)
			(arc
				(start 34.206688 -256.824988)
				(mid 34.210589 -256.805465)
				(end 34.221674 -256.78892)
			)
			(arc
				(start 34.268156 -256.742438)
				(mid 34.28469 -256.731327)
				(end 34.304224 -256.727452)
			)
			(arc
				(start 34.35096 -256.727452)
				(mid 34.370347 -256.723502)
				(end 34.386774 -256.712466)
			)
			(arc
				(start 34.434526 -256.664968)
				(mid 34.450972 -256.654042)
				(end 34.47034 -256.650236)
			)
			(arc
				(start 35.651186 -256.650236)
				(mid 35.687107 -256.635357)
				(end 35.701986 -256.599436)
			)
			(arc
				(start 35.701986 -256.235962)
				(mid 35.698085 -256.216439)
				(end 35.687 -256.199894)
			)
			(arc
				(start 35.658806 -256.1717)
				(mid 35.642272 -256.160589)
				(end 35.622738 -256.156714)
			)
			(arc
				(start 33.470088 -256.156714)
				(mid 33.450565 -256.160615)
				(end 33.43402 -256.1717)
			)
			(arc
				(start 33.295082 -256.310638)
				(mid 33.283971 -256.327172)
				(end 33.280096 -256.346706)
			)
			(arc
				(start 33.280096 -256.979928)
				(mid 33.283997 -256.999451)
				(end 33.295082 -257.015996)
			)
			(arc
				(start 33.346644 -257.067558)
				(mid 33.363178 -257.078669)
				(end 33.382712 -257.082544)
			)
		)
		(stroke
			(width 0)
			(type solid)
		)
		(fill yes)
		(layer "F.Cu")
		(net "PCEPLL5_VDDA18_PEX0_R")
	)
	(gr_poly
		(pts
			(xy 118.618 -256.6416) (xy 118.618 -256.544064) (xy 118.5926 -256.518664) (xy 118.22303 -256.518664)
			(xy 117.876066 -256.1717) (xy 117.86489 -256.160524) (xy 117.86489 -255.703324) (xy 117.86489 -254.982726)
			(xy 117.245384 -254.36322) (xy 116.984018 -254.36322) (xy 116.93144 -254.310642) (xy 116.93144 -254.174498)
			(xy 117.226842 -253.879096) (xy 117.402356 -253.879096)
			(arc
				(start 117.875812 -254.352298)
				(mid 117.958189 -254.407404)
				(end 118.05539 -254.42672)
			)
			(arc
				(start 118.05539 -254.42672)
				(mid 118.234995 -254.352325)
				(end 118.30939 -254.17272)
			)
			(arc
				(start 118.30939 -254.17272)
				(mid 118.29004 -254.075533)
				(end 118.234968 -253.993142)
			)
			(xy 117.682518 -253.440692) (xy 117.682518 -252.7554) (xy 117.391688 -252.46457) (xy 116.24691 -252.46457)
			(xy 116.13388 -252.5776) (xy 116.13388 -253.878588) (xy 116.194332 -253.878588) (xy 116.42344 -254.107696)
			(xy 116.42344 -254.55372) (xy 116.421408 -254.555752) (xy 116.421408 -254.794766) (xy 116.43106 -254.804418)
			(xy 116.569744 -254.804418) (xy 117.147594 -254.804418) (xy 117.48389 -255.140714) (xy 117.48389 -255.725168)
			(xy 117.48389 -255.994916) (xy 118.140988 -256.652014) (xy 118.607586 -256.652014)
		)
		(stroke
			(width 0)
			(type solid)
		)
		(fill yes)
		(layer "F.Cu")
		(net "P0V8_PEX0_VREF")
	)
	(gr_poly
		(pts
			(arc
				(start 147.23364 -280.637742)
				(mid 147.253134 -280.633958)
				(end 147.269708 -280.62301)
			)
			(arc
				(start 147.333716 -280.559002)
				(mid 147.344827 -280.542468)
				(end 147.348702 -280.522934)
			)
			(arc
				(start 147.348702 -280.380186)
				(mid 147.352603 -280.360663)
				(end 147.363688 -280.344118)
			)
			(arc
				(start 147.41017 -280.297636)
				(mid 147.426704 -280.286525)
				(end 147.446238 -280.28265)
			)
			(arc
				(start 147.492974 -280.28265)
				(mid 147.512361 -280.2787)
				(end 147.528788 -280.267664)
			)
			(arc
				(start 147.57654 -280.220166)
				(mid 147.592957 -280.209104)
				(end 147.612354 -280.20518)
			)
			(arc
				(start 148.7932 -280.20518)
				(mid 148.829121 -280.190301)
				(end 148.844 -280.15438)
			)
			(arc
				(start 148.844 -279.79116)
				(mid 148.840099 -279.771637)
				(end 148.829014 -279.755092)
			)
			(arc
				(start 148.80082 -279.726898)
				(mid 148.784286 -279.715787)
				(end 148.764752 -279.711912)
			)
			(arc
				(start 146.612102 -279.711912)
				(mid 146.592579 -279.715813)
				(end 146.576034 -279.726898)
			)
			(arc
				(start 146.437096 -279.865836)
				(mid 146.425985 -279.88237)
				(end 146.42211 -279.901904)
			)
			(arc
				(start 146.42211 -280.535126)
				(mid 146.426011 -280.554649)
				(end 146.437096 -280.571194)
			)
			(arc
				(start 146.488658 -280.622756)
				(mid 146.505192 -280.633867)
				(end 146.524726 -280.637742)
			)
		)
		(stroke
			(width 0)
			(type solid)
		)
		(fill yes)
		(layer "F.Cu")
		(net "SYSPLL_VDDA18_PEX1_R")
	)
	(gr_poly
		(pts
			(arc
				(start 150.191724 -260.282944)
				(mid 150.211218 -260.27916)
				(end 150.227792 -260.268212)
			)
			(arc
				(start 150.2918 -260.204204)
				(mid 150.302911 -260.18767)
				(end 150.306786 -260.168136)
			)
			(arc
				(start 150.306786 -260.025388)
				(mid 150.310687 -260.005865)
				(end 150.321772 -259.98932)
			)
			(arc
				(start 150.368254 -259.942838)
				(mid 150.384788 -259.931727)
				(end 150.404322 -259.927852)
			)
			(arc
				(start 150.451058 -259.927852)
				(mid 150.470445 -259.923902)
				(end 150.486872 -259.912866)
			)
			(arc
				(start 150.534624 -259.865368)
				(mid 150.55107 -259.854442)
				(end 150.570438 -259.850636)
			)
			(arc
				(start 151.751284 -259.850636)
				(mid 151.787205 -259.835757)
				(end 151.802084 -259.799836)
			)
			(arc
				(start 151.802084 -259.436362)
				(mid 151.798183 -259.416839)
				(end 151.787098 -259.400294)
			)
			(arc
				(start 151.758904 -259.3721)
				(mid 151.74237 -259.360989)
				(end 151.722836 -259.357114)
			)
			(arc
				(start 149.570186 -259.357114)
				(mid 149.550663 -259.361015)
				(end 149.534118 -259.3721)
			)
			(arc
				(start 149.39518 -259.511038)
				(mid 149.384069 -259.527572)
				(end 149.380194 -259.547106)
			)
			(arc
				(start 149.380194 -260.180328)
				(mid 149.384095 -260.199851)
				(end 149.39518 -260.216396)
			)
			(arc
				(start 149.446742 -260.267958)
				(mid 149.463276 -260.279069)
				(end 149.48281 -260.282944)
			)
		)
		(stroke
			(width 0)
			(type solid)
		)
		(fill yes)
		(layer "F.Cu")
		(net "PCEPLL3_VDDA18_PEX1_R")
	)
	(gr_poly
		(pts
			(arc
				(start 150.191724 -257.082544)
				(mid 150.211218 -257.07876)
				(end 150.227792 -257.067812)
			)
			(arc
				(start 150.2918 -257.003804)
				(mid 150.302911 -256.98727)
				(end 150.306786 -256.967736)
			)
			(arc
				(start 150.306786 -256.824988)
				(mid 150.310687 -256.805465)
				(end 150.321772 -256.78892)
			)
			(arc
				(start 150.368254 -256.742438)
				(mid 150.384788 -256.731327)
				(end 150.404322 -256.727452)
			)
			(arc
				(start 150.451058 -256.727452)
				(mid 150.470445 -256.723502)
				(end 150.486872 -256.712466)
			)
			(arc
				(start 150.534624 -256.664968)
				(mid 150.55107 -256.654042)
				(end 150.570438 -256.650236)
			)
			(arc
				(start 151.751284 -256.650236)
				(mid 151.787205 -256.635357)
				(end 151.802084 -256.599436)
			)
			(arc
				(start 151.802084 -256.235962)
				(mid 151.798183 -256.216439)
				(end 151.787098 -256.199894)
			)
			(arc
				(start 151.758904 -256.1717)
				(mid 151.74237 -256.160589)
				(end 151.722836 -256.156714)
			)
			(arc
				(start 149.570186 -256.156714)
				(mid 149.550663 -256.160615)
				(end 149.534118 -256.1717)
			)
			(arc
				(start 149.39518 -256.310638)
				(mid 149.384069 -256.327172)
				(end 149.380194 -256.346706)
			)
			(arc
				(start 149.380194 -256.979928)
				(mid 149.384095 -256.999451)
				(end 149.39518 -257.015996)
			)
			(arc
				(start 149.446742 -257.067558)
				(mid 149.463276 -257.078669)
				(end 149.48281 -257.082544)
			)
		)
		(stroke
			(width 0)
			(type solid)
		)
		(fill yes)
		(layer "F.Cu")
		(net "PCEPLL5_VDDA18_PEX1_R")
	)
	(gr_poly
		(pts
			(arc
				(start 263.333484 -280.637742)
				(mid 263.352978 -280.633958)
				(end 263.369552 -280.62301)
			)
			(arc
				(start 263.43356 -280.559002)
				(mid 263.444671 -280.542468)
				(end 263.448546 -280.522934)
			)
			(arc
				(start 263.448546 -280.380186)
				(mid 263.452447 -280.360663)
				(end 263.463532 -280.344118)
			)
			(arc
				(start 263.510014 -280.297636)
				(mid 263.526548 -280.286525)
				(end 263.546082 -280.28265)
			)
			(arc
				(start 263.592818 -280.28265)
				(mid 263.612205 -280.2787)
				(end 263.628632 -280.267664)
			)
			(arc
				(start 263.676384 -280.220166)
				(mid 263.692801 -280.209104)
				(end 263.712198 -280.20518)
			)
			(arc
				(start 264.893044 -280.20518)
				(mid 264.928965 -280.190301)
				(end 264.943844 -280.15438)
			)
			(arc
				(start 264.943844 -279.79116)
				(mid 264.939943 -279.771637)
				(end 264.928858 -279.755092)
			)
			(arc
				(start 264.900664 -279.726898)
				(mid 264.88413 -279.715787)
				(end 264.864596 -279.711912)
			)
			(arc
				(start 262.711946 -279.711912)
				(mid 262.692423 -279.715813)
				(end 262.675878 -279.726898)
			)
			(arc
				(start 262.53694 -279.865836)
				(mid 262.525829 -279.88237)
				(end 262.521954 -279.901904)
			)
			(arc
				(start 262.521954 -280.535126)
				(mid 262.525855 -280.554649)
				(end 262.53694 -280.571194)
			)
			(arc
				(start 262.588502 -280.622756)
				(mid 262.605036 -280.633867)
				(end 262.62457 -280.637742)
			)
		)
		(stroke
			(width 0)
			(type solid)
		)
		(fill yes)
		(layer "F.Cu")
		(net "SYSPLL_VDDA18_PEX2_R")
	)
	(gr_poly
		(pts
			(arc
				(start 266.291568 -260.282944)
				(mid 266.311062 -260.27916)
				(end 266.327636 -260.268212)
			)
			(arc
				(start 266.391644 -260.204204)
				(mid 266.402755 -260.18767)
				(end 266.40663 -260.168136)
			)
			(arc
				(start 266.40663 -260.025388)
				(mid 266.410531 -260.005865)
				(end 266.421616 -259.98932)
			)
			(arc
				(start 266.468098 -259.942838)
				(mid 266.484632 -259.931727)
				(end 266.504166 -259.927852)
			)
			(arc
				(start 266.550902 -259.927852)
				(mid 266.570289 -259.923902)
				(end 266.586716 -259.912866)
			)
			(arc
				(start 266.634468 -259.865368)
				(mid 266.650914 -259.854442)
				(end 266.670282 -259.850636)
			)
			(arc
				(start 267.851128 -259.850636)
				(mid 267.887049 -259.835757)
				(end 267.901928 -259.799836)
			)
			(arc
				(start 267.901928 -259.436362)
				(mid 267.898027 -259.416839)
				(end 267.886942 -259.400294)
			)
			(arc
				(start 267.858748 -259.3721)
				(mid 267.842214 -259.360989)
				(end 267.82268 -259.357114)
			)
			(arc
				(start 265.67003 -259.357114)
				(mid 265.650507 -259.361015)
				(end 265.633962 -259.3721)
			)
			(arc
				(start 265.495024 -259.511038)
				(mid 265.483913 -259.527572)
				(end 265.480038 -259.547106)
			)
			(arc
				(start 265.480038 -260.180328)
				(mid 265.483939 -260.199851)
				(end 265.495024 -260.216396)
			)
			(arc
				(start 265.546586 -260.267958)
				(mid 265.56312 -260.279069)
				(end 265.582654 -260.282944)
			)
		)
		(stroke
			(width 0)
			(type solid)
		)
		(fill yes)
		(layer "F.Cu")
		(net "PCEPLL3_VDDA18_PEX2_R")
	)
	(gr_poly
		(pts
			(arc
				(start 266.291568 -257.082544)
				(mid 266.311062 -257.07876)
				(end 266.327636 -257.067812)
			)
			(arc
				(start 266.391644 -257.003804)
				(mid 266.402755 -256.98727)
				(end 266.40663 -256.967736)
			)
			(arc
				(start 266.40663 -256.824988)
				(mid 266.410531 -256.805465)
				(end 266.421616 -256.78892)
			)
			(arc
				(start 266.468098 -256.742438)
				(mid 266.484632 -256.731327)
				(end 266.504166 -256.727452)
			)
			(arc
				(start 266.550902 -256.727452)
				(mid 266.570289 -256.723502)
				(end 266.586716 -256.712466)
			)
			(arc
				(start 266.634468 -256.664968)
				(mid 266.650914 -256.654042)
				(end 266.670282 -256.650236)
			)
			(arc
				(start 267.851128 -256.650236)
				(mid 267.887049 -256.635357)
				(end 267.901928 -256.599436)
			)
			(arc
				(start 267.901928 -256.235962)
				(mid 267.898027 -256.216439)
				(end 267.886942 -256.199894)
			)
			(arc
				(start 267.858748 -256.1717)
				(mid 267.842214 -256.160589)
				(end 267.82268 -256.156714)
			)
			(arc
				(start 265.67003 -256.156714)
				(mid 265.650507 -256.160615)
				(end 265.633962 -256.1717)
			)
			(arc
				(start 265.495024 -256.310638)
				(mid 265.483913 -256.327172)
				(end 265.480038 -256.346706)
			)
			(arc
				(start 265.480038 -256.979928)
				(mid 265.483939 -256.999451)
				(end 265.495024 -257.015996)
			)
			(arc
				(start 265.546586 -257.067558)
				(mid 265.56312 -257.078669)
				(end 265.582654 -257.082544)
			)
		)
		(stroke
			(width 0)
			(type solid)
		)
		(fill yes)
		(layer "F.Cu")
		(net "PCEPLL5_VDDA18_PEX2_R")
	)
	(gr_poly
		(pts
			(arc
				(start 374.31726 -263.504172)
				(mid 374.336783 -263.500271)
				(end 374.353328 -263.489186)
			)
			(arc
				(start 374.613424 -263.22909)
				(mid 374.624535 -263.212556)
				(end 374.62841 -263.193022)
			)
			(arc
				(start 374.62841 -262.913368)
				(mid 374.613531 -262.877447)
				(end 374.57761 -262.862568)
			)
			(arc
				(start 373.952516 -262.862568)
				(mid 373.933159 -262.858735)
				(end 373.916702 -262.847836)
			)
			(arc
				(start 373.657876 -262.58901)
				(mid 373.64695 -262.572564)
				(end 373.643144 -262.553196)
			)
			(arc
				(start 373.643144 -262.543544)
				(mid 373.639194 -262.524157)
				(end 373.628158 -262.50773)
			)
			(arc
				(start 373.315738 -262.19531)
				(mid 373.304627 -262.178776)
				(end 373.300752 -262.159242)
			)
			(arc
				(start 373.300752 -260.711188)
				(mid 373.296851 -260.691665)
				(end 373.285766 -260.67512)
			)
			(arc
				(start 373.248936 -260.63829)
				(mid 373.232402 -260.627179)
				(end 373.212868 -260.623304)
			)
			(arc
				(start 371.983508 -260.623304)
				(mid 371.963985 -260.627205)
				(end 371.94744 -260.63829)
			)
			(arc
				(start 371.940328 -260.645402)
				(mid 371.929217 -260.661936)
				(end 371.925342 -260.68147)
			)
			(arc
				(start 371.925342 -262.427212)
				(mid 371.929243 -262.446735)
				(end 371.940328 -262.46328)
			)
			(arc
				(start 372.966234 -263.489186)
				(mid 372.982768 -263.500297)
				(end 373.002302 -263.504172)
			)
		)
		(stroke
			(width 0)
			(type solid)
		)
		(fill yes)
		(layer "F.Cu")
		(net "GND")
	)
	(gr_poly
		(pts
			(arc
				(start 379.433582 -280.637742)
				(mid 379.453076 -280.633958)
				(end 379.46965 -280.62301)
			)
			(arc
				(start 379.533658 -280.559002)
				(mid 379.544769 -280.542468)
				(end 379.548644 -280.522934)
			)
			(arc
				(start 379.548644 -280.380186)
				(mid 379.552545 -280.360663)
				(end 379.56363 -280.344118)
			)
			(arc
				(start 379.610112 -280.297636)
				(mid 379.626646 -280.286525)
				(end 379.64618 -280.28265)
			)
			(arc
				(start 379.692916 -280.28265)
				(mid 379.712303 -280.2787)
				(end 379.72873 -280.267664)
			)
			(arc
				(start 379.776482 -280.220166)
				(mid 379.792899 -280.209104)
				(end 379.812296 -280.20518)
			)
			(arc
				(start 380.993142 -280.20518)
				(mid 381.029063 -280.190301)
				(end 381.043942 -280.15438)
			)
			(arc
				(start 381.043942 -279.79116)
				(mid 381.040041 -279.771637)
				(end 381.028956 -279.755092)
			)
			(arc
				(start 381.000762 -279.726898)
				(mid 380.984228 -279.715787)
				(end 380.964694 -279.711912)
			)
			(arc
				(start 378.812044 -279.711912)
				(mid 378.792521 -279.715813)
				(end 378.775976 -279.726898)
			)
			(arc
				(start 378.637038 -279.865836)
				(mid 378.625927 -279.88237)
				(end 378.622052 -279.901904)
			)
			(arc
				(start 378.622052 -280.535126)
				(mid 378.625953 -280.554649)
				(end 378.637038 -280.571194)
			)
			(arc
				(start 378.6886 -280.622756)
				(mid 378.705134 -280.633867)
				(end 378.724668 -280.637742)
			)
		)
		(stroke
			(width 0)
			(type solid)
		)
		(fill yes)
		(layer "F.Cu")
		(net "SYSPLL_VDDA18_PEX3_R")
	)
	(gr_poly
		(pts
			(arc
				(start 382.391666 -260.282944)
				(mid 382.41116 -260.27916)
				(end 382.427734 -260.268212)
			)
			(arc
				(start 382.491742 -260.204204)
				(mid 382.502853 -260.18767)
				(end 382.506728 -260.168136)
			)
			(arc
				(start 382.506728 -260.025388)
				(mid 382.510629 -260.005865)
				(end 382.521714 -259.98932)
			)
			(arc
				(start 382.568196 -259.942838)
				(mid 382.58473 -259.931727)
				(end 382.604264 -259.927852)
			)
			(arc
				(start 382.651 -259.927852)
				(mid 382.670387 -259.923902)
				(end 382.686814 -259.912866)
			)
			(arc
				(start 382.734566 -259.865368)
				(mid 382.751012 -259.854442)
				(end 382.77038 -259.850636)
			)
			(arc
				(start 383.951226 -259.850636)
				(mid 383.987147 -259.835757)
				(end 384.002026 -259.799836)
			)
			(arc
				(start 384.002026 -259.436362)
				(mid 383.998125 -259.416839)
				(end 383.98704 -259.400294)
			)
			(arc
				(start 383.958846 -259.3721)
				(mid 383.942312 -259.360989)
				(end 383.922778 -259.357114)
			)
			(arc
				(start 381.770128 -259.357114)
				(mid 381.750605 -259.361015)
				(end 381.73406 -259.3721)
			)
			(arc
				(start 381.595122 -259.511038)
				(mid 381.584011 -259.527572)
				(end 381.580136 -259.547106)
			)
			(arc
				(start 381.580136 -260.180328)
				(mid 381.584037 -260.199851)
				(end 381.595122 -260.216396)
			)
			(arc
				(start 381.646684 -260.267958)
				(mid 381.663218 -260.279069)
				(end 381.682752 -260.282944)
			)
		)
		(stroke
			(width 0)
			(type solid)
		)
		(fill yes)
		(layer "F.Cu")
		(net "PCEPLL3_VDDA18_PEX3_R")
	)
	(gr_poly
		(pts
			(arc
				(start 382.391666 -257.082544)
				(mid 382.41116 -257.07876)
				(end 382.427734 -257.067812)
			)
			(arc
				(start 382.491742 -257.003804)
				(mid 382.502853 -256.98727)
				(end 382.506728 -256.967736)
			)
			(arc
				(start 382.506728 -256.824988)
				(mid 382.510629 -256.805465)
				(end 382.521714 -256.78892)
			)
			(arc
				(start 382.568196 -256.742438)
				(mid 382.58473 -256.731327)
				(end 382.604264 -256.727452)
			)
			(arc
				(start 382.651 -256.727452)
				(mid 382.670387 -256.723502)
				(end 382.686814 -256.712466)
			)
			(arc
				(start 382.734566 -256.664968)
				(mid 382.751012 -256.654042)
				(end 382.77038 -256.650236)
			)
			(arc
				(start 383.951226 -256.650236)
				(mid 383.987147 -256.635357)
				(end 384.002026 -256.599436)
			)
			(arc
				(start 384.002026 -256.235962)
				(mid 383.998125 -256.216439)
				(end 383.98704 -256.199894)
			)
			(arc
				(start 383.958846 -256.1717)
				(mid 383.942312 -256.160589)
				(end 383.922778 -256.156714)
			)
			(arc
				(start 381.770128 -256.156714)
				(mid 381.750605 -256.160615)
				(end 381.73406 -256.1717)
			)
			(arc
				(start 381.595122 -256.310638)
				(mid 381.584011 -256.327172)
				(end 381.580136 -256.346706)
			)
			(arc
				(start 381.580136 -256.979928)
				(mid 381.584037 -256.999451)
				(end 381.595122 -257.015996)
			)
			(arc
				(start 381.646684 -257.067558)
				(mid 381.663218 -257.078669)
				(end 381.682752 -257.082544)
			)
		)
		(stroke
			(width 0)
			(type solid)
		)
		(fill yes)
		(layer "F.Cu")
		(net "PCEPLL5_VDDA18_PEX3_R")
	)
	(gr_poly
		(pts
			(arc
				(start 385.664202 -262.227314)
				(mid 385.683725 -262.223413)
				(end 385.70027 -262.212328)
			)
			(arc
				(start 385.793234 -262.119364)
				(mid 385.804345 -262.10283)
				(end 385.80822 -262.083296)
			)
			(arc
				(start 385.80822 -256.970276)
				(mid 385.804319 -256.950753)
				(end 385.793234 -256.934208)
			)
			(arc
				(start 385.70027 -256.841244)
				(mid 385.683736 -256.830133)
				(end 385.664202 -256.826258)
			)
			(arc
				(start 384.952494 -256.826258)
				(mid 384.932971 -256.830159)
				(end 384.916426 -256.841244)
			)
			(xy 384.842512 -256.915158) (xy 384.837178 -256.946654)
			(arc
				(start 384.844036 -256.961132)
				(mid 384.865973 -257.024653)
				(end 384.8735 -257.091434)
			)
			(arc
				(start 384.8735 -258.867656)
				(mid 384.856631 -258.96723)
				(end 384.808222 -259.05587)
			)
			(arc
				(start 384.808222 -259.05587)
				(mid 384.800096 -259.070695)
				(end 384.7973 -259.087366)
			)
			(arc
				(start 384.7973 -260.072124)
				(mid 384.800111 -260.088789)
				(end 384.808222 -260.10362)
			)
			(arc
				(start 384.808222 -260.10362)
				(mid 384.856657 -260.192251)
				(end 384.8735 -260.291834)
			)
			(arc
				(start 384.8735 -262.068056)
				(mid 384.871335 -262.10335)
				(end 384.865118 -262.13816)
			)
			(xy 384.86207 -262.151114) (xy 384.869182 -262.17626)
			(arc
				(start 384.90525 -262.212328)
				(mid 384.921784 -262.223439)
				(end 384.941318 -262.227314)
			)
		)
		(stroke
			(width 0)
			(type solid)
		)
		(fill yes)
		(layer "F.Cu")
		(net "GND")
	)
	(gr_poly
		(pts
			(xy 461.615536 -271.911826) (xy 461.615536 -258.6101) (xy 461.437228 -258.431792) (xy 460.739744 -258.431792)
			(xy 446.487296 -258.431792) (xy 445.7827 -258.431792) (xy 445.645286 -258.569206) (xy 445.645286 -267.592048)
			(xy 446.411858 -268.35862) (xy 446.411858 -271.284192) (xy 447.231516 -272.10385) (xy 448.013836 -272.10385)
			(arc
				(start 450.261736 -272.10385)
				(mid 450.281259 -272.099949)
				(end 450.297804 -272.088864)
			)
			(arc
				(start 450.318886 -272.067782)
				(mid 450.329948 -272.051365)
				(end 450.333872 -272.031968)
			)
			(arc
				(start 450.333872 -262.043672)
				(mid 450.337705 -262.024315)
				(end 450.348604 -262.007858)
			)
			(arc
				(start 450.351144 -262.005064)
				(mid 450.362206 -261.988647)
				(end 450.36613 -261.96925)
			)
			(arc
				(start 450.36613 -261.580376)
				(mid 450.370031 -261.560853)
				(end 450.381116 -261.544308)
			)
			(arc
				(start 450.670422 -261.255002)
				(mid 450.686956 -261.243891)
				(end 450.70649 -261.240016)
			)
			(arc
				(start 457.143612 -261.240016)
				(mid 457.163135 -261.243917)
				(end 457.17968 -261.255002)
			)
			(arc
				(start 457.676758 -261.75208)
				(mid 457.687869 -261.768614)
				(end 457.691744 -261.788148)
			)
			(arc
				(start 457.691744 -272.082768)
				(mid 457.695645 -272.102291)
				(end 457.70673 -272.118836)
			)
			(arc
				(start 457.732384 -272.14449)
				(mid 457.748918 -272.155601)
				(end 457.768452 -272.159476)
			)
			(xy 460.653638 -272.159476) (xy 460.659988 -272.165826) (xy 461.361536 -272.165826)
		)
		(stroke
			(width 0)
			(type solid)
		)
		(fill yes)
		(layer "F.Cu")
		(net "P1V25_SERDES_VDDPLL_PEX3")
	)
	(gr_poly
		(pts
			(xy 246.973852 -156.178758) (xy 246.973852 -154.263852) (xy 246.761 -154.051) (xy 246.761 -150.876)
			(xy 246.973852 -150.663148) (xy 246.973852 -145.575782) (xy 247.862598 -144.687036) (xy 249.462798 -144.687036)
			(xy 249.671586 -144.895824) (xy 250.181872 -145.406364) (xy 250.181872 -146.616674) (xy 250.321064 -146.755866)
			(xy 250.655328 -146.755866) (xy 250.908058 -147.008596) (xy 250.908058 -147.499832) (xy 251.006356 -147.59813)
			(xy 251.006356 -148.203666) (xy 251.022866 -148.220176) (xy 251.227336 -148.220176) (xy 251.236734 -148.210778)
			(xy 251.236734 -147.310856) (xy 251.338588 -147.209002) (xy 251.338588 -147.197572) (xy 251.66701 -146.86915)
			(xy 251.66701 -144.967198) (xy 251.10821 -144.408398) (xy 251.10821 -141.441424) (xy 251.115576 -141.434058)
			(xy 251.115576 -140.053314) (xy 251.563886 -139.605004) (xy 252.408944 -139.605004) (xy 252.663706 -139.350242)
			(xy 252.663706 -136.331198) (xy 252.473714 -136.141206) (xy 245.652036 -136.141206) (xy 245.142004 -135.631174)
			(xy 244.724936 -135.631174) (xy 244.625368 -135.730742) (xy 244.625368 -137.86993) (xy 244.6782 -137.922762)
			(xy 245.009416 -137.922762) (xy 245.022624 -137.909554) (xy 245.122192 -137.909554) (xy 245.340632 -137.909554)
			(xy 245.406926 -137.975848) (xy 245.406926 -138.194288) (xy 245.406926 -139.267692) (xy 245.405402 -139.267692)
			(xy 245.18493 -139.488164) (xy 243.37518 -139.488164) (xy 243.059712 -139.803632) (xy 243.059712 -140.814806)
			(xy 243.05514 -140.819378) (xy 243.05514 -156.299154) (xy 243.06911 -156.313124) (xy 246.839486 -156.313124)
		)
		(stroke
			(width 0)
			(type solid)
		)
		(fill yes)
		(layer "F.Cu")
		(net "P12V_NIC4_R")
	)
	(gr_poly
		(pts
			(xy 258.675632 -262.510524) (xy 258.675632 -262.217916) (xy 258.894072 -261.999476) (xy 259.832094 -261.999476)
			(xy 259.895086 -261.936484) (xy 259.895086 -261.16153)
			(arc
				(start 259.800344 -261.066788)
				(mid 259.789233 -261.050254)
				(end 259.785358 -261.03072)
			)
			(arc
				(start 259.785358 -260.644386)
				(mid 259.781457 -260.624863)
				(end 259.770372 -260.608318)
			)
			(arc
				(start 259.388356 -260.226302)
				(mid 259.377245 -260.209768)
				(end 259.37337 -260.190234)
			)
			(arc
				(start 259.37337 -259.921502)
				(mid 259.369469 -259.901979)
				(end 259.358384 -259.885434)
			)
			(xy 259.35813 -259.88518)
			(arc
				(start 259.35813 -259.055362)
				(mid 259.354229 -259.035839)
				(end 259.343144 -259.019294)
			)
			(arc
				(start 259.25399 -258.93014)
				(mid 259.237456 -258.919029)
				(end 259.217922 -258.915154)
			)
			(arc
				(start 257.927856 -258.915154)
				(mid 257.908333 -258.919055)
				(end 257.891788 -258.93014)
			)
			(arc
				(start 257.812032 -259.009896)
				(mid 257.801058 -259.026459)
				(end 257.7973 -259.045964)
			)
			(xy 257.7973 -261.618222) (xy 257.598926 -261.816596) (xy 256.992628 -261.816596) (xy 256.93624 -261.872984)
			(xy 256.93624 -262.451596) (xy 256.977642 -262.492998) (xy 257.154426 -262.492998) (xy 257.156712 -262.490712)
			(xy 257.389122 -262.490712) (xy 257.474466 -262.405368) (xy 258.073906 -262.405368) (xy 258.173982 -262.505444)
			(arc
				(start 258.362196 -262.505444)
				(mid 258.429951 -262.511125)
				(end 258.4958 -262.52805)
			)
			(xy 258.658106 -262.52805)
		)
		(stroke
			(width 0)
			(type solid)
		)
		(fill yes)
		(layer "F.Cu")
		(net "P1V8_VDDA_PEX2")
	)
	(gr_poly
		(pts
			(arc
				(start 275.37791 -22.717252)
				(mid 275.397297 -22.713302)
				(end 275.413724 -22.702266)
			)
			(xy 275.438616 -22.702266) (xy 275.445728 -22.709632) (xy 275.46427 -22.717252)
			(arc
				(start 279.03678 -22.717252)
				(mid 279.056303 -22.713351)
				(end 279.072848 -22.702266)
			)
			(xy 279.073356 -22.701504)
			(arc
				(start 279.073356 -18.805906)
				(mid 279.077306 -18.786519)
				(end 279.088342 -18.770092)
			)
			(arc
				(start 279.10028 -18.758154)
				(mid 279.115115 -18.722251)
				(end 279.10028 -18.686272)
			)
			(arc
				(start 279.052782 -18.638774)
				(mid 279.036248 -18.627663)
				(end 279.016714 -18.623788)
			)
			(xy 278.047704 -18.623788) (xy 278.046942 -18.623026) (xy 272.85823 -18.623026) (xy 272.843498 -18.637758)
			(xy 272.843244 -18.638012) (xy 272.825972 -18.655284) (xy 272.825718 -18.655538) (xy 272.810986 -18.67027)
			(xy 272.810986 -21.936202) (xy 272.825718 -21.950934) (xy 272.825972 -21.951188) (xy 272.843244 -21.96846)
			(xy 272.843498 -21.968714) (xy 272.85823 -21.983446)
			(arc
				(start 274.228306 -21.983446)
				(mid 274.247829 -21.987347)
				(end 274.264374 -21.998432)
			)
			(arc
				(start 274.475956 -22.210014)
				(mid 274.487067 -22.226548)
				(end 274.490942 -22.246082)
			)
			(arc
				(start 274.490942 -22.584918)
				(mid 274.494843 -22.604441)
				(end 274.505928 -22.620986)
			)
			(arc
				(start 274.587208 -22.702266)
				(mid 274.603742 -22.713377)
				(end 274.623276 -22.717252)
			)
		)
		(stroke
			(width 0)
			(type solid)
		)
		(fill yes)
		(layer "F.Cu")
		(net "P12V_SSD9")
	)
	(gr_poly
		(pts
			(xy 363.07395 -156.178758) (xy 363.07395 -154.28595) (xy 362.839 -154.051) (xy 362.839 -150.876)
			(xy 363.07395 -150.64105) (xy 363.07395 -145.575782) (xy 363.962696 -144.687036) (xy 365.562896 -144.687036)
			(xy 365.771684 -144.895824) (xy 366.28197 -145.406364) (xy 366.28197 -146.616674) (xy 366.421162 -146.755866)
			(xy 366.755426 -146.755866) (xy 367.008156 -147.008596) (xy 367.008156 -147.499832) (xy 367.106454 -147.59813)
			(xy 367.106454 -148.203666) (xy 367.122964 -148.220176) (xy 367.327434 -148.220176) (xy 367.336832 -148.210778)
			(xy 367.336832 -147.310856) (xy 367.438686 -147.209002) (xy 367.438686 -147.197572) (xy 367.767108 -146.86915)
			(xy 367.767108 -144.967198) (xy 367.208308 -144.408398) (xy 367.208308 -141.441424) (xy 367.215674 -141.434058)
			(xy 367.215674 -140.053314) (xy 367.663984 -139.605004) (xy 368.509042 -139.605004) (xy 368.763804 -139.350242)
			(xy 368.763804 -136.331198) (xy 368.573812 -136.141206) (xy 361.752134 -136.141206) (xy 361.242102 -135.631174)
			(xy 360.825034 -135.631174) (xy 360.725466 -135.730742) (xy 360.725466 -137.86993) (xy 360.778298 -137.922762)
			(xy 361.109514 -137.922762) (xy 361.122722 -137.909554) (xy 361.22229 -137.909554) (xy 361.426252 -137.909554)
			(xy 361.507024 -137.990326) (xy 361.507024 -138.194288) (xy 361.507024 -139.267692) (xy 361.5055 -139.267692)
			(xy 361.285028 -139.488164) (xy 359.475278 -139.488164) (xy 359.15981 -139.803632) (xy 359.15981 -140.814806)
			(xy 359.155238 -140.819378) (xy 359.155238 -156.299154) (xy 359.169208 -156.313124) (xy 362.939584 -156.313124)
		)
		(stroke
			(width 0)
			(type solid)
		)
		(fill yes)
		(layer "F.Cu")
		(net "P12V_NIC6_R")
	)
	(gr_poly
		(pts
			(xy 14.77391 -156.178758) (xy 14.77391 -154.21991) (xy 14.478 -153.924) (xy 14.478 -150.876) (xy 14.77391 -150.58009)
			(xy 14.77391 -145.575782) (xy 15.662656 -144.687036) (xy 17.262856 -144.687036) (xy 17.471644 -144.895824)
			(xy 17.98193 -145.406364) (xy 17.98193 -146.616674) (xy 18.121122 -146.755866) (xy 18.455386 -146.755866)
			(xy 18.708116 -147.008596) (xy 18.708116 -147.499832) (xy 18.806414 -147.59813) (xy 18.806414 -148.203666)
			(xy 18.822924 -148.220176) (xy 19.027394 -148.220176) (xy 19.036792 -148.210778) (xy 19.036792 -147.310856)
			(xy 19.138646 -147.209002) (xy 19.138646 -147.197572) (xy 19.467068 -146.86915) (xy 19.467068 -144.967198)
			(xy 18.908268 -144.408398) (xy 18.908268 -141.441424) (xy 18.915634 -141.434058) (xy 18.915634 -140.053314)
			(xy 19.363944 -139.605004) (xy 20.209002 -139.605004) (xy 20.463764 -139.350242) (xy 20.463764 -136.331198)
			(xy 20.273772 -136.141206) (xy 13.452094 -136.141206) (xy 12.942062 -135.631174) (xy 12.524994 -135.631174)
			(xy 12.425426 -135.730742) (xy 12.425426 -137.86993) (xy 12.478258 -137.922762) (xy 12.809474 -137.922762)
			(xy 12.822682 -137.909554) (xy 12.92225 -137.909554) (xy 13.083032 -137.909554) (xy 13.206984 -138.033506)
			(xy 13.206984 -138.194288) (xy 13.206984 -139.267692) (xy 13.20546 -139.267692) (xy 12.984988 -139.488164)
			(xy 11.175238 -139.488164) (xy 10.85977 -139.803632) (xy 10.85977 -140.814806) (xy 10.855198 -140.819378)
			(xy 10.855198 -151.45131) (xy 10.88009 -151.476202) (xy 10.88009 -156.313124) (xy 14.639544 -156.313124)
		)
		(stroke
			(width 0)
			(type solid)
		)
		(fill yes)
		(layer "F.Cu")
		(net "P12V_NIC0_R")
	)
	(gr_poly
		(pts
			(xy 130.873754 -156.178758) (xy 130.873754 -154.241754) (xy 130.683 -154.051) (xy 130.683 -150.876)
			(xy 130.873754 -150.685246) (xy 130.873754 -145.575782) (xy 131.7625 -144.687036) (xy 133.3627 -144.687036)
			(xy 133.571488 -144.895824) (xy 134.081774 -145.406364) (xy 134.081774 -146.616674) (xy 134.220966 -146.755866)
			(xy 134.55523 -146.755866) (xy 134.80796 -147.008596) (xy 134.80796 -147.499832) (xy 134.906258 -147.59813)
			(xy 134.906258 -148.203666) (xy 134.922768 -148.220176) (xy 135.127238 -148.220176) (xy 135.136636 -148.210778)
			(xy 135.136636 -147.310856) (xy 135.23849 -147.209002) (xy 135.23849 -147.197572) (xy 135.566912 -146.86915)
			(xy 135.566912 -144.967198) (xy 135.008112 -144.408398) (xy 135.008112 -141.441424) (xy 135.015478 -141.434058)
			(xy 135.015478 -140.053314) (xy 135.463788 -139.605004) (xy 136.308846 -139.605004) (xy 136.563608 -139.350242)
			(xy 136.563608 -136.331198) (xy 136.373616 -136.141206) (xy 129.551938 -136.141206) (xy 129.041906 -135.631174)
			(xy 128.624838 -135.631174) (xy 128.52527 -135.730742) (xy 128.52527 -137.86993) (xy 128.578102 -137.922762)
			(xy 128.909318 -137.922762) (xy 128.922526 -137.909554) (xy 129.022094 -137.909554) (xy 129.192782 -137.909554)
			(xy 129.301748 -138.01852) (xy 129.301748 -138.189208) (xy 129.306828 -138.194288) (xy 129.306828 -139.267692)
			(xy 129.305304 -139.267692) (xy 129.084832 -139.488164) (xy 127.275082 -139.488164) (xy 126.959614 -139.803632)
			(xy 126.959614 -140.814806) (xy 126.955042 -140.819378) (xy 126.955042 -156.299154) (xy 126.969012 -156.313124)
			(xy 130.739388 -156.313124)
		)
		(stroke
			(width 0)
			(type solid)
		)
		(fill yes)
		(layer "F.Cu")
		(net "P12V_NIC2_R")
	)
	(gr_poly
		(pts
			(arc
				(start 185.278014 -22.717252)
				(mid 185.297401 -22.713302)
				(end 185.313828 -22.702266)
			)
			(arc
				(start 185.33872 -22.702266)
				(mid 185.355137 -22.713328)
				(end 185.374534 -22.717252)
			)
			(arc
				(start 188.936884 -22.717252)
				(mid 188.956407 -22.713351)
				(end 188.972952 -22.702266)
			)
			(xy 188.97346 -22.701504)
			(arc
				(start 188.97346 -18.805906)
				(mid 188.97741 -18.786519)
				(end 188.988446 -18.770092)
			)
			(arc
				(start 189.000384 -18.758154)
				(mid 189.015219 -18.722251)
				(end 189.000384 -18.686272)
			)
			(arc
				(start 188.952886 -18.638774)
				(mid 188.936352 -18.627663)
				(end 188.916818 -18.623788)
			)
			(xy 187.947808 -18.623788) (xy 187.947046 -18.623026) (xy 182.758334 -18.623026) (xy 182.743602 -18.637758)
			(xy 182.743348 -18.638012) (xy 182.726076 -18.655284) (xy 182.725822 -18.655538) (xy 182.71109 -18.67027)
			(xy 182.71109 -21.936202) (xy 182.725822 -21.950934) (xy 182.726076 -21.951188) (xy 182.743348 -21.96846)
			(xy 182.743602 -21.968714) (xy 182.758334 -21.983446)
			(arc
				(start 184.12841 -21.983446)
				(mid 184.147933 -21.987347)
				(end 184.164478 -21.998432)
			)
			(arc
				(start 184.37606 -22.210014)
				(mid 184.387171 -22.226548)
				(end 184.391046 -22.246082)
			)
			(arc
				(start 184.391046 -22.584918)
				(mid 184.394947 -22.604441)
				(end 184.406032 -22.620986)
			)
			(arc
				(start 184.487312 -22.702266)
				(mid 184.503846 -22.713377)
				(end 184.52338 -22.717252)
			)
		)
		(stroke
			(width 0)
			(type solid)
		)
		(fill yes)
		(layer "F.Cu")
		(net "P12V_SSD6")
	)
	(gr_poly
		(pts
			(arc
				(start 211.277962 -22.717252)
				(mid 211.297349 -22.713302)
				(end 211.313776 -22.702266)
			)
			(arc
				(start 211.338668 -22.702266)
				(mid 211.355085 -22.713328)
				(end 211.374482 -22.717252)
			)
			(arc
				(start 214.936832 -22.717252)
				(mid 214.956355 -22.713351)
				(end 214.9729 -22.702266)
			)
			(xy 214.973408 -22.701504)
			(arc
				(start 214.973408 -18.805906)
				(mid 214.977358 -18.786519)
				(end 214.988394 -18.770092)
			)
			(arc
				(start 215.000332 -18.758154)
				(mid 215.015167 -18.722251)
				(end 215.000332 -18.686272)
			)
			(arc
				(start 214.952834 -18.638774)
				(mid 214.9363 -18.627663)
				(end 214.916766 -18.623788)
			)
			(xy 213.947756 -18.623788) (xy 213.946994 -18.623026) (xy 208.758282 -18.623026) (xy 208.74355 -18.637758)
			(xy 208.743296 -18.638012) (xy 208.726024 -18.655284) (xy 208.72577 -18.655538) (xy 208.711038 -18.67027)
			(xy 208.711038 -21.936202) (xy 208.72577 -21.950934) (xy 208.726024 -21.951188) (xy 208.743296 -21.96846)
			(xy 208.74355 -21.968714) (xy 208.758282 -21.983446)
			(arc
				(start 210.128358 -21.983446)
				(mid 210.147881 -21.987347)
				(end 210.164426 -21.998432)
			)
			(arc
				(start 210.376008 -22.210014)
				(mid 210.387119 -22.226548)
				(end 210.390994 -22.246082)
			)
			(arc
				(start 210.390994 -22.584918)
				(mid 210.394895 -22.604441)
				(end 210.40598 -22.620986)
			)
			(arc
				(start 210.48726 -22.702266)
				(mid 210.503794 -22.713377)
				(end 210.523328 -22.717252)
			)
		)
		(stroke
			(width 0)
			(type solid)
		)
		(fill yes)
		(layer "F.Cu")
		(net "P12V_SSD7")
	)
	(gr_poly
		(pts
			(arc
				(start 249.377962 -22.717252)
				(mid 249.397349 -22.713302)
				(end 249.413776 -22.702266)
			)
			(arc
				(start 249.438668 -22.702266)
				(mid 249.455085 -22.713328)
				(end 249.474482 -22.717252)
			)
			(arc
				(start 253.036832 -22.717252)
				(mid 253.056355 -22.713351)
				(end 253.0729 -22.702266)
			)
			(xy 253.073408 -22.701504)
			(arc
				(start 253.073408 -18.805906)
				(mid 253.077358 -18.786519)
				(end 253.088394 -18.770092)
			)
			(arc
				(start 253.100332 -18.758154)
				(mid 253.115167 -18.722251)
				(end 253.100332 -18.686272)
			)
			(arc
				(start 253.052834 -18.638774)
				(mid 253.0363 -18.627663)
				(end 253.016766 -18.623788)
			)
			(xy 252.047756 -18.623788) (xy 252.046994 -18.623026) (xy 246.858282 -18.623026) (xy 246.84355 -18.637758)
			(xy 246.843296 -18.638012) (xy 246.826024 -18.655284) (xy 246.82577 -18.655538) (xy 246.811038 -18.67027)
			(xy 246.811038 -21.936202) (xy 246.82577 -21.950934) (xy 246.826024 -21.951188) (xy 246.843296 -21.96846)
			(xy 246.84355 -21.968714) (xy 246.858282 -21.983446)
			(arc
				(start 248.228358 -21.983446)
				(mid 248.247881 -21.987347)
				(end 248.264426 -21.998432)
			)
			(arc
				(start 248.476008 -22.210014)
				(mid 248.487119 -22.226548)
				(end 248.490994 -22.246082)
			)
			(arc
				(start 248.490994 -22.584918)
				(mid 248.494895 -22.604441)
				(end 248.50598 -22.620986)
			)
			(arc
				(start 248.58726 -22.702266)
				(mid 248.603794 -22.713377)
				(end 248.623328 -22.717252)
			)
		)
		(stroke
			(width 0)
			(type solid)
		)
		(fill yes)
		(layer "F.Cu")
		(net "P12V_SSD8")
	)
	(gr_poly
		(pts
			(xy 350.84766 -256.63652) (xy 350.84766 -256.54) (xy 350.826324 -256.518664) (xy 350.53524 -256.518664)
			(xy 350.423226 -256.518664) (xy 350.076262 -256.1717) (xy 350.065086 -256.160524) (xy 350.065086 -255.703324)
			(xy 350.065086 -254.982726) (xy 349.44558 -254.36322) (xy 349.184214 -254.36322) (xy 349.131636 -254.310642)
			(xy 349.131636 -254.174498) (xy 349.427038 -253.879096) (xy 349.602552 -253.879096)
			(arc
				(start 350.076008 -254.352298)
				(mid 350.158385 -254.407404)
				(end 350.255586 -254.42672)
			)
			(arc
				(start 350.255586 -254.42672)
				(mid 350.435191 -254.352325)
				(end 350.509586 -254.17272)
			)
			(arc
				(start 350.509586 -254.17272)
				(mid 350.490236 -254.075533)
				(end 350.435164 -253.993142)
			)
			(xy 349.882714 -253.440692) (xy 349.882714 -252.7554) (xy 349.591884 -252.46457) (xy 348.447106 -252.46457)
			(xy 348.334076 -252.5776) (xy 348.334076 -253.878588) (xy 348.394528 -253.878588) (xy 348.623636 -254.107696)
			(xy 348.623636 -254.55372) (xy 348.621604 -254.555752) (xy 348.621604 -254.794766) (xy 348.631256 -254.804418)
			(xy 348.76994 -254.804418) (xy 349.34779 -254.804418) (xy 349.684086 -255.140714) (xy 349.684086 -255.725168)
			(xy 349.684086 -255.994916) (xy 349.828358 -256.139188) (xy 350.341438 -256.652014) (xy 350.532954 -256.652014)
			(xy 350.832166 -256.652014)
		)
		(stroke
			(width 0)
			(type solid)
		)
		(fill yes)
		(layer "F.Cu")
		(net "P0V8_PEX2_VREF")
	)
	(gr_poly
		(pts
			(xy 113.312448 -318.475868) (xy 113.312448 -308.799484) (xy 113.16716 -308.654196) (xy 111.841026 -308.654196)
			(xy 101.815138 -308.654196) (xy 101.791516 -308.654196) (xy 101.07168 -308.654196) (xy 100.612194 -308.19471)
			(xy 100.612194 -303.726088) (xy 100.612194 -303.644046) (xy 100.854764 -303.401476) (xy 115.831112 -303.401476)
			(xy 115.96624 -303.266348) (xy 117.99443 -301.238158) (xy 117.99443 -300.616112) (xy 117.99443 -294.06469)
			(xy 117.872764 -293.943024) (xy 117.709188 -293.943024)
			(arc
				(start 96.188784 -293.943024)
				(mid 96.169261 -293.946925)
				(end 96.152716 -293.95801)
			)
			(arc
				(start 95.732854 -294.377872)
				(mid 95.721743 -294.394406)
				(end 95.717868 -294.41394)
			)
			(xy 95.717868 -298.797726) (xy 95.717868 -314.186062)
			(arc
				(start 95.717868 -314.434728)
				(mid 95.723368 -314.457465)
				(end 95.738442 -314.475368)
			)
			(arc
				(start 95.738442 -314.475368)
				(mid 97.516285 -316.299836)
				(end 98.630486 -318.590676)
			)
			(arc
				(start 98.630486 -318.590676)
				(mid 98.643149 -318.611795)
				(end 98.664268 -318.624458)
			)
			(xy 98.801682 -318.761872) (xy 113.026444 -318.761872)
		)
		(stroke
			(width 0)
			(type solid)
		)
		(fill yes)
		(layer "F.Cu")
		(net "P0V8_PEX0")
	)
	(gr_poly
		(pts
			(arc
				(start 132.2832 -179.03444)
				(mid 132.325377 -179.027631)
				(end 132.368036 -179.025296)
			)
			(arc
				(start 132.368036 -179.025296)
				(mid 132.410693 -179.027645)
				(end 132.452872 -179.03444)
			)
			(xy 132.457952 -179.035456)
			(arc
				(start 133.987286 -179.035456)
				(mid 134.006809 -179.031555)
				(end 134.023354 -179.02047)
			)
			(arc
				(start 134.097268 -178.946556)
				(mid 134.108379 -178.930022)
				(end 134.112254 -178.910488)
			)
			(arc
				(start 134.112254 -176.398428)
				(mid 134.108353 -176.378905)
				(end 134.097268 -176.36236)
			)
			(arc
				(start 134.003796 -176.268888)
				(mid 133.987262 -176.257777)
				(end 133.967728 -176.253902)
			)
			(arc
				(start 131.460748 -176.253902)
				(mid 131.441225 -176.257803)
				(end 131.42468 -176.268888)
			)
			(arc
				(start 131.335018 -176.35855)
				(mid 131.323907 -176.375084)
				(end 131.320032 -176.394618)
			)
			(xy 131.320032 -176.597056)
			(arc
				(start 131.322318 -176.604168)
				(mid 131.339848 -176.722278)
				(end 131.322318 -176.840388)
			)
			(xy 131.320032 -176.8475) (xy 131.320032 -178.0032)
			(arc
				(start 131.322826 -178.011074)
				(mid 131.339356 -178.076198)
				(end 131.344924 -178.143154)
			)
			(arc
				(start 131.344924 -178.143154)
				(mid 131.339336 -178.210107)
				(end 131.322826 -178.275234)
			)
			(xy 131.320032 -178.283108)
			(arc
				(start 131.320032 -178.682396)
				(mid 131.323933 -178.701919)
				(end 131.335018 -178.718464)
			)
			(arc
				(start 131.637024 -179.02047)
				(mid 131.653558 -179.031581)
				(end 131.673092 -179.035456)
			)
			(xy 132.27812 -179.035456)
		)
		(stroke
			(width 0)
			(type solid)
		)
		(fill yes)
		(layer "F.Cu")
		(net "GND")
	)
	(gr_poly
		(pts
			(arc
				(start 33.185862 -295.399206)
				(mid 33.205385 -295.395305)
				(end 33.22193 -295.38422)
			)
			(arc
				(start 33.336738 -295.269412)
				(mid 33.3478 -295.252995)
				(end 33.351724 -295.233598)
			)
			(arc
				(start 33.351724 -293.439088)
				(mid 33.347774 -293.419701)
				(end 33.336738 -293.403274)
			)
			(arc
				(start 33.209738 -293.276274)
				(mid 33.193204 -293.265163)
				(end 33.17367 -293.261288)
			)
			(arc
				(start 32.937958 -293.261288)
				(mid 32.918435 -293.265189)
				(end 32.90189 -293.276274)
			)
			(arc
				(start 32.794448 -293.383716)
				(mid 32.777914 -293.394827)
				(end 32.75838 -293.398702)
			)
			(arc
				(start 32.01797 -293.398702)
				(mid 31.998447 -293.394801)
				(end 31.981902 -293.383716)
			)
			(arc
				(start 31.951676 -293.35349)
				(mid 31.935259 -293.342428)
				(end 31.915862 -293.338504)
			)
			(xy 31.530036 -293.338504) (xy 31.511494 -293.346378) (xy 31.510986 -293.346886)
			(arc
				(start 31.510986 -293.761922)
				(mid 31.507085 -293.781445)
				(end 31.496 -293.79799)
			)
			(arc
				(start 31.4706 -293.82339)
				(mid 31.454066 -293.834501)
				(end 31.434532 -293.838376)
			)
			(arc
				(start 30.625796 -293.838376)
				(mid 30.606273 -293.842277)
				(end 30.589728 -293.853362)
			)
			(arc
				(start 30.500574 -293.942516)
				(mid 30.489463 -293.95905)
				(end 30.485588 -293.978584)
			)
			(arc
				(start 30.485588 -295.26865)
				(mid 30.489489 -295.288173)
				(end 30.500574 -295.304718)
			)
			(arc
				(start 30.58033 -295.384474)
				(mid 30.596893 -295.395448)
				(end 30.616398 -295.399206)
			)
		)
		(stroke
			(width 0)
			(type solid)
		)
		(fill yes)
		(layer "F.Cu")
		(net "PCEPLL2_VDDA18_PEX0")
	)
	(gr_poly
		(pts
			(arc
				(start 33.185862 -292.198806)
				(mid 33.205385 -292.194905)
				(end 33.22193 -292.18382)
			)
			(arc
				(start 33.336738 -292.069012)
				(mid 33.3478 -292.052595)
				(end 33.351724 -292.033198)
			)
			(arc
				(start 33.351724 -290.238688)
				(mid 33.347774 -290.219301)
				(end 33.336738 -290.202874)
			)
			(arc
				(start 33.209738 -290.075874)
				(mid 33.193204 -290.064763)
				(end 33.17367 -290.060888)
			)
			(arc
				(start 32.937958 -290.060888)
				(mid 32.918435 -290.064789)
				(end 32.90189 -290.075874)
			)
			(arc
				(start 32.794448 -290.183316)
				(mid 32.777914 -290.194427)
				(end 32.75838 -290.198302)
			)
			(arc
				(start 32.01797 -290.198302)
				(mid 31.998447 -290.194401)
				(end 31.981902 -290.183316)
			)
			(arc
				(start 31.951676 -290.15309)
				(mid 31.935259 -290.142028)
				(end 31.915862 -290.138104)
			)
			(xy 31.530036 -290.138104) (xy 31.511494 -290.145978) (xy 31.510986 -290.146486)
			(arc
				(start 31.510986 -290.561522)
				(mid 31.507085 -290.581045)
				(end 31.496 -290.59759)
			)
			(arc
				(start 31.4706 -290.62299)
				(mid 31.454066 -290.634101)
				(end 31.434532 -290.637976)
			)
			(arc
				(start 30.625796 -290.637976)
				(mid 30.606273 -290.641877)
				(end 30.589728 -290.652962)
			)
			(arc
				(start 30.500574 -290.742116)
				(mid 30.489463 -290.75865)
				(end 30.485588 -290.778184)
			)
			(arc
				(start 30.485588 -292.06825)
				(mid 30.489489 -292.087773)
				(end 30.500574 -292.104318)
			)
			(arc
				(start 30.58033 -292.184074)
				(mid 30.596893 -292.195048)
				(end 30.616398 -292.198806)
			)
		)
		(stroke
			(width 0)
			(type solid)
		)
		(fill yes)
		(layer "F.Cu")
		(net "PCEPLL4_VDDA18_PEX0")
	)
	(gr_poly
		(pts
			(arc
				(start 33.185862 -288.998406)
				(mid 33.205385 -288.994505)
				(end 33.22193 -288.98342)
			)
			(arc
				(start 33.336738 -288.868612)
				(mid 33.3478 -288.852195)
				(end 33.351724 -288.832798)
			)
			(arc
				(start 33.351724 -287.038288)
				(mid 33.347774 -287.018901)
				(end 33.336738 -287.002474)
			)
			(arc
				(start 33.209738 -286.875474)
				(mid 33.193204 -286.864363)
				(end 33.17367 -286.860488)
			)
			(arc
				(start 32.937958 -286.860488)
				(mid 32.918435 -286.864389)
				(end 32.90189 -286.875474)
			)
			(arc
				(start 32.794448 -286.982916)
				(mid 32.777914 -286.994027)
				(end 32.75838 -286.997902)
			)
			(arc
				(start 32.01797 -286.997902)
				(mid 31.998447 -286.994001)
				(end 31.981902 -286.982916)
			)
			(arc
				(start 31.951676 -286.95269)
				(mid 31.935259 -286.941628)
				(end 31.915862 -286.937704)
			)
			(xy 31.530036 -286.937704) (xy 31.511494 -286.945578) (xy 31.510986 -286.946086)
			(arc
				(start 31.510986 -287.361122)
				(mid 31.507085 -287.380645)
				(end 31.496 -287.39719)
			)
			(arc
				(start 31.4706 -287.42259)
				(mid 31.454066 -287.433701)
				(end 31.434532 -287.437576)
			)
			(arc
				(start 30.625796 -287.437576)
				(mid 30.606273 -287.441477)
				(end 30.589728 -287.452562)
			)
			(arc
				(start 30.500574 -287.541716)
				(mid 30.489463 -287.55825)
				(end 30.485588 -287.577784)
			)
			(arc
				(start 30.485588 -288.86785)
				(mid 30.489489 -288.887373)
				(end 30.500574 -288.903918)
			)
			(arc
				(start 30.58033 -288.983674)
				(mid 30.596893 -288.994648)
				(end 30.616398 -288.998406)
			)
		)
		(stroke
			(width 0)
			(type solid)
		)
		(fill yes)
		(layer "F.Cu")
		(net "PCEPLL6_VDDA18_PEX0")
	)
	(gr_poly
		(pts
			(arc
				(start 33.185862 -285.798006)
				(mid 33.205385 -285.794105)
				(end 33.22193 -285.78302)
			)
			(arc
				(start 33.336738 -285.668212)
				(mid 33.3478 -285.651795)
				(end 33.351724 -285.632398)
			)
			(arc
				(start 33.351724 -283.837888)
				(mid 33.347774 -283.818501)
				(end 33.336738 -283.802074)
			)
			(arc
				(start 33.209738 -283.675074)
				(mid 33.193204 -283.663963)
				(end 33.17367 -283.660088)
			)
			(arc
				(start 32.937958 -283.660088)
				(mid 32.918435 -283.663989)
				(end 32.90189 -283.675074)
			)
			(arc
				(start 32.794448 -283.782516)
				(mid 32.777914 -283.793627)
				(end 32.75838 -283.797502)
			)
			(arc
				(start 32.01797 -283.797502)
				(mid 31.998447 -283.793601)
				(end 31.981902 -283.782516)
			)
			(arc
				(start 31.951676 -283.75229)
				(mid 31.935259 -283.741228)
				(end 31.915862 -283.737304)
			)
			(xy 31.530036 -283.737304) (xy 31.511494 -283.745178) (xy 31.510986 -283.745686)
			(arc
				(start 31.510986 -284.160722)
				(mid 31.507085 -284.180245)
				(end 31.496 -284.19679)
			)
			(arc
				(start 31.4706 -284.22219)
				(mid 31.454066 -284.233301)
				(end 31.434532 -284.237176)
			)
			(arc
				(start 30.625796 -284.237176)
				(mid 30.606273 -284.241077)
				(end 30.589728 -284.252162)
			)
			(arc
				(start 30.500574 -284.341316)
				(mid 30.489463 -284.35785)
				(end 30.485588 -284.377384)
			)
			(arc
				(start 30.485588 -285.66745)
				(mid 30.489489 -285.686973)
				(end 30.500574 -285.703518)
			)
			(arc
				(start 30.58033 -285.783274)
				(mid 30.596893 -285.794248)
				(end 30.616398 -285.798006)
			)
		)
		(stroke
			(width 0)
			(type solid)
		)
		(fill yes)
		(layer "F.Cu")
		(net "PCEPLL7_VDDA18_PEX0")
	)
	(gr_poly
		(pts
			(arc
				(start 149.28596 -301.800006)
				(mid 149.305483 -301.796105)
				(end 149.322028 -301.78502)
			)
			(arc
				(start 149.436836 -301.670212)
				(mid 149.447898 -301.653795)
				(end 149.451822 -301.634398)
			)
			(arc
				(start 149.451822 -299.839888)
				(mid 149.447872 -299.820501)
				(end 149.436836 -299.804074)
			)
			(arc
				(start 149.309836 -299.677074)
				(mid 149.293302 -299.665963)
				(end 149.273768 -299.662088)
			)
			(arc
				(start 149.038056 -299.662088)
				(mid 149.018533 -299.665989)
				(end 149.001988 -299.677074)
			)
			(arc
				(start 148.894546 -299.784516)
				(mid 148.878012 -299.795627)
				(end 148.858478 -299.799502)
			)
			(arc
				(start 148.118068 -299.799502)
				(mid 148.098545 -299.795601)
				(end 148.082 -299.784516)
			)
			(arc
				(start 148.051774 -299.75429)
				(mid 148.035357 -299.743228)
				(end 148.01596 -299.739304)
			)
			(xy 147.630134 -299.739304) (xy 147.611592 -299.747178) (xy 147.611084 -299.747686)
			(arc
				(start 147.611084 -300.162722)
				(mid 147.607183 -300.182245)
				(end 147.596098 -300.19879)
			)
			(arc
				(start 147.570698 -300.22419)
				(mid 147.554164 -300.235301)
				(end 147.53463 -300.239176)
			)
			(arc
				(start 146.725894 -300.239176)
				(mid 146.706371 -300.243077)
				(end 146.689826 -300.254162)
			)
			(arc
				(start 146.600672 -300.343316)
				(mid 146.589561 -300.35985)
				(end 146.585686 -300.379384)
			)
			(arc
				(start 146.585686 -301.66945)
				(mid 146.589587 -301.688973)
				(end 146.600672 -301.705518)
			)
			(arc
				(start 146.680428 -301.785274)
				(mid 146.696991 -301.796248)
				(end 146.716496 -301.800006)
			)
		)
		(stroke
			(width 0)
			(type solid)
		)
		(fill yes)
		(layer "F.Cu")
		(net "PCEPLL1_VDDA18_PEX1")
	)
	(gr_poly
		(pts
			(arc
				(start 149.28596 -295.399206)
				(mid 149.305483 -295.395305)
				(end 149.322028 -295.38422)
			)
			(arc
				(start 149.436836 -295.269412)
				(mid 149.447898 -295.252995)
				(end 149.451822 -295.233598)
			)
			(arc
				(start 149.451822 -293.439088)
				(mid 149.447872 -293.419701)
				(end 149.436836 -293.403274)
			)
			(arc
				(start 149.309836 -293.276274)
				(mid 149.293302 -293.265163)
				(end 149.273768 -293.261288)
			)
			(arc
				(start 149.038056 -293.261288)
				(mid 149.018533 -293.265189)
				(end 149.001988 -293.276274)
			)
			(arc
				(start 148.894546 -293.383716)
				(mid 148.878012 -293.394827)
				(end 148.858478 -293.398702)
			)
			(arc
				(start 148.118068 -293.398702)
				(mid 148.098545 -293.394801)
				(end 148.082 -293.383716)
			)
			(arc
				(start 148.051774 -293.35349)
				(mid 148.035357 -293.342428)
				(end 148.01596 -293.338504)
			)
			(xy 147.630134 -293.338504) (xy 147.611592 -293.346378) (xy 147.611084 -293.346886)
			(arc
				(start 147.611084 -293.761922)
				(mid 147.607183 -293.781445)
				(end 147.596098 -293.79799)
			)
			(arc
				(start 147.570698 -293.82339)
				(mid 147.554164 -293.834501)
				(end 147.53463 -293.838376)
			)
			(arc
				(start 146.725894 -293.838376)
				(mid 146.706371 -293.842277)
				(end 146.689826 -293.853362)
			)
			(arc
				(start 146.600672 -293.942516)
				(mid 146.589561 -293.95905)
				(end 146.585686 -293.978584)
			)
			(arc
				(start 146.585686 -295.26865)
				(mid 146.589587 -295.288173)
				(end 146.600672 -295.304718)
			)
			(arc
				(start 146.680428 -295.384474)
				(mid 146.696991 -295.395448)
				(end 146.716496 -295.399206)
			)
		)
		(stroke
			(width 0)
			(type solid)
		)
		(fill yes)
		(layer "F.Cu")
		(net "PCEPLL2_VDDA18_PEX1")
	)
	(gr_poly
		(pts
			(arc
				(start 149.28596 -292.198806)
				(mid 149.305483 -292.194905)
				(end 149.322028 -292.18382)
			)
			(arc
				(start 149.436836 -292.069012)
				(mid 149.447898 -292.052595)
				(end 149.451822 -292.033198)
			)
			(arc
				(start 149.451822 -290.238688)
				(mid 149.447872 -290.219301)
				(end 149.436836 -290.202874)
			)
			(arc
				(start 149.309836 -290.075874)
				(mid 149.293302 -290.064763)
				(end 149.273768 -290.060888)
			)
			(arc
				(start 149.038056 -290.060888)
				(mid 149.018533 -290.064789)
				(end 149.001988 -290.075874)
			)
			(arc
				(start 148.894546 -290.183316)
				(mid 148.878012 -290.194427)
				(end 148.858478 -290.198302)
			)
			(arc
				(start 148.118068 -290.198302)
				(mid 148.098545 -290.194401)
				(end 148.082 -290.183316)
			)
			(arc
				(start 148.051774 -290.15309)
				(mid 148.035357 -290.142028)
				(end 148.01596 -290.138104)
			)
			(xy 147.630134 -290.138104) (xy 147.611592 -290.145978) (xy 147.611084 -290.146486)
			(arc
				(start 147.611084 -290.561522)
				(mid 147.607183 -290.581045)
				(end 147.596098 -290.59759)
			)
			(arc
				(start 147.570698 -290.62299)
				(mid 147.554164 -290.634101)
				(end 147.53463 -290.637976)
			)
			(arc
				(start 146.725894 -290.637976)
				(mid 146.706371 -290.641877)
				(end 146.689826 -290.652962)
			)
			(arc
				(start 146.600672 -290.742116)
				(mid 146.589561 -290.75865)
				(end 146.585686 -290.778184)
			)
			(arc
				(start 146.585686 -292.06825)
				(mid 146.589587 -292.087773)
				(end 146.600672 -292.104318)
			)
			(arc
				(start 146.680428 -292.184074)
				(mid 146.696991 -292.195048)
				(end 146.716496 -292.198806)
			)
		)
		(stroke
			(width 0)
			(type solid)
		)
		(fill yes)
		(layer "F.Cu")
		(net "PCEPLL4_VDDA18_PEX1")
	)
	(gr_poly
		(pts
			(arc
				(start 149.28596 -288.998406)
				(mid 149.305483 -288.994505)
				(end 149.322028 -288.98342)
			)
			(arc
				(start 149.436836 -288.868612)
				(mid 149.447898 -288.852195)
				(end 149.451822 -288.832798)
			)
			(arc
				(start 149.451822 -287.038288)
				(mid 149.447872 -287.018901)
				(end 149.436836 -287.002474)
			)
			(arc
				(start 149.309836 -286.875474)
				(mid 149.293302 -286.864363)
				(end 149.273768 -286.860488)
			)
			(arc
				(start 149.038056 -286.860488)
				(mid 149.018533 -286.864389)
				(end 149.001988 -286.875474)
			)
			(arc
				(start 148.894546 -286.982916)
				(mid 148.878012 -286.994027)
				(end 148.858478 -286.997902)
			)
			(arc
				(start 148.118068 -286.997902)
				(mid 148.098545 -286.994001)
				(end 148.082 -286.982916)
			)
			(arc
				(start 148.051774 -286.95269)
				(mid 148.035357 -286.941628)
				(end 148.01596 -286.937704)
			)
			(xy 147.630134 -286.937704) (xy 147.611592 -286.945578) (xy 147.611084 -286.946086)
			(arc
				(start 147.611084 -287.361122)
				(mid 147.607183 -287.380645)
				(end 147.596098 -287.39719)
			)
			(arc
				(start 147.570698 -287.42259)
				(mid 147.554164 -287.433701)
				(end 147.53463 -287.437576)
			)
			(arc
				(start 146.725894 -287.437576)
				(mid 146.706371 -287.441477)
				(end 146.689826 -287.452562)
			)
			(arc
				(start 146.600672 -287.541716)
				(mid 146.589561 -287.55825)
				(end 146.585686 -287.577784)
			)
			(arc
				(start 146.585686 -288.86785)
				(mid 146.589587 -288.887373)
				(end 146.600672 -288.903918)
			)
			(arc
				(start 146.680428 -288.983674)
				(mid 146.696991 -288.994648)
				(end 146.716496 -288.998406)
			)
		)
		(stroke
			(width 0)
			(type solid)
		)
		(fill yes)
		(layer "F.Cu")
		(net "PCEPLL6_VDDA18_PEX1")
	)
	(gr_poly
		(pts
			(arc
				(start 149.28596 -285.798006)
				(mid 149.305483 -285.794105)
				(end 149.322028 -285.78302)
			)
			(arc
				(start 149.436836 -285.668212)
				(mid 149.447898 -285.651795)
				(end 149.451822 -285.632398)
			)
			(arc
				(start 149.451822 -283.837888)
				(mid 149.447872 -283.818501)
				(end 149.436836 -283.802074)
			)
			(arc
				(start 149.309836 -283.675074)
				(mid 149.293302 -283.663963)
				(end 149.273768 -283.660088)
			)
			(arc
				(start 149.038056 -283.660088)
				(mid 149.018533 -283.663989)
				(end 149.001988 -283.675074)
			)
			(arc
				(start 148.894546 -283.782516)
				(mid 148.878012 -283.793627)
				(end 148.858478 -283.797502)
			)
			(arc
				(start 148.118068 -283.797502)
				(mid 148.098545 -283.793601)
				(end 148.082 -283.782516)
			)
			(arc
				(start 148.051774 -283.75229)
				(mid 148.035357 -283.741228)
				(end 148.01596 -283.737304)
			)
			(xy 147.630134 -283.737304) (xy 147.611592 -283.745178) (xy 147.611084 -283.745686)
			(arc
				(start 147.611084 -284.160722)
				(mid 147.607183 -284.180245)
				(end 147.596098 -284.19679)
			)
			(arc
				(start 147.570698 -284.22219)
				(mid 147.554164 -284.233301)
				(end 147.53463 -284.237176)
			)
			(arc
				(start 146.725894 -284.237176)
				(mid 146.706371 -284.241077)
				(end 146.689826 -284.252162)
			)
			(arc
				(start 146.600672 -284.341316)
				(mid 146.589561 -284.35785)
				(end 146.585686 -284.377384)
			)
			(arc
				(start 146.585686 -285.66745)
				(mid 146.589587 -285.686973)
				(end 146.600672 -285.703518)
			)
			(arc
				(start 146.680428 -285.783274)
				(mid 146.696991 -285.794248)
				(end 146.716496 -285.798006)
			)
		)
		(stroke
			(width 0)
			(type solid)
		)
		(fill yes)
		(layer "F.Cu")
		(net "PCEPLL7_VDDA18_PEX1")
	)
	(gr_poly
		(pts
			(arc
				(start 265.385804 -301.800006)
				(mid 265.405327 -301.796105)
				(end 265.421872 -301.78502)
			)
			(arc
				(start 265.53668 -301.670212)
				(mid 265.547742 -301.653795)
				(end 265.551666 -301.634398)
			)
			(arc
				(start 265.551666 -299.839888)
				(mid 265.547716 -299.820501)
				(end 265.53668 -299.804074)
			)
			(arc
				(start 265.40968 -299.677074)
				(mid 265.393146 -299.665963)
				(end 265.373612 -299.662088)
			)
			(arc
				(start 265.1379 -299.662088)
				(mid 265.118377 -299.665989)
				(end 265.101832 -299.677074)
			)
			(arc
				(start 264.99439 -299.784516)
				(mid 264.977856 -299.795627)
				(end 264.958322 -299.799502)
			)
			(arc
				(start 264.217912 -299.799502)
				(mid 264.198389 -299.795601)
				(end 264.181844 -299.784516)
			)
			(arc
				(start 264.151618 -299.75429)
				(mid 264.135201 -299.743228)
				(end 264.115804 -299.739304)
			)
			(xy 263.729978 -299.739304) (xy 263.711436 -299.747178) (xy 263.710928 -299.747686)
			(arc
				(start 263.710928 -300.162722)
				(mid 263.707027 -300.182245)
				(end 263.695942 -300.19879)
			)
			(arc
				(start 263.670542 -300.22419)
				(mid 263.654008 -300.235301)
				(end 263.634474 -300.239176)
			)
			(arc
				(start 262.825738 -300.239176)
				(mid 262.806215 -300.243077)
				(end 262.78967 -300.254162)
			)
			(arc
				(start 262.700516 -300.343316)
				(mid 262.689405 -300.35985)
				(end 262.68553 -300.379384)
			)
			(arc
				(start 262.68553 -301.66945)
				(mid 262.689431 -301.688973)
				(end 262.700516 -301.705518)
			)
			(arc
				(start 262.780272 -301.785274)
				(mid 262.796835 -301.796248)
				(end 262.81634 -301.800006)
			)
		)
		(stroke
			(width 0)
			(type solid)
		)
		(fill yes)
		(layer "F.Cu")
		(net "PCEPLL1_VDDA18_PEX2")
	)
	(gr_poly
		(pts
			(arc
				(start 265.385804 -295.399206)
				(mid 265.405327 -295.395305)
				(end 265.421872 -295.38422)
			)
			(arc
				(start 265.53668 -295.269412)
				(mid 265.547742 -295.252995)
				(end 265.551666 -295.233598)
			)
			(arc
				(start 265.551666 -293.439088)
				(mid 265.547716 -293.419701)
				(end 265.53668 -293.403274)
			)
			(arc
				(start 265.40968 -293.276274)
				(mid 265.393146 -293.265163)
				(end 265.373612 -293.261288)
			)
			(arc
				(start 265.1379 -293.261288)
				(mid 265.118377 -293.265189)
				(end 265.101832 -293.276274)
			)
			(arc
				(start 264.99439 -293.383716)
				(mid 264.977856 -293.394827)
				(end 264.958322 -293.398702)
			)
			(arc
				(start 264.217912 -293.398702)
				(mid 264.198389 -293.394801)
				(end 264.181844 -293.383716)
			)
			(arc
				(start 264.151618 -293.35349)
				(mid 264.135201 -293.342428)
				(end 264.115804 -293.338504)
			)
			(xy 263.729978 -293.338504) (xy 263.711436 -293.346378) (xy 263.710928 -293.346886)
			(arc
				(start 263.710928 -293.761922)
				(mid 263.707027 -293.781445)
				(end 263.695942 -293.79799)
			)
			(arc
				(start 263.670542 -293.82339)
				(mid 263.654008 -293.834501)
				(end 263.634474 -293.838376)
			)
			(arc
				(start 262.825738 -293.838376)
				(mid 262.806215 -293.842277)
				(end 262.78967 -293.853362)
			)
			(arc
				(start 262.700516 -293.942516)
				(mid 262.689405 -293.95905)
				(end 262.68553 -293.978584)
			)
			(arc
				(start 262.68553 -295.26865)
				(mid 262.689431 -295.288173)
				(end 262.700516 -295.304718)
			)
			(arc
				(start 262.780272 -295.384474)
				(mid 262.796835 -295.395448)
				(end 262.81634 -295.399206)
			)
		)
		(stroke
			(width 0)
			(type solid)
		)
		(fill yes)
		(layer "F.Cu")
		(net "PCEPLL2_VDDA18_PEX2")
	)
	(gr_poly
		(pts
			(arc
				(start 265.385804 -292.198806)
				(mid 265.405327 -292.194905)
				(end 265.421872 -292.18382)
			)
			(arc
				(start 265.53668 -292.069012)
				(mid 265.547742 -292.052595)
				(end 265.551666 -292.033198)
			)
			(arc
				(start 265.551666 -290.238688)
				(mid 265.547716 -290.219301)
				(end 265.53668 -290.202874)
			)
			(arc
				(start 265.40968 -290.075874)
				(mid 265.393146 -290.064763)
				(end 265.373612 -290.060888)
			)
			(arc
				(start 265.1379 -290.060888)
				(mid 265.118377 -290.064789)
				(end 265.101832 -290.075874)
			)
			(arc
				(start 264.99439 -290.183316)
				(mid 264.977856 -290.194427)
				(end 264.958322 -290.198302)
			)
			(arc
				(start 264.217912 -290.198302)
				(mid 264.198389 -290.194401)
				(end 264.181844 -290.183316)
			)
			(arc
				(start 264.151618 -290.15309)
				(mid 264.135201 -290.142028)
				(end 264.115804 -290.138104)
			)
			(xy 263.729978 -290.138104) (xy 263.711436 -290.145978) (xy 263.710928 -290.146486)
			(arc
				(start 263.710928 -290.561522)
				(mid 263.707027 -290.581045)
				(end 263.695942 -290.59759)
			)
			(arc
				(start 263.670542 -290.62299)
				(mid 263.654008 -290.634101)
				(end 263.634474 -290.637976)
			)
			(arc
				(start 262.825738 -290.637976)
				(mid 262.806215 -290.641877)
				(end 262.78967 -290.652962)
			)
			(arc
				(start 262.700516 -290.742116)
				(mid 262.689405 -290.75865)
				(end 262.68553 -290.778184)
			)
			(arc
				(start 262.68553 -292.06825)
				(mid 262.689431 -292.087773)
				(end 262.700516 -292.104318)
			)
			(arc
				(start 262.780272 -292.184074)
				(mid 262.796835 -292.195048)
				(end 262.81634 -292.198806)
			)
		)
		(stroke
			(width 0)
			(type solid)
		)
		(fill yes)
		(layer "F.Cu")
		(net "PCEPLL4_VDDA18_PEX2")
	)
	(gr_poly
		(pts
			(arc
				(start 265.385804 -288.998406)
				(mid 265.405327 -288.994505)
				(end 265.421872 -288.98342)
			)
			(arc
				(start 265.53668 -288.868612)
				(mid 265.547742 -288.852195)
				(end 265.551666 -288.832798)
			)
			(arc
				(start 265.551666 -287.038288)
				(mid 265.547716 -287.018901)
				(end 265.53668 -287.002474)
			)
			(arc
				(start 265.40968 -286.875474)
				(mid 265.393146 -286.864363)
				(end 265.373612 -286.860488)
			)
			(arc
				(start 265.1379 -286.860488)
				(mid 265.118377 -286.864389)
				(end 265.101832 -286.875474)
			)
			(arc
				(start 264.99439 -286.982916)
				(mid 264.977856 -286.994027)
				(end 264.958322 -286.997902)
			)
			(arc
				(start 264.217912 -286.997902)
				(mid 264.198389 -286.994001)
				(end 264.181844 -286.982916)
			)
			(arc
				(start 264.151618 -286.95269)
				(mid 264.135201 -286.941628)
				(end 264.115804 -286.937704)
			)
			(xy 263.729978 -286.937704) (xy 263.711436 -286.945578) (xy 263.710928 -286.946086)
			(arc
				(start 263.710928 -287.361122)
				(mid 263.707027 -287.380645)
				(end 263.695942 -287.39719)
			)
			(arc
				(start 263.670542 -287.42259)
				(mid 263.654008 -287.433701)
				(end 263.634474 -287.437576)
			)
			(arc
				(start 262.825738 -287.437576)
				(mid 262.806215 -287.441477)
				(end 262.78967 -287.452562)
			)
			(arc
				(start 262.700516 -287.541716)
				(mid 262.689405 -287.55825)
				(end 262.68553 -287.577784)
			)
			(arc
				(start 262.68553 -288.86785)
				(mid 262.689431 -288.887373)
				(end 262.700516 -288.903918)
			)
			(arc
				(start 262.780272 -288.983674)
				(mid 262.796835 -288.994648)
				(end 262.81634 -288.998406)
			)
		)
		(stroke
			(width 0)
			(type solid)
		)
		(fill yes)
		(layer "F.Cu")
		(net "PCEPLL6_VDDA18_PEX2")
	)
	(gr_poly
		(pts
			(arc
				(start 265.385804 -285.798006)
				(mid 265.405327 -285.794105)
				(end 265.421872 -285.78302)
			)
			(arc
				(start 265.53668 -285.668212)
				(mid 265.547742 -285.651795)
				(end 265.551666 -285.632398)
			)
			(arc
				(start 265.551666 -283.837888)
				(mid 265.547716 -283.818501)
				(end 265.53668 -283.802074)
			)
			(arc
				(start 265.40968 -283.675074)
				(mid 265.393146 -283.663963)
				(end 265.373612 -283.660088)
			)
			(arc
				(start 265.1379 -283.660088)
				(mid 265.118377 -283.663989)
				(end 265.101832 -283.675074)
			)
			(arc
				(start 264.99439 -283.782516)
				(mid 264.977856 -283.793627)
				(end 264.958322 -283.797502)
			)
			(arc
				(start 264.217912 -283.797502)
				(mid 264.198389 -283.793601)
				(end 264.181844 -283.782516)
			)
			(arc
				(start 264.151618 -283.75229)
				(mid 264.135201 -283.741228)
				(end 264.115804 -283.737304)
			)
			(xy 263.729978 -283.737304) (xy 263.711436 -283.745178) (xy 263.710928 -283.745686)
			(arc
				(start 263.710928 -284.160722)
				(mid 263.707027 -284.180245)
				(end 263.695942 -284.19679)
			)
			(arc
				(start 263.670542 -284.22219)
				(mid 263.654008 -284.233301)
				(end 263.634474 -284.237176)
			)
			(arc
				(start 262.825738 -284.237176)
				(mid 262.806215 -284.241077)
				(end 262.78967 -284.252162)
			)
			(arc
				(start 262.700516 -284.341316)
				(mid 262.689405 -284.35785)
				(end 262.68553 -284.377384)
			)
			(arc
				(start 262.68553 -285.66745)
				(mid 262.689431 -285.686973)
				(end 262.700516 -285.703518)
			)
			(arc
				(start 262.780272 -285.783274)
				(mid 262.796835 -285.794248)
				(end 262.81634 -285.798006)
			)
		)
		(stroke
			(width 0)
			(type solid)
		)
		(fill yes)
		(layer "F.Cu")
		(net "PCEPLL7_VDDA18_PEX2")
	)
	(gr_poly
		(pts
			(arc
				(start 381.485902 -301.800006)
				(mid 381.505425 -301.796105)
				(end 381.52197 -301.78502)
			)
			(arc
				(start 381.636778 -301.670212)
				(mid 381.64784 -301.653795)
				(end 381.651764 -301.634398)
			)
			(arc
				(start 381.651764 -299.839888)
				(mid 381.647814 -299.820501)
				(end 381.636778 -299.804074)
			)
			(arc
				(start 381.509778 -299.677074)
				(mid 381.493244 -299.665963)
				(end 381.47371 -299.662088)
			)
			(arc
				(start 381.237998 -299.662088)
				(mid 381.218475 -299.665989)
				(end 381.20193 -299.677074)
			)
			(arc
				(start 381.094488 -299.784516)
				(mid 381.077954 -299.795627)
				(end 381.05842 -299.799502)
			)
			(arc
				(start 380.31801 -299.799502)
				(mid 380.298487 -299.795601)
				(end 380.281942 -299.784516)
			)
			(arc
				(start 380.251716 -299.75429)
				(mid 380.235299 -299.743228)
				(end 380.215902 -299.739304)
			)
			(xy 379.830076 -299.739304) (xy 379.811534 -299.747178) (xy 379.811026 -299.747686)
			(arc
				(start 379.811026 -300.162722)
				(mid 379.807125 -300.182245)
				(end 379.79604 -300.19879)
			)
			(arc
				(start 379.77064 -300.22419)
				(mid 379.754106 -300.235301)
				(end 379.734572 -300.239176)
			)
			(arc
				(start 378.925836 -300.239176)
				(mid 378.906313 -300.243077)
				(end 378.889768 -300.254162)
			)
			(arc
				(start 378.800614 -300.343316)
				(mid 378.789503 -300.35985)
				(end 378.785628 -300.379384)
			)
			(arc
				(start 378.785628 -301.66945)
				(mid 378.789529 -301.688973)
				(end 378.800614 -301.705518)
			)
			(arc
				(start 378.88037 -301.785274)
				(mid 378.896933 -301.796248)
				(end 378.916438 -301.800006)
			)
		)
		(stroke
			(width 0)
			(type solid)
		)
		(fill yes)
		(layer "F.Cu")
		(net "PCEPLL1_VDDA18_PEX3")
	)
	(gr_poly
		(pts
			(arc
				(start 381.485902 -295.399206)
				(mid 381.505425 -295.395305)
				(end 381.52197 -295.38422)
			)
			(arc
				(start 381.636778 -295.269412)
				(mid 381.64784 -295.252995)
				(end 381.651764 -295.233598)
			)
			(arc
				(start 381.651764 -293.439088)
				(mid 381.647814 -293.419701)
				(end 381.636778 -293.403274)
			)
			(arc
				(start 381.509778 -293.276274)
				(mid 381.493244 -293.265163)
				(end 381.47371 -293.261288)
			)
			(arc
				(start 381.237998 -293.261288)
				(mid 381.218475 -293.265189)
				(end 381.20193 -293.276274)
			)
			(arc
				(start 381.094488 -293.383716)
				(mid 381.077954 -293.394827)
				(end 381.05842 -293.398702)
			)
			(arc
				(start 380.31801 -293.398702)
				(mid 380.298487 -293.394801)
				(end 380.281942 -293.383716)
			)
			(arc
				(start 380.251716 -293.35349)
				(mid 380.235299 -293.342428)
				(end 380.215902 -293.338504)
			)
			(xy 379.830076 -293.338504) (xy 379.811534 -293.346378) (xy 379.811026 -293.346886)
			(arc
				(start 379.811026 -293.761922)
				(mid 379.807125 -293.781445)
				(end 379.79604 -293.79799)
			)
			(arc
				(start 379.77064 -293.82339)
				(mid 379.754106 -293.834501)
				(end 379.734572 -293.838376)
			)
			(arc
				(start 378.925836 -293.838376)
				(mid 378.906313 -293.842277)
				(end 378.889768 -293.853362)
			)
			(arc
				(start 378.800614 -293.942516)
				(mid 378.789503 -293.95905)
				(end 378.785628 -293.978584)
			)
			(arc
				(start 378.785628 -295.26865)
				(mid 378.789529 -295.288173)
				(end 378.800614 -295.304718)
			)
			(arc
				(start 378.88037 -295.384474)
				(mid 378.896933 -295.395448)
				(end 378.916438 -295.399206)
			)
		)
		(stroke
			(width 0)
			(type solid)
		)
		(fill yes)
		(layer "F.Cu")
		(net "PCEPLL2_VDDA18_PEX3")
	)
	(gr_poly
		(pts
			(arc
				(start 381.485902 -292.198806)
				(mid 381.505425 -292.194905)
				(end 381.52197 -292.18382)
			)
			(arc
				(start 381.636778 -292.069012)
				(mid 381.64784 -292.052595)
				(end 381.651764 -292.033198)
			)
			(arc
				(start 381.651764 -290.238688)
				(mid 381.647814 -290.219301)
				(end 381.636778 -290.202874)
			)
			(arc
				(start 381.509778 -290.075874)
				(mid 381.493244 -290.064763)
				(end 381.47371 -290.060888)
			)
			(arc
				(start 381.237998 -290.060888)
				(mid 381.218475 -290.064789)
				(end 381.20193 -290.075874)
			)
			(arc
				(start 381.094488 -290.183316)
				(mid 381.077954 -290.194427)
				(end 381.05842 -290.198302)
			)
			(arc
				(start 380.31801 -290.198302)
				(mid 380.298487 -290.194401)
				(end 380.281942 -290.183316)
			)
			(arc
				(start 380.251716 -290.15309)
				(mid 380.235299 -290.142028)
				(end 380.215902 -290.138104)
			)
			(xy 379.830076 -290.138104) (xy 379.811534 -290.145978) (xy 379.811026 -290.146486)
			(arc
				(start 379.811026 -290.561522)
				(mid 379.807125 -290.581045)
				(end 379.79604 -290.59759)
			)
			(arc
				(start 379.77064 -290.62299)
				(mid 379.754106 -290.634101)
				(end 379.734572 -290.637976)
			)
			(arc
				(start 378.925836 -290.637976)
				(mid 378.906313 -290.641877)
				(end 378.889768 -290.652962)
			)
			(arc
				(start 378.800614 -290.742116)
				(mid 378.789503 -290.75865)
				(end 378.785628 -290.778184)
			)
			(arc
				(start 378.785628 -292.06825)
				(mid 378.789529 -292.087773)
				(end 378.800614 -292.104318)
			)
			(arc
				(start 378.88037 -292.184074)
				(mid 378.896933 -292.195048)
				(end 378.916438 -292.198806)
			)
		)
		(stroke
			(width 0)
			(type solid)
		)
		(fill yes)
		(layer "F.Cu")
		(net "PCEPLL4_VDDA18_PEX3")
	)
	(gr_poly
		(pts
			(arc
				(start 381.485902 -288.998406)
				(mid 381.505425 -288.994505)
				(end 381.52197 -288.98342)
			)
			(arc
				(start 381.636778 -288.868612)
				(mid 381.64784 -288.852195)
				(end 381.651764 -288.832798)
			)
			(arc
				(start 381.651764 -287.038288)
				(mid 381.647814 -287.018901)
				(end 381.636778 -287.002474)
			)
			(arc
				(start 381.509778 -286.875474)
				(mid 381.493244 -286.864363)
				(end 381.47371 -286.860488)
			)
			(arc
				(start 381.237998 -286.860488)
				(mid 381.218475 -286.864389)
				(end 381.20193 -286.875474)
			)
			(arc
				(start 381.094488 -286.982916)
				(mid 381.077954 -286.994027)
				(end 381.05842 -286.997902)
			)
			(arc
				(start 380.31801 -286.997902)
				(mid 380.298487 -286.994001)
				(end 380.281942 -286.982916)
			)
			(arc
				(start 380.251716 -286.95269)
				(mid 380.235299 -286.941628)
				(end 380.215902 -286.937704)
			)
			(xy 379.830076 -286.937704) (xy 379.811534 -286.945578) (xy 379.811026 -286.946086)
			(arc
				(start 379.811026 -287.361122)
				(mid 379.807125 -287.380645)
				(end 379.79604 -287.39719)
			)
			(arc
				(start 379.77064 -287.42259)
				(mid 379.754106 -287.433701)
				(end 379.734572 -287.437576)
			)
			(arc
				(start 378.925836 -287.437576)
				(mid 378.906313 -287.441477)
				(end 378.889768 -287.452562)
			)
			(arc
				(start 378.800614 -287.541716)
				(mid 378.789503 -287.55825)
				(end 378.785628 -287.577784)
			)
			(arc
				(start 378.785628 -288.86785)
				(mid 378.789529 -288.887373)
				(end 378.800614 -288.903918)
			)
			(arc
				(start 378.88037 -288.983674)
				(mid 378.896933 -288.994648)
				(end 378.916438 -288.998406)
			)
		)
		(stroke
			(width 0)
			(type solid)
		)
		(fill yes)
		(layer "F.Cu")
		(net "PCEPLL6_VDDA18_PEX3")
	)
	(gr_poly
		(pts
			(arc
				(start 381.485902 -285.798006)
				(mid 381.505425 -285.794105)
				(end 381.52197 -285.78302)
			)
			(arc
				(start 381.636778 -285.668212)
				(mid 381.64784 -285.651795)
				(end 381.651764 -285.632398)
			)
			(arc
				(start 381.651764 -283.837888)
				(mid 381.647814 -283.818501)
				(end 381.636778 -283.802074)
			)
			(arc
				(start 381.509778 -283.675074)
				(mid 381.493244 -283.663963)
				(end 381.47371 -283.660088)
			)
			(arc
				(start 381.237998 -283.660088)
				(mid 381.218475 -283.663989)
				(end 381.20193 -283.675074)
			)
			(arc
				(start 381.094488 -283.782516)
				(mid 381.077954 -283.793627)
				(end 381.05842 -283.797502)
			)
			(arc
				(start 380.31801 -283.797502)
				(mid 380.298487 -283.793601)
				(end 380.281942 -283.782516)
			)
			(arc
				(start 380.251716 -283.75229)
				(mid 380.235299 -283.741228)
				(end 380.215902 -283.737304)
			)
			(xy 379.830076 -283.737304) (xy 379.811534 -283.745178) (xy 379.811026 -283.745686)
			(arc
				(start 379.811026 -284.160722)
				(mid 379.807125 -284.180245)
				(end 379.79604 -284.19679)
			)
			(arc
				(start 379.77064 -284.22219)
				(mid 379.754106 -284.233301)
				(end 379.734572 -284.237176)
			)
			(arc
				(start 378.925836 -284.237176)
				(mid 378.906313 -284.241077)
				(end 378.889768 -284.252162)
			)
			(arc
				(start 378.800614 -284.341316)
				(mid 378.789503 -284.35785)
				(end 378.785628 -284.377384)
			)
			(arc
				(start 378.785628 -285.66745)
				(mid 378.789529 -285.686973)
				(end 378.800614 -285.703518)
			)
			(arc
				(start 378.88037 -285.783274)
				(mid 378.896933 -285.794248)
				(end 378.916438 -285.798006)
			)
		)
		(stroke
			(width 0)
			(type solid)
		)
		(fill yes)
		(layer "F.Cu")
		(net "PCEPLL7_VDDA18_PEX3")
	)
	(gr_poly
		(pts
			(arc
				(start 69.177916 -22.717252)
				(mid 69.197303 -22.713302)
				(end 69.21373 -22.702266)
			)
			(xy 69.238622 -22.702266) (xy 69.245734 -22.709632) (xy 69.264276 -22.717252)
			(arc
				(start 72.836786 -22.717252)
				(mid 72.856309 -22.713351)
				(end 72.872854 -22.702266)
			)
			(xy 72.873616 -22.701504)
			(arc
				(start 72.873616 -18.805906)
				(mid 72.877449 -18.786549)
				(end 72.888348 -18.770092)
			)
			(arc
				(start 72.900286 -18.758154)
				(mid 72.915121 -18.722251)
				(end 72.900286 -18.686272)
			)
			(arc
				(start 72.852788 -18.638774)
				(mid 72.836254 -18.627663)
				(end 72.81672 -18.623788)
			)
			(xy 71.84771 -18.623788) (xy 71.846948 -18.623026)
			(arc
				(start 66.679318 -18.623026)
				(mid 66.659795 -18.626927)
				(end 66.64325 -18.638012)
			)
			(arc
				(start 66.625978 -18.655284)
				(mid 66.614867 -18.671818)
				(end 66.610992 -18.691352)
			)
			(arc
				(start 66.610992 -21.91512)
				(mid 66.614893 -21.934643)
				(end 66.625978 -21.951188)
			)
			(arc
				(start 66.64325 -21.96846)
				(mid 66.659784 -21.979571)
				(end 66.679318 -21.983446)
			)
			(arc
				(start 68.028312 -21.983446)
				(mid 68.047835 -21.987347)
				(end 68.06438 -21.998432)
			)
			(arc
				(start 68.275962 -22.210014)
				(mid 68.287073 -22.226548)
				(end 68.290948 -22.246082)
			)
			(arc
				(start 68.290948 -22.584918)
				(mid 68.294849 -22.604441)
				(end 68.305934 -22.620986)
			)
			(arc
				(start 68.387214 -22.702266)
				(mid 68.403748 -22.713377)
				(end 68.423282 -22.717252)
			)
		)
		(stroke
			(width 0)
			(type solid)
		)
		(fill yes)
		(layer "F.Cu")
		(net "P12V_SSD2")
	)
	(gr_poly
		(pts
			(arc
				(start 95.177864 -22.717252)
				(mid 95.197251 -22.713302)
				(end 95.213678 -22.702266)
			)
			(xy 95.23857 -22.702266) (xy 95.245682 -22.709632) (xy 95.264224 -22.717252)
			(arc
				(start 98.836734 -22.717252)
				(mid 98.856257 -22.713351)
				(end 98.872802 -22.702266)
			)
			(xy 98.873564 -22.701504)
			(arc
				(start 98.873564 -18.805906)
				(mid 98.877397 -18.786549)
				(end 98.888296 -18.770092)
			)
			(arc
				(start 98.900234 -18.758154)
				(mid 98.915069 -18.722251)
				(end 98.900234 -18.686272)
			)
			(arc
				(start 98.852736 -18.638774)
				(mid 98.836202 -18.627663)
				(end 98.816668 -18.623788)
			)
			(xy 97.847658 -18.623788) (xy 97.846896 -18.623026)
			(arc
				(start 92.679266 -18.623026)
				(mid 92.659743 -18.626927)
				(end 92.643198 -18.638012)
			)
			(arc
				(start 92.625926 -18.655284)
				(mid 92.614815 -18.671818)
				(end 92.61094 -18.691352)
			)
			(arc
				(start 92.61094 -21.91512)
				(mid 92.614841 -21.934643)
				(end 92.625926 -21.951188)
			)
			(arc
				(start 92.643198 -21.96846)
				(mid 92.659732 -21.979571)
				(end 92.679266 -21.983446)
			)
			(arc
				(start 94.02826 -21.983446)
				(mid 94.047783 -21.987347)
				(end 94.064328 -21.998432)
			)
			(arc
				(start 94.27591 -22.210014)
				(mid 94.287021 -22.226548)
				(end 94.290896 -22.246082)
			)
			(arc
				(start 94.290896 -22.584918)
				(mid 94.294797 -22.604441)
				(end 94.305882 -22.620986)
			)
			(arc
				(start 94.387162 -22.702266)
				(mid 94.403696 -22.713377)
				(end 94.42323 -22.717252)
			)
		)
		(stroke
			(width 0)
			(type solid)
		)
		(fill yes)
		(layer "F.Cu")
		(net "P12V_SSD3")
	)
	(gr_poly
		(pts
			(arc
				(start 391.478008 -22.717252)
				(mid 391.497395 -22.713302)
				(end 391.513822 -22.702266)
			)
			(xy 391.538714 -22.702266) (xy 391.545826 -22.709632) (xy 391.564368 -22.717252)
			(arc
				(start 395.136878 -22.717252)
				(mid 395.156401 -22.713351)
				(end 395.172946 -22.702266)
			)
			(xy 395.173708 -22.701504)
			(arc
				(start 395.173708 -18.805906)
				(mid 395.177541 -18.786549)
				(end 395.18844 -18.770092)
			)
			(arc
				(start 395.200378 -18.758154)
				(mid 395.215213 -18.722251)
				(end 395.200378 -18.686272)
			)
			(arc
				(start 395.15288 -18.638774)
				(mid 395.136346 -18.627663)
				(end 395.116812 -18.623788)
			)
			(xy 394.147802 -18.623788) (xy 394.14704 -18.623026)
			(arc
				(start 388.97941 -18.623026)
				(mid 388.959887 -18.626927)
				(end 388.943342 -18.638012)
			)
			(arc
				(start 388.92607 -18.655284)
				(mid 388.914959 -18.671818)
				(end 388.911084 -18.691352)
			)
			(arc
				(start 388.911084 -21.91512)
				(mid 388.914985 -21.934643)
				(end 388.92607 -21.951188)
			)
			(arc
				(start 388.943342 -21.96846)
				(mid 388.959876 -21.979571)
				(end 388.97941 -21.983446)
			)
			(arc
				(start 390.328404 -21.983446)
				(mid 390.347927 -21.987347)
				(end 390.364472 -21.998432)
			)
			(arc
				(start 390.576054 -22.210014)
				(mid 390.587165 -22.226548)
				(end 390.59104 -22.246082)
			)
			(arc
				(start 390.59104 -22.584918)
				(mid 390.594941 -22.604441)
				(end 390.606026 -22.620986)
			)
			(arc
				(start 390.687306 -22.702266)
				(mid 390.70384 -22.713377)
				(end 390.723374 -22.717252)
			)
		)
		(stroke
			(width 0)
			(type solid)
		)
		(fill yes)
		(layer "F.Cu")
		(net "P12V_SSD13")
	)
	(gr_poly
		(pts
			(arc
				(start 25.554686 -261.37743)
				(mid 25.574073 -261.37348)
				(end 25.5905 -261.362444)
			)
			(arc
				(start 25.654762 -261.298436)
				(mid 25.671208 -261.28751)
				(end 25.690576 -261.283704)
			)
			(arc
				(start 27.37358 -261.283704)
				(mid 27.392967 -261.279754)
				(end 27.409394 -261.268718)
			)
			(arc
				(start 27.619198 -261.058914)
				(mid 27.630309 -261.04238)
				(end 27.634184 -261.022846)
			)
			(arc
				(start 27.634184 -260.68528)
				(mid 27.630234 -260.665893)
				(end 27.619198 -260.649466)
			)
			(arc
				(start 27.392376 -260.422644)
				(mid 27.36174 -260.386821)
				(end 27.337004 -260.346698)
			)
			(xy 27.333448 -260.33984)
			(arc
				(start 27.113992 -260.120384)
				(mid 27.102881 -260.10385)
				(end 27.099006 -260.084316)
			)
			(arc
				(start 27.099006 -258.894326)
				(mid 27.095105 -258.874803)
				(end 27.08402 -258.858258)
			)
			(arc
				(start 27.078178 -258.852416)
				(mid 27.061644 -258.841305)
				(end 27.04211 -258.83743)
			)
			(arc
				(start 25.404826 -258.83743)
				(mid 25.385303 -258.841331)
				(end 25.368758 -258.852416)
			)
			(arc
				(start 25.225756 -258.995418)
				(mid 25.214645 -259.011952)
				(end 25.21077 -259.031486)
			)
			(arc
				(start 25.21077 -260.479794)
				(mid 25.214671 -260.499317)
				(end 25.225756 -260.515862)
			)
			(arc
				(start 25.356058 -260.646164)
				(mid 25.367169 -260.662698)
				(end 25.371044 -260.682232)
			)
			(arc
				(start 25.371044 -261.277862)
				(mid 25.374945 -261.297385)
				(end 25.38603 -261.31393)
			)
			(arc
				(start 25.434544 -261.362444)
				(mid 25.451078 -261.373555)
				(end 25.470612 -261.37743)
			)
		)
		(stroke
			(width 0)
			(type solid)
		)
		(fill yes)
		(layer "F.Cu")
		(net "P1V8_VDDA_PEX0")
	)
	(gr_poly
		(pts
			(arc
				(start 43.177968 -22.717252)
				(mid 43.197355 -22.713302)
				(end 43.213782 -22.702266)
			)
			(arc
				(start 43.238674 -22.702266)
				(mid 43.255091 -22.713328)
				(end 43.274488 -22.717252)
			)
			(arc
				(start 46.836838 -22.717252)
				(mid 46.856361 -22.713351)
				(end 46.872906 -22.702266)
			)
			(xy 46.873668 -22.701504)
			(arc
				(start 46.873668 -18.805906)
				(mid 46.877501 -18.786549)
				(end 46.8884 -18.770092)
			)
			(arc
				(start 46.900338 -18.758154)
				(mid 46.915173 -18.722251)
				(end 46.900338 -18.686272)
			)
			(arc
				(start 46.85284 -18.638774)
				(mid 46.836306 -18.627663)
				(end 46.816772 -18.623788)
			)
			(xy 45.847762 -18.623788) (xy 45.847 -18.623026)
			(arc
				(start 40.67937 -18.623026)
				(mid 40.659847 -18.626927)
				(end 40.643302 -18.638012)
			)
			(arc
				(start 40.62603 -18.655284)
				(mid 40.614919 -18.671818)
				(end 40.611044 -18.691352)
			)
			(arc
				(start 40.611044 -21.91512)
				(mid 40.614945 -21.934643)
				(end 40.62603 -21.951188)
			)
			(arc
				(start 40.643302 -21.96846)
				(mid 40.659836 -21.979571)
				(end 40.67937 -21.983446)
			)
			(arc
				(start 42.028364 -21.983446)
				(mid 42.047887 -21.987347)
				(end 42.064432 -21.998432)
			)
			(arc
				(start 42.276014 -22.210014)
				(mid 42.287125 -22.226548)
				(end 42.291 -22.246082)
			)
			(arc
				(start 42.291 -22.584918)
				(mid 42.294901 -22.604441)
				(end 42.305986 -22.620986)
			)
			(arc
				(start 42.387266 -22.702266)
				(mid 42.4038 -22.713377)
				(end 42.423334 -22.717252)
			)
		)
		(stroke
			(width 0)
			(type solid)
		)
		(fill yes)
		(layer "F.Cu")
		(net "P12V_SSD1")
	)
	(gr_poly
		(pts
			(arc
				(start 133.278118 -22.717252)
				(mid 133.297505 -22.713302)
				(end 133.313932 -22.702266)
			)
			(arc
				(start 133.338824 -22.702266)
				(mid 133.355241 -22.713328)
				(end 133.374638 -22.717252)
			)
			(arc
				(start 136.936988 -22.717252)
				(mid 136.956511 -22.713351)
				(end 136.973056 -22.702266)
			)
			(xy 136.973564 -22.701504)
			(arc
				(start 136.973564 -18.805906)
				(mid 136.977514 -18.786519)
				(end 136.98855 -18.770092)
			)
			(arc
				(start 137.000488 -18.758154)
				(mid 137.015323 -18.722251)
				(end 137.000488 -18.686272)
			)
			(arc
				(start 136.95299 -18.638774)
				(mid 136.936456 -18.627663)
				(end 136.916922 -18.623788)
			)
			(xy 135.947912 -18.623788) (xy 135.94715 -18.623026)
			(arc
				(start 130.77952 -18.623026)
				(mid 130.759997 -18.626927)
				(end 130.743452 -18.638012)
			)
			(arc
				(start 130.72618 -18.655284)
				(mid 130.715069 -18.671818)
				(end 130.711194 -18.691352)
			)
			(arc
				(start 130.711194 -21.91512)
				(mid 130.715095 -21.934643)
				(end 130.72618 -21.951188)
			)
			(arc
				(start 130.743452 -21.96846)
				(mid 130.759986 -21.979571)
				(end 130.77952 -21.983446)
			)
			(arc
				(start 132.128514 -21.983446)
				(mid 132.148037 -21.987347)
				(end 132.164582 -21.998432)
			)
			(arc
				(start 132.376164 -22.210014)
				(mid 132.387275 -22.226548)
				(end 132.39115 -22.246082)
			)
			(arc
				(start 132.39115 -22.584918)
				(mid 132.395051 -22.604441)
				(end 132.406136 -22.620986)
			)
			(arc
				(start 132.487416 -22.702266)
				(mid 132.50395 -22.713377)
				(end 132.523484 -22.717252)
			)
		)
		(stroke
			(width 0)
			(type solid)
		)
		(fill yes)
		(layer "F.Cu")
		(net "P12V_SSD4")
	)
	(gr_poly
		(pts
			(arc
				(start 159.278066 -22.717252)
				(mid 159.297453 -22.713302)
				(end 159.31388 -22.702266)
			)
			(arc
				(start 159.338772 -22.702266)
				(mid 159.355189 -22.713328)
				(end 159.374586 -22.717252)
			)
			(arc
				(start 162.936936 -22.717252)
				(mid 162.956459 -22.713351)
				(end 162.973004 -22.702266)
			)
			(xy 162.973512 -22.701504)
			(arc
				(start 162.973512 -18.805906)
				(mid 162.977462 -18.786519)
				(end 162.988498 -18.770092)
			)
			(arc
				(start 163.000436 -18.758154)
				(mid 163.015271 -18.722251)
				(end 163.000436 -18.686272)
			)
			(arc
				(start 162.952938 -18.638774)
				(mid 162.936404 -18.627663)
				(end 162.91687 -18.623788)
			)
			(xy 161.94786 -18.623788) (xy 161.947098 -18.623026)
			(arc
				(start 156.779468 -18.623026)
				(mid 156.759945 -18.626927)
				(end 156.7434 -18.638012)
			)
			(arc
				(start 156.726128 -18.655284)
				(mid 156.715017 -18.671818)
				(end 156.711142 -18.691352)
			)
			(arc
				(start 156.711142 -21.91512)
				(mid 156.715043 -21.934643)
				(end 156.726128 -21.951188)
			)
			(arc
				(start 156.7434 -21.96846)
				(mid 156.759934 -21.979571)
				(end 156.779468 -21.983446)
			)
			(arc
				(start 158.128462 -21.983446)
				(mid 158.147985 -21.987347)
				(end 158.16453 -21.998432)
			)
			(arc
				(start 158.376112 -22.210014)
				(mid 158.387223 -22.226548)
				(end 158.391098 -22.246082)
			)
			(arc
				(start 158.391098 -22.584918)
				(mid 158.394999 -22.604441)
				(end 158.406084 -22.620986)
			)
			(arc
				(start 158.487364 -22.702266)
				(mid 158.503898 -22.713377)
				(end 158.523432 -22.717252)
			)
		)
		(stroke
			(width 0)
			(type solid)
		)
		(fill yes)
		(layer "F.Cu")
		(net "P12V_SSD5")
	)
	(gr_poly
		(pts
			(arc
				(start 301.377858 -22.717252)
				(mid 301.397245 -22.713302)
				(end 301.413672 -22.702266)
			)
			(arc
				(start 301.438564 -22.702266)
				(mid 301.454981 -22.713328)
				(end 301.474378 -22.717252)
			)
			(arc
				(start 305.036728 -22.717252)
				(mid 305.056251 -22.713351)
				(end 305.072796 -22.702266)
			)
			(xy 305.073304 -22.701504)
			(arc
				(start 305.073304 -18.805906)
				(mid 305.077254 -18.786519)
				(end 305.08829 -18.770092)
			)
			(arc
				(start 305.100228 -18.758154)
				(mid 305.115063 -18.722251)
				(end 305.100228 -18.686272)
			)
			(arc
				(start 305.05273 -18.638774)
				(mid 305.036196 -18.627663)
				(end 305.016662 -18.623788)
			)
			(xy 304.047652 -18.623788) (xy 304.04689 -18.623026)
			(arc
				(start 298.87926 -18.623026)
				(mid 298.859737 -18.626927)
				(end 298.843192 -18.638012)
			)
			(arc
				(start 298.82592 -18.655284)
				(mid 298.814809 -18.671818)
				(end 298.810934 -18.691352)
			)
			(arc
				(start 298.810934 -21.91512)
				(mid 298.814835 -21.934643)
				(end 298.82592 -21.951188)
			)
			(arc
				(start 298.843192 -21.96846)
				(mid 298.859726 -21.979571)
				(end 298.87926 -21.983446)
			)
			(arc
				(start 300.228254 -21.983446)
				(mid 300.247777 -21.987347)
				(end 300.264322 -21.998432)
			)
			(arc
				(start 300.475904 -22.210014)
				(mid 300.487015 -22.226548)
				(end 300.49089 -22.246082)
			)
			(arc
				(start 300.49089 -22.584918)
				(mid 300.494791 -22.604441)
				(end 300.505876 -22.620986)
			)
			(arc
				(start 300.587156 -22.702266)
				(mid 300.60369 -22.713377)
				(end 300.623224 -22.717252)
			)
		)
		(stroke
			(width 0)
			(type solid)
		)
		(fill yes)
		(layer "F.Cu")
		(net "P12V_SSD10")
	)
	(gr_poly
		(pts
			(arc
				(start 327.377806 -22.717252)
				(mid 327.397193 -22.713302)
				(end 327.41362 -22.702266)
			)
			(arc
				(start 327.438512 -22.702266)
				(mid 327.454929 -22.713328)
				(end 327.474326 -22.717252)
			)
			(arc
				(start 331.036676 -22.717252)
				(mid 331.056199 -22.713351)
				(end 331.072744 -22.702266)
			)
			(xy 331.073252 -22.701504)
			(arc
				(start 331.073252 -18.805906)
				(mid 331.077202 -18.786519)
				(end 331.088238 -18.770092)
			)
			(arc
				(start 331.100176 -18.758154)
				(mid 331.115011 -18.722251)
				(end 331.100176 -18.686272)
			)
			(arc
				(start 331.052678 -18.638774)
				(mid 331.036144 -18.627663)
				(end 331.01661 -18.623788)
			)
			(xy 330.0476 -18.623788) (xy 330.046838 -18.623026)
			(arc
				(start 324.879208 -18.623026)
				(mid 324.859685 -18.626927)
				(end 324.84314 -18.638012)
			)
			(arc
				(start 324.825868 -18.655284)
				(mid 324.814757 -18.671818)
				(end 324.810882 -18.691352)
			)
			(arc
				(start 324.810882 -21.91512)
				(mid 324.814783 -21.934643)
				(end 324.825868 -21.951188)
			)
			(arc
				(start 324.84314 -21.96846)
				(mid 324.859674 -21.979571)
				(end 324.879208 -21.983446)
			)
			(arc
				(start 326.228202 -21.983446)
				(mid 326.247725 -21.987347)
				(end 326.26427 -21.998432)
			)
			(arc
				(start 326.475852 -22.210014)
				(mid 326.486963 -22.226548)
				(end 326.490838 -22.246082)
			)
			(arc
				(start 326.490838 -22.584918)
				(mid 326.494739 -22.604441)
				(end 326.505824 -22.620986)
			)
			(arc
				(start 326.587104 -22.702266)
				(mid 326.603638 -22.713377)
				(end 326.623172 -22.717252)
			)
		)
		(stroke
			(width 0)
			(type solid)
		)
		(fill yes)
		(layer "F.Cu")
		(net "P12V_SSD11")
	)
	(gr_poly
		(pts
			(arc
				(start 365.47806 -22.717252)
				(mid 365.497447 -22.713302)
				(end 365.513874 -22.702266)
			)
			(arc
				(start 365.538766 -22.702266)
				(mid 365.555183 -22.713328)
				(end 365.57458 -22.717252)
			)
			(arc
				(start 369.13693 -22.717252)
				(mid 369.156453 -22.713351)
				(end 369.172998 -22.702266)
			)
			(xy 369.17376 -22.701504)
			(arc
				(start 369.17376 -18.805906)
				(mid 369.177593 -18.786549)
				(end 369.188492 -18.770092)
			)
			(arc
				(start 369.20043 -18.758154)
				(mid 369.215265 -18.722251)
				(end 369.20043 -18.686272)
			)
			(arc
				(start 369.152932 -18.638774)
				(mid 369.136398 -18.627663)
				(end 369.116864 -18.623788)
			)
			(xy 368.147854 -18.623788) (xy 368.147092 -18.623026)
			(arc
				(start 362.979462 -18.623026)
				(mid 362.959939 -18.626927)
				(end 362.943394 -18.638012)
			)
			(arc
				(start 362.926122 -18.655284)
				(mid 362.915011 -18.671818)
				(end 362.911136 -18.691352)
			)
			(arc
				(start 362.911136 -21.91512)
				(mid 362.915037 -21.934643)
				(end 362.926122 -21.951188)
			)
			(arc
				(start 362.943394 -21.96846)
				(mid 362.959928 -21.979571)
				(end 362.979462 -21.983446)
			)
			(arc
				(start 364.328456 -21.983446)
				(mid 364.347979 -21.987347)
				(end 364.364524 -21.998432)
			)
			(arc
				(start 364.576106 -22.210014)
				(mid 364.587217 -22.226548)
				(end 364.591092 -22.246082)
			)
			(arc
				(start 364.591092 -22.584918)
				(mid 364.594993 -22.604441)
				(end 364.606078 -22.620986)
			)
			(arc
				(start 364.687358 -22.702266)
				(mid 364.703892 -22.713377)
				(end 364.723426 -22.717252)
			)
		)
		(stroke
			(width 0)
			(type solid)
		)
		(fill yes)
		(layer "F.Cu")
		(net "P12V_SSD12")
	)
	(gr_poly
		(pts
			(arc
				(start 417.477956 -22.717252)
				(mid 417.497343 -22.713302)
				(end 417.51377 -22.702266)
			)
			(arc
				(start 417.538662 -22.702266)
				(mid 417.555079 -22.713328)
				(end 417.574476 -22.717252)
			)
			(arc
				(start 421.136826 -22.717252)
				(mid 421.156349 -22.713351)
				(end 421.172894 -22.702266)
			)
			(xy 421.173656 -22.701504)
			(arc
				(start 421.173656 -18.805906)
				(mid 421.177489 -18.786549)
				(end 421.188388 -18.770092)
			)
			(arc
				(start 421.200326 -18.758154)
				(mid 421.215161 -18.722251)
				(end 421.200326 -18.686272)
			)
			(arc
				(start 421.152828 -18.638774)
				(mid 421.136294 -18.627663)
				(end 421.11676 -18.623788)
			)
			(xy 420.14775 -18.623788) (xy 420.146988 -18.623026)
			(arc
				(start 414.979358 -18.623026)
				(mid 414.959835 -18.626927)
				(end 414.94329 -18.638012)
			)
			(arc
				(start 414.926018 -18.655284)
				(mid 414.914907 -18.671818)
				(end 414.911032 -18.691352)
			)
			(arc
				(start 414.911032 -21.91512)
				(mid 414.914933 -21.934643)
				(end 414.926018 -21.951188)
			)
			(arc
				(start 414.94329 -21.96846)
				(mid 414.959824 -21.979571)
				(end 414.979358 -21.983446)
			)
			(arc
				(start 416.328352 -21.983446)
				(mid 416.347875 -21.987347)
				(end 416.36442 -21.998432)
			)
			(arc
				(start 416.576002 -22.210014)
				(mid 416.587113 -22.226548)
				(end 416.590988 -22.246082)
			)
			(arc
				(start 416.590988 -22.584918)
				(mid 416.594889 -22.604441)
				(end 416.605974 -22.620986)
			)
			(arc
				(start 416.687254 -22.702266)
				(mid 416.703788 -22.713377)
				(end 416.723322 -22.717252)
			)
		)
		(stroke
			(width 0)
			(type solid)
		)
		(fill yes)
		(layer "F.Cu")
		(net "P12V_SSD14")
	)
	(gr_poly
		(pts
			(arc
				(start 443.477904 -22.717252)
				(mid 443.497291 -22.713302)
				(end 443.513718 -22.702266)
			)
			(arc
				(start 443.53861 -22.702266)
				(mid 443.555027 -22.713328)
				(end 443.574424 -22.717252)
			)
			(arc
				(start 447.136774 -22.717252)
				(mid 447.156297 -22.713351)
				(end 447.172842 -22.702266)
			)
			(xy 447.173604 -22.701504)
			(arc
				(start 447.173604 -18.805906)
				(mid 447.177437 -18.786549)
				(end 447.188336 -18.770092)
			)
			(arc
				(start 447.200274 -18.758154)
				(mid 447.215109 -18.722251)
				(end 447.200274 -18.686272)
			)
			(arc
				(start 447.152776 -18.638774)
				(mid 447.136242 -18.627663)
				(end 447.116708 -18.623788)
			)
			(xy 446.147698 -18.623788) (xy 446.146936 -18.623026)
			(arc
				(start 440.979306 -18.623026)
				(mid 440.959783 -18.626927)
				(end 440.943238 -18.638012)
			)
			(arc
				(start 440.925966 -18.655284)
				(mid 440.914855 -18.671818)
				(end 440.91098 -18.691352)
			)
			(arc
				(start 440.91098 -21.91512)
				(mid 440.914881 -21.934643)
				(end 440.925966 -21.951188)
			)
			(arc
				(start 440.943238 -21.96846)
				(mid 440.959772 -21.979571)
				(end 440.979306 -21.983446)
			)
			(arc
				(start 442.3283 -21.983446)
				(mid 442.347823 -21.987347)
				(end 442.364368 -21.998432)
			)
			(arc
				(start 442.57595 -22.210014)
				(mid 442.587061 -22.226548)
				(end 442.590936 -22.246082)
			)
			(arc
				(start 442.590936 -22.584918)
				(mid 442.594837 -22.604441)
				(end 442.605922 -22.620986)
			)
			(arc
				(start 442.687202 -22.702266)
				(mid 442.703736 -22.713377)
				(end 442.72327 -22.717252)
			)
		)
		(stroke
			(width 0)
			(type solid)
		)
		(fill yes)
		(layer "F.Cu")
		(net "P12V_SSD15")
	)
	(gr_poly
		(pts
			(xy 211.896452 -117.711982) (xy 211.896452 -116.581428) (xy 211.896452 -113.652554) (xy 211.894928 -113.646458)
			(xy 211.894928 -111.986822) (xy 211.689188 -111.781082) (xy 208.651348 -111.781082) (xy 208.549748 -111.882682)
			(arc
				(start 208.549748 -113.432336)
				(mid 208.545847 -113.451859)
				(end 208.534762 -113.468404)
			)
			(arc
				(start 208.381346 -113.62182)
				(mid 208.370235 -113.638354)
				(end 208.36636 -113.657888)
			)
			(xy 208.36636 -113.926112) (xy 208.373218 -113.93297)
			(arc
				(start 209.348578 -113.93297)
				(mid 209.368101 -113.929069)
				(end 209.384646 -113.917984)
			)
			(arc
				(start 209.798412 -113.503964)
				(mid 209.814946 -113.492853)
				(end 209.83448 -113.488978)
			)
			(arc
				(start 210.629754 -113.488978)
				(mid 210.649277 -113.492879)
				(end 210.665822 -113.503964)
			)
			(arc
				(start 210.697064 -113.535206)
				(mid 210.708175 -113.55174)
				(end 210.71205 -113.571274)
			)
			(arc
				(start 210.71205 -116.290598)
				(mid 210.708149 -116.310121)
				(end 210.697064 -116.326666)
			)
			(arc
				(start 210.67776 -116.34597)
				(mid 210.661226 -116.357081)
				(end 210.641692 -116.360956)
			)
			(arc
				(start 209.741262 -116.360956)
				(mid 209.721739 -116.357055)
				(end 209.705194 -116.34597)
			)
			(arc
				(start 209.645758 -116.286534)
				(mid 209.629224 -116.275423)
				(end 209.60969 -116.271548)
			)
			(xy 208.504028 -116.271548) (xy 208.485486 -116.279168) (xy 208.482692 -116.281962) (xy 208.482692 -117.700298)
			(xy 208.482692 -118.041166) (xy 208.498948 -118.057422)
			(arc
				(start 208.528412 -118.086886)
				(mid 208.544946 -118.097997)
				(end 208.56448 -118.101872)
			)
			(xy 210.872832 -118.101872) (xy 211.506562 -118.101872)
		)
		(stroke
			(width 0)
			(type solid)
		)
		(fill yes)
		(layer "F.Cu")
		(net "GND")
	)
	(gr_poly
		(pts
			(arc
				(start 224.070672 -276.739096)
				(mid 224.090029 -276.735263)
				(end 224.106486 -276.724364)
			)
			(arc
				(start 224.271586 -276.559264)
				(mid 224.282512 -276.542818)
				(end 224.286318 -276.52345)
			)
			(arc
				(start 224.286318 -275.875242)
				(mid 224.287335 -275.865126)
				(end 224.290382 -275.85543)
			)
			(xy 224.29851 -275.836126)
			(arc
				(start 224.299018 -275.82749)
				(mid 224.303517 -275.809845)
				(end 224.314004 -275.794978)
			)
			(arc
				(start 226.68103 -273.427952)
				(mid 226.692141 -273.411418)
				(end 226.696016 -273.391884)
			)
			(arc
				(start 226.696016 -261.900924)
				(mid 226.692115 -261.881401)
				(end 226.68103 -261.864856)
			)
			(xy 226.527868 -261.711694) (xy 226.520756 -261.704328) (xy 226.50196 -261.696708)
			(arc
				(start 220.295978 -261.696708)
				(mid 220.276455 -261.700609)
				(end 220.25991 -261.711694)
			)
			(xy 219.982034 -261.98957) (xy 219.974668 -261.996682) (xy 219.967048 -262.015478) (xy 219.967048 -272.085054)
			(xy 219.512642 -272.53946) (xy 216.218008 -272.53946) (xy 215.882474 -272.874994) (xy 215.882474 -276.751034)
			(arc
				(start 215.898984 -276.75078)
				(mid 216.16893 -276.862596)
				(end 216.280746 -277.132542)
			)
			(arc
				(start 216.280746 -277.132542)
				(mid 216.228675 -277.325016)
				(end 216.08669 -277.465028)
			)
			(xy 216.14003 -277.518368) (xy 223.2914 -277.518368)
		)
		(stroke
			(width 0)
			(type solid)
		)
		(fill yes)
		(layer "F.Cu")
		(net "P1V25_PEX1")
	)
	(gr_poly
		(pts
			(arc
				(start 31.133542 -296.639742)
				(mid 31.153036 -296.635958)
				(end 31.16961 -296.62501)
			)
			(arc
				(start 31.233618 -296.561002)
				(mid 31.244729 -296.544468)
				(end 31.248604 -296.524934)
			)
			(arc
				(start 31.248604 -296.382186)
				(mid 31.252505 -296.362663)
				(end 31.26359 -296.346118)
			)
			(arc
				(start 31.310072 -296.299636)
				(mid 31.326606 -296.288525)
				(end 31.34614 -296.28465)
			)
			(arc
				(start 31.392876 -296.28465)
				(mid 31.412263 -296.2807)
				(end 31.42869 -296.269664)
			)
			(arc
				(start 31.476442 -296.222166)
				(mid 31.492859 -296.211104)
				(end 31.512256 -296.20718)
			)
			(arc
				(start 31.943802 -296.20718)
				(mid 31.963189 -296.21113)
				(end 31.979616 -296.222166)
			)
			(arc
				(start 32.027368 -296.269664)
				(mid 32.043785 -296.280726)
				(end 32.063182 -296.28465)
			)
			(arc
				(start 32.668464 -296.28465)
				(mid 32.687987 -296.280749)
				(end 32.704532 -296.269664)
			)
			(arc
				(start 32.728916 -296.24528)
				(mid 32.740027 -296.228746)
				(end 32.743902 -296.209212)
			)
			(arc
				(start 32.743902 -295.79316)
				(mid 32.740001 -295.773637)
				(end 32.728916 -295.757092)
			)
			(arc
				(start 32.700722 -295.728898)
				(mid 32.684188 -295.717787)
				(end 32.664654 -295.713912)
			)
			(arc
				(start 30.512004 -295.713912)
				(mid 30.492481 -295.717813)
				(end 30.475936 -295.728898)
			)
			(arc
				(start 30.336998 -295.867836)
				(mid 30.325887 -295.88437)
				(end 30.322012 -295.903904)
			)
			(arc
				(start 30.322012 -296.537126)
				(mid 30.325913 -296.556649)
				(end 30.336998 -296.573194)
			)
			(arc
				(start 30.38856 -296.624756)
				(mid 30.405094 -296.635867)
				(end 30.424628 -296.639742)
			)
		)
		(stroke
			(width 0)
			(type solid)
		)
		(fill yes)
		(layer "F.Cu")
		(net "PCEPLL0_VDDA18_PEX0_R")
	)
	(gr_poly
		(pts
			(arc
				(start 33.185862 -298.599606)
				(mid 33.205385 -298.595705)
				(end 33.22193 -298.58462)
			)
			(arc
				(start 33.345882 -298.460668)
				(mid 33.356993 -298.444134)
				(end 33.360868 -298.4246)
			)
			(arc
				(start 33.360868 -296.648886)
				(mid 33.356967 -296.629363)
				(end 33.345882 -296.612818)
			)
			(arc
				(start 33.209738 -296.476674)
				(mid 33.193204 -296.465563)
				(end 33.17367 -296.461688)
			)
			(arc
				(start 32.937958 -296.461688)
				(mid 32.918435 -296.465589)
				(end 32.90189 -296.476674)
			)
			(arc
				(start 32.794448 -296.584116)
				(mid 32.777914 -296.595227)
				(end 32.75838 -296.599102)
			)
			(arc
				(start 32.01797 -296.599102)
				(mid 31.998447 -296.595201)
				(end 31.981902 -296.584116)
			)
			(arc
				(start 31.87446 -296.476674)
				(mid 31.857926 -296.465563)
				(end 31.838392 -296.461688)
			)
			(arc
				(start 31.617666 -296.461688)
				(mid 31.598143 -296.465589)
				(end 31.581598 -296.476674)
			)
			(arc
				(start 31.525972 -296.5323)
				(mid 31.514861 -296.548834)
				(end 31.510986 -296.568368)
			)
			(arc
				(start 31.510986 -296.962322)
				(mid 31.507085 -296.981845)
				(end 31.496 -296.99839)
			)
			(arc
				(start 31.4706 -297.02379)
				(mid 31.454066 -297.034901)
				(end 31.434532 -297.038776)
			)
			(arc
				(start 30.625796 -297.038776)
				(mid 30.606273 -297.042677)
				(end 30.589728 -297.053762)
			)
			(arc
				(start 30.500574 -297.142916)
				(mid 30.489463 -297.15945)
				(end 30.485588 -297.178984)
			)
			(arc
				(start 30.485588 -298.46905)
				(mid 30.489489 -298.488573)
				(end 30.500574 -298.505118)
			)
			(arc
				(start 30.58033 -298.584874)
				(mid 30.596893 -298.595848)
				(end 30.616398 -298.599606)
			)
		)
		(stroke
			(width 0)
			(type solid)
		)
		(fill yes)
		(layer "F.Cu")
		(net "PCEPLL0_VDDA18_PEX0")
	)
	(gr_poly
		(pts
			(arc
				(start 147.23364 -296.639742)
				(mid 147.253134 -296.635958)
				(end 147.269708 -296.62501)
			)
			(arc
				(start 147.333716 -296.561002)
				(mid 147.344827 -296.544468)
				(end 147.348702 -296.524934)
			)
			(arc
				(start 147.348702 -296.382186)
				(mid 147.352603 -296.362663)
				(end 147.363688 -296.346118)
			)
			(arc
				(start 147.41017 -296.299636)
				(mid 147.426704 -296.288525)
				(end 147.446238 -296.28465)
			)
			(arc
				(start 147.492974 -296.28465)
				(mid 147.512361 -296.2807)
				(end 147.528788 -296.269664)
			)
			(arc
				(start 147.57654 -296.222166)
				(mid 147.592957 -296.211104)
				(end 147.612354 -296.20718)
			)
			(arc
				(start 148.0439 -296.20718)
				(mid 148.063287 -296.21113)
				(end 148.079714 -296.222166)
			)
			(arc
				(start 148.127466 -296.269664)
				(mid 148.143883 -296.280726)
				(end 148.16328 -296.28465)
			)
			(arc
				(start 148.768562 -296.28465)
				(mid 148.788085 -296.280749)
				(end 148.80463 -296.269664)
			)
			(arc
				(start 148.829014 -296.24528)
				(mid 148.840125 -296.228746)
				(end 148.844 -296.209212)
			)
			(arc
				(start 148.844 -295.79316)
				(mid 148.840099 -295.773637)
				(end 148.829014 -295.757092)
			)
			(arc
				(start 148.80082 -295.728898)
				(mid 148.784286 -295.717787)
				(end 148.764752 -295.713912)
			)
			(arc
				(start 146.612102 -295.713912)
				(mid 146.592579 -295.717813)
				(end 146.576034 -295.728898)
			)
			(arc
				(start 146.437096 -295.867836)
				(mid 146.425985 -295.88437)
				(end 146.42211 -295.903904)
			)
			(arc
				(start 146.42211 -296.537126)
				(mid 146.426011 -296.556649)
				(end 146.437096 -296.573194)
			)
			(arc
				(start 146.488658 -296.624756)
				(mid 146.505192 -296.635867)
				(end 146.524726 -296.639742)
			)
		)
		(stroke
			(width 0)
			(type solid)
		)
		(fill yes)
		(layer "F.Cu")
		(net "PCEPLL0_VDDA18_PEX1_R")
	)
	(gr_poly
		(pts
			(arc
				(start 149.28596 -298.599606)
				(mid 149.305483 -298.595705)
				(end 149.322028 -298.58462)
			)
			(arc
				(start 149.44598 -298.460668)
				(mid 149.457091 -298.444134)
				(end 149.460966 -298.4246)
			)
			(arc
				(start 149.460966 -296.648886)
				(mid 149.457065 -296.629363)
				(end 149.44598 -296.612818)
			)
			(arc
				(start 149.309836 -296.476674)
				(mid 149.293302 -296.465563)
				(end 149.273768 -296.461688)
			)
			(arc
				(start 149.038056 -296.461688)
				(mid 149.018533 -296.465589)
				(end 149.001988 -296.476674)
			)
			(arc
				(start 148.894546 -296.584116)
				(mid 148.878012 -296.595227)
				(end 148.858478 -296.599102)
			)
			(arc
				(start 148.118068 -296.599102)
				(mid 148.098545 -296.595201)
				(end 148.082 -296.584116)
			)
			(arc
				(start 147.974558 -296.476674)
				(mid 147.958024 -296.465563)
				(end 147.93849 -296.461688)
			)
			(arc
				(start 147.717764 -296.461688)
				(mid 147.698241 -296.465589)
				(end 147.681696 -296.476674)
			)
			(arc
				(start 147.62607 -296.5323)
				(mid 147.614959 -296.548834)
				(end 147.611084 -296.568368)
			)
			(arc
				(start 147.611084 -296.962322)
				(mid 147.607183 -296.981845)
				(end 147.596098 -296.99839)
			)
			(arc
				(start 147.570698 -297.02379)
				(mid 147.554164 -297.034901)
				(end 147.53463 -297.038776)
			)
			(arc
				(start 146.725894 -297.038776)
				(mid 146.706371 -297.042677)
				(end 146.689826 -297.053762)
			)
			(arc
				(start 146.600672 -297.142916)
				(mid 146.589561 -297.15945)
				(end 146.585686 -297.178984)
			)
			(arc
				(start 146.585686 -298.46905)
				(mid 146.589587 -298.488573)
				(end 146.600672 -298.505118)
			)
			(arc
				(start 146.680428 -298.584874)
				(mid 146.696991 -298.595848)
				(end 146.716496 -298.599606)
			)
		)
		(stroke
			(width 0)
			(type solid)
		)
		(fill yes)
		(layer "F.Cu")
		(net "PCEPLL0_VDDA18_PEX1")
	)
	(gr_poly
		(pts
			(arc
				(start 263.333484 -296.639742)
				(mid 263.352978 -296.635958)
				(end 263.369552 -296.62501)
			)
			(arc
				(start 263.43356 -296.561002)
				(mid 263.444671 -296.544468)
				(end 263.448546 -296.524934)
			)
			(arc
				(start 263.448546 -296.382186)
				(mid 263.452447 -296.362663)
				(end 263.463532 -296.346118)
			)
			(arc
				(start 263.510014 -296.299636)
				(mid 263.526548 -296.288525)
				(end 263.546082 -296.28465)
			)
			(arc
				(start 263.592818 -296.28465)
				(mid 263.612205 -296.2807)
				(end 263.628632 -296.269664)
			)
			(arc
				(start 263.676384 -296.222166)
				(mid 263.692801 -296.211104)
				(end 263.712198 -296.20718)
			)
			(arc
				(start 264.143744 -296.20718)
				(mid 264.163131 -296.21113)
				(end 264.179558 -296.222166)
			)
			(arc
				(start 264.22731 -296.269664)
				(mid 264.243727 -296.280726)
				(end 264.263124 -296.28465)
			)
			(arc
				(start 264.868406 -296.28465)
				(mid 264.887929 -296.280749)
				(end 264.904474 -296.269664)
			)
			(arc
				(start 264.928858 -296.24528)
				(mid 264.939969 -296.228746)
				(end 264.943844 -296.209212)
			)
			(arc
				(start 264.943844 -295.79316)
				(mid 264.939943 -295.773637)
				(end 264.928858 -295.757092)
			)
			(arc
				(start 264.900664 -295.728898)
				(mid 264.88413 -295.717787)
				(end 264.864596 -295.713912)
			)
			(arc
				(start 262.711946 -295.713912)
				(mid 262.692423 -295.717813)
				(end 262.675878 -295.728898)
			)
			(arc
				(start 262.53694 -295.867836)
				(mid 262.525829 -295.88437)
				(end 262.521954 -295.903904)
			)
			(arc
				(start 262.521954 -296.537126)
				(mid 262.525855 -296.556649)
				(end 262.53694 -296.573194)
			)
			(arc
				(start 262.588502 -296.624756)
				(mid 262.605036 -296.635867)
				(end 262.62457 -296.639742)
			)
		)
		(stroke
			(width 0)
			(type solid)
		)
		(fill yes)
		(layer "F.Cu")
		(net "PCEPLL0_VDDA18_PEX2_R")
	)
	(gr_poly
		(pts
			(arc
				(start 263.550146 -414.650428)
				(mid 263.569669 -414.646527)
				(end 263.586214 -414.635442)
			)
			(arc
				(start 264.71626 -413.505396)
				(mid 264.727371 -413.488862)
				(end 264.731246 -413.469328)
			)
			(arc
				(start 264.731246 -397.83639)
				(mid 264.727345 -397.816867)
				(end 264.71626 -397.800322)
			)
			(arc
				(start 262.915654 -395.999716)
				(mid 262.904543 -395.983182)
				(end 262.900668 -395.963648)
			)
			(arc
				(start 262.900668 -393.551664)
				(mid 262.896767 -393.532141)
				(end 262.885682 -393.515596)
			)
			(arc
				(start 261.51586 -392.145774)
				(mid 261.499326 -392.134663)
				(end 261.479792 -392.130788)
			)
			(arc
				(start 255.25095 -392.130788)
				(mid 255.231427 -392.134689)
				(end 255.214882 -392.145774)
			)
			(arc
				(start 254.616204 -392.744452)
				(mid 254.605093 -392.760986)
				(end 254.601218 -392.78052)
			)
			(arc
				(start 254.601218 -398.561306)
				(mid 254.597317 -398.580829)
				(end 254.586232 -398.597374)
			)
			(arc
				(start 253.530862 -399.652998)
				(mid 253.514328 -399.664109)
				(end 253.494794 -399.667984)
			)
			(arc
				(start 246.96674 -399.667984)
				(mid 246.947217 -399.671885)
				(end 246.930672 -399.68297)
			)
			(arc
				(start 244.422168 -402.191474)
				(mid 244.405634 -402.202585)
				(end 244.3861 -402.20646)
			)
			(arc
				(start 239.48898 -402.20646)
				(mid 239.469457 -402.210361)
				(end 239.452912 -402.221446)
			)
			(arc
				(start 238.291878 -403.38248)
				(mid 238.280767 -403.399014)
				(end 238.276892 -403.418548)
			)
			(arc
				(start 238.276892 -413.657288)
				(mid 238.280793 -413.676811)
				(end 238.291878 -413.693356)
			)
			(arc
				(start 239.233964 -414.635442)
				(mid 239.250498 -414.646553)
				(end 239.270032 -414.650428)
			)
		)
		(stroke
			(width 0)
			(type solid)
		)
		(fill yes)
		(layer "F.Cu")
		(net "GND")
	)
	(gr_poly
		(pts
			(arc
				(start 265.385804 -298.599606)
				(mid 265.405327 -298.595705)
				(end 265.421872 -298.58462)
			)
			(arc
				(start 265.545824 -298.460668)
				(mid 265.556935 -298.444134)
				(end 265.56081 -298.4246)
			)
			(arc
				(start 265.56081 -296.648886)
				(mid 265.556909 -296.629363)
				(end 265.545824 -296.612818)
			)
			(arc
				(start 265.40968 -296.476674)
				(mid 265.393146 -296.465563)
				(end 265.373612 -296.461688)
			)
			(arc
				(start 265.1379 -296.461688)
				(mid 265.118377 -296.465589)
				(end 265.101832 -296.476674)
			)
			(arc
				(start 264.99439 -296.584116)
				(mid 264.977856 -296.595227)
				(end 264.958322 -296.599102)
			)
			(arc
				(start 264.217912 -296.599102)
				(mid 264.198389 -296.595201)
				(end 264.181844 -296.584116)
			)
			(arc
				(start 264.074402 -296.476674)
				(mid 264.057868 -296.465563)
				(end 264.038334 -296.461688)
			)
			(arc
				(start 263.817608 -296.461688)
				(mid 263.798085 -296.465589)
				(end 263.78154 -296.476674)
			)
			(arc
				(start 263.725914 -296.5323)
				(mid 263.714803 -296.548834)
				(end 263.710928 -296.568368)
			)
			(arc
				(start 263.710928 -296.962322)
				(mid 263.707027 -296.981845)
				(end 263.695942 -296.99839)
			)
			(arc
				(start 263.670542 -297.02379)
				(mid 263.654008 -297.034901)
				(end 263.634474 -297.038776)
			)
			(arc
				(start 262.825738 -297.038776)
				(mid 262.806215 -297.042677)
				(end 262.78967 -297.053762)
			)
			(arc
				(start 262.700516 -297.142916)
				(mid 262.689405 -297.15945)
				(end 262.68553 -297.178984)
			)
			(arc
				(start 262.68553 -298.46905)
				(mid 262.689431 -298.488573)
				(end 262.700516 -298.505118)
			)
			(arc
				(start 262.780272 -298.584874)
				(mid 262.796835 -298.595848)
				(end 262.81634 -298.599606)
			)
		)
		(stroke
			(width 0)
			(type solid)
		)
		(fill yes)
		(layer "F.Cu")
		(net "PCEPLL0_VDDA18_PEX2")
	)
	(gr_poly
		(pts
			(arc
				(start 379.433582 -296.639742)
				(mid 379.453076 -296.635958)
				(end 379.46965 -296.62501)
			)
			(arc
				(start 379.533658 -296.561002)
				(mid 379.544769 -296.544468)
				(end 379.548644 -296.524934)
			)
			(arc
				(start 379.548644 -296.382186)
				(mid 379.552545 -296.362663)
				(end 379.56363 -296.346118)
			)
			(arc
				(start 379.610112 -296.299636)
				(mid 379.626646 -296.288525)
				(end 379.64618 -296.28465)
			)
			(arc
				(start 379.692916 -296.28465)
				(mid 379.712303 -296.2807)
				(end 379.72873 -296.269664)
			)
			(arc
				(start 379.776482 -296.222166)
				(mid 379.792899 -296.211104)
				(end 379.812296 -296.20718)
			)
			(arc
				(start 380.243842 -296.20718)
				(mid 380.263229 -296.21113)
				(end 380.279656 -296.222166)
			)
			(arc
				(start 380.327408 -296.269664)
				(mid 380.343825 -296.280726)
				(end 380.363222 -296.28465)
			)
			(arc
				(start 380.968504 -296.28465)
				(mid 380.988027 -296.280749)
				(end 381.004572 -296.269664)
			)
			(arc
				(start 381.028956 -296.24528)
				(mid 381.040067 -296.228746)
				(end 381.043942 -296.209212)
			)
			(arc
				(start 381.043942 -295.79316)
				(mid 381.040041 -295.773637)
				(end 381.028956 -295.757092)
			)
			(arc
				(start 381.000762 -295.728898)
				(mid 380.984228 -295.717787)
				(end 380.964694 -295.713912)
			)
			(arc
				(start 378.812044 -295.713912)
				(mid 378.792521 -295.717813)
				(end 378.775976 -295.728898)
			)
			(arc
				(start 378.637038 -295.867836)
				(mid 378.625927 -295.88437)
				(end 378.622052 -295.903904)
			)
			(arc
				(start 378.622052 -296.537126)
				(mid 378.625953 -296.556649)
				(end 378.637038 -296.573194)
			)
			(arc
				(start 378.6886 -296.624756)
				(mid 378.705134 -296.635867)
				(end 378.724668 -296.639742)
			)
		)
		(stroke
			(width 0)
			(type solid)
		)
		(fill yes)
		(layer "F.Cu")
		(net "PCEPLL0_VDDA18_PEX3_R")
	)
	(gr_poly
		(pts
			(arc
				(start 381.485902 -298.599606)
				(mid 381.505425 -298.595705)
				(end 381.52197 -298.58462)
			)
			(arc
				(start 381.645922 -298.460668)
				(mid 381.657033 -298.444134)
				(end 381.660908 -298.4246)
			)
			(arc
				(start 381.660908 -296.648886)
				(mid 381.657007 -296.629363)
				(end 381.645922 -296.612818)
			)
			(arc
				(start 381.509778 -296.476674)
				(mid 381.493244 -296.465563)
				(end 381.47371 -296.461688)
			)
			(arc
				(start 381.237998 -296.461688)
				(mid 381.218475 -296.465589)
				(end 381.20193 -296.476674)
			)
			(arc
				(start 381.094488 -296.584116)
				(mid 381.077954 -296.595227)
				(end 381.05842 -296.599102)
			)
			(arc
				(start 380.31801 -296.599102)
				(mid 380.298487 -296.595201)
				(end 380.281942 -296.584116)
			)
			(arc
				(start 380.1745 -296.476674)
				(mid 380.157966 -296.465563)
				(end 380.138432 -296.461688)
			)
			(arc
				(start 379.917706 -296.461688)
				(mid 379.898183 -296.465589)
				(end 379.881638 -296.476674)
			)
			(arc
				(start 379.826012 -296.5323)
				(mid 379.814901 -296.548834)
				(end 379.811026 -296.568368)
			)
			(arc
				(start 379.811026 -296.962322)
				(mid 379.807125 -296.981845)
				(end 379.79604 -296.99839)
			)
			(arc
				(start 379.77064 -297.02379)
				(mid 379.754106 -297.034901)
				(end 379.734572 -297.038776)
			)
			(arc
				(start 378.925836 -297.038776)
				(mid 378.906313 -297.042677)
				(end 378.889768 -297.053762)
			)
			(arc
				(start 378.800614 -297.142916)
				(mid 378.789503 -297.15945)
				(end 378.785628 -297.178984)
			)
			(arc
				(start 378.785628 -298.46905)
				(mid 378.789529 -298.488573)
				(end 378.800614 -298.505118)
			)
			(arc
				(start 378.88037 -298.584874)
				(mid 378.896933 -298.595848)
				(end 378.916438 -298.599606)
			)
		)
		(stroke
			(width 0)
			(type solid)
		)
		(fill yes)
		(layer "F.Cu")
		(net "PCEPLL0_VDDA18_PEX3")
	)
	(gr_poly
		(pts
			(arc
				(start 375.094246 -262.541258)
				(mid 375.171876 -262.51718)
				(end 375.252742 -262.509)
			)
			(arc
				(start 375.664984 -262.509)
				(mid 375.684341 -262.505167)
				(end 375.700798 -262.494268)
			)
			(arc
				(start 375.885456 -262.30961)
				(mid 375.896567 -262.293076)
				(end 375.900442 -262.273542)
			)
			(xy 375.900442 -261.076694) (xy 375.896632 -261.063486)
			(arc
				(start 375.893076 -261.05739)
				(mid 375.887433 -261.044582)
				(end 375.885456 -261.03072)
			)
			(arc
				(start 375.885456 -260.644386)
				(mid 375.881555 -260.624863)
				(end 375.87047 -260.608318)
			)
			(arc
				(start 375.488454 -260.226302)
				(mid 375.477343 -260.209768)
				(end 375.473468 -260.190234)
			)
			(arc
				(start 375.473468 -259.921502)
				(mid 375.469567 -259.901979)
				(end 375.458482 -259.885434)
			)
			(xy 375.458228 -259.88518)
			(arc
				(start 375.458228 -259.055362)
				(mid 375.454327 -259.035839)
				(end 375.443242 -259.019294)
			)
			(xy 375.354088 -258.93014) (xy 375.346976 -258.922774) (xy 375.32818 -258.915154)
			(arc
				(start 374.027954 -258.915154)
				(mid 374.008431 -258.919055)
				(end 373.991886 -258.93014)
			)
			(xy 373.912384 -259.009642)
			(arc
				(start 373.907558 -259.01523)
				(mid 373.899965 -259.029766)
				(end 373.897398 -259.045964)
			)
			(arc
				(start 373.897398 -262.447786)
				(mid 373.901348 -262.467173)
				(end 373.912384 -262.4836)
			)
			(arc
				(start 373.919242 -262.490458)
				(mid 373.935659 -262.50152)
				(end 373.955056 -262.505444)
			)
			(arc
				(start 374.462294 -262.505444)
				(mid 374.52003 -262.509634)
				(end 374.576594 -262.521954)
			)
			(arc
				(start 374.576594 -262.521954)
				(mid 374.602698 -262.530605)
				(end 374.628156 -262.541004)
			)
			(xy 374.638062 -262.545322) (xy 375.084594 -262.545322)
		)
		(stroke
			(width 0)
			(type solid)
		)
		(fill yes)
		(layer "F.Cu")
		(net "P1V8_VDDA_PEX3")
	)
	(gr_poly
		(pts
			(arc
				(start 142.308326 -263.266428)
				(mid 142.327849 -263.262527)
				(end 142.344394 -263.251442)
			)
			(arc
				(start 142.442946 -263.15289)
				(mid 142.454057 -263.136356)
				(end 142.457932 -263.116822)
			)
			(arc
				(start 142.457932 -262.869426)
				(mid 142.450165 -262.842429)
				(end 142.42923 -262.823706)
			)
			(arc
				(start 142.328138 -262.774938)
				(mid 142.313431 -262.76882)
				(end 142.298166 -262.76427)
			)
			(xy 142.286228 -262.762746) (xy 141.857476 -262.762746) (xy 141.856714 -262.763508)
			(arc
				(start 140.781786 -262.763508)
				(mid 140.762429 -262.759675)
				(end 140.745972 -262.748776)
			)
			(arc
				(start 140.608304 -262.611108)
				(mid 140.597378 -262.594662)
				(end 140.593572 -262.575294)
			)
			(xy 140.593572 -262.563864) (xy 140.590524 -262.560816) (xy 140.590524 -261.92099) (xy 140.593572 -261.918196)
			(arc
				(start 140.593572 -261.873492)
				(mid 140.597405 -261.854135)
				(end 140.608304 -261.837678)
			)
			(arc
				(start 140.764514 -261.681468)
				(mid 140.78096 -261.670542)
				(end 140.800328 -261.666736)
			)
			(arc
				(start 140.82395 -261.666736)
				(mid 140.843337 -261.662786)
				(end 140.859764 -261.65175)
			)
			(arc
				(start 141.082776 -261.428738)
				(mid 141.093887 -261.412204)
				(end 141.097762 -261.39267)
			)
			(xy 141.097762 -260.63067) (xy 141.090142 -260.612128) (xy 141.08303 -260.605016)
			(arc
				(start 140.133578 -260.605016)
				(mid 140.114055 -260.608917)
				(end 140.09751 -260.620002)
			)
			(arc
				(start 139.980416 -260.737096)
				(mid 139.969305 -260.75363)
				(end 139.96543 -260.773164)
			)
			(arc
				(start 139.96543 -263.054338)
				(mid 139.969331 -263.073861)
				(end 139.980416 -263.090406)
			)
			(arc
				(start 140.141452 -263.251442)
				(mid 140.157986 -263.262553)
				(end 140.17752 -263.266428)
			)
		)
		(stroke
			(width 0)
			(type solid)
		)
		(fill yes)
		(layer "F.Cu")
		(net "GND")
	)
	(gr_poly
		(pts
			(xy 16.486124 -321.52844) (xy 16.486124 -309.921656) (xy 16.246348 -309.68188) (xy 14.924024 -309.68188)
			(xy 13.480542 -309.68188) (xy 13.35659 -309.805832) (xy 13.35659 -311.385712) (xy 13.35659 -318.771016)
			(xy 12.784328 -319.343278) (xy 10.389616 -319.343278) (xy 9.246616 -318.200278) (xy 9.246616 -305.029616)
			(xy 9.205214 -304.988214) (xy 5.701538 -304.988214) (xy 5.593334 -305.096418) (xy 5.593334 -307.852318)
			(arc
				(start 5.999988 -308.258972)
				(mid 7.12187 -309.660282)
				(end 7.522464 -311.410096)
			)
			(arc
				(start 7.522464 -311.410096)
				(mid 7.042909 -313.314864)
				(end 5.718556 -314.765436)
			)
			(xy 5.718556 -316.772036) (xy 5.713476 -316.777116) (xy 5.713476 -317.87084) (xy 5.715508 -317.872872)
			(xy 5.715508 -320.361818) (xy 5.715508 -321.753738) (xy 5.90804 -321.94627) (xy 16.068294 -321.94627)
		)
		(stroke
			(width 0)
			(type solid)
		)
		(fill yes)
		(layer "F.Cu")
		(net "GND")
	)
	(gr_poly
		(pts
			(xy 122.744484 -122.912632) (xy 122.744484 -121.782078) (xy 122.744484 -118.853204) (xy 122.74296 -118.847108)
			(xy 122.74296 -117.023388) (xy 122.56643 -116.846858) (xy 122.31497 -116.846858)
			(arc
				(start 119.479822 -116.846858)
				(mid 119.460299 -116.850759)
				(end 119.443754 -116.861844)
			)
			(arc
				(start 119.412766 -116.892832)
				(mid 119.401655 -116.909366)
				(end 119.39778 -116.9289)
			)
			(arc
				(start 119.39778 -118.632986)
				(mid 119.393879 -118.652509)
				(end 119.382794 -118.669054)
			)
			(arc
				(start 119.229378 -118.82247)
				(mid 119.218267 -118.839004)
				(end 119.214392 -118.858538)
			)
			(xy 119.214392 -119.126762) (xy 119.22125 -119.13362)
			(arc
				(start 120.19661 -119.13362)
				(mid 120.216133 -119.129719)
				(end 120.232678 -119.118634)
			)
			(arc
				(start 120.646444 -118.704614)
				(mid 120.662978 -118.693503)
				(end 120.682512 -118.689628)
			)
			(arc
				(start 121.477786 -118.689628)
				(mid 121.497309 -118.693529)
				(end 121.513854 -118.704614)
			)
			(arc
				(start 121.545096 -118.735856)
				(mid 121.556207 -118.75239)
				(end 121.560082 -118.771924)
			)
			(arc
				(start 121.560082 -121.491248)
				(mid 121.556181 -121.510771)
				(end 121.545096 -121.527316)
			)
			(arc
				(start 121.525792 -121.54662)
				(mid 121.509258 -121.557731)
				(end 121.489724 -121.561606)
			)
			(arc
				(start 120.589294 -121.561606)
				(mid 120.569771 -121.557705)
				(end 120.553226 -121.54662)
			)
			(arc
				(start 120.49379 -121.487184)
				(mid 120.477256 -121.476073)
				(end 120.457722 -121.472198)
			)
			(xy 119.35206 -121.472198) (xy 119.333518 -121.479818) (xy 119.330724 -121.482612) (xy 119.330724 -122.900948)
			(xy 119.330724 -123.241816) (xy 119.34698 -123.258072)
			(arc
				(start 119.376444 -123.287536)
				(mid 119.392978 -123.298647)
				(end 119.412512 -123.302522)
			)
			(xy 121.720864 -123.302522) (xy 122.354594 -123.302522)
		)
		(stroke
			(width 0)
			(type solid)
		)
		(fill yes)
		(layer "F.Cu")
		(net "GND")
	)
	(gr_poly
		(pts
			(xy 234.072684 -117.663468) (xy 234.072684 -113.457736) (xy 234.548426 -112.981994) (xy 236.84484 -112.981994)
			(xy 237.015274 -112.81156) (xy 237.015274 -100.312982) (xy 235.997242 -99.29495) (xy 227.61448 -99.29495)
			(xy 226.227132 -100.682298) (xy 225.57105 -100.682298) (xy 225.555556 -100.697792) (xy 224.559368 -100.697792)
			(xy 224.549208 -100.707952) (xy 224.549208 -101.191568) (xy 224.544128 -101.196648) (xy 224.412048 -101.328982)
			(xy 222.068898 -101.328982) (xy 221.882716 -101.515164) (xy 221.882716 -103.249222) (xy 221.975934 -103.34244)
			(arc
				(start 222.418402 -103.34244)
				(mid 222.437925 -103.338539)
				(end 222.45447 -103.327454)
			)
			(arc
				(start 222.473266 -103.308658)
				(mid 222.4898 -103.297547)
				(end 222.509334 -103.293672)
			)
			(arc
				(start 224.817178 -103.293672)
				(mid 224.836672 -103.297456)
				(end 224.853246 -103.308404)
			)
			(arc
				(start 224.872296 -103.327708)
				(mid 224.888859 -103.338682)
				(end 224.908364 -103.34244)
			)
			(xy 224.909888 -103.34244) (xy 224.920302 -103.338122) (xy 225.029268 -103.338122) (xy 225.033586 -103.34244)
			(xy 225.038666 -103.34244)
			(arc
				(start 225.857562 -104.161336)
				(mid 225.874096 -104.172447)
				(end 225.89363 -104.176322)
			)
			(arc
				(start 228.675184 -104.176322)
				(mid 228.694707 -104.172421)
				(end 228.711252 -104.161336)
			)
			(arc
				(start 228.723444 -104.149144)
				(mid 228.739978 -104.138033)
				(end 228.759512 -104.134158)
			)
			(xy 232.356406 -104.134158) (xy 232.367836 -104.132888) (xy 232.580942 -104.132888) (xy 232.82656 -104.378506)
			(xy 232.82656 -106.429556) (xy 232.63987 -106.616246) (xy 232.63987 -106.627422) (xy 231.924352 -107.34294)
			(xy 231.924352 -108.009944) (xy 231.920542 -108.0135) (xy 231.920542 -112.514126) (xy 232.738676 -113.33226)
			(xy 232.77068 -113.36401) (xy 232.77068 -117.654832) (xy 232.79227 -117.676422) (xy 234.05973 -117.676422)
		)
		(stroke
			(width 0)
			(type solid)
		)
		(fill yes)
		(layer "F.Cu")
		(net "P12V_AUX")
	)
	(gr_poly
		(pts
			(arc
				(start 6.931406 -17.789398)
				(mid 6.950929 -17.785497)
				(end 6.967474 -17.774412)
			)
			(xy 7.013194 -17.728692) (xy 7.013194 -17.686782) (xy 7.008876 -17.682464) (xy 7.001256 -17.663922)
			(arc
				(start 7.001256 -14.901418)
				(mid 6.997355 -14.881895)
				(end 6.98627 -14.86535)
			)
			(arc
				(start 6.938264 -14.817344)
				(mid 6.921701 -14.80637)
				(end 6.902196 -14.802612)
			)
			(arc
				(start 6.300978 -14.802612)
				(mid 6.281591 -14.798662)
				(end 6.265164 -14.787626)
			)
			(xy 6.263894 -14.786356) (xy 6.245352 -14.778736)
			(arc
				(start 6.22935 -14.778736)
				(mid 6.209827 -14.774835)
				(end 6.193282 -14.76375)
			)
			(arc
				(start 6.103112 -14.67358)
				(mid 6.092001 -14.657046)
				(end 6.088126 -14.637512)
			)
			(arc
				(start 6.088126 -14.63167)
				(mid 6.084176 -14.612283)
				(end 6.07314 -14.595856)
			)
			(arc
				(start 6.003036 -14.525498)
				(mid 5.99211 -14.509052)
				(end 5.988304 -14.489684)
			)
			(arc
				(start 5.988304 -12.81811)
				(mid 5.992137 -12.798753)
				(end 6.003036 -12.782296)
			)
			(arc
				(start 6.07314 -12.711938)
				(mid 6.084202 -12.695521)
				(end 6.088126 -12.676124)
			)
			(arc
				(start 6.088126 -12.577572)
				(mid 6.084225 -12.558049)
				(end 6.07314 -12.541504)
			)
			(arc
				(start 5.769102 -12.237466)
				(mid 5.752568 -12.226355)
				(end 5.733034 -12.22248)
			)
			(arc
				(start 4.66979 -12.22248)
				(mid 4.650267 -12.226381)
				(end 4.633722 -12.237466)
			)
			(arc
				(start 4.477004 -12.394184)
				(mid 4.465893 -12.410718)
				(end 4.462018 -12.430252)
			)
			(arc
				(start 4.462018 -17.348454)
				(mid 4.465919 -17.367977)
				(end 4.477004 -17.384522)
			)
			(arc
				(start 4.866894 -17.774412)
				(mid 4.883428 -17.785523)
				(end 4.902962 -17.789398)
			)
		)
		(stroke
			(width 0)
			(type solid)
		)
		(fill yes)
		(layer "F.Cu")
		(net "GND")
	)
	(gr_poly
		(pts
			(arc
				(start 248.882916 -215.99652)
				(mid 248.902439 -215.992619)
				(end 248.918984 -215.981534)
			)
			(arc
				(start 249.105928 -215.79459)
				(mid 249.117039 -215.778056)
				(end 249.120914 -215.758522)
			)
			(arc
				(start 249.120914 -215.313768)
				(mid 249.117013 -215.294245)
				(end 249.105928 -215.2777)
			)
			(arc
				(start 248.792238 -214.96401)
				(mid 248.781127 -214.947476)
				(end 248.777252 -214.927942)
			)
			(arc
				(start 248.777252 -213.378542)
				(mid 248.773351 -213.359019)
				(end 248.762266 -213.342474)
			)
			(arc
				(start 248.670572 -213.25078)
				(mid 248.654038 -213.239669)
				(end 248.634504 -213.235794)
			)
			(arc
				(start 248.554748 -213.235794)
				(mid 248.535225 -213.231893)
				(end 248.51868 -213.220808)
			)
			(arc
				(start 248.367042 -213.06917)
				(mid 248.355931 -213.052636)
				(end 248.352056 -213.033102)
			)
			(arc
				(start 248.352056 -212.907372)
				(mid 248.349931 -212.893086)
				(end 248.343928 -212.87994)
			)
			(arc
				(start 248.343928 -212.87994)
				(mid 248.296792 -212.782965)
				(end 248.274332 -212.677502)
			)
			(arc
				(start 248.274332 -212.677502)
				(mid 248.269714 -212.660476)
				(end 248.2596 -212.646006)
			)
			(arc
				(start 248.212864 -212.59927)
				(mid 248.19633 -212.588159)
				(end 248.176796 -212.584284)
			)
			(arc
				(start 247.062244 -212.584284)
				(mid 247.042721 -212.588185)
				(end 247.026176 -212.59927)
			)
			(arc
				(start 246.919496 -212.70595)
				(mid 246.908385 -212.722484)
				(end 246.90451 -212.742018)
			)
			(xy 246.90451 -214.250778)
			(arc
				(start 246.907558 -214.25916)
				(mid 246.930423 -214.389208)
				(end 246.907558 -214.519256)
			)
			(xy 246.90451 -214.527638) (xy 246.90451 -215.180672) (xy 247.015508 -215.29167) (xy 247.71096 -215.29167)
			(xy 247.943878 -215.524588) (xy 247.943878 -215.949276) (xy 247.991122 -215.99652)
		)
		(stroke
			(width 0)
			(type solid)
		)
		(fill yes)
		(layer "F.Cu")
		(net "GND")
	)
	(gr_poly
		(pts
			(arc
				(start 258.14147 -214.864188)
				(mid 258.160993 -214.860287)
				(end 258.177538 -214.849202)
			)
			(arc
				(start 258.227576 -214.799164)
				(mid 258.238502 -214.782718)
				(end 258.242308 -214.76335)
			)
			(xy 258.242308 -213.663022) (xy 258.242562 -213.655402)
			(arc
				(start 258.242562 -213.548468)
				(mid 258.238661 -213.528945)
				(end 258.227576 -213.5124)
			)
			(xy 258.036822 -213.321646) (xy 258.01066 -213.314788)
			(arc
				(start 257.997198 -213.318598)
				(mid 257.920575 -213.33442)
				(end 257.842512 -213.33968)
			)
			(arc
				(start 257.226562 -213.33968)
				(mid 257.186078 -213.338305)
				(end 257.14579 -213.334092)
			)
			(xy 257.142234 -213.333584)
			(arc
				(start 257.08356 -213.333584)
				(mid 257.064037 -213.329683)
				(end 257.047492 -213.318598)
			)
			(xy 257.036316 -213.307422) (xy 257.026156 -213.303612) (xy 257.02006 -213.301326) (xy 257.01117 -213.298024)
			(arc
				(start 255.573276 -213.298024)
				(mid 255.553753 -213.301925)
				(end 255.537208 -213.31301)
			)
			(arc
				(start 255.447546 -213.402672)
				(mid 255.436435 -213.419206)
				(end 255.43256 -213.43874)
			)
			(arc
				(start 255.43256 -214.487252)
				(mid 255.436461 -214.506775)
				(end 255.447546 -214.52332)
			)
			(arc
				(start 255.468628 -214.544402)
				(mid 255.485162 -214.555513)
				(end 255.504696 -214.559388)
			)
			(xy 255.731518 -214.559388)
			(arc
				(start 255.740662 -214.555832)
				(mid 255.813875 -214.534616)
				(end 255.88976 -214.527384)
			)
			(arc
				(start 256.259584 -214.527384)
				(mid 256.335478 -214.534572)
				(end 256.408682 -214.555832)
			)
			(xy 256.417826 -214.559388)
			(arc
				(start 256.427224 -214.559388)
				(mid 256.446747 -214.563289)
				(end 256.463292 -214.574374)
			)
			(xy 256.48031 -214.591392)
			(arc
				(start 256.487676 -214.597488)
				(mid 256.518569 -214.620709)
				(end 256.547112 -214.646764)
			)
			(arc
				(start 256.749804 -214.849202)
				(mid 256.766338 -214.860313)
				(end 256.785872 -214.864188)
			)
		)
		(stroke
			(width 0)
			(type solid)
		)
		(fill yes)
		(layer "F.Cu")
		(net "P3V3_AUX")
	)
	(gr_poly
		(pts
			(arc
				(start 448.30365 -230.287068)
				(mid 448.323007 -230.283235)
				(end 448.339464 -230.272336)
			)
			(arc
				(start 448.345814 -230.265986)
				(mid 448.356925 -230.249452)
				(end 448.3608 -230.229918)
			)
			(arc
				(start 448.3608 -230.145082)
				(mid 448.356899 -230.125559)
				(end 448.345814 -230.109014)
			)
			(arc
				(start 448.293744 -230.056944)
				(mid 448.27721 -230.045833)
				(end 448.257676 -230.041958)
			)
			(xy 448.013074 -230.041958)
			(arc
				(start 448.007232 -230.043228)
				(mid 447.965849 -230.050409)
				(end 447.92392 -230.05288)
			)
			(arc
				(start 447.565018 -230.05288)
				(mid 447.523088 -230.050419)
				(end 447.481706 -230.043228)
			)
			(xy 447.475864 -230.041958) (xy 447.465958 -230.041958) (xy 447.462656 -230.038656)
			(arc
				(start 447.450972 -230.034846)
				(mid 447.371388 -229.998211)
				(end 447.302636 -229.943914)
			)
			(arc
				(start 446.354454 -228.995986)
				(mid 446.33792 -228.984875)
				(end 446.318386 -228.981)
			)
			(arc
				(start 445.681608 -228.981)
				(mid 445.662085 -228.977099)
				(end 445.64554 -228.966014)
			)
			(arc
				(start 445.084962 -228.405436)
				(mid 445.068428 -228.394325)
				(end 445.048894 -228.39045)
			)
			(arc
				(start 443.13729 -228.39045)
				(mid 443.117767 -228.394351)
				(end 443.101222 -228.405436)
			)
			(arc
				(start 442.907166 -228.599492)
				(mid 442.896055 -228.616026)
				(end 442.89218 -228.63556)
			)
			(arc
				(start 442.89218 -229.99192)
				(mid 442.896081 -230.011443)
				(end 442.907166 -230.027988)
			)
			(arc
				(start 442.947044 -230.067866)
				(mid 442.963461 -230.078928)
				(end 442.982858 -230.082852)
			)
			(arc
				(start 446.687956 -230.082852)
				(mid 446.707313 -230.086685)
				(end 446.72377 -230.097584)
			)
			(arc
				(start 446.735454 -230.109014)
				(mid 446.751871 -230.120076)
				(end 446.771268 -230.124)
			)
			(xy 446.786 -230.124)
			(arc
				(start 446.934336 -230.272336)
				(mid 446.950782 -230.283262)
				(end 446.97015 -230.287068)
			)
		)
		(stroke
			(width 0)
			(type solid)
		)
		(fill yes)
		(layer "F.Cu")
		(net "P3V3_AUX")
	)
	(gr_poly
		(pts
			(arc
				(start 238.984536 -376.463306)
				(mid 239.020457 -376.448427)
				(end 239.035336 -376.412506)
			)
			(arc
				(start 239.035336 -375.163588)
				(mid 239.046767 -375.071153)
				(end 239.080294 -374.984264)
			)
			(arc
				(start 239.080294 -374.984264)
				(mid 239.084674 -374.972684)
				(end 239.086136 -374.960388)
			)
			(arc
				(start 239.086136 -374.604788)
				(mid 239.123482 -374.514626)
				(end 239.213644 -374.47728)
			)
			(arc
				(start 239.620044 -374.47728)
				(mid 239.710206 -374.514626)
				(end 239.747552 -374.604788)
			)
			(arc
				(start 239.747552 -374.960388)
				(mid 239.749 -374.972687)
				(end 239.753394 -374.984264)
			)
			(arc
				(start 239.753394 -374.984264)
				(mid 239.786878 -375.071164)
				(end 239.798352 -375.163588)
			)
			(arc
				(start 239.798352 -376.412506)
				(mid 239.813231 -376.448427)
				(end 239.849152 -376.463306)
			)
			(arc
				(start 241.763296 -376.463306)
				(mid 241.782819 -376.459405)
				(end 241.799364 -376.44832)
			)
			(arc
				(start 242.225576 -376.022108)
				(mid 242.236687 -376.005574)
				(end 242.240562 -375.98604)
			)
			(arc
				(start 242.240562 -368.70005)
				(mid 242.236661 -368.680527)
				(end 242.225576 -368.663982)
			)
			(arc
				(start 242.013486 -368.451892)
				(mid 241.996952 -368.440781)
				(end 241.977418 -368.436906)
			)
			(arc
				(start 236.34446 -368.436906)
				(mid 236.324937 -368.440807)
				(end 236.308392 -368.451892)
			)
			(arc
				(start 236.066076 -368.694208)
				(mid 236.054965 -368.710742)
				(end 236.05109 -368.730276)
			)
			(arc
				(start 236.05109 -376.1613)
				(mid 236.054991 -376.180823)
				(end 236.066076 -376.197368)
			)
			(arc
				(start 236.317028 -376.44832)
				(mid 236.333562 -376.459431)
				(end 236.353096 -376.463306)
			)
		)
		(stroke
			(width 0)
			(type solid)
		)
		(fill yes)
		(layer "F.Cu")
		(net "P12V_STBY_R1")
	)
	(gr_poly
		(pts
			(xy 93.820996 -119.135398) (xy 93.934026 -119.135398) (xy 94.513908 -118.555516) (xy 96.722946 -118.555516)
			(xy 96.980756 -118.297706) (xy 96.980756 -116.483384) (xy 100.70211 -116.483384) (xy 100.70211 -114.19078)
			(xy 100.308664 -113.797334) (xy 97.776284 -113.797334) (xy 97.253298 -113.274348) (xy 97.253298 -113.25352)
			(xy 96.966024 -112.966246) (xy 93.394276 -112.966246) (xy 92.971366 -112.543336) (xy 92.971366 -111.491014)
			(xy 92.85986 -111.379508) (xy 86.437724 -111.379508) (xy 84.951062 -112.86617) (xy 75.32497 -112.86617)
			(xy 75.228958 -112.962182) (xy 75.228958 -114.010948) (xy 75.35164 -114.13363) (xy 86.102952 -114.13363)
			(xy 87.604092 -112.63249) (xy 90.784934 -112.63249) (xy 90.785188 -112.632236) (xy 92.25661 -112.632236)
			(xy 92.449904 -112.82553)
			(arc
				(start 92.449904 -114.956336)
				(mid 92.446003 -114.975859)
				(end 92.434918 -114.992404)
			)
			(arc
				(start 92.281502 -115.14582)
				(mid 92.270391 -115.162354)
				(end 92.266516 -115.181888)
			)
			(xy 92.266516 -115.450112) (xy 92.273374 -115.45697)
			(arc
				(start 93.248734 -115.45697)
				(mid 93.268257 -115.453069)
				(end 93.284802 -115.441984)
			)
			(arc
				(start 93.698568 -115.027964)
				(mid 93.715102 -115.016853)
				(end 93.734636 -115.012978)
			)
			(arc
				(start 94.52991 -115.012978)
				(mid 94.549433 -115.016879)
				(end 94.565978 -115.027964)
			)
			(arc
				(start 94.59722 -115.059206)
				(mid 94.608331 -115.07574)
				(end 94.612206 -115.095274)
			)
			(arc
				(start 94.612206 -117.814598)
				(mid 94.608305 -117.834121)
				(end 94.59722 -117.850666)
			)
			(arc
				(start 94.577916 -117.86997)
				(mid 94.561382 -117.881081)
				(end 94.541848 -117.884956)
			)
			(arc
				(start 93.641418 -117.884956)
				(mid 93.621895 -117.881055)
				(end 93.60535 -117.86997)
			)
			(arc
				(start 93.545914 -117.810534)
				(mid 93.52938 -117.799423)
				(end 93.509846 -117.795548)
			)
			(xy 92.404184 -117.795548) (xy 92.385642 -117.803168) (xy 92.382848 -117.805962) (xy 92.382848 -118.965218)
			(xy 92.557092 -119.139462) (xy 93.816932 -119.139462)
		)
		(stroke
			(width 0)
			(type solid)
		)
		(fill yes)
		(layer "F.Cu")
		(net "GND")
	)
	(gr_poly
		(pts
			(xy 326.020938 -119.135398) (xy 326.133968 -119.135398) (xy 326.71385 -118.555516) (xy 328.922888 -118.555516)
			(xy 329.180698 -118.297706) (xy 329.180698 -116.483384) (xy 332.902052 -116.483384) (xy 332.902052 -114.19078)
			(xy 332.508606 -113.797334) (xy 329.976226 -113.797334) (xy 329.45324 -113.274348) (xy 329.45324 -113.25352)
			(xy 329.165966 -112.966246) (xy 325.594218 -112.966246) (xy 325.171308 -112.543336) (xy 325.171308 -111.491014)
			(xy 325.059802 -111.379508) (xy 318.637666 -111.379508) (xy 317.151004 -112.86617) (xy 307.524912 -112.86617)
			(xy 307.4289 -112.962182) (xy 307.4289 -114.010948) (xy 307.551582 -114.13363) (xy 318.302894 -114.13363)
			(xy 319.804034 -112.63249) (xy 322.984876 -112.63249) (xy 322.98513 -112.632236) (xy 324.456552 -112.632236)
			(xy 324.649846 -112.82553)
			(arc
				(start 324.649846 -114.956336)
				(mid 324.645945 -114.975859)
				(end 324.63486 -114.992404)
			)
			(arc
				(start 324.481444 -115.14582)
				(mid 324.470333 -115.162354)
				(end 324.466458 -115.181888)
			)
			(xy 324.466458 -115.450112) (xy 324.473316 -115.45697)
			(arc
				(start 325.448676 -115.45697)
				(mid 325.468199 -115.453069)
				(end 325.484744 -115.441984)
			)
			(arc
				(start 325.89851 -115.027964)
				(mid 325.915044 -115.016853)
				(end 325.934578 -115.012978)
			)
			(arc
				(start 326.729852 -115.012978)
				(mid 326.749375 -115.016879)
				(end 326.76592 -115.027964)
			)
			(arc
				(start 326.797162 -115.059206)
				(mid 326.808273 -115.07574)
				(end 326.812148 -115.095274)
			)
			(arc
				(start 326.812148 -117.814598)
				(mid 326.808247 -117.834121)
				(end 326.797162 -117.850666)
			)
			(arc
				(start 326.777858 -117.86997)
				(mid 326.761324 -117.881081)
				(end 326.74179 -117.884956)
			)
			(arc
				(start 325.84136 -117.884956)
				(mid 325.821837 -117.881055)
				(end 325.805292 -117.86997)
			)
			(arc
				(start 325.745856 -117.810534)
				(mid 325.729322 -117.799423)
				(end 325.709788 -117.795548)
			)
			(xy 324.604126 -117.795548) (xy 324.585584 -117.803168) (xy 324.58279 -117.805962) (xy 324.58279 -118.965218)
			(xy 324.757034 -119.139462) (xy 326.016874 -119.139462)
		)
		(stroke
			(width 0)
			(type solid)
		)
		(fill yes)
		(layer "F.Cu")
		(net "GND")
	)
	(gr_poly
		(pts
			(xy 442.121036 -119.135398) (xy 442.234066 -119.135398) (xy 442.813948 -118.555516) (xy 445.022986 -118.555516)
			(xy 445.280796 -118.297706) (xy 445.280796 -116.483384) (xy 449.00215 -116.483384) (xy 449.00215 -114.19078)
			(xy 448.608704 -113.797334) (xy 446.076324 -113.797334) (xy 445.553338 -113.274348) (xy 445.553338 -113.25352)
			(xy 445.266064 -112.966246) (xy 441.694316 -112.966246) (xy 441.271406 -112.543336) (xy 441.271406 -111.491014)
			(xy 441.1599 -111.379508) (xy 434.737764 -111.379508) (xy 433.251102 -112.86617) (xy 423.62501 -112.86617)
			(xy 423.528998 -112.962182) (xy 423.528998 -114.010948) (xy 423.65168 -114.13363) (xy 434.402992 -114.13363)
			(xy 435.904132 -112.63249) (xy 439.084974 -112.63249) (xy 439.085228 -112.632236) (xy 440.55665 -112.632236)
			(xy 440.749944 -112.82553)
			(arc
				(start 440.749944 -114.956336)
				(mid 440.746043 -114.975859)
				(end 440.734958 -114.992404)
			)
			(arc
				(start 440.581542 -115.14582)
				(mid 440.570431 -115.162354)
				(end 440.566556 -115.181888)
			)
			(xy 440.566556 -115.450112) (xy 440.573414 -115.45697)
			(arc
				(start 441.548774 -115.45697)
				(mid 441.568297 -115.453069)
				(end 441.584842 -115.441984)
			)
			(arc
				(start 441.998608 -115.027964)
				(mid 442.015142 -115.016853)
				(end 442.034676 -115.012978)
			)
			(arc
				(start 442.82995 -115.012978)
				(mid 442.849473 -115.016879)
				(end 442.866018 -115.027964)
			)
			(arc
				(start 442.89726 -115.059206)
				(mid 442.908371 -115.07574)
				(end 442.912246 -115.095274)
			)
			(arc
				(start 442.912246 -117.814598)
				(mid 442.908345 -117.834121)
				(end 442.89726 -117.850666)
			)
			(arc
				(start 442.877956 -117.86997)
				(mid 442.861422 -117.881081)
				(end 442.841888 -117.884956)
			)
			(arc
				(start 441.941458 -117.884956)
				(mid 441.921935 -117.881055)
				(end 441.90539 -117.86997)
			)
			(arc
				(start 441.845954 -117.810534)
				(mid 441.82942 -117.799423)
				(end 441.809886 -117.795548)
			)
			(xy 440.704224 -117.795548) (xy 440.685682 -117.803168) (xy 440.682888 -117.805962) (xy 440.682888 -118.965218)
			(xy 440.857132 -119.139462) (xy 442.116972 -119.139462)
		)
		(stroke
			(width 0)
			(type solid)
		)
		(fill yes)
		(layer "F.Cu")
		(net "GND")
	)
	(gr_poly
		(pts
			(arc
				(start 3.86842 -39.929308)
				(mid 3.904341 -39.914429)
				(end 3.91922 -39.878508)
			)
			(arc
				(start 3.91922 -39.041324)
				(mid 3.915319 -39.021801)
				(end 3.904234 -39.005256)
			)
			(arc
				(start 3.490214 -38.59149)
				(mid 3.479103 -38.574956)
				(end 3.475228 -38.555422)
			)
			(arc
				(start 3.475228 -37.760148)
				(mid 3.479129 -37.740625)
				(end 3.490214 -37.72408)
			)
			(arc
				(start 3.521456 -37.692838)
				(mid 3.53799 -37.681727)
				(end 3.557524 -37.677852)
			)
			(arc
				(start 6.276848 -37.677852)
				(mid 6.296371 -37.681753)
				(end 6.312916 -37.692838)
			)
			(arc
				(start 6.33222 -37.712142)
				(mid 6.343331 -37.728676)
				(end 6.347206 -37.74821)
			)
			(arc
				(start 6.347206 -38.64864)
				(mid 6.343305 -38.668163)
				(end 6.33222 -38.684708)
			)
			(arc
				(start 6.272784 -38.744144)
				(mid 6.261673 -38.760678)
				(end 6.257798 -38.780212)
			)
			(xy 6.257798 -39.885874) (xy 6.265418 -39.904416) (xy 6.268212 -39.906956)
			(arc
				(start 7.636764 -39.906956)
				(mid 7.656121 -39.903123)
				(end 7.672578 -39.892224)
			)
			(xy 7.677404 -39.887398)
			(arc
				(start 7.677404 -36.85286)
				(mid 7.673503 -36.833337)
				(end 7.662418 -36.816792)
			)
			(arc
				(start 7.354062 -36.508436)
				(mid 7.337528 -36.497325)
				(end 7.317994 -36.49345)
			)
			(arc
				(start 1.88849 -36.49345)
				(mid 1.868967 -36.497351)
				(end 1.852422 -36.508436)
			)
			(arc
				(start 1.647444 -36.713414)
				(mid 1.636333 -36.729948)
				(end 1.632458 -36.749482)
			)
			(arc
				(start 1.632458 -39.758112)
				(mid 1.636359 -39.777635)
				(end 1.647444 -39.79418)
			)
			(arc
				(start 1.678432 -39.825168)
				(mid 1.694966 -39.836279)
				(end 1.7145 -39.840154)
			)
			(arc
				(start 3.418586 -39.840154)
				(mid 3.438109 -39.844055)
				(end 3.454654 -39.85514)
			)
			(arc
				(start 3.513836 -39.914322)
				(mid 3.530253 -39.925384)
				(end 3.54965 -39.929308)
			)
		)
		(stroke
			(width 0)
			(type solid)
		)
		(fill yes)
		(layer "F.Cu")
		(net "GND")
	)
	(gr_poly
		(pts
			(xy 54.40426 -29.227018)
			(arc
				(start 54.40426 -28.251658)
				(mid 54.400359 -28.232135)
				(end 54.389274 -28.21559)
			)
			(arc
				(start 53.975254 -27.801824)
				(mid 53.964143 -27.78529)
				(end 53.960268 -27.765756)
			)
			(arc
				(start 53.960268 -26.970482)
				(mid 53.964169 -26.950959)
				(end 53.975254 -26.934414)
			)
			(arc
				(start 54.006496 -26.903172)
				(mid 54.02303 -26.892061)
				(end 54.042564 -26.888186)
			)
			(arc
				(start 56.761888 -26.888186)
				(mid 56.781411 -26.892087)
				(end 56.797956 -26.903172)
			)
			(arc
				(start 56.81726 -26.922476)
				(mid 56.828371 -26.93901)
				(end 56.832246 -26.958544)
			)
			(arc
				(start 56.832246 -27.858974)
				(mid 56.828345 -27.878497)
				(end 56.81726 -27.895042)
			)
			(arc
				(start 56.757824 -27.954478)
				(mid 56.746713 -27.971012)
				(end 56.742838 -27.990546)
			)
			(xy 56.742838 -29.096208) (xy 56.750458 -29.11475) (xy 56.753252 -29.117544) (xy 58.171588 -29.117544)
			(xy 58.512456 -29.117544) (xy 58.528712 -29.101288)
			(arc
				(start 58.558176 -29.071824)
				(mid 58.569287 -29.05529)
				(end 58.573162 -29.035756)
			)
			(arc
				(start 58.573162 -26.727404)
				(mid 58.569261 -26.707881)
				(end 58.558176 -26.691336)
			)
			(xy 58.387742 -26.520902) (xy 58.36666 -26.513282)
			(arc
				(start 58.35523 -26.514552)
				(mid 58.33214 -26.516117)
				(end 58.309002 -26.516584)
			)
			(xy 57.653174 -26.516584) (xy 57.32653 -26.516584) (xy 57.137046 -26.3271) (xy 57.137046 -25.788112)
			(xy 57.052718 -25.703784) (xy 54.123844 -25.703784) (xy 54.117748 -25.705308) (xy 52.294028 -25.705308)
			(xy 52.117498 -25.881838) (xy 52.117498 -26.133298)
			(arc
				(start 52.117498 -28.968446)
				(mid 52.121399 -28.987969)
				(end 52.132484 -29.004514)
			)
			(arc
				(start 52.163472 -29.035502)
				(mid 52.180006 -29.046613)
				(end 52.19954 -29.050488)
			)
			(arc
				(start 53.903626 -29.050488)
				(mid 53.923149 -29.054389)
				(end 53.939694 -29.065474)
			)
			(arc
				(start 54.09311 -29.21889)
				(mid 54.109644 -29.230001)
				(end 54.129178 -29.233876)
			)
			(xy 54.397402 -29.233876)
		)
		(stroke
			(width 0)
			(type solid)
		)
		(fill yes)
		(layer "F.Cu")
		(net "GND")
	)
	(gr_poly
		(pts
			(xy 80.404208 -29.227018)
			(arc
				(start 80.404208 -28.251658)
				(mid 80.400307 -28.232135)
				(end 80.389222 -28.21559)
			)
			(arc
				(start 79.975202 -27.801824)
				(mid 79.964091 -27.78529)
				(end 79.960216 -27.765756)
			)
			(arc
				(start 79.960216 -26.970482)
				(mid 79.964117 -26.950959)
				(end 79.975202 -26.934414)
			)
			(arc
				(start 80.006444 -26.903172)
				(mid 80.022978 -26.892061)
				(end 80.042512 -26.888186)
			)
			(arc
				(start 82.761836 -26.888186)
				(mid 82.781359 -26.892087)
				(end 82.797904 -26.903172)
			)
			(arc
				(start 82.817208 -26.922476)
				(mid 82.828319 -26.93901)
				(end 82.832194 -26.958544)
			)
			(arc
				(start 82.832194 -27.858974)
				(mid 82.828293 -27.878497)
				(end 82.817208 -27.895042)
			)
			(arc
				(start 82.757772 -27.954478)
				(mid 82.746661 -27.971012)
				(end 82.742786 -27.990546)
			)
			(xy 82.742786 -29.096208) (xy 82.750406 -29.11475) (xy 82.7532 -29.117544) (xy 84.171536 -29.117544)
			(xy 84.512404 -29.117544) (xy 84.52866 -29.101288)
			(arc
				(start 84.558124 -29.071824)
				(mid 84.569235 -29.05529)
				(end 84.57311 -29.035756)
			)
			(arc
				(start 84.57311 -26.727404)
				(mid 84.569209 -26.707881)
				(end 84.558124 -26.691336)
			)
			(xy 84.38769 -26.520902) (xy 84.366608 -26.513282)
			(arc
				(start 84.355178 -26.514552)
				(mid 84.332088 -26.516117)
				(end 84.30895 -26.516584)
			)
			(xy 83.653122 -26.516584) (xy 83.326478 -26.516584) (xy 83.136994 -26.3271) (xy 83.136994 -25.788112)
			(xy 83.052666 -25.703784) (xy 80.123792 -25.703784) (xy 80.117696 -25.705308) (xy 78.293976 -25.705308)
			(xy 78.117446 -25.881838) (xy 78.117446 -26.133298)
			(arc
				(start 78.117446 -28.968446)
				(mid 78.121347 -28.987969)
				(end 78.132432 -29.004514)
			)
			(arc
				(start 78.16342 -29.035502)
				(mid 78.179954 -29.046613)
				(end 78.199488 -29.050488)
			)
			(arc
				(start 79.903574 -29.050488)
				(mid 79.923097 -29.054389)
				(end 79.939642 -29.065474)
			)
			(arc
				(start 80.093058 -29.21889)
				(mid 80.109592 -29.230001)
				(end 80.129126 -29.233876)
			)
			(xy 80.39735 -29.233876)
		)
		(stroke
			(width 0)
			(type solid)
		)
		(fill yes)
		(layer "F.Cu")
		(net "GND")
	)
	(gr_poly
		(pts
			(xy 118.504462 -29.227018)
			(arc
				(start 118.504462 -28.251658)
				(mid 118.500561 -28.232135)
				(end 118.489476 -28.21559)
			)
			(arc
				(start 118.075456 -27.801824)
				(mid 118.064345 -27.78529)
				(end 118.06047 -27.765756)
			)
			(arc
				(start 118.06047 -26.970482)
				(mid 118.064371 -26.950959)
				(end 118.075456 -26.934414)
			)
			(arc
				(start 118.106698 -26.903172)
				(mid 118.123232 -26.892061)
				(end 118.142766 -26.888186)
			)
			(arc
				(start 120.86209 -26.888186)
				(mid 120.881613 -26.892087)
				(end 120.898158 -26.903172)
			)
			(arc
				(start 120.917462 -26.922476)
				(mid 120.928573 -26.93901)
				(end 120.932448 -26.958544)
			)
			(arc
				(start 120.932448 -27.858974)
				(mid 120.928547 -27.878497)
				(end 120.917462 -27.895042)
			)
			(arc
				(start 120.858026 -27.954478)
				(mid 120.846915 -27.971012)
				(end 120.84304 -27.990546)
			)
			(xy 120.84304 -29.096208) (xy 120.85066 -29.11475) (xy 120.853454 -29.117544) (xy 122.27179 -29.117544)
			(xy 122.612658 -29.117544) (xy 122.628914 -29.101288)
			(arc
				(start 122.658378 -29.071824)
				(mid 122.669489 -29.05529)
				(end 122.673364 -29.035756)
			)
			(arc
				(start 122.673364 -26.727404)
				(mid 122.669463 -26.707881)
				(end 122.658378 -26.691336)
			)
			(xy 122.487944 -26.520902) (xy 122.466862 -26.513282)
			(arc
				(start 122.455432 -26.514552)
				(mid 122.432342 -26.516117)
				(end 122.409204 -26.516584)
			)
			(xy 121.753376 -26.516584) (xy 121.426732 -26.516584) (xy 121.237248 -26.3271) (xy 121.237248 -25.788112)
			(xy 121.15292 -25.703784) (xy 118.224046 -25.703784) (xy 118.21795 -25.705308) (xy 116.39423 -25.705308)
			(xy 116.2177 -25.881838) (xy 116.2177 -26.133298)
			(arc
				(start 116.2177 -28.968446)
				(mid 116.221601 -28.987969)
				(end 116.232686 -29.004514)
			)
			(arc
				(start 116.263674 -29.035502)
				(mid 116.280208 -29.046613)
				(end 116.299742 -29.050488)
			)
			(arc
				(start 118.003828 -29.050488)
				(mid 118.023351 -29.054389)
				(end 118.039896 -29.065474)
			)
			(arc
				(start 118.193312 -29.21889)
				(mid 118.209846 -29.230001)
				(end 118.22938 -29.233876)
			)
			(xy 118.497604 -29.233876)
		)
		(stroke
			(width 0)
			(type solid)
		)
		(fill yes)
		(layer "F.Cu")
		(net "GND")
	)
	(gr_poly
		(pts
			(xy 144.50441 -29.227018)
			(arc
				(start 144.50441 -28.251658)
				(mid 144.500509 -28.232135)
				(end 144.489424 -28.21559)
			)
			(arc
				(start 144.075404 -27.801824)
				(mid 144.064293 -27.78529)
				(end 144.060418 -27.765756)
			)
			(arc
				(start 144.060418 -26.970482)
				(mid 144.064319 -26.950959)
				(end 144.075404 -26.934414)
			)
			(arc
				(start 144.106646 -26.903172)
				(mid 144.12318 -26.892061)
				(end 144.142714 -26.888186)
			)
			(arc
				(start 146.862038 -26.888186)
				(mid 146.881561 -26.892087)
				(end 146.898106 -26.903172)
			)
			(arc
				(start 146.91741 -26.922476)
				(mid 146.928521 -26.93901)
				(end 146.932396 -26.958544)
			)
			(arc
				(start 146.932396 -27.858974)
				(mid 146.928495 -27.878497)
				(end 146.91741 -27.895042)
			)
			(arc
				(start 146.857974 -27.954478)
				(mid 146.846863 -27.971012)
				(end 146.842988 -27.990546)
			)
			(xy 146.842988 -29.096208) (xy 146.850608 -29.11475) (xy 146.853402 -29.117544) (xy 148.271738 -29.117544)
			(xy 148.612606 -29.117544) (xy 148.628862 -29.101288)
			(arc
				(start 148.658326 -29.071824)
				(mid 148.669437 -29.05529)
				(end 148.673312 -29.035756)
			)
			(arc
				(start 148.673312 -26.727404)
				(mid 148.669411 -26.707881)
				(end 148.658326 -26.691336)
			)
			(xy 148.487892 -26.520902) (xy 148.46681 -26.513282)
			(arc
				(start 148.45538 -26.514552)
				(mid 148.43229 -26.516117)
				(end 148.409152 -26.516584)
			)
			(xy 147.753324 -26.516584) (xy 147.42668 -26.516584) (xy 147.237196 -26.3271) (xy 147.237196 -25.788112)
			(xy 147.152868 -25.703784) (xy 144.223994 -25.703784) (xy 144.217898 -25.705308) (xy 142.394178 -25.705308)
			(xy 142.217648 -25.881838) (xy 142.217648 -26.133298)
			(arc
				(start 142.217648 -28.968446)
				(mid 142.221549 -28.987969)
				(end 142.232634 -29.004514)
			)
			(arc
				(start 142.263622 -29.035502)
				(mid 142.280156 -29.046613)
				(end 142.29969 -29.050488)
			)
			(arc
				(start 144.003776 -29.050488)
				(mid 144.023299 -29.054389)
				(end 144.039844 -29.065474)
			)
			(arc
				(start 144.19326 -29.21889)
				(mid 144.209794 -29.230001)
				(end 144.229328 -29.233876)
			)
			(xy 144.497552 -29.233876)
		)
		(stroke
			(width 0)
			(type solid)
		)
		(fill yes)
		(layer "F.Cu")
		(net "GND")
	)
	(gr_poly
		(pts
			(xy 170.504358 -29.227018)
			(arc
				(start 170.504358 -28.251658)
				(mid 170.500457 -28.232135)
				(end 170.489372 -28.21559)
			)
			(arc
				(start 170.075352 -27.801824)
				(mid 170.064241 -27.78529)
				(end 170.060366 -27.765756)
			)
			(arc
				(start 170.060366 -26.970482)
				(mid 170.064267 -26.950959)
				(end 170.075352 -26.934414)
			)
			(arc
				(start 170.106594 -26.903172)
				(mid 170.123128 -26.892061)
				(end 170.142662 -26.888186)
			)
			(arc
				(start 172.861986 -26.888186)
				(mid 172.881509 -26.892087)
				(end 172.898054 -26.903172)
			)
			(arc
				(start 172.917358 -26.922476)
				(mid 172.928469 -26.93901)
				(end 172.932344 -26.958544)
			)
			(arc
				(start 172.932344 -27.858974)
				(mid 172.928443 -27.878497)
				(end 172.917358 -27.895042)
			)
			(arc
				(start 172.857922 -27.954478)
				(mid 172.846811 -27.971012)
				(end 172.842936 -27.990546)
			)
			(xy 172.842936 -29.096208) (xy 172.850556 -29.11475) (xy 172.85335 -29.117544) (xy 174.271686 -29.117544)
			(xy 174.612554 -29.117544) (xy 174.62881 -29.101288)
			(arc
				(start 174.658274 -29.071824)
				(mid 174.669385 -29.05529)
				(end 174.67326 -29.035756)
			)
			(arc
				(start 174.67326 -26.727404)
				(mid 174.669359 -26.707881)
				(end 174.658274 -26.691336)
			)
			(xy 174.48784 -26.520902) (xy 174.466758 -26.513282)
			(arc
				(start 174.455328 -26.514552)
				(mid 174.432238 -26.516117)
				(end 174.4091 -26.516584)
			)
			(xy 173.753272 -26.516584) (xy 173.426628 -26.516584) (xy 173.237144 -26.3271) (xy 173.237144 -25.788112)
			(xy 173.152816 -25.703784) (xy 170.223942 -25.703784) (xy 170.217846 -25.705308) (xy 168.394126 -25.705308)
			(xy 168.217596 -25.881838) (xy 168.217596 -26.133298)
			(arc
				(start 168.217596 -28.968446)
				(mid 168.221497 -28.987969)
				(end 168.232582 -29.004514)
			)
			(arc
				(start 168.26357 -29.035502)
				(mid 168.280104 -29.046613)
				(end 168.299638 -29.050488)
			)
			(arc
				(start 170.003724 -29.050488)
				(mid 170.023247 -29.054389)
				(end 170.039792 -29.065474)
			)
			(arc
				(start 170.193208 -29.21889)
				(mid 170.209742 -29.230001)
				(end 170.229276 -29.233876)
			)
			(xy 170.4975 -29.233876)
		)
		(stroke
			(width 0)
			(type solid)
		)
		(fill yes)
		(layer "F.Cu")
		(net "GND")
	)
	(gr_poly
		(pts
			(xy 196.504306 -29.227018)
			(arc
				(start 196.504306 -28.251658)
				(mid 196.500405 -28.232135)
				(end 196.48932 -28.21559)
			)
			(arc
				(start 196.0753 -27.801824)
				(mid 196.064189 -27.78529)
				(end 196.060314 -27.765756)
			)
			(arc
				(start 196.060314 -26.970482)
				(mid 196.064215 -26.950959)
				(end 196.0753 -26.934414)
			)
			(arc
				(start 196.106542 -26.903172)
				(mid 196.123076 -26.892061)
				(end 196.14261 -26.888186)
			)
			(arc
				(start 198.861934 -26.888186)
				(mid 198.881457 -26.892087)
				(end 198.898002 -26.903172)
			)
			(arc
				(start 198.917306 -26.922476)
				(mid 198.928417 -26.93901)
				(end 198.932292 -26.958544)
			)
			(arc
				(start 198.932292 -27.858974)
				(mid 198.928391 -27.878497)
				(end 198.917306 -27.895042)
			)
			(arc
				(start 198.85787 -27.954478)
				(mid 198.846759 -27.971012)
				(end 198.842884 -27.990546)
			)
			(xy 198.842884 -29.096208) (xy 198.850504 -29.11475) (xy 198.853298 -29.117544) (xy 200.271634 -29.117544)
			(xy 200.612502 -29.117544) (xy 200.628758 -29.101288)
			(arc
				(start 200.658222 -29.071824)
				(mid 200.669333 -29.05529)
				(end 200.673208 -29.035756)
			)
			(arc
				(start 200.673208 -26.727404)
				(mid 200.669307 -26.707881)
				(end 200.658222 -26.691336)
			)
			(xy 200.487788 -26.520902) (xy 200.466706 -26.513282)
			(arc
				(start 200.455276 -26.514552)
				(mid 200.432186 -26.516117)
				(end 200.409048 -26.516584)
			)
			(xy 199.75322 -26.516584) (xy 199.426576 -26.516584) (xy 199.237092 -26.3271) (xy 199.237092 -25.788112)
			(xy 199.152764 -25.703784) (xy 196.22389 -25.703784) (xy 196.217794 -25.705308) (xy 194.394074 -25.705308)
			(xy 194.217544 -25.881838) (xy 194.217544 -26.133298)
			(arc
				(start 194.217544 -28.968446)
				(mid 194.221445 -28.987969)
				(end 194.23253 -29.004514)
			)
			(arc
				(start 194.263518 -29.035502)
				(mid 194.280052 -29.046613)
				(end 194.299586 -29.050488)
			)
			(arc
				(start 196.003672 -29.050488)
				(mid 196.023195 -29.054389)
				(end 196.03974 -29.065474)
			)
			(arc
				(start 196.193156 -29.21889)
				(mid 196.20969 -29.230001)
				(end 196.229224 -29.233876)
			)
			(xy 196.497448 -29.233876)
		)
		(stroke
			(width 0)
			(type solid)
		)
		(fill yes)
		(layer "F.Cu")
		(net "GND")
	)
	(gr_poly
		(pts
			(xy 234.604306 -29.227018)
			(arc
				(start 234.604306 -28.251658)
				(mid 234.600405 -28.232135)
				(end 234.58932 -28.21559)
			)
			(arc
				(start 234.1753 -27.801824)
				(mid 234.164189 -27.78529)
				(end 234.160314 -27.765756)
			)
			(arc
				(start 234.160314 -26.970482)
				(mid 234.164215 -26.950959)
				(end 234.1753 -26.934414)
			)
			(arc
				(start 234.206542 -26.903172)
				(mid 234.223076 -26.892061)
				(end 234.24261 -26.888186)
			)
			(arc
				(start 236.961934 -26.888186)
				(mid 236.981457 -26.892087)
				(end 236.998002 -26.903172)
			)
			(arc
				(start 237.017306 -26.922476)
				(mid 237.028417 -26.93901)
				(end 237.032292 -26.958544)
			)
			(arc
				(start 237.032292 -27.858974)
				(mid 237.028391 -27.878497)
				(end 237.017306 -27.895042)
			)
			(arc
				(start 236.95787 -27.954478)
				(mid 236.946759 -27.971012)
				(end 236.942884 -27.990546)
			)
			(xy 236.942884 -29.096208) (xy 236.950504 -29.11475) (xy 236.953298 -29.117544) (xy 238.371634 -29.117544)
			(xy 238.712502 -29.117544) (xy 238.728758 -29.101288)
			(arc
				(start 238.758222 -29.071824)
				(mid 238.769333 -29.05529)
				(end 238.773208 -29.035756)
			)
			(arc
				(start 238.773208 -26.727404)
				(mid 238.769307 -26.707881)
				(end 238.758222 -26.691336)
			)
			(xy 238.587788 -26.520902) (xy 238.566706 -26.513282)
			(arc
				(start 238.555276 -26.514552)
				(mid 238.532186 -26.516117)
				(end 238.509048 -26.516584)
			)
			(xy 237.85322 -26.516584) (xy 237.526576 -26.516584) (xy 237.337092 -26.3271) (xy 237.337092 -25.788112)
			(xy 237.252764 -25.703784) (xy 234.32389 -25.703784) (xy 234.317794 -25.705308) (xy 232.494074 -25.705308)
			(xy 232.317544 -25.881838) (xy 232.317544 -26.133298)
			(arc
				(start 232.317544 -28.968446)
				(mid 232.321445 -28.987969)
				(end 232.33253 -29.004514)
			)
			(arc
				(start 232.363518 -29.035502)
				(mid 232.380052 -29.046613)
				(end 232.399586 -29.050488)
			)
			(arc
				(start 234.103672 -29.050488)
				(mid 234.123195 -29.054389)
				(end 234.13974 -29.065474)
			)
			(arc
				(start 234.293156 -29.21889)
				(mid 234.30969 -29.230001)
				(end 234.329224 -29.233876)
			)
			(xy 234.597448 -29.233876)
		)
		(stroke
			(width 0)
			(type solid)
		)
		(fill yes)
		(layer "F.Cu")
		(net "GND")
	)
	(gr_poly
		(pts
			(xy 260.604254 -29.227018)
			(arc
				(start 260.604254 -28.251658)
				(mid 260.600353 -28.232135)
				(end 260.589268 -28.21559)
			)
			(arc
				(start 260.175248 -27.801824)
				(mid 260.164137 -27.78529)
				(end 260.160262 -27.765756)
			)
			(arc
				(start 260.160262 -26.970482)
				(mid 260.164163 -26.950959)
				(end 260.175248 -26.934414)
			)
			(arc
				(start 260.20649 -26.903172)
				(mid 260.223024 -26.892061)
				(end 260.242558 -26.888186)
			)
			(arc
				(start 262.961882 -26.888186)
				(mid 262.981405 -26.892087)
				(end 262.99795 -26.903172)
			)
			(arc
				(start 263.017254 -26.922476)
				(mid 263.028365 -26.93901)
				(end 263.03224 -26.958544)
			)
			(arc
				(start 263.03224 -27.858974)
				(mid 263.028339 -27.878497)
				(end 263.017254 -27.895042)
			)
			(arc
				(start 262.957818 -27.954478)
				(mid 262.946707 -27.971012)
				(end 262.942832 -27.990546)
			)
			(xy 262.942832 -29.096208) (xy 262.950452 -29.11475) (xy 262.953246 -29.117544) (xy 264.371582 -29.117544)
			(xy 264.71245 -29.117544) (xy 264.728706 -29.101288)
			(arc
				(start 264.75817 -29.071824)
				(mid 264.769281 -29.05529)
				(end 264.773156 -29.035756)
			)
			(arc
				(start 264.773156 -26.727404)
				(mid 264.769255 -26.707881)
				(end 264.75817 -26.691336)
			)
			(xy 264.587736 -26.520902) (xy 264.566654 -26.513282)
			(arc
				(start 264.555224 -26.514552)
				(mid 264.532134 -26.516117)
				(end 264.508996 -26.516584)
			)
			(xy 263.853168 -26.516584) (xy 263.526524 -26.516584) (xy 263.33704 -26.3271) (xy 263.33704 -25.788112)
			(xy 263.252712 -25.703784) (xy 260.323838 -25.703784) (xy 260.317742 -25.705308) (xy 258.494022 -25.705308)
			(xy 258.317492 -25.881838) (xy 258.317492 -26.133298)
			(arc
				(start 258.317492 -28.968446)
				(mid 258.321393 -28.987969)
				(end 258.332478 -29.004514)
			)
			(arc
				(start 258.363466 -29.035502)
				(mid 258.38 -29.046613)
				(end 258.399534 -29.050488)
			)
			(arc
				(start 260.10362 -29.050488)
				(mid 260.123143 -29.054389)
				(end 260.139688 -29.065474)
			)
			(arc
				(start 260.293104 -29.21889)
				(mid 260.309638 -29.230001)
				(end 260.329172 -29.233876)
			)
			(xy 260.597396 -29.233876)
		)
		(stroke
			(width 0)
			(type solid)
		)
		(fill yes)
		(layer "F.Cu")
		(net "GND")
	)
	(gr_poly
		(pts
			(xy 286.604202 -29.227018)
			(arc
				(start 286.604202 -28.251658)
				(mid 286.600301 -28.232135)
				(end 286.589216 -28.21559)
			)
			(arc
				(start 286.175196 -27.801824)
				(mid 286.164085 -27.78529)
				(end 286.16021 -27.765756)
			)
			(arc
				(start 286.16021 -26.970482)
				(mid 286.164111 -26.950959)
				(end 286.175196 -26.934414)
			)
			(arc
				(start 286.206438 -26.903172)
				(mid 286.222972 -26.892061)
				(end 286.242506 -26.888186)
			)
			(arc
				(start 288.96183 -26.888186)
				(mid 288.981353 -26.892087)
				(end 288.997898 -26.903172)
			)
			(arc
				(start 289.017202 -26.922476)
				(mid 289.028313 -26.93901)
				(end 289.032188 -26.958544)
			)
			(arc
				(start 289.032188 -27.858974)
				(mid 289.028287 -27.878497)
				(end 289.017202 -27.895042)
			)
			(arc
				(start 288.957766 -27.954478)
				(mid 288.946655 -27.971012)
				(end 288.94278 -27.990546)
			)
			(xy 288.94278 -29.096208) (xy 288.9504 -29.11475) (xy 288.953194 -29.117544) (xy 290.37153 -29.117544)
			(xy 290.712398 -29.117544) (xy 290.728654 -29.101288)
			(arc
				(start 290.758118 -29.071824)
				(mid 290.769229 -29.05529)
				(end 290.773104 -29.035756)
			)
			(arc
				(start 290.773104 -26.727404)
				(mid 290.769203 -26.707881)
				(end 290.758118 -26.691336)
			)
			(xy 290.587684 -26.520902) (xy 290.566602 -26.513282)
			(arc
				(start 290.555172 -26.514552)
				(mid 290.532082 -26.516117)
				(end 290.508944 -26.516584)
			)
			(xy 289.853116 -26.516584) (xy 289.526472 -26.516584) (xy 289.336988 -26.3271) (xy 289.336988 -25.788112)
			(xy 289.25266 -25.703784) (xy 286.323786 -25.703784) (xy 286.31769 -25.705308) (xy 284.49397 -25.705308)
			(xy 284.31744 -25.881838) (xy 284.31744 -26.133298)
			(arc
				(start 284.31744 -28.968446)
				(mid 284.321341 -28.987969)
				(end 284.332426 -29.004514)
			)
			(arc
				(start 284.363414 -29.035502)
				(mid 284.379948 -29.046613)
				(end 284.399482 -29.050488)
			)
			(arc
				(start 286.103568 -29.050488)
				(mid 286.123091 -29.054389)
				(end 286.139636 -29.065474)
			)
			(arc
				(start 286.293052 -29.21889)
				(mid 286.309586 -29.230001)
				(end 286.32912 -29.233876)
			)
			(xy 286.597344 -29.233876)
		)
		(stroke
			(width 0)
			(type solid)
		)
		(fill yes)
		(layer "F.Cu")
		(net "GND")
	)
	(gr_poly
		(pts
			(xy 312.60415 -29.227018)
			(arc
				(start 312.60415 -28.251658)
				(mid 312.600249 -28.232135)
				(end 312.589164 -28.21559)
			)
			(arc
				(start 312.175144 -27.801824)
				(mid 312.164033 -27.78529)
				(end 312.160158 -27.765756)
			)
			(arc
				(start 312.160158 -26.970482)
				(mid 312.164059 -26.950959)
				(end 312.175144 -26.934414)
			)
			(arc
				(start 312.206386 -26.903172)
				(mid 312.22292 -26.892061)
				(end 312.242454 -26.888186)
			)
			(arc
				(start 314.961778 -26.888186)
				(mid 314.981301 -26.892087)
				(end 314.997846 -26.903172)
			)
			(arc
				(start 315.01715 -26.922476)
				(mid 315.028261 -26.93901)
				(end 315.032136 -26.958544)
			)
			(arc
				(start 315.032136 -27.858974)
				(mid 315.028235 -27.878497)
				(end 315.01715 -27.895042)
			)
			(arc
				(start 314.957714 -27.954478)
				(mid 314.946603 -27.971012)
				(end 314.942728 -27.990546)
			)
			(xy 314.942728 -29.096208) (xy 314.950348 -29.11475) (xy 314.953142 -29.117544) (xy 316.371478 -29.117544)
			(xy 316.712346 -29.117544) (xy 316.728602 -29.101288)
			(arc
				(start 316.758066 -29.071824)
				(mid 316.769177 -29.05529)
				(end 316.773052 -29.035756)
			)
			(arc
				(start 316.773052 -26.727404)
				(mid 316.769151 -26.707881)
				(end 316.758066 -26.691336)
			)
			(xy 316.587632 -26.520902) (xy 316.56655 -26.513282)
			(arc
				(start 316.55512 -26.514552)
				(mid 316.53203 -26.516117)
				(end 316.508892 -26.516584)
			)
			(xy 315.853064 -26.516584) (xy 315.52642 -26.516584) (xy 315.336936 -26.3271) (xy 315.336936 -25.788112)
			(xy 315.252608 -25.703784) (xy 312.323734 -25.703784) (xy 312.317638 -25.705308) (xy 310.493918 -25.705308)
			(xy 310.317388 -25.881838) (xy 310.317388 -26.133298)
			(arc
				(start 310.317388 -28.968446)
				(mid 310.321289 -28.987969)
				(end 310.332374 -29.004514)
			)
			(arc
				(start 310.363362 -29.035502)
				(mid 310.379896 -29.046613)
				(end 310.39943 -29.050488)
			)
			(arc
				(start 312.103516 -29.050488)
				(mid 312.123039 -29.054389)
				(end 312.139584 -29.065474)
			)
			(arc
				(start 312.293 -29.21889)
				(mid 312.309534 -29.230001)
				(end 312.329068 -29.233876)
			)
			(xy 312.597292 -29.233876)
		)
		(stroke
			(width 0)
			(type solid)
		)
		(fill yes)
		(layer "F.Cu")
		(net "GND")
	)
	(gr_poly
		(pts
			(xy 350.704404 -29.227018)
			(arc
				(start 350.704404 -28.251658)
				(mid 350.700503 -28.232135)
				(end 350.689418 -28.21559)
			)
			(arc
				(start 350.275398 -27.801824)
				(mid 350.264287 -27.78529)
				(end 350.260412 -27.765756)
			)
			(arc
				(start 350.260412 -26.970482)
				(mid 350.264313 -26.950959)
				(end 350.275398 -26.934414)
			)
			(arc
				(start 350.30664 -26.903172)
				(mid 350.323174 -26.892061)
				(end 350.342708 -26.888186)
			)
			(arc
				(start 353.062032 -26.888186)
				(mid 353.081555 -26.892087)
				(end 353.0981 -26.903172)
			)
			(arc
				(start 353.117404 -26.922476)
				(mid 353.128515 -26.93901)
				(end 353.13239 -26.958544)
			)
			(arc
				(start 353.13239 -27.858974)
				(mid 353.128489 -27.878497)
				(end 353.117404 -27.895042)
			)
			(arc
				(start 353.057968 -27.954478)
				(mid 353.046857 -27.971012)
				(end 353.042982 -27.990546)
			)
			(xy 353.042982 -29.096208) (xy 353.050602 -29.11475) (xy 353.053396 -29.117544) (xy 354.471732 -29.117544)
			(xy 354.8126 -29.117544) (xy 354.828856 -29.101288)
			(arc
				(start 354.85832 -29.071824)
				(mid 354.869431 -29.05529)
				(end 354.873306 -29.035756)
			)
			(arc
				(start 354.873306 -26.727404)
				(mid 354.869405 -26.707881)
				(end 354.85832 -26.691336)
			)
			(xy 354.687886 -26.520902) (xy 354.666804 -26.513282)
			(arc
				(start 354.655374 -26.514552)
				(mid 354.632284 -26.516117)
				(end 354.609146 -26.516584)
			)
			(xy 353.953318 -26.516584) (xy 353.626674 -26.516584) (xy 353.43719 -26.3271) (xy 353.43719 -25.788112)
			(xy 353.352862 -25.703784) (xy 350.423988 -25.703784) (xy 350.417892 -25.705308) (xy 348.594172 -25.705308)
			(xy 348.417642 -25.881838) (xy 348.417642 -26.133298)
			(arc
				(start 348.417642 -28.968446)
				(mid 348.421543 -28.987969)
				(end 348.432628 -29.004514)
			)
			(arc
				(start 348.463616 -29.035502)
				(mid 348.48015 -29.046613)
				(end 348.499684 -29.050488)
			)
			(arc
				(start 350.20377 -29.050488)
				(mid 350.223293 -29.054389)
				(end 350.239838 -29.065474)
			)
			(arc
				(start 350.393254 -29.21889)
				(mid 350.409788 -29.230001)
				(end 350.429322 -29.233876)
			)
			(xy 350.697546 -29.233876)
		)
		(stroke
			(width 0)
			(type solid)
		)
		(fill yes)
		(layer "F.Cu")
		(net "GND")
	)
	(gr_poly
		(pts
			(xy 376.704352 -29.227018)
			(arc
				(start 376.704352 -28.251658)
				(mid 376.700451 -28.232135)
				(end 376.689366 -28.21559)
			)
			(arc
				(start 376.275346 -27.801824)
				(mid 376.264235 -27.78529)
				(end 376.26036 -27.765756)
			)
			(arc
				(start 376.26036 -26.970482)
				(mid 376.264261 -26.950959)
				(end 376.275346 -26.934414)
			)
			(arc
				(start 376.306588 -26.903172)
				(mid 376.323122 -26.892061)
				(end 376.342656 -26.888186)
			)
			(arc
				(start 379.06198 -26.888186)
				(mid 379.081503 -26.892087)
				(end 379.098048 -26.903172)
			)
			(arc
				(start 379.117352 -26.922476)
				(mid 379.128463 -26.93901)
				(end 379.132338 -26.958544)
			)
			(arc
				(start 379.132338 -27.858974)
				(mid 379.128437 -27.878497)
				(end 379.117352 -27.895042)
			)
			(arc
				(start 379.057916 -27.954478)
				(mid 379.046805 -27.971012)
				(end 379.04293 -27.990546)
			)
			(xy 379.04293 -29.096208) (xy 379.05055 -29.11475) (xy 379.053344 -29.117544) (xy 380.47168 -29.117544)
			(xy 380.812548 -29.117544) (xy 380.828804 -29.101288)
			(arc
				(start 380.858268 -29.071824)
				(mid 380.869379 -29.05529)
				(end 380.873254 -29.035756)
			)
			(arc
				(start 380.873254 -26.727404)
				(mid 380.869353 -26.707881)
				(end 380.858268 -26.691336)
			)
			(xy 380.687834 -26.520902) (xy 380.666752 -26.513282)
			(arc
				(start 380.655322 -26.514552)
				(mid 380.632232 -26.516117)
				(end 380.609094 -26.516584)
			)
			(xy 379.953266 -26.516584) (xy 379.626622 -26.516584) (xy 379.437138 -26.3271) (xy 379.437138 -25.788112)
			(xy 379.35281 -25.703784) (xy 376.423936 -25.703784) (xy 376.41784 -25.705308) (xy 374.59412 -25.705308)
			(xy 374.41759 -25.881838) (xy 374.41759 -26.133298)
			(arc
				(start 374.41759 -28.968446)
				(mid 374.421491 -28.987969)
				(end 374.432576 -29.004514)
			)
			(arc
				(start 374.463564 -29.035502)
				(mid 374.480098 -29.046613)
				(end 374.499632 -29.050488)
			)
			(arc
				(start 376.203718 -29.050488)
				(mid 376.223241 -29.054389)
				(end 376.239786 -29.065474)
			)
			(arc
				(start 376.393202 -29.21889)
				(mid 376.409736 -29.230001)
				(end 376.42927 -29.233876)
			)
			(xy 376.697494 -29.233876)
		)
		(stroke
			(width 0)
			(type solid)
		)
		(fill yes)
		(layer "F.Cu")
		(net "GND")
	)
	(gr_poly
		(pts
			(xy 402.7043 -29.227018)
			(arc
				(start 402.7043 -28.251658)
				(mid 402.700399 -28.232135)
				(end 402.689314 -28.21559)
			)
			(arc
				(start 402.275294 -27.801824)
				(mid 402.264183 -27.78529)
				(end 402.260308 -27.765756)
			)
			(arc
				(start 402.260308 -26.970482)
				(mid 402.264209 -26.950959)
				(end 402.275294 -26.934414)
			)
			(arc
				(start 402.306536 -26.903172)
				(mid 402.32307 -26.892061)
				(end 402.342604 -26.888186)
			)
			(arc
				(start 405.061928 -26.888186)
				(mid 405.081451 -26.892087)
				(end 405.097996 -26.903172)
			)
			(arc
				(start 405.1173 -26.922476)
				(mid 405.128411 -26.93901)
				(end 405.132286 -26.958544)
			)
			(arc
				(start 405.132286 -27.858974)
				(mid 405.128385 -27.878497)
				(end 405.1173 -27.895042)
			)
			(arc
				(start 405.057864 -27.954478)
				(mid 405.046753 -27.971012)
				(end 405.042878 -27.990546)
			)
			(xy 405.042878 -29.096208) (xy 405.050498 -29.11475) (xy 405.053292 -29.117544) (xy 406.471628 -29.117544)
			(xy 406.812496 -29.117544) (xy 406.828752 -29.101288)
			(arc
				(start 406.858216 -29.071824)
				(mid 406.869327 -29.05529)
				(end 406.873202 -29.035756)
			)
			(arc
				(start 406.873202 -26.727404)
				(mid 406.869301 -26.707881)
				(end 406.858216 -26.691336)
			)
			(xy 406.687782 -26.520902) (xy 406.6667 -26.513282)
			(arc
				(start 406.65527 -26.514552)
				(mid 406.63218 -26.516117)
				(end 406.609042 -26.516584)
			)
			(xy 405.953214 -26.516584) (xy 405.62657 -26.516584) (xy 405.437086 -26.3271) (xy 405.437086 -25.788112)
			(xy 405.352758 -25.703784) (xy 402.423884 -25.703784) (xy 402.417788 -25.705308) (xy 400.594068 -25.705308)
			(xy 400.417538 -25.881838) (xy 400.417538 -26.133298)
			(arc
				(start 400.417538 -28.968446)
				(mid 400.421439 -28.987969)
				(end 400.432524 -29.004514)
			)
			(arc
				(start 400.463512 -29.035502)
				(mid 400.480046 -29.046613)
				(end 400.49958 -29.050488)
			)
			(arc
				(start 402.203666 -29.050488)
				(mid 402.223189 -29.054389)
				(end 402.239734 -29.065474)
			)
			(arc
				(start 402.39315 -29.21889)
				(mid 402.409684 -29.230001)
				(end 402.429218 -29.233876)
			)
			(xy 402.697442 -29.233876)
		)
		(stroke
			(width 0)
			(type solid)
		)
		(fill yes)
		(layer "F.Cu")
		(net "GND")
	)
	(gr_poly
		(pts
			(xy 428.704248 -29.227018)
			(arc
				(start 428.704248 -28.251658)
				(mid 428.700347 -28.232135)
				(end 428.689262 -28.21559)
			)
			(arc
				(start 428.275242 -27.801824)
				(mid 428.264131 -27.78529)
				(end 428.260256 -27.765756)
			)
			(arc
				(start 428.260256 -26.970482)
				(mid 428.264157 -26.950959)
				(end 428.275242 -26.934414)
			)
			(arc
				(start 428.306484 -26.903172)
				(mid 428.323018 -26.892061)
				(end 428.342552 -26.888186)
			)
			(arc
				(start 431.061876 -26.888186)
				(mid 431.081399 -26.892087)
				(end 431.097944 -26.903172)
			)
			(arc
				(start 431.117248 -26.922476)
				(mid 431.128359 -26.93901)
				(end 431.132234 -26.958544)
			)
			(arc
				(start 431.132234 -27.858974)
				(mid 431.128333 -27.878497)
				(end 431.117248 -27.895042)
			)
			(arc
				(start 431.057812 -27.954478)
				(mid 431.046701 -27.971012)
				(end 431.042826 -27.990546)
			)
			(xy 431.042826 -29.096208) (xy 431.050446 -29.11475) (xy 431.05324 -29.117544) (xy 432.471576 -29.117544)
			(xy 432.812444 -29.117544) (xy 432.8287 -29.101288)
			(arc
				(start 432.858164 -29.071824)
				(mid 432.869275 -29.05529)
				(end 432.87315 -29.035756)
			)
			(arc
				(start 432.87315 -26.727404)
				(mid 432.869249 -26.707881)
				(end 432.858164 -26.691336)
			)
			(xy 432.68773 -26.520902) (xy 432.666648 -26.513282)
			(arc
				(start 432.655218 -26.514552)
				(mid 432.632128 -26.516117)
				(end 432.60899 -26.516584)
			)
			(xy 431.953162 -26.516584) (xy 431.626518 -26.516584) (xy 431.437034 -26.3271) (xy 431.437034 -25.788112)
			(xy 431.352706 -25.703784) (xy 428.423832 -25.703784) (xy 428.417736 -25.705308) (xy 426.594016 -25.705308)
			(xy 426.417486 -25.881838) (xy 426.417486 -26.133298)
			(arc
				(start 426.417486 -28.968446)
				(mid 426.421387 -28.987969)
				(end 426.432472 -29.004514)
			)
			(arc
				(start 426.46346 -29.035502)
				(mid 426.479994 -29.046613)
				(end 426.499528 -29.050488)
			)
			(arc
				(start 428.203614 -29.050488)
				(mid 428.223137 -29.054389)
				(end 428.239682 -29.065474)
			)
			(arc
				(start 428.393098 -29.21889)
				(mid 428.409632 -29.230001)
				(end 428.429166 -29.233876)
			)
			(xy 428.69739 -29.233876)
		)
		(stroke
			(width 0)
			(type solid)
		)
		(fill yes)
		(layer "F.Cu")
		(net "GND")
	)
	(gr_poly
		(pts
			(xy 376.95378 -258.225544)
			(arc
				(start 376.95378 -257.767582)
				(mid 376.977035 -257.65076)
				(end 377.043188 -257.551682)
			)
			(xy 377.043442 -257.551682) (xy 377.19127 -257.403854)
			(arc
				(start 377.19127 -257.4036)
				(mid 377.290312 -257.337359)
				(end 377.40717 -257.314192)
			)
			(xy 381.072644 -257.314192) (xy 381.103378 -257.315716) (xy 381.115062 -257.316732) (xy 381.136144 -257.309366)
			(arc
				(start 381.230124 -257.215386)
				(mid 381.241235 -257.198852)
				(end 381.24511 -257.179318)
			)
			(arc
				(start 381.24511 -256.143506)
				(mid 381.241209 -256.123983)
				(end 381.230124 -256.107438)
			)
			(arc
				(start 381.045466 -255.92278)
				(mid 381.02902 -255.911854)
				(end 381.009652 -255.908048)
			)
			(arc
				(start 377.540774 -255.908048)
				(mid 377.507035 -255.906093)
				(end 377.473718 -255.900428)
			)
			(xy 377.46813 -255.899158)
			(arc
				(start 377.33986 -255.899158)
				(mid 377.320337 -255.895257)
				(end 377.303792 -255.884172)
			)
			(arc
				(start 377.149614 -255.729994)
				(mid 377.138503 -255.71346)
				(end 377.134628 -255.693926)
			)
			(xy 377.134628 -255.635252) (xy 377.129548 -255.620012)
			(arc
				(start 377.124722 -255.613408)
				(mid 377.080004 -255.527444)
				(end 377.064524 -255.431798)
			)
			(arc
				(start 377.064524 -254.420624)
				(mid 377.060691 -254.401267)
				(end 377.049792 -254.38481)
			)
			(arc
				(start 376.970798 -254.305816)
				(mid 376.954264 -254.294705)
				(end 376.93473 -254.29083)
			)
			(arc
				(start 375.653046 -254.29083)
				(mid 375.633523 -254.294731)
				(end 375.616978 -254.305816)
			)
			(xy 375.566432 -254.356362) (xy 375.56313 -254.392684)
			(arc
				(start 375.57329 -254.40767)
				(mid 375.612351 -254.489208)
				(end 375.625868 -254.578612)
			)
			(arc
				(start 375.625868 -258.116832)
				(mid 375.629701 -258.136189)
				(end 375.6406 -258.152646)
			)
			(arc
				(start 375.70156 -258.213606)
				(mid 375.718094 -258.224717)
				(end 375.737628 -258.228592)
			)
			(xy 376.950732 -258.228592)
		)
		(stroke
			(width 0)
			(type solid)
		)
		(fill yes)
		(layer "F.Cu")
		(net "GND")
	)
	(gr_poly
		(pts
			(xy 114.450114 -254.829056) (xy 114.468656 -254.829564) (xy 114.751358 -254.829564) (xy 114.77625 -254.813308)
			(arc
				(start 114.7826 -254.799592)
				(mid 115.13058 -254.574368)
				(end 115.47856 -254.799592)
			)
			(xy 115.48491 -254.813308) (xy 115.509802 -254.829564)
			(arc
				(start 115.590828 -254.829564)
				(mid 115.598538 -254.829015)
				(end 115.606068 -254.827278)
			)
			(xy 115.626896 -254.820674)
			(arc
				(start 115.632992 -254.816864)
				(mid 115.749689 -254.762439)
				(end 115.877086 -254.743712)
			)
			(arc
				(start 115.87734 -254.743712)
				(mid 115.954177 -254.750351)
				(end 116.028724 -254.770128)
			)
			(xy 116.032534 -254.771652)
			(arc
				(start 116.041424 -254.773176)
				(mid 116.063466 -254.772342)
				(end 116.08308 -254.762254)
			)
			(xy 116.091462 -254.755142) (xy 116.101114 -254.734822)
			(arc
				(start 116.101114 -254.342646)
				(mid 116.097213 -254.323123)
				(end 116.086128 -254.306578)
			)
			(xy 115.927632 -254.148082) (xy 115.92052 -254.140716) (xy 115.901724 -254.133096) (xy 115.879372 -254.110744)
			(xy 115.879372 -254.100076) (xy 115.864386 -254.08509)
			(arc
				(start 115.4811 -253.70155)
				(mid 115.469989 -253.685016)
				(end 115.466114 -253.665482)
			)
			(arc
				(start 115.466114 -252.437646)
				(mid 115.462213 -252.418123)
				(end 115.451128 -252.401578)
			)
			(xy 115.3541 -252.30455) (xy 115.346988 -252.297184) (xy 115.328192 -252.289564)
			(arc
				(start 113.963196 -252.289564)
				(mid 113.943673 -252.293465)
				(end 113.927128 -252.30455)
			)
			(xy 113.8301 -252.401578) (xy 113.822734 -252.40869) (xy 113.815114 -252.427486)
			(arc
				(start 113.815114 -254.427482)
				(mid 113.819015 -254.447005)
				(end 113.8301 -254.46355)
			)
			(arc
				(start 114.181128 -254.814578)
				(mid 114.197662 -254.825689)
				(end 114.217196 -254.829564)
			)
			(xy 114.431572 -254.829564)
		)
		(stroke
			(width 0)
			(type solid)
		)
		(fill yes)
		(layer "F.Cu")
		(net "GND")
	)
	(gr_poly
		(pts
			(xy 346.65031 -254.829056) (xy 346.668852 -254.829564) (xy 346.951554 -254.829564) (xy 346.976446 -254.813308)
			(arc
				(start 346.982796 -254.799592)
				(mid 347.330776 -254.574368)
				(end 347.678756 -254.799592)
			)
			(xy 347.685106 -254.813308) (xy 347.709998 -254.829564)
			(arc
				(start 347.791024 -254.829564)
				(mid 347.798734 -254.829015)
				(end 347.806264 -254.827278)
			)
			(xy 347.827092 -254.820674)
			(arc
				(start 347.833188 -254.816864)
				(mid 347.949885 -254.762439)
				(end 348.077282 -254.743712)
			)
			(arc
				(start 348.077536 -254.743712)
				(mid 348.154373 -254.750351)
				(end 348.22892 -254.770128)
			)
			(xy 348.23273 -254.771652)
			(arc
				(start 348.24162 -254.773176)
				(mid 348.263662 -254.772342)
				(end 348.283276 -254.762254)
			)
			(xy 348.291658 -254.755142) (xy 348.30131 -254.734822)
			(arc
				(start 348.30131 -254.342646)
				(mid 348.297409 -254.323123)
				(end 348.286324 -254.306578)
			)
			(xy 348.127828 -254.148082) (xy 348.120716 -254.140716) (xy 348.10192 -254.133096) (xy 348.079568 -254.110744)
			(xy 348.079568 -254.100076) (xy 348.064582 -254.08509)
			(arc
				(start 347.681296 -253.70155)
				(mid 347.670185 -253.685016)
				(end 347.66631 -253.665482)
			)
			(arc
				(start 347.66631 -252.437646)
				(mid 347.662409 -252.418123)
				(end 347.651324 -252.401578)
			)
			(xy 347.554296 -252.30455) (xy 347.547184 -252.297184) (xy 347.528388 -252.289564)
			(arc
				(start 346.163392 -252.289564)
				(mid 346.143869 -252.293465)
				(end 346.127324 -252.30455)
			)
			(xy 346.030296 -252.401578) (xy 346.02293 -252.40869) (xy 346.01531 -252.427486)
			(arc
				(start 346.01531 -254.427482)
				(mid 346.019211 -254.447005)
				(end 346.030296 -254.46355)
			)
			(arc
				(start 346.381324 -254.814578)
				(mid 346.397858 -254.825689)
				(end 346.417392 -254.829564)
			)
			(xy 346.631768 -254.829564)
		)
		(stroke
			(width 0)
			(type solid)
		)
		(fill yes)
		(layer "F.Cu")
		(net "GND")
	)
	(gr_poly
		(pts
			(xy 106.61269 -113.393728) (xy 106.61269 -109.679486) (xy 106.502708 -109.569504) (xy 103.538528 -109.569504)
			(xy 103.339138 -109.370114) (xy 103.339138 -108.435902) (xy 103.201216 -108.29798) (xy 98.662998 -108.29798)
			(xy 98.510598 -108.14558) (xy 98.510598 -105.469182) (xy 98.509582 -105.468166) (xy 98.509582 -101.772212)
			(xy 99.049332 -101.232462) (xy 99.049332 -100.22713) (xy 99.001072 -100.17887) (xy 96.750378 -100.17887)
			(xy 96.744282 -100.184966) (xy 96.744282 -100.869242) (xy 96.598486 -101.015038) (xy 94.488762 -101.015038)
			(xy 94.447868 -101.055932) (xy 94.447868 -104.213152) (xy 94.001082 -104.659938) (xy 92.54236 -104.659938)
			(xy 92.076778 -104.194356) (xy 92.076778 -103.06939) (xy 91.774264 -102.766876)
			(arc
				(start 91.546426 -102.766876)
				(mid 91.526903 -102.762975)
				(end 91.510358 -102.75189)
			)
			(arc
				(start 91.2876 -102.529132)
				(mid 91.276489 -102.512598)
				(end 91.272614 -102.493064)
			)
			(arc
				(start 91.272614 -102.17404)
				(mid 91.271677 -102.164072)
				(end 91.268804 -102.154482)
			)
			(arc
				(start 91.209622 -102.01148)
				(mid 91.198722 -101.981909)
				(end 91.190318 -101.951536)
			)
			(xy 91.188794 -101.944424) (xy 91.181936 -101.932232) (xy 91.174316 -101.924612)
			(arc
				(start 91.174316 -101.383338)
				(mid 91.170415 -101.363815)
				(end 91.15933 -101.34727)
			)
			(arc
				(start 91.14409 -101.33203)
				(mid 91.127556 -101.320919)
				(end 91.108022 -101.317044)
			)
			(arc
				(start 91.044522 -101.317044)
				(mid 91.024999 -101.320945)
				(end 91.008454 -101.33203)
			)
			(arc
				(start 90.958924 -101.38156)
				(mid 90.947813 -101.398094)
				(end 90.943938 -101.417628)
			)
			(arc
				(start 90.943938 -102.072186)
				(mid 90.940037 -102.091709)
				(end 90.928952 -102.108254)
			)
			(xy 90.92819 -102.108762)
			(arc
				(start 90.92819 -102.148386)
				(mid 90.924309 -102.167607)
				(end 90.913458 -102.183946)
			)
			(arc
				(start 90.528648 -102.56901)
				(mid 90.517586 -102.585427)
				(end 90.513662 -102.604824)
			)
			(xy 90.513662 -108.84662) (xy 90.513662 -110.931706) (xy 90.677238 -111.095282) (xy 90.87993 -111.095282)
			(xy 93.072204 -111.095282) (xy 93.2307 -111.253778) (xy 93.2307 -112.4204) (xy 93.449648 -112.639348)
			(xy 97.028254 -112.639348) (xy 97.814638 -113.425732) (xy 106.580686 -113.425732)
		)
		(stroke
			(width 0)
			(type solid)
		)
		(fill yes)
		(layer "F.Cu")
		(net "P12V_NIC1_R")
	)
	(gr_poly
		(pts
			(xy 333.73822 -113.400332) (xy 338.806028 -113.400332) (xy 338.812632 -113.393728) (xy 338.812632 -109.679486)
			(xy 338.70265 -109.569504) (xy 335.73847 -109.569504) (xy 335.53908 -109.370114) (xy 335.53908 -108.435902)
			(xy 335.401158 -108.29798) (xy 330.86294 -108.29798) (xy 330.71054 -108.14558) (xy 330.71054 -105.469182)
			(xy 330.709524 -105.468166) (xy 330.709524 -101.772212) (xy 331.249274 -101.232462) (xy 331.249274 -100.22713)
			(xy 331.201014 -100.17887) (xy 328.95032 -100.17887) (xy 328.944224 -100.184966) (xy 328.944224 -100.869242)
			(xy 328.798428 -101.015038) (xy 326.688704 -101.015038) (xy 326.64781 -101.055932) (xy 326.64781 -104.213152)
			(xy 326.201024 -104.659938) (xy 324.742302 -104.659938) (xy 324.27672 -104.194356) (xy 324.27672 -103.06939)
			(xy 323.974206 -102.766876)
			(arc
				(start 323.746368 -102.766876)
				(mid 323.726845 -102.762975)
				(end 323.7103 -102.75189)
			)
			(arc
				(start 323.487542 -102.529132)
				(mid 323.476431 -102.512598)
				(end 323.472556 -102.493064)
			)
			(arc
				(start 323.472556 -102.17404)
				(mid 323.471619 -102.164072)
				(end 323.468746 -102.154482)
			)
			(arc
				(start 323.409564 -102.01148)
				(mid 323.398664 -101.981909)
				(end 323.39026 -101.951536)
			)
			(xy 323.388736 -101.944424) (xy 323.381878 -101.932232) (xy 323.374258 -101.924612)
			(arc
				(start 323.374258 -101.383338)
				(mid 323.370357 -101.363815)
				(end 323.359272 -101.34727)
			)
			(arc
				(start 323.344032 -101.33203)
				(mid 323.327498 -101.320919)
				(end 323.307964 -101.317044)
			)
			(arc
				(start 323.244464 -101.317044)
				(mid 323.224941 -101.320945)
				(end 323.208396 -101.33203)
			)
			(arc
				(start 323.158866 -101.38156)
				(mid 323.147755 -101.398094)
				(end 323.14388 -101.417628)
			)
			(arc
				(start 323.14388 -102.072186)
				(mid 323.139979 -102.091709)
				(end 323.128894 -102.108254)
			)
			(xy 323.128132 -102.108762)
			(arc
				(start 323.128132 -102.148386)
				(mid 323.124251 -102.167607)
				(end 323.1134 -102.183946)
			)
			(arc
				(start 322.72859 -102.56901)
				(mid 322.717528 -102.585427)
				(end 322.713604 -102.604824)
			)
			(xy 322.713604 -110.931706) (xy 322.87718 -111.095282) (xy 325.272146 -111.095282) (xy 325.430642 -111.253778)
			(xy 325.430642 -112.4204) (xy 325.64959 -112.639348) (xy 329.228196 -112.639348) (xy 330.01458 -113.425732)
			(xy 333.71282 -113.425732)
		)
		(stroke
			(width 0)
			(type solid)
		)
		(fill yes)
		(layer "F.Cu")
		(net "P12V_NIC5_R")
	)
	(gr_poly
		(pts
			(xy 449.838318 -113.400332) (xy 454.906126 -113.400332) (xy 454.91273 -113.393728) (xy 454.91273 -109.679486)
			(xy 454.802748 -109.569504) (xy 451.838568 -109.569504) (xy 451.639178 -109.370114) (xy 451.639178 -108.435902)
			(xy 451.501256 -108.29798) (xy 446.963038 -108.29798) (xy 446.810638 -108.14558) (xy 446.810638 -105.469182)
			(xy 446.809622 -105.468166) (xy 446.809622 -101.772212) (xy 447.349372 -101.232462) (xy 447.349372 -100.22713)
			(xy 447.301112 -100.17887) (xy 445.08293 -100.17887) (xy 445.064134 -100.197666) (xy 445.064134 -100.84943)
			(xy 444.898526 -101.015038) (xy 442.788802 -101.015038) (xy 442.747908 -101.055932) (xy 442.747908 -104.213152)
			(xy 442.301122 -104.659938) (xy 440.8424 -104.659938) (xy 440.376818 -104.194356) (xy 440.376818 -103.06939)
			(xy 440.074304 -102.766876)
			(arc
				(start 439.846466 -102.766876)
				(mid 439.826943 -102.762975)
				(end 439.810398 -102.75189)
			)
			(arc
				(start 439.58764 -102.529132)
				(mid 439.576529 -102.512598)
				(end 439.572654 -102.493064)
			)
			(arc
				(start 439.572654 -102.17404)
				(mid 439.571717 -102.164072)
				(end 439.568844 -102.154482)
			)
			(arc
				(start 439.509662 -102.01148)
				(mid 439.498762 -101.981909)
				(end 439.490358 -101.951536)
			)
			(xy 439.488834 -101.944424) (xy 439.481976 -101.932232) (xy 439.474356 -101.924612)
			(arc
				(start 439.474356 -101.383338)
				(mid 439.470455 -101.363815)
				(end 439.45937 -101.34727)
			)
			(arc
				(start 439.44413 -101.33203)
				(mid 439.427596 -101.320919)
				(end 439.408062 -101.317044)
			)
			(arc
				(start 439.344562 -101.317044)
				(mid 439.325039 -101.320945)
				(end 439.308494 -101.33203)
			)
			(arc
				(start 439.258964 -101.38156)
				(mid 439.247853 -101.398094)
				(end 439.243978 -101.417628)
			)
			(arc
				(start 439.243978 -102.072186)
				(mid 439.240077 -102.091709)
				(end 439.228992 -102.108254)
			)
			(xy 439.22823 -102.108762)
			(arc
				(start 439.22823 -102.148386)
				(mid 439.224349 -102.167607)
				(end 439.213498 -102.183946)
			)
			(arc
				(start 438.828688 -102.56901)
				(mid 438.817626 -102.585427)
				(end 438.813702 -102.604824)
			)
			(xy 438.813702 -110.931706) (xy 438.977278 -111.095282) (xy 441.372244 -111.095282) (xy 441.53074 -111.253778)
			(xy 441.53074 -112.4204) (xy 441.749688 -112.639348) (xy 445.328294 -112.639348) (xy 446.114678 -113.425732)
			(xy 449.812918 -113.425732)
		)
		(stroke
			(width 0)
			(type solid)
		)
		(fill yes)
		(layer "F.Cu")
		(net "P12V_NIC7_R")
	)
	(gr_poly
		(pts
			(arc
				(start 305.08702 -230.062278)
				(mid 305.106543 -230.058377)
				(end 305.123088 -230.047292)
			)
			(arc
				(start 317.539878 -217.630502)
				(mid 317.550989 -217.613968)
				(end 317.554864 -217.594434)
			)
			(arc
				(start 317.554864 -165.775386)
				(mid 317.558765 -165.755863)
				(end 317.56985 -165.739318)
			)
			(arc
				(start 326.203564 -157.105604)
				(mid 326.214675 -157.08907)
				(end 326.21855 -157.069536)
			)
			(arc
				(start 326.21855 -140.027914)
				(mid 326.222451 -140.008391)
				(end 326.233536 -139.991846)
			)
			(arc
				(start 331.663802 -134.56158)
				(mid 331.680336 -134.550469)
				(end 331.69987 -134.546594)
			)
			(arc
				(start 336.722212 -134.546594)
				(mid 336.741735 -134.542693)
				(end 336.75828 -134.531608)
			)
			(arc
				(start 337.399376 -133.890512)
				(mid 337.410487 -133.873978)
				(end 337.414362 -133.854444)
			)
			(arc
				(start 337.414362 -132.249164)
				(mid 337.410461 -132.229641)
				(end 337.399376 -132.213096)
			)
			(arc
				(start 336.514186 -131.327906)
				(mid 336.497652 -131.316795)
				(end 336.478118 -131.31292)
			)
			(arc
				(start 330.144374 -131.31292)
				(mid 330.124851 -131.316821)
				(end 330.108306 -131.327906)
			)
			(arc
				(start 322.450714 -138.985498)
				(mid 322.439603 -139.002032)
				(end 322.435728 -139.021566)
			)
			(arc
				(start 322.435728 -153.531062)
				(mid 322.431827 -153.550585)
				(end 322.420742 -153.56713)
			)
			(arc
				(start 316.872874 -159.114998)
				(mid 316.85634 -159.126109)
				(end 316.836806 -159.129984)
			)
			(arc
				(start 314.519564 -159.129984)
				(mid 314.500041 -159.133885)
				(end 314.483496 -159.14497)
			)
			(arc
				(start 313.298586 -160.32988)
				(mid 313.287475 -160.346414)
				(end 313.2836 -160.365948)
			)
			(arc
				(start 313.2836 -215.580976)
				(mid 313.279699 -215.600499)
				(end 313.268614 -215.617044)
			)
			(arc
				(start 302.255428 -226.63023)
				(mid 302.238894 -226.641341)
				(end 302.21936 -226.645216)
			)
			(arc
				(start 301.468282 -226.645216)
				(mid 301.448759 -226.649117)
				(end 301.432214 -226.660202)
			)
			(arc
				(start 301.096172 -226.996244)
				(mid 301.085061 -227.012778)
				(end 301.081186 -227.032312)
			)
			(arc
				(start 301.081186 -229.491794)
				(mid 301.085087 -229.511317)
				(end 301.096172 -229.527862)
			)
			(arc
				(start 301.615602 -230.047292)
				(mid 301.632136 -230.058403)
				(end 301.65167 -230.062278)
			)
		)
		(stroke
			(width 0)
			(type solid)
		)
		(fill yes)
		(layer "F.Cu")
		(net "P5V_AUX")
	)
	(gr_poly
		(pts
			(xy 28.404312 -29.227018)
			(arc
				(start 28.404312 -28.251658)
				(mid 28.400411 -28.232135)
				(end 28.389326 -28.21559)
			)
			(arc
				(start 27.975306 -27.801824)
				(mid 27.964195 -27.78529)
				(end 27.96032 -27.765756)
			)
			(arc
				(start 27.96032 -26.970482)
				(mid 27.964221 -26.950959)
				(end 27.975306 -26.934414)
			)
			(arc
				(start 28.006548 -26.903172)
				(mid 28.023082 -26.892061)
				(end 28.042616 -26.888186)
			)
			(arc
				(start 30.76194 -26.888186)
				(mid 30.781463 -26.892087)
				(end 30.798008 -26.903172)
			)
			(arc
				(start 30.817312 -26.922476)
				(mid 30.828423 -26.93901)
				(end 30.832298 -26.958544)
			)
			(arc
				(start 30.832298 -27.858974)
				(mid 30.828397 -27.878497)
				(end 30.817312 -27.895042)
			)
			(arc
				(start 30.757876 -27.954478)
				(mid 30.746765 -27.971012)
				(end 30.74289 -27.990546)
			)
			(xy 30.74289 -29.096208) (xy 30.75051 -29.11475) (xy 30.753304 -29.117544) (xy 32.17164 -29.117544)
			(xy 32.512508 -29.117544) (xy 32.528764 -29.101288)
			(arc
				(start 32.558228 -29.071824)
				(mid 32.569339 -29.05529)
				(end 32.573214 -29.035756)
			)
			(arc
				(start 32.573214 -26.727404)
				(mid 32.569313 -26.707881)
				(end 32.558228 -26.691336)
			)
			(xy 32.387794 -26.520902) (xy 32.366712 -26.513282)
			(arc
				(start 32.355282 -26.514552)
				(mid 32.332192 -26.516117)
				(end 32.309054 -26.516584)
			)
			(xy 31.653226 -26.516584) (xy 31.326582 -26.516584) (xy 31.137098 -26.3271) (xy 31.137098 -25.788112)
			(xy 31.05277 -25.703784) (xy 28.123896 -25.703784)
			(arc
				(start 28.117038 -25.705562)
				(mid 27.151099 -25.912036)
				(end 26.16708 -25.997916)
			)
			(arc
				(start 26.16708 -25.997916)
				(mid 26.131972 -26.013236)
				(end 26.11755 -26.048716)
			)
			(arc
				(start 26.11755 -28.968446)
				(mid 26.121451 -28.987969)
				(end 26.132536 -29.004514)
			)
			(arc
				(start 26.163524 -29.035502)
				(mid 26.180058 -29.046613)
				(end 26.199592 -29.050488)
			)
			(arc
				(start 27.903678 -29.050488)
				(mid 27.923201 -29.054389)
				(end 27.939746 -29.065474)
			)
			(arc
				(start 28.093162 -29.21889)
				(mid 28.109696 -29.230001)
				(end 28.12923 -29.233876)
			)
			(xy 28.397454 -29.233876)
		)
		(stroke
			(width 0)
			(type solid)
		)
		(fill yes)
		(layer "F.Cu")
		(net "GND")
	)
	(gr_poly
		(pts
			(arc
				(start 103.226362 -244.03558)
				(mid 103.245885 -244.031679)
				(end 103.26243 -244.020594)
			)
			(arc
				(start 103.791258 -243.491766)
				(mid 103.807792 -243.480655)
				(end 103.827326 -243.47678)
			)
			(xy 107.168442 -243.47678) (xy 113.923826 -243.47678) (xy 113.948718 -243.451888) (xy 115.542822 -241.857784)
			(xy 115.542822 -234.561888) (xy 113.810288 -232.829354) (xy 99.342956 -232.829354) (xy 99.088956 -233.083354)
			(xy 99.088956 -237.147354) (xy 99.215956 -237.274354) (xy 108.247942 -237.274354) (xy 108.613448 -237.63986)
			(xy 108.613448 -239.10671) (xy 107.951524 -239.768634)
			(arc
				(start 103.612188 -239.768634)
				(mid 103.592665 -239.772535)
				(end 103.57612 -239.78362)
			)
			(arc
				(start 103.349298 -240.010442)
				(mid 103.338187 -240.026976)
				(end 103.334312 -240.04651)
			)
			(arc
				(start 103.334312 -241.605562)
				(mid 103.330411 -241.625085)
				(end 103.319326 -241.64163)
			)
			(arc
				(start 102.4255 -242.535456)
				(mid 102.408966 -242.546567)
				(end 102.389432 -242.550442)
			)
			(arc
				(start 101.221286 -242.550442)
				(mid 101.201763 -242.554343)
				(end 101.185218 -242.565428)
			)
			(arc
				(start 101.075998 -242.674648)
				(mid 101.064887 -242.691182)
				(end 101.061012 -242.710716)
			)
			(arc
				(start 101.061012 -243.002816)
				(mid 101.057111 -243.022339)
				(end 101.046026 -243.038884)
			)
			(arc
				(start 100.823268 -243.261642)
				(mid 100.806734 -243.272753)
				(end 100.7872 -243.276628)
			)
			(arc
				(start 100.697538 -243.276628)
				(mid 100.680873 -243.279439)
				(end 100.666042 -243.28755)
			)
			(arc
				(start 100.666042 -243.28755)
				(mid 100.555473 -243.347694)
				(end 100.431346 -243.368576)
			)
			(xy 100.224844 -243.368576) (xy 100.218748 -243.374926)
			(arc
				(start 99.677474 -243.374926)
				(mid 99.657951 -243.378827)
				(end 99.641406 -243.389912)
			)
			(arc
				(start 99.626166 -243.405152)
				(mid 99.615055 -243.421686)
				(end 99.61118 -243.44122)
			)
			(arc
				(start 99.61118 -243.50472)
				(mid 99.615081 -243.524243)
				(end 99.626166 -243.540788)
			)
			(arc
				(start 99.675696 -243.590318)
				(mid 99.69223 -243.601429)
				(end 99.711764 -243.605304)
			)
			(arc
				(start 100.48494 -243.605304)
				(mid 100.504463 -243.609205)
				(end 100.521008 -243.62029)
			)
			(xy 100.607876 -243.707158) (xy 100.619306 -243.707158)
			(arc
				(start 100.932742 -244.020594)
				(mid 100.949276 -244.031705)
				(end 100.96881 -244.03558)
			)
		)
		(stroke
			(width 0)
			(type solid)
		)
		(fill yes)
		(layer "F.Cu")
		(net "P1V8_PEX_R")
	)
	(gr_poly
		(pts
			(xy 34.426652 -301.677324) (xy 34.426652 -296.284396) (xy 34.515806 -296.195242) (xy 34.72561 -295.985438)
			(xy 34.72561 -280.616406) (xy 34.628074 -280.51887)
			(arc
				(start 34.622486 -280.514044)
				(mid 34.60807 -280.506491)
				(end 34.592006 -280.503884)
			)
			(arc
				(start 33.772856 -280.503884)
				(mid 33.756792 -280.506491)
				(end 33.742376 -280.514044)
			)
			(xy 33.736788 -280.51887)
			(arc
				(start 33.630108 -280.62555)
				(mid 33.619182 -280.641996)
				(end 33.615376 -280.661364)
			)
			(arc
				(start 33.615376 -282.518612)
				(mid 33.617386 -282.532759)
				(end 33.62325 -282.54579)
			)
			(xy 33.62325 -283.832808) (xy 33.620964 -283.835094)
			(arc
				(start 33.616138 -283.840682)
				(mid 33.608585 -283.855098)
				(end 33.605978 -283.871162)
			)
			(arc
				(start 33.605978 -285.709614)
				(mid 33.608585 -285.725678)
				(end 33.616138 -285.740094)
			)
			(xy 33.620964 -285.745682) (xy 33.62325 -285.747968) (xy 33.62325 -287.033208) (xy 33.620964 -287.035494)
			(arc
				(start 33.616138 -287.041082)
				(mid 33.608585 -287.055498)
				(end 33.605978 -287.071562)
			)
			(arc
				(start 33.605978 -288.910014)
				(mid 33.608585 -288.926078)
				(end 33.616138 -288.940494)
			)
			(xy 33.620964 -288.946082) (xy 33.62325 -288.948368) (xy 33.62325 -290.233608) (xy 33.620964 -290.235894)
			(arc
				(start 33.616138 -290.241482)
				(mid 33.608585 -290.255898)
				(end 33.605978 -290.271962)
			)
			(arc
				(start 33.605978 -292.110414)
				(mid 33.608585 -292.126478)
				(end 33.616138 -292.140894)
			)
			(xy 33.620964 -292.146482) (xy 33.62325 -292.148768) (xy 33.62325 -293.434008) (xy 33.620964 -293.436294)
			(arc
				(start 33.616138 -293.441882)
				(mid 33.608585 -293.456298)
				(end 33.605978 -293.472362)
			)
			(arc
				(start 33.605978 -295.310814)
				(mid 33.608585 -295.326878)
				(end 33.616138 -295.341294)
			)
			(xy 33.620964 -295.346882) (xy 33.62325 -295.349168)
			(arc
				(start 33.62325 -296.636186)
				(mid 33.617379 -296.649215)
				(end 33.615376 -296.663364)
			)
			(arc
				(start 33.615376 -298.520612)
				(mid 33.617386 -298.534759)
				(end 33.62325 -298.54779)
			)
			(xy 33.62325 -299.463206) (xy 33.69691 -299.536866) (xy 33.69691 -299.760894) (xy 33.691068 -299.766736)
			(xy 33.691068 -300.507908) (xy 33.605978 -300.592998)
			(arc
				(start 33.605978 -301.711614)
				(mid 33.608585 -301.727678)
				(end 33.616138 -301.742094)
			)
			(xy 33.620964 -301.747682) (xy 33.672526 -301.799244)
			(arc
				(start 33.678114 -301.80407)
				(mid 33.69253 -301.811623)
				(end 33.708594 -301.81423)
			)
			(xy 34.289746 -301.81423)
		)
		(stroke
			(width 0)
			(type solid)
		)
		(fill yes)
		(layer "F.Cu")
		(net "GND")
	)
	(gr_poly
		(pts
			(arc
				(start 105.084118 -393.934188)
				(mid 105.103641 -393.930287)
				(end 105.120186 -393.919202)
			)
			(arc
				(start 105.146856 -393.892532)
				(mid 105.157967 -393.875998)
				(end 105.161842 -393.856464)
			)
			(arc
				(start 105.161842 -390.525)
				(mid 105.156704 -390.502991)
				(end 105.142538 -390.485376)
			)
			(xy 105.07091 -390.42848) (xy 105.048558 -390.4234)
			(arc
				(start 105.037128 -390.426194)
				(mid 104.95765 -390.440054)
				(end 104.877108 -390.444736)
			)
			(arc
				(start 104.877108 -390.444736)
				(mid 104.758834 -390.434669)
				(end 104.643936 -390.404858)
			)
			(arc
				(start 104.643936 -390.404858)
				(mid 104.627052 -390.402001)
				(end 104.610154 -390.404858)
			)
			(arc
				(start 104.610154 -390.404858)
				(mid 104.495259 -390.434686)
				(end 104.376982 -390.444736)
			)
			(arc
				(start 104.376982 -390.444736)
				(mid 104.207357 -390.423896)
				(end 104.047798 -390.362694)
			)
			(xy 104.04221 -390.3599) (xy 104.030272 -390.356852) (xy 103.723694 -390.356852) (xy 103.711756 -390.3599)
			(arc
				(start 103.706168 -390.362694)
				(mid 103.546598 -390.423854)
				(end 103.376984 -390.444736)
			)
			(arc
				(start 103.376984 -390.444736)
				(mid 103.25871 -390.434669)
				(end 103.143812 -390.404858)
			)
			(arc
				(start 103.143812 -390.404858)
				(mid 103.127048 -390.402015)
				(end 103.110284 -390.404858)
			)
			(arc
				(start 103.110284 -390.404858)
				(mid 102.995389 -390.434686)
				(end 102.877112 -390.444736)
			)
			(arc
				(start 102.877112 -390.444736)
				(mid 102.758838 -390.434669)
				(end 102.64394 -390.404858)
			)
			(arc
				(start 102.64394 -390.404858)
				(mid 102.627056 -390.402001)
				(end 102.610158 -390.404858)
			)
			(arc
				(start 102.610158 -390.404858)
				(mid 102.495263 -390.434686)
				(end 102.376986 -390.444736)
			)
			(arc
				(start 102.376986 -390.444736)
				(mid 102.258712 -390.434669)
				(end 102.143814 -390.404858)
			)
			(arc
				(start 102.143814 -390.404858)
				(mid 102.12693 -390.402001)
				(end 102.110032 -390.404858)
			)
			(arc
				(start 102.110032 -390.404858)
				(mid 101.995137 -390.434686)
				(end 101.87686 -390.444736)
			)
			(arc
				(start 101.87686 -390.444736)
				(mid 101.786048 -390.438778)
				(end 101.696774 -390.421114)
			)
			(xy 101.685344 -390.418066) (xy 101.662484 -390.422638)
			(arc
				(start 101.589078 -390.479026)
				(mid 101.574411 -390.496897)
				(end 101.569266 -390.519412)
			)
			(arc
				(start 101.569266 -393.86383)
				(mid 101.573167 -393.883353)
				(end 101.584252 -393.899898)
			)
			(arc
				(start 101.603556 -393.919202)
				(mid 101.62009 -393.930313)
				(end 101.639624 -393.934188)
			)
		)
		(stroke
			(width 0)
			(type solid)
		)
		(fill yes)
		(layer "F.Cu")
		(net "GND")
	)
	(gr_poly
		(pts
			(xy 150.52675 -301.677324) (xy 150.52675 -296.284396) (xy 150.615904 -296.195242) (xy 150.825708 -295.985438)
			(xy 150.825708 -280.616406) (xy 150.728172 -280.51887)
			(arc
				(start 150.722584 -280.514044)
				(mid 150.708168 -280.506491)
				(end 150.692104 -280.503884)
			)
			(arc
				(start 149.872954 -280.503884)
				(mid 149.85689 -280.506491)
				(end 149.842474 -280.514044)
			)
			(xy 149.836886 -280.51887)
			(arc
				(start 149.730206 -280.62555)
				(mid 149.71928 -280.641996)
				(end 149.715474 -280.661364)
			)
			(arc
				(start 149.715474 -282.518612)
				(mid 149.717484 -282.532759)
				(end 149.723348 -282.54579)
			)
			(xy 149.723348 -283.832808) (xy 149.721062 -283.835094)
			(arc
				(start 149.716236 -283.840682)
				(mid 149.708683 -283.855098)
				(end 149.706076 -283.871162)
			)
			(arc
				(start 149.706076 -285.709614)
				(mid 149.708683 -285.725678)
				(end 149.716236 -285.740094)
			)
			(xy 149.721062 -285.745682) (xy 149.723348 -285.747968) (xy 149.723348 -287.033208) (xy 149.721062 -287.035494)
			(arc
				(start 149.716236 -287.041082)
				(mid 149.708683 -287.055498)
				(end 149.706076 -287.071562)
			)
			(arc
				(start 149.706076 -288.910014)
				(mid 149.708683 -288.926078)
				(end 149.716236 -288.940494)
			)
			(xy 149.721062 -288.946082) (xy 149.723348 -288.948368) (xy 149.723348 -290.233608) (xy 149.721062 -290.235894)
			(arc
				(start 149.716236 -290.241482)
				(mid 149.708683 -290.255898)
				(end 149.706076 -290.271962)
			)
			(arc
				(start 149.706076 -292.110414)
				(mid 149.708683 -292.126478)
				(end 149.716236 -292.140894)
			)
			(xy 149.721062 -292.146482) (xy 149.723348 -292.148768) (xy 149.723348 -293.434008) (xy 149.721062 -293.436294)
			(arc
				(start 149.716236 -293.441882)
				(mid 149.708683 -293.456298)
				(end 149.706076 -293.472362)
			)
			(arc
				(start 149.706076 -295.310814)
				(mid 149.708683 -295.326878)
				(end 149.716236 -295.341294)
			)
			(xy 149.721062 -295.346882) (xy 149.723348 -295.349168)
			(arc
				(start 149.723348 -296.636186)
				(mid 149.717477 -296.649215)
				(end 149.715474 -296.663364)
			)
			(arc
				(start 149.715474 -298.520612)
				(mid 149.717484 -298.534759)
				(end 149.723348 -298.54779)
			)
			(xy 149.723348 -299.463206) (xy 149.797008 -299.536866) (xy 149.797008 -299.760894) (xy 149.791166 -299.766736)
			(xy 149.791166 -300.507908) (xy 149.706076 -300.592998)
			(arc
				(start 149.706076 -301.711614)
				(mid 149.708683 -301.727678)
				(end 149.716236 -301.742094)
			)
			(xy 149.721062 -301.747682) (xy 149.772624 -301.799244)
			(arc
				(start 149.778212 -301.80407)
				(mid 149.792628 -301.811623)
				(end 149.808692 -301.81423)
			)
			(xy 150.389844 -301.81423)
		)
		(stroke
			(width 0)
			(type solid)
		)
		(fill yes)
		(layer "F.Cu")
		(net "GND")
	)
	(gr_poly
		(pts
			(xy 266.626594 -301.677324) (xy 266.626594 -296.284396) (xy 266.715748 -296.195242) (xy 266.925552 -295.985438)
			(xy 266.925552 -280.616406) (xy 266.828016 -280.51887)
			(arc
				(start 266.822428 -280.514044)
				(mid 266.808012 -280.506491)
				(end 266.791948 -280.503884)
			)
			(arc
				(start 265.972798 -280.503884)
				(mid 265.956734 -280.506491)
				(end 265.942318 -280.514044)
			)
			(xy 265.93673 -280.51887)
			(arc
				(start 265.83005 -280.62555)
				(mid 265.819124 -280.641996)
				(end 265.815318 -280.661364)
			)
			(arc
				(start 265.815318 -282.518612)
				(mid 265.817328 -282.532759)
				(end 265.823192 -282.54579)
			)
			(xy 265.823192 -283.832808) (xy 265.820906 -283.835094)
			(arc
				(start 265.81608 -283.840682)
				(mid 265.808527 -283.855098)
				(end 265.80592 -283.871162)
			)
			(arc
				(start 265.80592 -285.709614)
				(mid 265.808527 -285.725678)
				(end 265.81608 -285.740094)
			)
			(xy 265.820906 -285.745682) (xy 265.823192 -285.747968) (xy 265.823192 -287.033208) (xy 265.820906 -287.035494)
			(arc
				(start 265.81608 -287.041082)
				(mid 265.808527 -287.055498)
				(end 265.80592 -287.071562)
			)
			(arc
				(start 265.80592 -288.910014)
				(mid 265.808527 -288.926078)
				(end 265.81608 -288.940494)
			)
			(xy 265.820906 -288.946082) (xy 265.823192 -288.948368) (xy 265.823192 -290.233608) (xy 265.820906 -290.235894)
			(arc
				(start 265.81608 -290.241482)
				(mid 265.808527 -290.255898)
				(end 265.80592 -290.271962)
			)
			(arc
				(start 265.80592 -292.110414)
				(mid 265.808527 -292.126478)
				(end 265.81608 -292.140894)
			)
			(xy 265.820906 -292.146482) (xy 265.823192 -292.148768) (xy 265.823192 -293.434008) (xy 265.820906 -293.436294)
			(arc
				(start 265.81608 -293.441882)
				(mid 265.808527 -293.456298)
				(end 265.80592 -293.472362)
			)
			(arc
				(start 265.80592 -295.310814)
				(mid 265.808527 -295.326878)
				(end 265.81608 -295.341294)
			)
			(xy 265.820906 -295.346882) (xy 265.823192 -295.349168)
			(arc
				(start 265.823192 -296.636186)
				(mid 265.817321 -296.649215)
				(end 265.815318 -296.663364)
			)
			(arc
				(start 265.815318 -298.520612)
				(mid 265.817328 -298.534759)
				(end 265.823192 -298.54779)
			)
			(xy 265.823192 -299.463206) (xy 265.896852 -299.536866) (xy 265.896852 -299.760894) (xy 265.89101 -299.766736)
			(xy 265.89101 -300.507908) (xy 265.80592 -300.592998)
			(arc
				(start 265.80592 -301.711614)
				(mid 265.808527 -301.727678)
				(end 265.81608 -301.742094)
			)
			(xy 265.820906 -301.747682) (xy 265.872468 -301.799244)
			(arc
				(start 265.878056 -301.80407)
				(mid 265.892472 -301.811623)
				(end 265.908536 -301.81423)
			)
			(xy 266.489688 -301.81423)
		)
		(stroke
			(width 0)
			(type solid)
		)
		(fill yes)
		(layer "F.Cu")
		(net "GND")
	)
	(gr_poly
		(pts
			(xy 382.726692 -301.677324) (xy 382.726692 -296.284396) (xy 382.815846 -296.195242) (xy 383.02565 -295.985438)
			(xy 383.02565 -280.616406) (xy 382.928114 -280.51887)
			(arc
				(start 382.922526 -280.514044)
				(mid 382.90811 -280.506491)
				(end 382.892046 -280.503884)
			)
			(arc
				(start 382.072896 -280.503884)
				(mid 382.056832 -280.506491)
				(end 382.042416 -280.514044)
			)
			(xy 382.036828 -280.51887)
			(arc
				(start 381.930148 -280.62555)
				(mid 381.919222 -280.641996)
				(end 381.915416 -280.661364)
			)
			(arc
				(start 381.915416 -282.518612)
				(mid 381.917426 -282.532759)
				(end 381.92329 -282.54579)
			)
			(xy 381.92329 -283.832808) (xy 381.921004 -283.835094)
			(arc
				(start 381.916178 -283.840682)
				(mid 381.908625 -283.855098)
				(end 381.906018 -283.871162)
			)
			(arc
				(start 381.906018 -285.709614)
				(mid 381.908625 -285.725678)
				(end 381.916178 -285.740094)
			)
			(xy 381.921004 -285.745682) (xy 381.92329 -285.747968) (xy 381.92329 -287.033208) (xy 381.921004 -287.035494)
			(arc
				(start 381.916178 -287.041082)
				(mid 381.908625 -287.055498)
				(end 381.906018 -287.071562)
			)
			(arc
				(start 381.906018 -288.910014)
				(mid 381.908625 -288.926078)
				(end 381.916178 -288.940494)
			)
			(xy 381.921004 -288.946082) (xy 381.92329 -288.948368) (xy 381.92329 -290.233608) (xy 381.921004 -290.235894)
			(arc
				(start 381.916178 -290.241482)
				(mid 381.908625 -290.255898)
				(end 381.906018 -290.271962)
			)
			(arc
				(start 381.906018 -292.110414)
				(mid 381.908625 -292.126478)
				(end 381.916178 -292.140894)
			)
			(xy 381.921004 -292.146482) (xy 381.92329 -292.148768) (xy 381.92329 -293.434008) (xy 381.921004 -293.436294)
			(arc
				(start 381.916178 -293.441882)
				(mid 381.908625 -293.456298)
				(end 381.906018 -293.472362)
			)
			(arc
				(start 381.906018 -295.310814)
				(mid 381.908625 -295.326878)
				(end 381.916178 -295.341294)
			)
			(xy 381.921004 -295.346882) (xy 381.92329 -295.349168)
			(arc
				(start 381.92329 -296.636186)
				(mid 381.917419 -296.649215)
				(end 381.915416 -296.663364)
			)
			(arc
				(start 381.915416 -298.520612)
				(mid 381.917426 -298.534759)
				(end 381.92329 -298.54779)
			)
			(xy 381.92329 -299.463206) (xy 381.99695 -299.536866) (xy 381.99695 -299.760894) (xy 381.991108 -299.766736)
			(xy 381.991108 -300.507908) (xy 381.906018 -300.592998)
			(arc
				(start 381.906018 -301.711614)
				(mid 381.908625 -301.727678)
				(end 381.916178 -301.742094)
			)
			(xy 381.921004 -301.747682) (xy 381.972566 -301.799244)
			(arc
				(start 381.978154 -301.80407)
				(mid 381.99257 -301.811623)
				(end 382.008634 -301.81423)
			)
			(xy 382.589786 -301.81423)
		)
		(stroke
			(width 0)
			(type solid)
		)
		(fill yes)
		(layer "F.Cu")
		(net "GND")
	)
	(gr_poly
		(pts
			(arc
				(start 119.660416 -184.373012)
				(mid 119.679939 -184.369111)
				(end 119.696484 -184.358026)
			)
			(arc
				(start 119.902986 -184.151524)
				(mid 119.914097 -184.13499)
				(end 119.917972 -184.115456)
			)
			(arc
				(start 119.917972 -166.653464)
				(mid 119.914071 -166.633941)
				(end 119.902986 -166.617396)
			)
			(arc
				(start 117.253004 -163.967414)
				(mid 117.23647 -163.956303)
				(end 117.216936 -163.952428)
			)
			(arc
				(start 112.557814 -163.952428)
				(mid 112.538291 -163.956329)
				(end 112.521746 -163.967414)
			)
			(xy 112.514888 -163.974272) (xy 112.507268 -163.992814)
			(arc
				(start 112.507268 -166.947342)
				(mid 112.511169 -166.966865)
				(end 112.522254 -166.98341)
			)
			(xy 112.529112 -166.990268) (xy 112.536732 -167.00881)
			(arc
				(start 112.536732 -167.239188)
				(mid 112.540682 -167.258575)
				(end 112.551718 -167.275002)
			)
			(arc
				(start 115.253516 -169.977054)
				(mid 115.264442 -169.9935)
				(end 115.268248 -170.012868)
			)
			(arc
				(start 115.268248 -176.34331)
				(mid 115.264415 -176.362667)
				(end 115.253516 -176.379124)
			)
			(arc
				(start 115.239038 -176.393856)
				(mid 115.227976 -176.410273)
				(end 115.224052 -176.42967)
			)
			(arc
				(start 115.224052 -181.726078)
				(mid 115.220151 -181.745601)
				(end 115.209066 -181.762146)
			)
			(arc
				(start 114.997484 -181.973728)
				(mid 114.98095 -181.984839)
				(end 114.961416 -181.988714)
			)
			(arc
				(start 106.392726 -181.988714)
				(mid 106.373203 -181.984813)
				(end 106.356658 -181.973728)
			)
			(arc
				(start 106.201972 -181.819042)
				(mid 106.190861 -181.802508)
				(end 106.186986 -181.782974)
			)
			(arc
				(start 106.186986 -169.581068)
				(mid 106.190887 -169.561545)
				(end 106.201972 -169.545)
			)
			(arc
				(start 107.93476 -167.812212)
				(mid 107.945871 -167.795678)
				(end 107.949746 -167.776144)
			)
			(arc
				(start 107.949746 -163.429442)
				(mid 107.953647 -163.409919)
				(end 107.964732 -163.393374)
			)
			(arc
				(start 108.883958 -162.474148)
				(mid 108.895069 -162.457614)
				(end 108.898944 -162.43808)
			)
			(arc
				(start 108.898944 -159.519874)
				(mid 108.895043 -159.500351)
				(end 108.883958 -159.483806)
			)
			(xy 108.879132 -159.47898) (xy 106.69778 -159.47898) (xy 106.692446 -159.473392)
			(arc
				(start 102.773734 -159.473392)
				(mid 102.754211 -159.477293)
				(end 102.737666 -159.488378)
			)
			(arc
				(start 101.030278 -161.195766)
				(mid 101.019167 -161.2123)
				(end 101.015292 -161.231834)
			)
			(arc
				(start 101.015292 -183.101234)
				(mid 101.019193 -183.120757)
				(end 101.030278 -183.137302)
			)
			(arc
				(start 102.251002 -184.358026)
				(mid 102.267536 -184.369137)
				(end 102.28707 -184.373012)
			)
		)
		(stroke
			(width 0)
			(type solid)
		)
		(fill yes)
		(layer "F.Cu")
		(net "GND")
	)
	(gr_poly
		(pts
			(xy 43.229276 -146.779234)
			(arc
				(start 46.488096 -146.779234)
				(mid 46.507619 -146.775333)
				(end 46.524164 -146.764248)
			)
			(arc
				(start 46.647608 -146.640804)
				(mid 46.658719 -146.62427)
				(end 46.662594 -146.604736)
			)
			(arc
				(start 46.662594 -143.072358)
				(mid 46.658693 -143.052835)
				(end 46.647608 -143.03629)
			)
			(arc
				(start 46.613826 -143.002508)
				(mid 46.597292 -142.991397)
				(end 46.577758 -142.987522)
			)
			(arc
				(start 42.97426 -142.987522)
				(mid 42.954737 -142.991423)
				(end 42.938192 -143.002508)
			)
			(arc
				(start 42.223436 -143.717264)
				(mid 42.206902 -143.728375)
				(end 42.187368 -143.73225)
			)
			(arc
				(start 40.735758 -143.73225)
				(mid 40.718621 -143.735137)
				(end 40.7035 -143.74368)
			)
			(arc
				(start 40.7035 -143.74368)
				(mid 40.381428 -143.85875)
				(end 40.059356 -143.74368)
			)
			(arc
				(start 40.059356 -143.74368)
				(mid 40.044214 -143.735197)
				(end 40.027098 -143.73225)
			)
			(arc
				(start 35.79495 -143.73225)
				(mid 35.775427 -143.728349)
				(end 35.758882 -143.717264)
			)
			(arc
				(start 35.437318 -143.3957)
				(mid 35.426207 -143.379166)
				(end 35.422332 -143.359632)
			)
			(arc
				(start 35.422332 -141.972284)
				(mid 35.418431 -141.952761)
				(end 35.407346 -141.936216)
			)
			(arc
				(start 34.738056 -141.266926)
				(mid 34.721522 -141.255815)
				(end 34.701988 -141.25194)
			)
			(arc
				(start 26.112978 -141.25194)
				(mid 26.093455 -141.248039)
				(end 26.07691 -141.236954)
			)
			(arc
				(start 25.07488 -140.234924)
				(mid 25.058346 -140.223813)
				(end 25.038812 -140.219938)
			)
			(arc
				(start 19.72818 -140.219938)
				(mid 19.708657 -140.223839)
				(end 19.692112 -140.234924)
			)
			(arc
				(start 19.473926 -140.45311)
				(mid 19.462815 -140.469644)
				(end 19.45894 -140.489178)
			)
			(arc
				(start 19.45894 -144.079722)
				(mid 19.462841 -144.099245)
				(end 19.473926 -144.11579)
			)
			(arc
				(start 19.85391 -144.495774)
				(mid 19.870444 -144.506885)
				(end 19.889978 -144.51076)
			)
			(arc
				(start 20.69338 -144.51076)
				(mid 20.712903 -144.514661)
				(end 20.729448 -144.525746)
			)
			(arc
				(start 20.835366 -144.631664)
				(mid 20.846477 -144.648198)
				(end 20.850352 -144.667732)
			)
			(arc
				(start 20.850352 -145.412968)
				(mid 20.854253 -145.432491)
				(end 20.865338 -145.449036)
			)
			(arc
				(start 21.01088 -145.594578)
				(mid 21.027414 -145.605689)
				(end 21.046948 -145.609564)
			)
			(arc
				(start 22.896576 -145.609564)
				(mid 22.916099 -145.613465)
				(end 22.932644 -145.62455)
			)
			(xy 24.92248 -147.614386) (xy 24.933656 -147.614386)
			(arc
				(start 24.97709 -147.65782)
				(mid 24.993624 -147.668931)
				(end 25.013158 -147.672806)
			)
			(xy 25.247346 -147.906994) (xy 42.101516 -147.906994)
		)
		(stroke
			(width 0)
			(type solid)
		)
		(fill yes)
		(layer "F.Cu")
		(net "P12V_NIC0")
	)
	(gr_poly
		(pts
			(xy 275.562314 -146.779234)
			(arc
				(start 278.688038 -146.779234)
				(mid 278.707561 -146.775333)
				(end 278.724106 -146.764248)
			)
			(arc
				(start 278.84755 -146.640804)
				(mid 278.858661 -146.62427)
				(end 278.862536 -146.604736)
			)
			(arc
				(start 278.862536 -143.072358)
				(mid 278.858635 -143.052835)
				(end 278.84755 -143.03629)
			)
			(arc
				(start 278.813768 -143.002508)
				(mid 278.797234 -142.991397)
				(end 278.7777 -142.987522)
			)
			(arc
				(start 275.174202 -142.987522)
				(mid 275.154679 -142.991423)
				(end 275.138134 -143.002508)
			)
			(arc
				(start 274.423378 -143.717264)
				(mid 274.406844 -143.728375)
				(end 274.38731 -143.73225)
			)
			(arc
				(start 272.9357 -143.73225)
				(mid 272.918563 -143.735137)
				(end 272.903442 -143.74368)
			)
			(arc
				(start 272.903442 -143.74368)
				(mid 272.58137 -143.85875)
				(end 272.259298 -143.74368)
			)
			(arc
				(start 272.259298 -143.74368)
				(mid 272.244156 -143.735197)
				(end 272.22704 -143.73225)
			)
			(arc
				(start 267.994892 -143.73225)
				(mid 267.975369 -143.728349)
				(end 267.958824 -143.717264)
			)
			(arc
				(start 267.63726 -143.3957)
				(mid 267.626149 -143.379166)
				(end 267.622274 -143.359632)
			)
			(arc
				(start 267.622274 -141.972284)
				(mid 267.618373 -141.952761)
				(end 267.607288 -141.936216)
			)
			(arc
				(start 266.937998 -141.266926)
				(mid 266.921464 -141.255815)
				(end 266.90193 -141.25194)
			)
			(arc
				(start 258.31292 -141.25194)
				(mid 258.293397 -141.248039)
				(end 258.276852 -141.236954)
			)
			(arc
				(start 257.274822 -140.234924)
				(mid 257.258288 -140.223813)
				(end 257.238754 -140.219938)
			)
			(arc
				(start 251.928122 -140.219938)
				(mid 251.908599 -140.223839)
				(end 251.892054 -140.234924)
			)
			(arc
				(start 251.673868 -140.45311)
				(mid 251.662757 -140.469644)
				(end 251.658882 -140.489178)
			)
			(arc
				(start 251.658882 -144.079722)
				(mid 251.662783 -144.099245)
				(end 251.673868 -144.11579)
			)
			(arc
				(start 252.053852 -144.495774)
				(mid 252.070386 -144.506885)
				(end 252.08992 -144.51076)
			)
			(arc
				(start 252.893322 -144.51076)
				(mid 252.912845 -144.514661)
				(end 252.92939 -144.525746)
			)
			(arc
				(start 253.035308 -144.631664)
				(mid 253.046419 -144.648198)
				(end 253.050294 -144.667732)
			)
			(arc
				(start 253.050294 -145.412968)
				(mid 253.054195 -145.432491)
				(end 253.06528 -145.449036)
			)
			(arc
				(start 253.210822 -145.594578)
				(mid 253.227356 -145.605689)
				(end 253.24689 -145.609564)
			)
			(arc
				(start 255.096518 -145.609564)
				(mid 255.116041 -145.613465)
				(end 255.132586 -145.62455)
			)
			(xy 257.122422 -147.614386) (xy 257.133598 -147.614386)
			(arc
				(start 257.177032 -147.65782)
				(mid 257.193566 -147.668931)
				(end 257.2131 -147.672806)
			)
			(xy 257.544824 -148.00453) (xy 274.337018 -148.00453)
		)
		(stroke
			(width 0)
			(type solid)
		)
		(fill yes)
		(layer "F.Cu")
		(net "P12V_NIC4")
	)
	(gr_poly
		(pts
			(xy 391.650982 -146.779234)
			(arc
				(start 394.788136 -146.779234)
				(mid 394.807659 -146.775333)
				(end 394.824204 -146.764248)
			)
			(arc
				(start 394.947648 -146.640804)
				(mid 394.958759 -146.62427)
				(end 394.962634 -146.604736)
			)
			(arc
				(start 394.962634 -143.072358)
				(mid 394.958733 -143.052835)
				(end 394.947648 -143.03629)
			)
			(arc
				(start 394.913866 -143.002508)
				(mid 394.897332 -142.991397)
				(end 394.877798 -142.987522)
			)
			(arc
				(start 391.2743 -142.987522)
				(mid 391.254777 -142.991423)
				(end 391.238232 -143.002508)
			)
			(arc
				(start 390.523476 -143.717264)
				(mid 390.506942 -143.728375)
				(end 390.487408 -143.73225)
			)
			(arc
				(start 389.035798 -143.73225)
				(mid 389.018661 -143.735137)
				(end 389.00354 -143.74368)
			)
			(arc
				(start 389.00354 -143.74368)
				(mid 388.681468 -143.85875)
				(end 388.359396 -143.74368)
			)
			(arc
				(start 388.359396 -143.74368)
				(mid 388.344254 -143.735197)
				(end 388.327138 -143.73225)
			)
			(arc
				(start 384.09499 -143.73225)
				(mid 384.075467 -143.728349)
				(end 384.058922 -143.717264)
			)
			(arc
				(start 383.737358 -143.3957)
				(mid 383.726247 -143.379166)
				(end 383.722372 -143.359632)
			)
			(arc
				(start 383.722372 -141.972284)
				(mid 383.718471 -141.952761)
				(end 383.707386 -141.936216)
			)
			(arc
				(start 383.038096 -141.266926)
				(mid 383.021562 -141.255815)
				(end 383.002028 -141.25194)
			)
			(arc
				(start 374.413018 -141.25194)
				(mid 374.393495 -141.248039)
				(end 374.37695 -141.236954)
			)
			(arc
				(start 373.37492 -140.234924)
				(mid 373.358386 -140.223813)
				(end 373.338852 -140.219938)
			)
			(arc
				(start 368.02822 -140.219938)
				(mid 368.008697 -140.223839)
				(end 367.992152 -140.234924)
			)
			(arc
				(start 367.773966 -140.45311)
				(mid 367.762855 -140.469644)
				(end 367.75898 -140.489178)
			)
			(arc
				(start 367.75898 -144.079722)
				(mid 367.762881 -144.099245)
				(end 367.773966 -144.11579)
			)
			(arc
				(start 368.15395 -144.495774)
				(mid 368.170484 -144.506885)
				(end 368.190018 -144.51076)
			)
			(arc
				(start 368.99342 -144.51076)
				(mid 369.012943 -144.514661)
				(end 369.029488 -144.525746)
			)
			(arc
				(start 369.135406 -144.631664)
				(mid 369.146517 -144.648198)
				(end 369.150392 -144.667732)
			)
			(arc
				(start 369.150392 -145.412968)
				(mid 369.154293 -145.432491)
				(end 369.165378 -145.449036)
			)
			(arc
				(start 369.31092 -145.594578)
				(mid 369.327454 -145.605689)
				(end 369.346988 -145.609564)
			)
			(arc
				(start 371.196616 -145.609564)
				(mid 371.216139 -145.613465)
				(end 371.232684 -145.62455)
			)
			(xy 373.22252 -147.614386) (xy 373.233696 -147.614386)
			(arc
				(start 373.27713 -147.65782)
				(mid 373.293664 -147.668931)
				(end 373.313198 -147.672806)
			)
			(xy 373.601234 -147.960842) (xy 390.469374 -147.960842)
		)
		(stroke
			(width 0)
			(type solid)
		)
		(fill yes)
		(layer "F.Cu")
		(net "P12V_NIC6")
	)
	(gr_poly
		(pts
			(xy 158.486094 -147.672806) (xy 159.379666 -146.779234)
			(arc
				(start 162.58794 -146.779234)
				(mid 162.607463 -146.775333)
				(end 162.624008 -146.764248)
			)
			(arc
				(start 162.747452 -146.640804)
				(mid 162.758563 -146.62427)
				(end 162.762438 -146.604736)
			)
			(arc
				(start 162.762438 -143.072358)
				(mid 162.758537 -143.052835)
				(end 162.747452 -143.03629)
			)
			(arc
				(start 162.71367 -143.002508)
				(mid 162.697136 -142.991397)
				(end 162.677602 -142.987522)
			)
			(arc
				(start 159.074104 -142.987522)
				(mid 159.054581 -142.991423)
				(end 159.038036 -143.002508)
			)
			(arc
				(start 158.32328 -143.717264)
				(mid 158.306746 -143.728375)
				(end 158.287212 -143.73225)
			)
			(arc
				(start 156.835602 -143.73225)
				(mid 156.818465 -143.735137)
				(end 156.803344 -143.74368)
			)
			(arc
				(start 156.803344 -143.74368)
				(mid 156.481272 -143.85875)
				(end 156.1592 -143.74368)
			)
			(arc
				(start 156.1592 -143.74368)
				(mid 156.144058 -143.735197)
				(end 156.126942 -143.73225)
			)
			(arc
				(start 151.894794 -143.73225)
				(mid 151.875271 -143.728349)
				(end 151.858726 -143.717264)
			)
			(arc
				(start 151.537162 -143.3957)
				(mid 151.526051 -143.379166)
				(end 151.522176 -143.359632)
			)
			(arc
				(start 151.522176 -141.972284)
				(mid 151.518275 -141.952761)
				(end 151.50719 -141.936216)
			)
			(arc
				(start 150.8379 -141.266926)
				(mid 150.821366 -141.255815)
				(end 150.801832 -141.25194)
			)
			(arc
				(start 142.212822 -141.25194)
				(mid 142.193299 -141.248039)
				(end 142.176754 -141.236954)
			)
			(arc
				(start 141.174724 -140.234924)
				(mid 141.15819 -140.223813)
				(end 141.138656 -140.219938)
			)
			(arc
				(start 135.828024 -140.219938)
				(mid 135.808501 -140.223839)
				(end 135.791956 -140.234924)
			)
			(arc
				(start 135.57377 -140.45311)
				(mid 135.562659 -140.469644)
				(end 135.558784 -140.489178)
			)
			(arc
				(start 135.558784 -144.079722)
				(mid 135.562685 -144.099245)
				(end 135.57377 -144.11579)
			)
			(arc
				(start 135.953754 -144.495774)
				(mid 135.970288 -144.506885)
				(end 135.989822 -144.51076)
			)
			(arc
				(start 136.793224 -144.51076)
				(mid 136.812747 -144.514661)
				(end 136.829292 -144.525746)
			)
			(arc
				(start 136.93521 -144.631664)
				(mid 136.946321 -144.648198)
				(end 136.950196 -144.667732)
			)
			(arc
				(start 136.950196 -145.412968)
				(mid 136.954097 -145.432491)
				(end 136.965182 -145.449036)
			)
			(arc
				(start 137.110724 -145.594578)
				(mid 137.127258 -145.605689)
				(end 137.146792 -145.609564)
			)
			(arc
				(start 138.99642 -145.609564)
				(mid 139.015943 -145.613465)
				(end 139.032488 -145.62455)
			)
			(xy 141.022324 -147.614386) (xy 141.0335 -147.614386)
			(arc
				(start 141.076934 -147.65782)
				(mid 141.093468 -147.668931)
				(end 141.113002 -147.672806)
			)
			(xy 141.379702 -147.939506) (xy 158.219394 -147.939506)
		)
		(stroke
			(width 0)
			(type solid)
		)
		(fill yes)
		(layer "F.Cu")
		(net "P12V_NIC2")
	)
	(gr_poly
		(pts
			(xy 142.452344 -262.532114)
			(arc
				(start 142.48003 -262.504428)
				(mid 142.491141 -262.487894)
				(end 142.495016 -262.46836)
			)
			(arc
				(start 142.495016 -262.170672)
				(mid 142.498917 -262.151149)
				(end 142.510002 -262.134604)
			)
			(arc
				(start 142.616936 -262.02767)
				(mid 142.63347 -262.016559)
				(end 142.653004 -262.012684)
			)
			(arc
				(start 142.702026 -262.012684)
				(mid 142.721413 -262.008734)
				(end 142.73784 -261.997698)
			)
			(arc
				(start 142.748762 -261.98703)
				(mid 142.765179 -261.975968)
				(end 142.784576 -261.972044)
			)
			(arc
				(start 142.926816 -261.972044)
				(mid 142.946173 -261.968211)
				(end 142.96263 -261.957312)
			)
			(arc
				(start 142.993872 -261.92607)
				(mid 143.004798 -261.909624)
				(end 143.008604 -261.890256)
			)
			(xy 143.008604 -261.44093) (xy 143.012414 -261.437374)
			(arc
				(start 143.012414 -261.323328)
				(mid 143.016315 -261.303805)
				(end 143.0274 -261.28726)
			)
			(arc
				(start 143.106902 -261.207758)
				(mid 143.123436 -261.196647)
				(end 143.14297 -261.192772)
			)
			(arc
				(start 143.605504 -261.192772)
				(mid 143.625027 -261.188871)
				(end 143.641572 -261.177786)
			)
			(arc
				(start 143.685514 -261.133844)
				(mid 143.696625 -261.11731)
				(end 143.7005 -261.097776)
			)
			(xy 143.7005 -261.076694) (xy 143.69669 -261.063486)
			(arc
				(start 143.693134 -261.05739)
				(mid 143.687491 -261.044582)
				(end 143.685514 -261.03072)
			)
			(arc
				(start 143.685514 -260.644386)
				(mid 143.681613 -260.624863)
				(end 143.670528 -260.608318)
			)
			(arc
				(start 143.288512 -260.226302)
				(mid 143.277401 -260.209768)
				(end 143.273526 -260.190234)
			)
			(arc
				(start 143.273526 -259.921502)
				(mid 143.269625 -259.901979)
				(end 143.25854 -259.885434)
			)
			(xy 143.258286 -259.88518)
			(arc
				(start 143.258286 -259.055362)
				(mid 143.254385 -259.035839)
				(end 143.2433 -259.019294)
			)
			(xy 143.154146 -258.93014) (xy 143.147034 -258.922774) (xy 143.128238 -258.915154)
			(arc
				(start 141.828012 -258.915154)
				(mid 141.808489 -258.919055)
				(end 141.791944 -258.93014)
			)
			(xy 141.712442 -259.009642)
			(arc
				(start 141.707616 -259.01523)
				(mid 141.700023 -259.029766)
				(end 141.697456 -259.045964)
			)
			(xy 141.697456 -261.737348) (xy 141.693392 -261.737348)
			(arc
				(start 141.693392 -261.778496)
				(mid 141.689491 -261.798019)
				(end 141.678406 -261.814564)
			)
			(arc
				(start 141.586966 -261.906004)
				(mid 141.570432 -261.917115)
				(end 141.550898 -261.92099)
			)
			(arc
				(start 140.905738 -261.92099)
				(mid 140.886215 -261.924891)
				(end 140.86967 -261.935976)
			)
			(arc
				(start 140.862812 -261.942834)
				(mid 140.851701 -261.959368)
				(end 140.847826 -261.978902)
			)
			(arc
				(start 140.847826 -262.469884)
				(mid 140.851727 -262.489407)
				(end 140.862812 -262.505952)
			)
			(xy 140.866114 -262.509254) (xy 141.596364 -262.509254)
			(arc
				(start 141.599412 -262.508746)
				(mid 141.62514 -262.50627)
				(end 141.650974 -262.505444)
			)
			(arc
				(start 142.262352 -262.505444)
				(mid 142.320088 -262.509634)
				(end 142.376652 -262.521954)
			)
			(xy 142.40891 -262.532876) (xy 142.423134 -262.538464)
		)
		(stroke
			(width 0)
			(type solid)
		)
		(fill yes)
		(layer "F.Cu")
		(net "P1V8_VDDA_PEX1")
	)
	(gr_poly
		(pts
			(arc
				(start 349.492824 -323.636894)
				(mid 349.512347 -323.632993)
				(end 349.528892 -323.621908)
			)
			(arc
				(start 349.704152 -323.446648)
				(mid 349.715263 -323.430114)
				(end 349.719138 -323.41058)
			)
			(xy 349.719138 -318.932052) (xy 349.703898 -318.907668)
			(arc
				(start 349.690436 -318.901064)
				(mid 349.533569 -318.760255)
				(end 349.475298 -318.557656)
			)
			(arc
				(start 349.475298 -318.557656)
				(mid 349.533514 -318.355022)
				(end 349.690436 -318.214248)
			)
			(xy 349.703898 -318.207644) (xy 349.719138 -318.18326) (xy 349.719138 -318.067436) (xy 349.703898 -318.043052)
			(arc
				(start 349.690436 -318.036448)
				(mid 349.533569 -317.895639)
				(end 349.475298 -317.69304)
			)
			(arc
				(start 349.475298 -317.69304)
				(mid 349.533514 -317.490406)
				(end 349.690436 -317.349632)
			)
			(xy 349.703898 -317.343028) (xy 349.719138 -317.318644) (xy 349.719138 -316.364366) (xy 349.703898 -316.339982)
			(arc
				(start 349.690436 -316.333378)
				(mid 349.533569 -316.192569)
				(end 349.475298 -315.98997)
			)
			(arc
				(start 349.475298 -315.98997)
				(mid 349.533514 -315.787336)
				(end 349.690436 -315.646562)
			)
			(xy 349.703898 -315.639958) (xy 349.719138 -315.615574)
			(arc
				(start 349.719138 -308.764432)
				(mid 349.715237 -308.744909)
				(end 349.704152 -308.728364)
			)
			(arc
				(start 349.68434 -308.708552)
				(mid 349.667806 -308.697441)
				(end 349.648272 -308.693566)
			)
			(arc
				(start 346.12834 -308.693566)
				(mid 346.108817 -308.697467)
				(end 346.092272 -308.708552)
			)
			(arc
				(start 346.064078 -308.736746)
				(mid 346.052967 -308.75328)
				(end 346.049092 -308.772814)
			)
			(arc
				(start 346.049092 -318.72301)
				(mid 346.045191 -318.742533)
				(end 346.034106 -318.759078)
			)
			(arc
				(start 345.697302 -319.095882)
				(mid 345.680768 -319.106993)
				(end 345.661234 -319.110868)
			)
			(arc
				(start 332.091792 -319.110868)
				(mid 332.072269 -319.114769)
				(end 332.055724 -319.125854)
			)
			(arc
				(start 331.926692 -319.254886)
				(mid 331.915581 -319.27142)
				(end 331.911706 -319.290954)
			)
			(arc
				(start 331.911706 -323.358256)
				(mid 331.915607 -323.377779)
				(end 331.926692 -323.394324)
			)
			(arc
				(start 332.154276 -323.621908)
				(mid 332.17081 -323.633019)
				(end 332.190344 -323.636894)
			)
		)
		(stroke
			(width 0)
			(type solid)
		)
		(fill yes)
		(layer "F.Cu")
		(net "P0V8_SERDES_VDDA_PEX2")
	)
	(gr_poly
		(pts
			(arc
				(start 106.321352 -355.800152)
				(mid 106.385379 -355.783046)
				(end 106.4514 -355.777292)
			)
			(arc
				(start 106.4514 -355.777292)
				(mid 106.474557 -355.77798)
				(end 106.497628 -355.780086)
			)
			(xy 106.509312 -355.78161) (xy 106.53141 -355.77399)
			(arc
				(start 106.741214 -355.564186)
				(mid 106.752325 -355.547652)
				(end 106.7562 -355.528118)
			)
			(arc
				(start 106.7562 -354.986082)
				(mid 106.752299 -354.966559)
				(end 106.741214 -354.950014)
			)
			(arc
				(start 106.669586 -354.878386)
				(mid 106.653052 -354.867275)
				(end 106.633518 -354.8634)
			)
			(arc
				(start 106.066082 -354.8634)
				(mid 106.046559 -354.859499)
				(end 106.030014 -354.848414)
			)
			(arc
				(start 105.932986 -354.751386)
				(mid 105.921875 -354.734852)
				(end 105.918 -354.715318)
			)
			(xy 105.918 -354.253038)
			(arc
				(start 105.915968 -354.245926)
				(mid 105.903823 -354.191657)
				(end 105.899712 -354.136198)
			)
			(arc
				(start 105.899712 -354.136198)
				(mid 105.903839 -354.080742)
				(end 105.915968 -354.02647)
			)
			(xy 105.918 -354.019358)
			(arc
				(start 105.918 -353.792282)
				(mid 105.921901 -353.772759)
				(end 105.932986 -353.756214)
			)
			(arc
				(start 106.055414 -353.633786)
				(mid 106.071948 -353.622675)
				(end 106.091482 -353.6188)
			)
			(arc
				(start 107.014518 -353.6188)
				(mid 107.034041 -353.614899)
				(end 107.050586 -353.603814)
			)
			(arc
				(start 107.198414 -353.455986)
				(mid 107.209525 -353.439452)
				(end 107.2134 -353.419918)
			)
			(arc
				(start 107.2134 -352.674682)
				(mid 107.209499 -352.655159)
				(end 107.198414 -352.638614)
			)
			(arc
				(start 107.152186 -352.592386)
				(mid 107.135652 -352.581275)
				(end 107.116118 -352.5774)
			)
			(arc
				(start 105.685082 -352.5774)
				(mid 105.665559 -352.581301)
				(end 105.649014 -352.592386)
			)
			(arc
				(start 105.526586 -352.714814)
				(mid 105.515475 -352.731348)
				(end 105.5116 -352.750882)
			)
			(arc
				(start 105.5116 -353.242118)
				(mid 105.507699 -353.261641)
				(end 105.496614 -353.278186)
			)
			(arc
				(start 105.247186 -353.527614)
				(mid 105.230652 -353.538725)
				(end 105.211118 -353.5426)
			)
			(arc
				(start 101.900482 -353.5426)
				(mid 101.880959 -353.538699)
				(end 101.864414 -353.527614)
			)
			(arc
				(start 101.665786 -353.328986)
				(mid 101.654675 -353.312452)
				(end 101.6508 -353.292918)
			)
			(arc
				(start 101.6508 -352.827082)
				(mid 101.646899 -352.807559)
				(end 101.635814 -352.791014)
			)
			(arc
				(start 101.538786 -352.693986)
				(mid 101.522252 -352.682875)
				(end 101.502718 -352.679)
			)
			(arc
				(start 100.452682 -352.679)
				(mid 100.433159 -352.682901)
				(end 100.416614 -352.693986)
			)
			(arc
				(start 100.268786 -352.841814)
				(mid 100.257675 -352.858348)
				(end 100.2538 -352.877882)
			)
			(arc
				(start 100.2538 -353.419918)
				(mid 100.257701 -353.439441)
				(end 100.268786 -353.455986)
			)
			(arc
				(start 100.848414 -354.035614)
				(mid 100.859525 -354.052148)
				(end 100.8634 -354.071682)
			)
			(arc
				(start 100.8634 -355.578918)
				(mid 100.867301 -355.598441)
				(end 100.878386 -355.614986)
			)
			(arc
				(start 101.051614 -355.788214)
				(mid 101.068148 -355.799325)
				(end 101.087682 -355.8032)
			)
			(xy 106.31297 -355.8032)
		)
		(stroke
			(width 0)
			(type solid)
		)
		(fill yes)
		(layer "F.Cu")
		(net "PEX_S3_REF_CLK_BUFFER_EN_N")
	)
	(gr_poly
		(pts
			(xy 345.205558 -318.761872) (xy 345.215623 -318.761438) (xy 345.234209 -318.753705) (xy 345.241626 -318.746886)
			(xy 345.497658 -318.490854) (xy 345.504502 -318.483455) (xy 345.512226 -318.464856) (xy 345.512644 -318.454786)
			(xy 345.512644 -308.820566) (xy 345.512213 -308.8105) (xy 345.504484 -308.79191) (xy 345.497658 -308.784498)
			(xy 345.382342 -308.669182) (xy 345.374944 -308.662336) (xy 345.356345 -308.65461) (xy 345.346274 -308.654196)
			(xy 333.292958 -308.654196) (xy 333.282891 -308.653765) (xy 333.264298 -308.646039) (xy 333.25689 -308.63921)
			(xy 332.827376 -308.209696) (xy 332.820522 -308.202301) (xy 332.812777 -308.183702) (xy 332.81239 -308.173628)
			(xy 332.81239 -303.665128) (xy 332.812826 -303.655063) (xy 332.820557 -303.636477) (xy 332.827376 -303.62906)
			(xy 333.039974 -303.416462) (xy 333.047373 -303.40962) (xy 333.065972 -303.401903) (xy 333.076042 -303.401476)
			(xy 348.010226 -303.401476) (xy 348.020294 -303.401048) (xy 348.038889 -303.393324) (xy 348.046294 -303.38649)
			(xy 350.17964 -301.253144) (xy 350.186484 -301.245745) (xy 350.194208 -301.227146) (xy 350.194626 -301.217076)
			(xy 350.194626 -294.085772) (xy 350.194198 -294.075703) (xy 350.18648 -294.057104) (xy 350.17964 -294.049704)
			(xy 350.087946 -293.95801) (xy 350.080545 -293.951171) (xy 350.061947 -293.943454) (xy 350.051878 -293.943024)
			(xy 328.38898 -293.943024) (xy 328.378912 -293.943451) (xy 328.360315 -293.951174) (xy 328.352912 -293.95801)
			(xy 328.174096 -294.136826) (xy 328.167254 -294.144226) (xy 328.15953 -294.162824) (xy 328.15911 -294.172894)
			(xy 328.15911 -313.355228) (xy 328.159539 -313.365296) (xy 328.167261 -313.383892) (xy 328.174096 -313.391296)
			(xy 331.189584 -316.406784) (xy 331.638146 -316.406784) (xy 331.642219 -316.351125) (xy 331.654354 -316.296652)
			(xy 331.67429 -316.244526) (xy 331.701604 -316.195858) (xy 331.735712 -316.151686) (xy 331.775889 -316.112951)
			(xy 331.821277 -316.080479) (xy 331.870909 -316.054961) (xy 331.923729 -316.036942) (xy 331.978608 -316.026805)
			(xy 332.034379 -316.024767) (xy 332.089853 -316.03087) (xy 332.143846 -316.044986) (xy 332.195209 -316.066813)
			(xy 332.242847 -316.095886) (xy 332.285743 -316.131585) (xy 332.322985 -316.173149) (xy 332.353779 -316.219693)
			(xy 332.377467 -316.270224) (xy 332.393545 -316.323666) (xy 332.401671 -316.37888) (xy 332.40218 -316.406784)
			(xy 332.401671 -316.434688) (xy 332.393545 -316.489902) (xy 332.377467 -316.543344) (xy 332.353779 -316.593875)
			(xy 332.322985 -316.640419) (xy 332.285743 -316.681983) (xy 332.242847 -316.717682) (xy 332.195209 -316.746755)
			(xy 332.143846 -316.768582) (xy 332.089853 -316.782698) (xy 332.034379 -316.788801) (xy 331.978608 -316.786763)
			(xy 331.923729 -316.776626) (xy 331.870909 -316.758607) (xy 331.821277 -316.733089) (xy 331.775889 -316.700617)
			(xy 331.735712 -316.661882) (xy 331.701604 -316.61771) (xy 331.67429 -316.569042) (xy 331.654354 -316.516916)
			(xy 331.642219 -316.462443) (xy 331.638146 -316.406784) (xy 331.189584 -316.406784) (xy 331.607414 -316.824614)
			(xy 331.614268 -316.832009) (xy 331.62201 -316.850608) (xy 331.6224 -316.860682) (xy 331.6224 -318.61379)
			(xy 331.622821 -318.623861) (xy 331.630533 -318.642468) (xy 331.637386 -318.649858) (xy 331.734414 -318.746886)
			(xy 331.741813 -318.753732) (xy 331.760411 -318.761463) (xy 331.770482 -318.761872)
		)
		(stroke
			(width 0)
			(type solid)
		)
		(fill yes)
		(layer "F.Cu")
		(net "P0V8_PEX2")
	)
	(gr_poly
		(pts
			(arc
				(start 247.98274 -298.161456)
				(mid 248.002263 -298.157555)
				(end 248.018808 -298.14647)
			)
			(arc
				(start 248.225818 -297.93946)
				(mid 248.236929 -297.922926)
				(end 248.240804 -297.903392)
			)
			(arc
				(start 248.240804 -296.280078)
				(mid 248.244705 -296.260555)
				(end 248.25579 -296.24401)
			)
			(arc
				(start 249.09145 -295.40835)
				(mid 249.102561 -295.391816)
				(end 249.106436 -295.372282)
			)
			(arc
				(start 249.106436 -281.366468)
				(mid 249.102535 -281.346945)
				(end 249.09145 -281.3304)
			)
			(arc
				(start 249.01017 -281.24912)
				(mid 248.993636 -281.238009)
				(end 248.974102 -281.234134)
			)
			(arc
				(start 245.08587 -281.234134)
				(mid 245.066347 -281.238035)
				(end 245.049802 -281.24912)
			)
			(arc
				(start 244.986556 -281.312366)
				(mid 244.975445 -281.3289)
				(end 244.97157 -281.348434)
			)
			(arc
				(start 244.97157 -293.57447)
				(mid 244.967669 -293.593993)
				(end 244.956584 -293.610538)
			)
			(arc
				(start 244.598952 -293.96817)
				(mid 244.582418 -293.979281)
				(end 244.562884 -293.983156)
			)
			(arc
				(start 236.508798 -293.983156)
				(mid 236.489275 -293.979255)
				(end 236.47273 -293.96817)
			)
			(arc
				(start 235.832142 -293.327582)
				(mid 235.821031 -293.311048)
				(end 235.817156 -293.291514)
			)
			(arc
				(start 235.817156 -284.620716)
				(mid 235.813255 -284.601193)
				(end 235.80217 -284.584648)
			)
			(arc
				(start 235.47578 -284.258258)
				(mid 235.459246 -284.247147)
				(end 235.439712 -284.243272)
			)
			(arc
				(start 233.870246 -284.243272)
				(mid 233.850723 -284.239371)
				(end 233.834178 -284.228286)
			)
			(arc
				(start 233.617516 -284.011624)
				(mid 233.606405 -283.99509)
				(end 233.60253 -283.975556)
			)
			(arc
				(start 233.60253 -281.410664)
				(mid 233.598629 -281.391141)
				(end 233.587544 -281.374596)
			)
			(arc
				(start 233.462068 -281.24912)
				(mid 233.445534 -281.238009)
				(end 233.426 -281.234134)
			)
			(arc
				(start 228.835712 -281.234134)
				(mid 228.816189 -281.238035)
				(end 228.799644 -281.24912)
			)
			(arc
				(start 228.736398 -281.312366)
				(mid 228.725287 -281.3289)
				(end 228.721412 -281.348434)
			)
			(arc
				(start 228.721412 -293.57447)
				(mid 228.717511 -293.593993)
				(end 228.706426 -293.610538)
			)
			(arc
				(start 228.348794 -293.96817)
				(mid 228.33226 -293.979281)
				(end 228.312726 -293.983156)
			)
			(arc
				(start 220.25864 -293.983156)
				(mid 220.239117 -293.979255)
				(end 220.222572 -293.96817)
			)
			(arc
				(start 219.581984 -293.327582)
				(mid 219.570873 -293.311048)
				(end 219.566998 -293.291514)
			)
			(arc
				(start 219.566998 -284.748986)
				(mid 219.563097 -284.729463)
				(end 219.552012 -284.712918)
			)
			(arc
				(start 219.097352 -284.258258)
				(mid 219.080818 -284.247147)
				(end 219.061284 -284.243272)
			)
			(arc
				(start 214.500714 -284.243272)
				(mid 214.481191 -284.247173)
				(end 214.464646 -284.258258)
			)
			(arc
				(start 213.39175 -285.331408)
				(mid 213.380639 -285.347942)
				(end 213.376764 -285.367476)
			)
			(arc
				(start 213.376764 -297.4721)
				(mid 213.380665 -297.491623)
				(end 213.39175 -297.508168)
			)
			(arc
				(start 214.030052 -298.14647)
				(mid 214.046586 -298.157581)
				(end 214.06612 -298.161456)
			)
		)
		(stroke
			(width 0)
			(type solid)
		)
		(fill yes)
		(layer "F.Cu")
		(net "GND")
	)
	(gr_poly
		(pts
			(arc
				(start 21.335238 -55.780686)
				(mid 21.354761 -55.776785)
				(end 21.371306 -55.7657)
			)
			(arc
				(start 21.392134 -55.744872)
				(mid 21.403196 -55.728455)
				(end 21.40712 -55.709058)
			)
			(arc
				(start 21.40712 -53.619908)
				(mid 21.402257 -53.59847)
				(end 21.388832 -53.581046)
			)
			(xy 21.320506 -53.523642) (xy 21.29917 -53.5178)
			(arc
				(start 21.287994 -53.519832)
				(mid 21.255222 -53.524051)
				(end 21.222208 -53.52542)
			)
			(arc
				(start 21.222208 -53.52542)
				(mid 21.158711 -53.520138)
				(end 21.096986 -53.504338)
			)
			(xy 21.07819 -53.497734) (xy 21.06422 -53.501036) (xy 21.05279 -53.502306) (xy 20.980146 -53.502306)
			(xy 20.733258 -53.502306) (xy 20.67433 -53.443378) (xy 20.67433 -53.19649)
			(arc
				(start 20.67433 -52.04079)
				(mid 20.670429 -52.021267)
				(end 20.659344 -52.004722)
			)
			(arc
				(start 18.03019 -49.375568)
				(mid 18.019079 -49.359034)
				(end 18.015204 -49.3395)
			)
			(arc
				(start 18.015204 -48.075596)
				(mid 18.019105 -48.056073)
				(end 18.03019 -48.039528)
			)
			(arc
				(start 18.924016 -47.145702)
				(mid 18.94055 -47.134591)
				(end 18.960084 -47.130716)
			)
			(arc
				(start 20.12823 -47.130716)
				(mid 20.147753 -47.126815)
				(end 20.164298 -47.11573)
			)
			(arc
				(start 20.273518 -47.00651)
				(mid 20.284629 -46.989976)
				(end 20.288504 -46.970442)
			)
			(arc
				(start 20.288504 -46.678342)
				(mid 20.292405 -46.658819)
				(end 20.30349 -46.642274)
			)
			(arc
				(start 20.526248 -46.419516)
				(mid 20.542782 -46.408405)
				(end 20.562316 -46.40453)
			)
			(arc
				(start 20.959064 -46.40453)
				(mid 20.968902 -46.403568)
				(end 20.978368 -46.40072)
			)
			(xy 21.064728 -46.364906) (xy 21.067522 -46.36389) (xy 21.077174 -46.359826)
			(arc
				(start 21.115782 -46.321218)
				(mid 21.132316 -46.310107)
				(end 21.15185 -46.306232)
			)
			(arc
				(start 21.672042 -46.306232)
				(mid 21.691565 -46.302331)
				(end 21.70811 -46.291246)
			)
			(arc
				(start 21.72335 -46.276006)
				(mid 21.734461 -46.259472)
				(end 21.738336 -46.239938)
			)
			(arc
				(start 21.738336 -46.176438)
				(mid 21.734435 -46.156915)
				(end 21.72335 -46.14037)
			)
			(arc
				(start 21.67382 -46.09084)
				(mid 21.657286 -46.079729)
				(end 21.637752 -46.075854)
			)
			(arc
				(start 20.864576 -46.075854)
				(mid 20.845053 -46.071953)
				(end 20.828508 -46.060868)
			)
			(xy 20.74164 -45.974) (xy 20.73021 -45.974)
			(arc
				(start 20.416774 -45.660564)
				(mid 20.40024 -45.649453)
				(end 20.380706 -45.645578)
			)
			(arc
				(start 13.930884 -45.645578)
				(mid 13.911361 -45.649479)
				(end 13.894816 -45.660564)
			)
			(arc
				(start 13.59154 -45.96384)
				(mid 13.580429 -45.980374)
				(end 13.576554 -45.999908)
			)
			(arc
				(start 13.576554 -55.02021)
				(mid 13.580455 -55.039733)
				(end 13.59154 -55.056278)
			)
			(arc
				(start 13.79093 -55.255668)
				(mid 13.807464 -55.266779)
				(end 13.826998 -55.270654)
			)
			(arc
				(start 20.408138 -55.270654)
				(mid 20.427661 -55.274555)
				(end 20.444206 -55.28564)
			)
			(arc
				(start 20.924266 -55.7657)
				(mid 20.9408 -55.776811)
				(end 20.960334 -55.780686)
			)
		)
		(stroke
			(width 0)
			(type solid)
		)
		(fill yes)
		(layer "F.Cu")
		(net "P12V_SSD0_R")
	)
	(gr_poly
		(pts
			(arc
				(start 237.65637 -53.953664)
				(mid 237.675893 -53.949763)
				(end 237.692438 -53.938678)
			)
			(arc
				(start 238.109506 -53.52161)
				(mid 238.120617 -53.505076)
				(end 238.124492 -53.485542)
			)
			(arc
				(start 238.124492 -53.019706)
				(mid 238.128393 -53.000183)
				(end 238.139478 -52.983638)
			)
			(arc
				(start 238.183166 -52.93995)
				(mid 238.1997 -52.928839)
				(end 238.219234 -52.924964)
			)
			(xy 240.747296 -52.924964) (xy 240.776506 -52.896262)
			(arc
				(start 240.777014 -52.875434)
				(mid 240.891843 -52.611359)
				(end 241.158522 -52.502816)
			)
			(arc
				(start 241.158522 -52.502816)
				(mid 241.428289 -52.614557)
				(end 241.54003 -52.884324)
			)
			(arc
				(start 241.54003 -52.884324)
				(mid 241.534208 -52.950743)
				(end 241.516916 -53.015134)
			)
			(xy 241.511836 -53.029104) (xy 241.518186 -53.057806)
			(arc
				(start 242.047776 -53.587396)
				(mid 242.06431 -53.598507)
				(end 242.083844 -53.602382)
			)
			(arc
				(start 244.312948 -53.602382)
				(mid 244.332471 -53.598481)
				(end 244.349016 -53.587396)
			)
			(arc
				(start 244.405912 -53.5305)
				(mid 244.417023 -53.513966)
				(end 244.420898 -53.494432)
			)
			(arc
				(start 244.420898 -50.38852)
				(mid 244.416997 -50.368997)
				(end 244.405912 -50.352452)
			)
			(arc
				(start 244.255036 -50.201576)
				(mid 244.238502 -50.190465)
				(end 244.218968 -50.18659)
			)
			(arc
				(start 242.377214 -50.18659)
				(mid 242.357691 -50.190491)
				(end 242.341146 -50.201576)
			)
			(arc
				(start 241.646202 -50.89652)
				(mid 241.629668 -50.907631)
				(end 241.610134 -50.911506)
			)
			(arc
				(start 240.287556 -50.911506)
				(mid 240.268169 -50.915456)
				(end 240.251742 -50.926492)
			)
			(arc
				(start 240.232438 -50.945542)
				(mid 240.216021 -50.956604)
				(end 240.196624 -50.960528)
			)
			(arc
				(start 237.88878 -50.960528)
				(mid 237.869393 -50.956578)
				(end 237.852966 -50.945542)
			)
			(arc
				(start 237.833662 -50.926492)
				(mid 237.817245 -50.91543)
				(end 237.797848 -50.911506)
			)
			(arc
				(start 237.593124 -50.911506)
				(mid 237.573601 -50.907605)
				(end 237.557056 -50.89652)
			)
			(arc
				(start 237.473744 -50.813208)
				(mid 237.462633 -50.796674)
				(end 237.458758 -50.77714)
			)
			(arc
				(start 237.458758 -50.422048)
				(mid 237.454857 -50.402525)
				(end 237.443772 -50.38598)
			)
			(arc
				(start 237.150402 -50.09261)
				(mid 237.133868 -50.081499)
				(end 237.114334 -50.077624)
			)
			(arc
				(start 234.917234 -50.077624)
				(mid 234.897711 -50.081525)
				(end 234.881166 -50.09261)
			)
			(arc
				(start 234.743498 -50.230278)
				(mid 234.732387 -50.246812)
				(end 234.728512 -50.266346)
			)
			(arc
				(start 234.728512 -53.760878)
				(mid 234.732413 -53.780401)
				(end 234.743498 -53.796946)
			)
			(arc
				(start 234.88523 -53.938678)
				(mid 234.901764 -53.949789)
				(end 234.921298 -53.953664)
			)
		)
		(stroke
			(width 0)
			(type solid)
		)
		(fill yes)
		(layer "F.Cu")
		(net "P3V3_AUX")
	)
	(gr_poly
		(pts
			(xy 366.675416 -280.45791) (xy 366.724946 -280.40838) (xy 366.724946 -279.086564)
			(arc
				(start 366.659414 -279.021032)
				(mid 365.405007 -277.742035)
				(end 364.946946 -276.010116)
			)
			(arc
				(start 364.946946 -276.010116)
				(mid 365.107205 -274.962709)
				(end 365.57331 -274.011136)
			)
			(xy 365.57331 -267.603224) (xy 364.876842 -266.906756) (xy 332.852268 -266.906756) (xy 332.29804 -267.460984)
			(xy 332.29804 -278.910288) (xy 332.432152 -279.0444) (xy 333.722218 -279.0444) (xy 333.815944 -278.950674)
			(xy 333.856838 -278.90978) (xy 333.856838 -278.442166) (xy 333.856838 -268.784578) (xy 333.856838 -268.458188)
			(xy 334.217772 -268.097254) (xy 338.73821 -268.097254) (xy 338.868258 -268.097254) (xy 339.099144 -268.32814)
			(xy 339.099144 -268.458188) (xy 339.099144 -268.940534)
			(arc
				(start 339.099144 -272.052796)
				(mid 339.103045 -272.072319)
				(end 339.11413 -272.088864)
			)
			(arc
				(start 339.168486 -272.14322)
				(mid 339.18502 -272.154331)
				(end 339.204554 -272.158206)
			)
			(arc
				(start 344.460322 -272.158206)
				(mid 344.479845 -272.162107)
				(end 344.49639 -272.173192)
			)
			(arc
				(start 344.841322 -272.518124)
				(mid 344.852433 -272.534658)
				(end 344.856308 -272.554192)
			)
			(arc
				(start 344.856308 -278.826214)
				(mid 344.851083 -278.832443)
				(end 344.84691 -278.839422)
			)
			(arc
				(start 344.844116 -278.84628)
				(mid 344.842262 -278.85393)
				(end 344.841576 -278.861774)
			)
			(arc
				(start 344.841576 -279.316434)
				(mid 344.845409 -279.335791)
				(end 344.856308 -279.352248)
			)
			(arc
				(start 344.865452 -279.361392)
				(mid 344.87145 -279.366452)
				(end 344.878152 -279.370536)
			)
			(arc
				(start 344.878152 -279.370536)
				(mid 344.889379 -279.374691)
				(end 344.901266 -279.376124)
			)
			(arc
				(start 350.27489 -279.376124)
				(mid 350.294413 -279.372223)
				(end 350.310958 -279.361138)
			)
			(arc
				(start 350.507554 -279.164542)
				(mid 350.518665 -279.148008)
				(end 350.52254 -279.128474)
			)
			(arc
				(start 350.52254 -272.477992)
				(mid 350.526441 -272.458469)
				(end 350.537526 -272.441924)
			)
			(xy 350.849438 -272.129758) (xy 356.185978 -272.129758) (xy 356.29342 -272.022316) (xy 356.29342 -268.927072)
			(xy 356.29342 -268.335506) (xy 356.410768 -268.218158) (xy 356.459536 -268.16939) (xy 361.143042 -268.16939)
			(xy 361.19181 -268.218158) (xy 361.472988 -268.499336) (xy 361.472988 -268.985746) (xy 361.472988 -276.42439)
			(xy 361.475782 -276.431248) (xy 361.475782 -277.583138) (xy 361.474258 -277.584662) (xy 361.474258 -279.329388)
			(xy 361.518708 -279.373838) (xy 365.261144 -279.373838) (xy 365.443516 -279.373838) (xy 366.048798 -279.97912)
			(xy 366.048798 -280.161492) (xy 366.048798 -280.505916) (xy 366.16132 -280.618438) (xy 366.514888 -280.618438)
		)
		(stroke
			(width 0)
			(type solid)
		)
		(fill yes)
		(layer "F.Cu")
		(net "GND")
	)
	(gr_poly
		(pts
			(arc
				(start 12.183872 -251.13742)
				(mid 12.203395 -251.133519)
				(end 12.21994 -251.122434)
			)
			(arc
				(start 12.454382 -250.887992)
				(mid 12.465493 -250.871458)
				(end 12.469368 -250.851924)
			)
			(arc
				(start 12.469368 -249.949716)
				(mid 12.465467 -249.930193)
				(end 12.454382 -249.913648)
			)
			(arc
				(start 11.728958 -249.188224)
				(mid 11.717847 -249.17169)
				(end 11.713972 -249.152156)
			)
			(arc
				(start 11.713972 -247.683274)
				(mid 11.717873 -247.663751)
				(end 11.728958 -247.647206)
			)
			(arc
				(start 11.774424 -247.60174)
				(mid 11.790958 -247.590629)
				(end 11.810492 -247.586754)
			)
			(arc
				(start 12.076684 -247.586754)
				(mid 12.1103 -247.573955)
				(end 12.126976 -247.54205)
			)
			(xy 12.126976 -247.266968) (xy 13.57884 -247.266968)
			(arc
				(start 13.57884 -247.54205)
				(mid 13.59546 -247.574018)
				(end 13.629132 -247.586754)
			)
			(arc
				(start 13.681964 -247.586754)
				(mid 13.701487 -247.590655)
				(end 13.718032 -247.60174)
			)
			(arc
				(start 14.028166 -247.911874)
				(mid 14.039277 -247.928408)
				(end 14.043152 -247.947942)
			)
			(arc
				(start 14.043152 -250.612656)
				(mid 14.047053 -250.632179)
				(end 14.058138 -250.648724)
			)
			(arc
				(start 14.187424 -250.77801)
				(mid 14.203841 -250.789072)
				(end 14.223238 -250.792996)
			)
			(arc
				(start 15.059406 -250.792996)
				(mid 15.078793 -250.789046)
				(end 15.09522 -250.77801)
			)
			(arc
				(start 15.303754 -250.569476)
				(mid 15.314816 -250.553059)
				(end 15.31874 -250.533662)
			)
			(arc
				(start 15.31874 -249.61342)
				(mid 15.31479 -249.594033)
				(end 15.303754 -249.577606)
			)
			(arc
				(start 14.838934 -249.112786)
				(mid 14.827823 -249.096252)
				(end 14.823948 -249.076718)
			)
			(arc
				(start 14.823948 -247.570244)
				(mid 14.827849 -247.550721)
				(end 14.838934 -247.534176)
			)
			(arc
				(start 14.871954 -247.501156)
				(mid 14.888488 -247.490045)
				(end 14.908022 -247.48617)
			)
			(xy 14.909292 -247.48617) (xy 14.909292 -247.266968) (xy 16.360648 -247.266968)
			(arc
				(start 16.360648 -247.438926)
				(mid 16.376799 -247.472461)
				(end 16.411448 -247.48617)
			)
			(xy 16.422878 -247.48617)
			(arc
				(start 16.559022 -247.622314)
				(mid 16.570133 -247.638848)
				(end 16.574008 -247.658382)
			)
			(arc
				(start 16.574008 -250.535948)
				(mid 16.577909 -250.555471)
				(end 16.588994 -250.572016)
			)
			(arc
				(start 16.736568 -250.71959)
				(mid 16.753102 -250.730701)
				(end 16.772636 -250.734576)
			)
			(arc
				(start 17.876266 -250.734576)
				(mid 17.895789 -250.730675)
				(end 17.912334 -250.71959)
			)
			(arc
				(start 17.993868 -250.638056)
				(mid 18.004794 -250.62161)
				(end 18.0086 -250.602242)
			)
			(arc
				(start 18.0086 -243.325142)
				(mid 18.004767 -243.305785)
				(end 17.993868 -243.289328)
			)
			(arc
				(start 17.597628 -242.893088)
				(mid 17.581094 -242.881977)
				(end 17.56156 -242.878102)
			)
			(arc
				(start 4.897882 -242.878102)
				(mid 4.878359 -242.882003)
				(end 4.861814 -242.893088)
			)
			(arc
				(start 1.480058 -246.274844)
				(mid 1.468947 -246.291378)
				(end 1.465072 -246.310912)
			)
			(arc
				(start 1.465072 -250.637802)
				(mid 1.468973 -250.657325)
				(end 1.480058 -250.67387)
			)
			(arc
				(start 1.928622 -251.122434)
				(mid 1.945156 -251.133545)
				(end 1.96469 -251.13742)
			)
		)
		(stroke
			(width 0)
			(type solid)
		)
		(fill yes)
		(layer "F.Cu")
		(net "GND")
	)
	(gr_poly
		(pts
			(arc
				(start 244.543326 -293.567358)
				(mid 244.562849 -293.563457)
				(end 244.579394 -293.552372)
			)
			(arc
				(start 244.63121 -293.500556)
				(mid 244.642321 -293.484022)
				(end 244.646196 -293.464488)
			)
			(arc
				(start 244.646196 -280.996136)
				(mid 244.642295 -280.976613)
				(end 244.63121 -280.960068)
			)
			(xy 244.418358 -280.747216) (xy 244.411246 -280.73985) (xy 244.39245 -280.73223)
			(arc
				(start 240.783364 -280.73223)
				(mid 240.763841 -280.728329)
				(end 240.747296 -280.717244)
			)
			(arc
				(start 240.385854 -280.355802)
				(mid 240.374743 -280.339268)
				(end 240.370868 -280.319734)
			)
			(arc
				(start 240.370868 -278.918924)
				(mid 240.374769 -278.899401)
				(end 240.385854 -278.882856)
			)
			(arc
				(start 240.697004 -278.571706)
				(mid 240.713538 -278.560595)
				(end 240.733072 -278.55672)
			)
			(arc
				(start 241.815874 -278.55672)
				(mid 241.835397 -278.552819)
				(end 241.851942 -278.541734)
			)
			(arc
				(start 242.124484 -278.269192)
				(mid 242.135595 -278.252658)
				(end 242.13947 -278.233124)
			)
			(arc
				(start 242.13947 -278.026368)
				(mid 242.143371 -278.006845)
				(end 242.154456 -277.9903)
			)
			(arc
				(start 242.377214 -277.767542)
				(mid 242.393748 -277.756431)
				(end 242.413282 -277.752556)
			)
			(arc
				(start 242.732306 -277.752556)
				(mid 242.742274 -277.751619)
				(end 242.751864 -277.748746)
			)
			(arc
				(start 242.894866 -277.689564)
				(mid 242.924189 -277.678696)
				(end 242.954302 -277.67026)
			)
			(xy 242.95481 -277.67026) (xy 242.96116 -277.66899) (xy 242.974114 -277.661878) (xy 242.992656 -277.654258)
			(xy 243.533168 -277.654258) (xy 243.551964 -277.646638) (xy 243.559076 -277.639272)
			(arc
				(start 243.574316 -277.624032)
				(mid 243.585427 -277.607498)
				(end 243.589302 -277.587964)
			)
			(xy 243.589302 -277.514304) (xy 243.581682 -277.495508) (xy 243.574316 -277.488396)
			(arc
				(start 243.524786 -277.438866)
				(mid 243.508252 -277.427755)
				(end 243.488718 -277.42388)
			)
			(arc
				(start 242.83416 -277.42388)
				(mid 242.820013 -277.42187)
				(end 242.806982 -277.416006)
			)
			(arc
				(start 242.806728 -277.415752)
				(mid 242.793798 -277.410075)
				(end 242.779804 -277.408132)
			)
			(arc
				(start 242.75796 -277.408132)
				(mid 242.738739 -277.404251)
				(end 242.7224 -277.3934)
			)
			(xy 242.593368 -277.264622) (xy 242.337336 -277.00859) (xy 242.330224 -277.001224) (xy 242.311428 -276.993604)
			(xy 241.001042 -276.993604) (xy 241.000788 -276.994112)
			(arc
				(start 240.44656 -276.994112)
				(mid 240.427173 -276.998062)
				(end 240.410746 -277.009098)
			)
			(xy 239.911636 -277.507954) (xy 239.911636 -277.508716)
			(arc
				(start 239.732312 -277.68804)
				(mid 239.715866 -277.698966)
				(end 239.696498 -277.702772)
			)
			(arc
				(start 234.582716 -277.702772)
				(mid 234.563329 -277.706722)
				(end 234.546902 -277.717758)
			)
			(xy 233.917744 -278.346916) (xy 233.910378 -278.354028) (xy 233.902758 -278.372824)
			(arc
				(start 233.902758 -283.82849)
				(mid 233.906659 -283.848013)
				(end 233.917744 -283.864558)
			)
			(arc
				(start 234.002072 -283.948886)
				(mid 234.018606 -283.959997)
				(end 234.03814 -283.963872)
			)
			(arc
				(start 235.68533 -283.963872)
				(mid 235.704853 -283.967773)
				(end 235.721398 -283.978858)
			)
			(arc
				(start 236.180376 -284.437836)
				(mid 236.191487 -284.45437)
				(end 236.195362 -284.473904)
			)
			(arc
				(start 236.195362 -293.072566)
				(mid 236.199263 -293.092089)
				(end 236.210348 -293.108634)
			)
			(arc
				(start 236.654086 -293.552372)
				(mid 236.67062 -293.563483)
				(end 236.690154 -293.567358)
			)
		)
		(stroke
			(width 0)
			(type solid)
		)
		(fill yes)
		(layer "F.Cu")
		(net "P1V25_PEX2_R")
	)
	(gr_poly
		(pts
			(arc
				(start 13.233908 -291.280596)
				(mid 13.253431 -291.276695)
				(end 13.269976 -291.26561)
			)
			(arc
				(start 13.321792 -291.213794)
				(mid 13.332903 -291.19726)
				(end 13.336778 -291.177726)
			)
			(arc
				(start 13.336778 -278.709374)
				(mid 13.332877 -278.689851)
				(end 13.321792 -278.673306)
			)
			(xy 13.10894 -278.460454) (xy 13.101828 -278.453088) (xy 13.083032 -278.445468)
			(arc
				(start 9.473946 -278.445468)
				(mid 9.454423 -278.441567)
				(end 9.437878 -278.430482)
			)
			(arc
				(start 9.076436 -278.06904)
				(mid 9.065325 -278.052506)
				(end 9.06145 -278.032972)
			)
			(arc
				(start 9.06145 -276.632162)
				(mid 9.065351 -276.612639)
				(end 9.076436 -276.596094)
			)
			(arc
				(start 9.387586 -276.284944)
				(mid 9.40412 -276.273833)
				(end 9.423654 -276.269958)
			)
			(arc
				(start 10.506456 -276.269958)
				(mid 10.525979 -276.266057)
				(end 10.542524 -276.254972)
			)
			(arc
				(start 10.815066 -275.98243)
				(mid 10.826177 -275.965896)
				(end 10.830052 -275.946362)
			)
			(arc
				(start 10.830052 -275.739606)
				(mid 10.833953 -275.720083)
				(end 10.845038 -275.703538)
			)
			(arc
				(start 11.067796 -275.48078)
				(mid 11.08433 -275.469669)
				(end 11.103864 -275.465794)
			)
			(xy 11.422888 -275.465794) (xy 11.436858 -275.464016) (xy 11.442446 -275.461984)
			(arc
				(start 11.585448 -275.402802)
				(mid 11.613659 -275.39241)
				(end 11.642598 -275.38426)
			)
			(xy 11.643614 -275.384006) (xy 11.645392 -275.383498) (xy 11.651742 -275.382228) (xy 11.664696 -275.375116)
			(xy 11.683238 -275.367496) (xy 12.22375 -275.367496) (xy 12.242546 -275.359876) (xy 12.249658 -275.35251)
			(arc
				(start 12.264898 -275.33727)
				(mid 12.276009 -275.320736)
				(end 12.279884 -275.301202)
			)
			(xy 12.279884 -275.227542) (xy 12.272264 -275.208746) (xy 12.264898 -275.201634)
			(arc
				(start 12.215368 -275.152104)
				(mid 12.198834 -275.140993)
				(end 12.1793 -275.137118)
			)
			(arc
				(start 11.524742 -275.137118)
				(mid 11.510735 -275.135222)
				(end 11.497818 -275.129498)
			)
			(xy 11.491722 -275.125434) (xy 11.478006 -275.121624)
			(arc
				(start 11.448796 -275.121624)
				(mid 11.429409 -275.117674)
				(end 11.412982 -275.106638)
			)
			(xy 11.28395 -274.97786) (xy 11.027918 -274.721828) (xy 11.020806 -274.714462) (xy 11.00201 -274.706842)
			(arc
				(start 9.85012 -274.706842)
				(mid 9.830597 -274.710743)
				(end 9.814052 -274.721828)
			)
			(arc
				(start 8.93953 -275.59635)
				(mid 8.922996 -275.607461)
				(end 8.903462 -275.611336)
			)
			(arc
				(start 8.240268 -275.611336)
				(mid 8.220745 -275.607435)
				(end 8.2042 -275.59635)
			)
			(xy 8.181848 -275.573998) (xy 8.174736 -275.566632) (xy 8.15594 -275.559012)
			(arc
				(start 3.13055 -275.559012)
				(mid 3.111027 -275.562913)
				(end 3.094482 -275.573998)
			)
			(xy 2.438146 -276.230334) (xy 2.43078 -276.237446) (xy 2.42316 -276.256242)
			(arc
				(start 2.42316 -280.857706)
				(mid 2.427061 -280.877229)
				(end 2.438146 -280.893774)
			)
			(arc
				(start 2.80289 -281.258518)
				(mid 2.819424 -281.269629)
				(end 2.838958 -281.273504)
			)
			(arc
				(start 3.916172 -281.273504)
				(mid 3.935695 -281.277405)
				(end 3.95224 -281.28849)
			)
			(arc
				(start 4.870958 -282.207208)
				(mid 4.882069 -282.223742)
				(end 4.885944 -282.243276)
			)
			(arc
				(start 4.885944 -290.785804)
				(mid 4.889845 -290.805327)
				(end 4.90093 -290.821872)
			)
			(arc
				(start 5.344668 -291.26561)
				(mid 5.361202 -291.276721)
				(end 5.380736 -291.280596)
			)
		)
		(stroke
			(width 0)
			(type solid)
		)
		(fill yes)
		(layer "F.Cu")
		(net "P1V25_PEX0_R")
	)
	(gr_poly
		(pts
			(xy 41.728136 -13.358114)
			(arc
				(start 34.964878 -13.358114)
				(mid 33.898562 -12.916432)
				(end 33.45688 -11.850116)
			)
			(arc
				(start 33.45688 -1.999996)
				(mid 33.019884 -0.944996)
				(end 31.964884 -0.508)
			)
			(arc
				(start 19.964908 -0.508)
				(mid 18.909908 -0.944996)
				(end 18.472912 -1.999996)
			)
			(xy 18.472912 -11.766042) (xy 18.980404 -11.766042)
			(arc
				(start 18.980404 -1.999996)
				(mid 19.268759 -1.303847)
				(end 19.964908 -1.015492)
			)
			(arc
				(start 31.964884 -1.015492)
				(mid 32.661033 -1.303847)
				(end 32.949388 -1.999996)
			)
			(arc
				(start 32.949388 -11.850116)
				(mid 33.539801 -13.275118)
				(end 34.964878 -13.865352)
			)
			(xy 41.728136 -13.865352)
		)
		(stroke
			(width 0)
			(type solid)
		)
		(fill yes)
		(layer "F.Cu")
		(net "GND")
	)
	(gr_poly
		(pts
			(xy 67.71767 -13.358114)
			(arc
				(start 60.96508 -13.358114)
				(mid 59.898764 -12.916432)
				(end 59.457082 -11.850116)
			)
			(arc
				(start 59.457082 -1.999996)
				(mid 59.020086 -0.944996)
				(end 57.965086 -0.508)
			)
			(arc
				(start 45.96511 -0.508)
				(mid 44.91011 -0.944996)
				(end 44.473114 -1.999996)
			)
			(xy 44.473114 -11.833352) (xy 44.980352 -11.833352)
			(arc
				(start 44.980352 -1.999996)
				(mid 45.268617 -1.303936)
				(end 45.964602 -1.015492)
			)
			(arc
				(start 57.965086 -1.015492)
				(mid 58.661325 -1.303831)
				(end 58.949844 -1.999996)
			)
			(arc
				(start 58.949844 -11.850116)
				(mid 59.540093 -13.275103)
				(end 60.96508 -13.865352)
			)
			(xy 67.71767 -13.865352)
		)
		(stroke
			(width 0)
			(type solid)
		)
		(fill yes)
		(layer "F.Cu")
		(net "GND")
	)
	(gr_poly
		(pts
			(xy 248.042684 -13.358114)
			(arc
				(start 241.164872 -13.358114)
				(mid 240.098721 -12.916342)
				(end 239.656874 -11.850116)
			)
			(arc
				(start 239.656874 -1.999996)
				(mid 239.219878 -0.944996)
				(end 238.164878 -0.508)
			)
			(arc
				(start 214.065104 -0.508)
				(mid 213.010104 -0.944996)
				(end 212.573108 -1.999996)
			)
			(xy 212.573108 -11.731244) (xy 213.0806 -11.731244)
			(arc
				(start 213.0806 -1.999996)
				(mid 213.368955 -1.303847)
				(end 214.065104 -1.015492)
			)
			(arc
				(start 238.164878 -1.015492)
				(mid 238.861117 -1.303831)
				(end 239.149636 -1.999996)
			)
			(arc
				(start 239.149636 -11.850116)
				(mid 239.73987 -13.275193)
				(end 241.164872 -13.865352)
			)
			(xy 248.042684 -13.865352)
		)
		(stroke
			(width 0)
			(type solid)
		)
		(fill yes)
		(layer "F.Cu")
		(net "GND")
	)
	(gr_poly
		(pts
			(arc
				(start 248.509282 -377.743466)
				(mid 248.545203 -377.728587)
				(end 248.560082 -377.692666)
			)
			(xy 248.560082 -377.489974) (xy 248.560336 -377.483116) (xy 248.560336 -377.481846) (xy 248.560336 -377.458986)
			(xy 248.5644 -377.454922)
			(arc
				(start 248.568464 -377.444762)
				(mid 248.597492 -377.399876)
				(end 248.642378 -377.370848)
			)
			(xy 248.652538 -377.366784)
			(arc
				(start 248.76887 -377.250706)
				(mid 248.785287 -377.239644)
				(end 248.804684 -377.23572)
			)
			(arc
				(start 249.078496 -377.23572)
				(mid 249.097883 -377.23967)
				(end 249.11431 -377.250706)
			)
			(xy 249.230642 -377.366784)
			(arc
				(start 249.240802 -377.370848)
				(mid 249.289845 -377.404236)
				(end 249.318526 -377.456192)
			)
			(arc
				(start 249.319796 -377.460256)
				(mid 249.322083 -377.468885)
				(end 249.322844 -377.477782)
			)
			(xy 249.322844 -377.481846) (xy 249.322844 -377.483116) (xy 249.323098 -377.489974)
			(arc
				(start 249.323098 -377.641358)
				(mid 249.326999 -377.660881)
				(end 249.338084 -377.677426)
			)
			(arc
				(start 249.389138 -377.72848)
				(mid 249.405672 -377.739591)
				(end 249.425206 -377.743466)
			)
			(arc
				(start 258.106164 -377.743466)
				(mid 258.140242 -377.73034)
				(end 258.15671 -377.697746)
			)
			(xy 258.15671 -377.489974) (xy 258.156964 -377.481846) (xy 258.156964 -377.458986)
			(arc
				(start 258.16179 -377.45416)
				(mid 258.19402 -377.399776)
				(end 258.248404 -377.367546)
			)
			(arc
				(start 258.365498 -377.250706)
				(mid 258.381915 -377.239644)
				(end 258.401312 -377.23572)
			)
			(arc
				(start 258.675124 -377.23572)
				(mid 258.694511 -377.23967)
				(end 258.710938 -377.250706)
			)
			(arc
				(start 258.828032 -377.367546)
				(mid 258.884334 -377.401736)
				(end 258.915916 -377.459494)
			)
			(arc
				(start 258.91617 -377.459748)
				(mid 258.918644 -377.468615)
				(end 258.919472 -377.477782)
			)
			(xy 258.919472 -377.481846) (xy 258.919726 -377.489974)
			(arc
				(start 258.919726 -377.646184)
				(mid 258.924409 -377.662951)
				(end 258.934458 -377.677172)
			)
			(arc
				(start 258.985766 -377.72848)
				(mid 259.0023 -377.739591)
				(end 259.021834 -377.743466)
			)
			(arc
				(start 263.87171 -377.743466)
				(mid 263.891233 -377.739565)
				(end 263.907778 -377.72848)
			)
			(arc
				(start 263.948164 -377.688094)
				(mid 263.953525 -377.681881)
				(end 263.957816 -377.674886)
			)
			(xy 263.968484 -377.653042)
			(arc
				(start 263.9695 -377.64466)
				(mid 264.624759 -375.371445)
				(end 265.91641 -373.389398)
			)
			(xy 265.91641 -368.848132) (xy 265.612372 -368.544094) (xy 243.539264 -368.544094) (xy 243.533676 -368.538506)
			(arc
				(start 242.778534 -368.538506)
				(mid 242.759011 -368.542407)
				(end 242.742466 -368.553492)
			)
			(xy 242.620038 -368.67592) (xy 242.612672 -368.683032) (xy 242.605052 -368.701828)
			(arc
				(start 242.605052 -377.229624)
				(mid 242.608953 -377.249147)
				(end 242.620038 -377.265692)
			)
			(arc
				(start 243.082826 -377.72848)
				(mid 243.09936 -377.739591)
				(end 243.118894 -377.743466)
			)
		)
		(stroke
			(width 0)
			(type solid)
		)
		(fill yes)
		(layer "F.Cu")
		(net "P12V_STBY_R2")
	)
	(gr_poly
		(pts
			(xy 274.270216 -13.358114)
			(arc
				(start 267.165074 -13.358114)
				(mid 266.098758 -12.916432)
				(end 265.657076 -11.850116)
			)
			(arc
				(start 265.657076 -1.999996)
				(mid 265.22008 -0.944996)
				(end 264.16508 -0.508)
			)
			(arc
				(start 252.165104 -0.508)
				(mid 251.110104 -0.944996)
				(end 250.673108 -1.999996)
			)
			(xy 250.673108 -11.771376) (xy 251.1806 -11.771376)
			(arc
				(start 251.1806 -1.999996)
				(mid 251.468955 -1.303847)
				(end 252.165104 -1.015492)
			)
			(arc
				(start 264.16508 -1.015492)
				(mid 264.861229 -1.303847)
				(end 265.149584 -1.999996)
			)
			(arc
				(start 265.149584 -11.850116)
				(mid 265.739997 -13.275118)
				(end 267.165074 -13.865352)
			)
			(xy 274.270216 -13.865352)
		)
		(stroke
			(width 0)
			(type solid)
		)
		(fill yes)
		(layer "F.Cu")
		(net "GND")
	)
	(gr_poly
		(pts
			(xy 300.058328 -13.358114)
			(arc
				(start 293.165022 -13.358114)
				(mid 292.098706 -12.916432)
				(end 291.657024 -11.850116)
			)
			(arc
				(start 291.657024 -1.999996)
				(mid 291.220028 -0.944996)
				(end 290.165028 -0.508)
			)
			(arc
				(start 278.165052 -0.508)
				(mid 277.110052 -0.944996)
				(end 276.673056 -1.999996)
			)
			(xy 276.673056 -11.76147) (xy 277.180548 -11.76147)
			(arc
				(start 277.180548 -1.999996)
				(mid 277.468903 -1.303847)
				(end 278.165052 -1.015492)
			)
			(arc
				(start 290.165028 -1.015492)
				(mid 290.861177 -1.303847)
				(end 291.149532 -1.999996)
			)
			(arc
				(start 291.149532 -11.850116)
				(mid 291.739945 -13.275118)
				(end 293.165022 -13.865352)
			)
			(xy 300.058328 -13.865352)
		)
		(stroke
			(width 0)
			(type solid)
		)
		(fill yes)
		(layer "F.Cu")
		(net "GND")
	)
	(gr_poly
		(pts
			(xy 442.060838 -13.358114)
			(arc
				(start 435.265068 -13.358114)
				(mid 434.198752 -12.916432)
				(end 433.75707 -11.850116)
			)
			(arc
				(start 433.75707 -1.999996)
				(mid 433.320074 -0.944996)
				(end 432.265074 -0.508)
			)
			(arc
				(start 420.265098 -0.508)
				(mid 419.210098 -0.944996)
				(end 418.773102 -1.999996)
			)
			(xy 418.773102 -11.838178) (xy 419.28034 -11.838178)
			(arc
				(start 419.28034 -1.999996)
				(mid 419.568605 -1.303936)
				(end 420.26459 -1.015492)
			)
			(arc
				(start 432.265074 -1.015492)
				(mid 432.961313 -1.303831)
				(end 433.249832 -1.999996)
			)
			(arc
				(start 433.249832 -11.850116)
				(mid 433.840081 -13.275103)
				(end 435.265068 -13.865352)
			)
			(xy 442.060838 -13.865352)
		)
		(stroke
			(width 0)
			(type solid)
		)
		(fill yes)
		(layer "F.Cu")
		(net "GND")
	)
	(gr_poly
		(pts
			(xy 132.291582 -13.80998) (xy 132.291582 -13.413486) (xy 132.23621 -13.358114)
			(arc
				(start 125.065028 -13.358114)
				(mid 123.998712 -12.916432)
				(end 123.55703 -11.850116)
			)
			(arc
				(start 123.55703 -1.999996)
				(mid 123.120034 -0.944996)
				(end 122.065034 -0.508)
			)
			(arc
				(start 97.965006 -0.508)
				(mid 96.910006 -0.944996)
				(end 96.47301 -1.999996)
			)
			(xy 96.47301 -11.766296) (xy 96.980248 -11.766296)
			(arc
				(start 96.980248 -1.999996)
				(mid 97.268513 -1.303936)
				(end 97.964498 -1.015492)
			)
			(arc
				(start 122.065034 -1.015492)
				(mid 122.761273 -1.303831)
				(end 123.049792 -1.999996)
			)
			(arc
				(start 123.049792 -11.850116)
				(mid 123.640041 -13.275103)
				(end 125.065028 -13.865352)
			)
			(xy 132.23621 -13.865352)
		)
		(stroke
			(width 0)
			(type solid)
		)
		(fill yes)
		(layer "F.Cu")
		(net "GND")
	)
	(gr_poly
		(pts
			(xy 158.365444 -13.805662) (xy 158.365444 -13.417804) (xy 158.305754 -13.358114)
			(arc
				(start 151.064976 -13.358114)
				(mid 149.99866 -12.916432)
				(end 149.556978 -11.850116)
			)
			(arc
				(start 149.556978 -1.999996)
				(mid 149.119982 -0.944996)
				(end 148.064982 -0.508)
			)
			(arc
				(start 136.065006 -0.508)
				(mid 135.010006 -0.944996)
				(end 134.57301 -1.999996)
			)
			(xy 134.57301 -11.729212) (xy 135.080248 -11.729212)
			(arc
				(start 135.080248 -1.999996)
				(mid 135.368513 -1.303936)
				(end 136.064498 -1.015492)
			)
			(arc
				(start 148.064982 -1.015492)
				(mid 148.761221 -1.303831)
				(end 149.04974 -1.999996)
			)
			(arc
				(start 149.04974 -11.850116)
				(mid 149.639989 -13.275103)
				(end 151.064976 -13.865352)
			)
			(xy 158.305754 -13.865352)
		)
		(stroke
			(width 0)
			(type solid)
		)
		(fill yes)
		(layer "F.Cu")
		(net "GND")
	)
	(gr_poly
		(pts
			(xy 183.766714 -13.358114)
			(arc
				(start 177.064924 -13.358114)
				(mid 175.998608 -12.916432)
				(end 175.556926 -11.850116)
			)
			(arc
				(start 175.556926 -1.999996)
				(mid 175.11993 -0.944996)
				(end 174.06493 -0.508)
			)
			(arc
				(start 162.064954 -0.508)
				(mid 161.009954 -0.944996)
				(end 160.572958 -1.999996)
			)
			(xy 160.572958 -11.850116) (xy 160.571942 -11.908536) (xy 161.079434 -11.908536) (xy 161.080196 -11.85037)
			(arc
				(start 161.080196 -1.999996)
				(mid 161.368461 -1.303936)
				(end 162.064446 -1.015492)
			)
			(arc
				(start 174.06493 -1.015492)
				(mid 174.761169 -1.303831)
				(end 175.049688 -1.999996)
			)
			(arc
				(start 175.049688 -11.850116)
				(mid 175.639937 -13.275103)
				(end 177.064924 -13.865352)
			)
			(xy 183.766714 -13.865352)
		)
		(stroke
			(width 0)
			(type solid)
		)
		(fill yes)
		(layer "F.Cu")
		(net "GND")
	)
	(gr_poly
		(pts
			(xy 134.47522 -280.45791) (xy 134.52475 -280.40838) (xy 134.52475 -279.086564)
			(arc
				(start 134.459218 -279.021032)
				(mid 133.204811 -277.742035)
				(end 132.74675 -276.010116)
			)
			(arc
				(start 132.74675 -276.010116)
				(mid 132.907009 -274.962709)
				(end 133.373114 -274.011136)
			)
			(xy 133.373114 -267.603224) (xy 132.676646 -266.906756)
			(arc
				(start 100.622862 -266.906756)
				(mid 100.603339 -266.910657)
				(end 100.586794 -266.921742)
			)
			(arc
				(start 100.111814 -267.396722)
				(mid 100.100703 -267.413256)
				(end 100.096828 -267.43279)
			)
			(xy 100.096828 -278.38527) (xy 100.096828 -278.820118) (xy 100.29698 -279.02027) (xy 101.567488 -279.02027)
			(xy 101.656642 -278.931116) (xy 101.656642 -278.442166) (xy 101.656642 -268.784578) (xy 101.656642 -268.602968)
			(xy 102.003606 -268.256004) (xy 102.10546 -268.15415) (xy 105.891584 -268.15415) (xy 105.908856 -268.15415)
			(xy 105.914698 -268.159992) (xy 106.66095 -268.159992) (xy 106.80065 -268.159992) (xy 106.898948 -268.25829)
			(xy 106.898948 -268.940534)
			(arc
				(start 106.898948 -272.052796)
				(mid 106.902849 -272.072319)
				(end 106.913934 -272.088864)
			)
			(arc
				(start 106.96829 -272.14322)
				(mid 106.984824 -272.154331)
				(end 107.004358 -272.158206)
			)
			(arc
				(start 112.260126 -272.158206)
				(mid 112.279649 -272.162107)
				(end 112.296194 -272.173192)
			)
			(arc
				(start 112.641126 -272.518124)
				(mid 112.652237 -272.534658)
				(end 112.656112 -272.554192)
			)
			(arc
				(start 112.656112 -278.826214)
				(mid 112.650887 -278.832443)
				(end 112.646714 -278.839422)
			)
			(arc
				(start 112.64392 -278.84628)
				(mid 112.642066 -278.85393)
				(end 112.64138 -278.861774)
			)
			(arc
				(start 112.64138 -279.316434)
				(mid 112.645213 -279.335791)
				(end 112.656112 -279.352248)
			)
			(arc
				(start 112.665256 -279.361392)
				(mid 112.671254 -279.366452)
				(end 112.677956 -279.370536)
			)
			(arc
				(start 112.677956 -279.370536)
				(mid 112.689183 -279.374691)
				(end 112.70107 -279.376124)
			)
			(arc
				(start 118.074694 -279.376124)
				(mid 118.094217 -279.372223)
				(end 118.110762 -279.361138)
			)
			(arc
				(start 118.307358 -279.164542)
				(mid 118.318469 -279.148008)
				(end 118.322344 -279.128474)
			)
			(arc
				(start 118.322344 -272.477992)
				(mid 118.326245 -272.458469)
				(end 118.33733 -272.441924)
			)
			(xy 118.649242 -272.129758) (xy 123.985782 -272.129758) (xy 124.093224 -272.022316) (xy 124.093224 -268.927072)
			(xy 124.093224 -268.66469) (xy 124.438918 -268.318996) (xy 124.535692 -268.222222) (xy 124.651008 -268.106906)
			(xy 129.015236 -268.106906) (xy 129.130552 -268.222222) (xy 129.257806 -268.349476) (xy 129.257806 -268.444472)
			(xy 129.272792 -268.459458) (xy 129.272792 -268.985746) (xy 129.272792 -276.42439) (xy 129.275586 -276.431248)
			(xy 129.275586 -277.583138) (xy 129.274062 -277.584662) (xy 129.274062 -279.329388) (xy 129.318512 -279.373838)
			(xy 133.060948 -279.373838) (xy 133.198616 -279.373838) (xy 133.848602 -280.023824) (xy 133.848602 -280.161492)
			(xy 133.848602 -280.505916) (xy 133.961124 -280.618438) (xy 134.314692 -280.618438)
		)
		(stroke
			(width 0)
			(type solid)
		)
		(fill yes)
		(layer "F.Cu")
		(net "GND")
	)
	(gr_poly
		(pts
			(xy 210.250024 -13.829284) (xy 210.250024 -13.394182) (xy 210.213956 -13.358114)
			(arc
				(start 203.064872 -13.358114)
				(mid 201.998721 -12.916342)
				(end 201.556874 -11.850116)
			)
			(arc
				(start 201.556874 -1.999996)
				(mid 201.119878 -0.944996)
				(end 200.064878 -0.508)
			)
			(arc
				(start 188.064902 -0.508)
				(mid 187.009902 -0.944996)
				(end 186.572906 -1.999996)
			)
			(xy 186.572906 -11.85037) (xy 186.572906 -11.867896) (xy 187.080144 -11.867896) (xy 187.080144 -11.850116)
			(arc
				(start 187.080144 -1.999996)
				(mid 187.368409 -1.303936)
				(end 188.064394 -1.015492)
			)
			(arc
				(start 200.064878 -1.015492)
				(mid 200.761117 -1.303831)
				(end 201.049636 -1.999996)
			)
			(arc
				(start 201.049636 -11.850116)
				(mid 201.63987 -13.275193)
				(end 203.064872 -13.865352)
			)
			(xy 210.213956 -13.865352)
		)
		(stroke
			(width 0)
			(type solid)
		)
		(fill yes)
		(layer "F.Cu")
		(net "GND")
	)
	(gr_poly
		(pts
			(arc
				(start 251.243338 -275.121116)
				(mid 251.259402 -275.118509)
				(end 251.273818 -275.110956)
			)
			(xy 251.279152 -275.106384)
			(arc
				(start 251.279152 -262.097012)
				(mid 251.275202 -262.077625)
				(end 251.264166 -262.061198)
			)
			(arc
				(start 250.821952 -261.618984)
				(mid 250.752412 -261.515049)
				(end 250.727972 -261.392416)
			)
			(arc
				(start 250.727972 -260.59384)
				(mid 250.724139 -260.574483)
				(end 250.71324 -260.558026)
			)
			(arc
				(start 249.68708 -259.531866)
				(mid 249.675969 -259.515332)
				(end 249.672094 -259.495798)
			)
			(arc
				(start 249.672094 -258.996942)
				(mid 249.675995 -258.977419)
				(end 249.68708 -258.960874)
			)
			(xy 250.441206 -258.206748) (xy 250.448064 -258.193794)
			(arc
				(start 250.449588 -258.186174)
				(mid 250.4963 -258.047335)
				(end 250.576588 -257.924808)
			)
			(arc
				(start 250.576588 -257.924808)
				(mid 250.585636 -257.909388)
				(end 250.58878 -257.891788)
			)
			(arc
				(start 250.58878 -252.739906)
				(mid 250.584879 -252.720383)
				(end 250.573794 -252.703838)
			)
			(arc
				(start 248.792492 -250.922536)
				(mid 248.775958 -250.911425)
				(end 248.756424 -250.90755)
			)
			(arc
				(start 244.075966 -250.90755)
				(mid 244.040045 -250.922429)
				(end 244.025166 -250.95835)
			)
			(arc
				(start 244.025166 -251.831856)
				(mid 244.029067 -251.851379)
				(end 244.040152 -251.867924)
			)
			(arc
				(start 244.243352 -252.071124)
				(mid 244.259886 -252.082235)
				(end 244.27942 -252.08611)
			)
			(arc
				(start 245.30812 -252.08611)
				(mid 245.327643 -252.082209)
				(end 245.344188 -252.071124)
			)
			(arc
				(start 245.657116 -251.758196)
				(mid 245.67365 -251.747085)
				(end 245.693184 -251.74321)
			)
			(xy 247.626886 -251.74321) (xy 247.62714 -251.743464)
			(arc
				(start 248.370598 -251.743464)
				(mid 248.390121 -251.747365)
				(end 248.406666 -251.75845)
			)
			(xy 249.308874 -252.660658) (xy 249.326654 -252.668278)
			(arc
				(start 249.33656 -252.668532)
				(mid 249.424752 -252.706775)
				(end 249.46102 -252.795786)
			)
			(xy 249.46102 -252.822964) (xy 249.468894 -252.84176) (xy 249.470672 -252.843538)
			(arc
				(start 249.470672 -256.977134)
				(mid 249.466771 -256.996657)
				(end 249.455686 -257.013202)
			)
			(arc
				(start 248.580402 -257.888486)
				(mid 248.569291 -257.90502)
				(end 248.565416 -257.924554)
			)
			(arc
				(start 248.565416 -261.457694)
				(mid 248.569317 -261.477217)
				(end 248.580402 -261.493762)
			)
			(arc
				(start 249.530362 -262.443468)
				(mid 249.541473 -262.460002)
				(end 249.545348 -262.479536)
			)
			(arc
				(start 249.545348 -273.147028)
				(mid 249.545958 -273.155135)
				(end 249.547888 -273.16303)
			)
			(xy 249.555254 -273.184874)
			(arc
				(start 249.559572 -273.191224)
				(mid 249.626085 -273.324212)
				(end 249.64898 -273.471132)
			)
			(arc
				(start 249.64898 -273.47164)
				(mid 249.626085 -273.61856)
				(end 249.559572 -273.751548)
			)
			(xy 249.555254 -273.757898)
			(arc
				(start 249.547888 -273.779742)
				(mid 249.545994 -273.787642)
				(end 249.545348 -273.795744)
			)
			(xy 249.545348 -274.289774)
			(arc
				(start 249.549412 -274.299426)
				(mid 249.577866 -274.391498)
				(end 249.587512 -274.487386)
			)
			(arc
				(start 249.587512 -274.487386)
				(mid 249.577899 -274.583281)
				(end 249.549412 -274.675346)
			)
			(xy 249.545348 -274.684998)
			(arc
				(start 249.545348 -274.940268)
				(mid 249.549249 -274.959791)
				(end 249.560334 -274.976336)
			)
			(arc
				(start 249.690128 -275.10613)
				(mid 249.706662 -275.117241)
				(end 249.726196 -275.121116)
			)
		)
		(stroke
			(width 0)
			(type solid)
		)
		(fill yes)
		(layer "F.Cu")
		(net "P3V3_AUX")
	)
	(gr_poly
		(pts
			(xy 93.415358 -13.358114)
			(arc
				(start 86.965028 -13.358114)
				(mid 85.898712 -12.916432)
				(end 85.45703 -11.850116)
			)
			(arc
				(start 85.45703 -1.999996)
				(mid 85.020034 -0.944996)
				(end 83.965034 -0.508)
			)
			(arc
				(start 71.965058 -0.508)
				(mid 70.910058 -0.944996)
				(end 70.473062 -1.999996)
			)
			(arc
				(start 70.473062 -11.850624)
				(mid 70.442762 -12.151171)
				(end 70.353174 -12.43965)
			)
			(arc
				(start 70.892162 -12.43965)
				(mid 70.95814 -12.148286)
				(end 70.9803 -11.85037)
			)
			(arc
				(start 70.9803 -1.999996)
				(mid 71.268565 -1.303936)
				(end 71.96455 -1.015492)
			)
			(arc
				(start 83.965034 -1.015492)
				(mid 84.661273 -1.303831)
				(end 84.949792 -1.999996)
			)
			(arc
				(start 84.949792 -11.850116)
				(mid 85.540041 -13.275103)
				(end 86.965028 -13.865352)
			)
			(xy 93.415358 -13.865352)
		)
		(stroke
			(width 0)
			(type solid)
		)
		(fill yes)
		(layer "F.Cu")
		(net "GND")
	)
	(gr_poly
		(pts
			(arc
				(start 109.167168 -394.546582)
				(mid 109.203089 -394.531703)
				(end 109.217968 -394.495782)
			)
			(arc
				(start 109.217968 -394.445236)
				(mid 109.232799 -394.371236)
				(end 109.274864 -394.308584)
			)
			(arc
				(start 109.369606 -394.213588)
				(mid 109.380955 -394.196081)
				(end 109.384338 -394.175488)
			)
			(xy 109.380782 -394.08989) (xy 109.371384 -394.071094)
			(arc
				(start 109.363256 -394.064236)
				(mid 109.303534 -393.985968)
				(end 109.282738 -393.889738)
			)
			(xy 109.282992 -393.889738) (xy 109.282992 -393.590526)
			(arc
				(start 109.282738 -393.590526)
				(mid 109.324146 -393.458584)
				(end 109.43463 -393.375388)
			)
			(xy 109.450124 -393.370054) (xy 109.46892 -393.343638)
			(arc
				(start 109.46892 -393.278614)
				(mid 109.467854 -393.268757)
				(end 109.464856 -393.25931)
			)
			(arc
				(start 109.071156 -392.308334)
				(mid 109.066393 -392.299519)
				(end 109.05998 -392.291824)
			)
			(xy 108.693204 -391.925048) (xy 108.652818 -391.924032)
			(arc
				(start 108.637832 -391.937748)
				(mid 108.519068 -392.010624)
				(end 108.382054 -392.036046)
			)
			(arc
				(start 108.382054 -392.036046)
				(mid 108.28061 -392.022382)
				(end 108.186474 -391.982198)
			)
			(arc
				(start 108.186474 -391.982198)
				(mid 108.174019 -391.976751)
				(end 108.160566 -391.974832)
			)
			(arc
				(start 107.92968 -391.974832)
				(mid 107.899449 -391.984995)
				(end 107.881166 -392.011154)
			)
			(arc
				(start 107.874308 -392.034014)
				(mid 107.874284 -392.063399)
				(end 107.890564 -392.087862)
			)
			(xy 107.912916 -392.108182)
			(arc
				(start 108.087414 -392.28268)
				(mid 108.137708 -392.347961)
				(end 108.16971 -392.423904)
			)
			(xy 108.174282 -392.440668) (xy 108.201206 -392.460988)
			(arc
				(start 108.472732 -392.460988)
				(mid 108.508653 -392.446109)
				(end 108.523532 -392.410188)
			)
			(xy 108.523532 -392.401044)
			(arc
				(start 108.790994 -392.401044)
				(mid 108.95147 -392.467885)
				(end 109.017054 -392.628882)
			)
			(xy 109.0168 -392.628882) (xy 109.0168 -392.928094)
			(arc
				(start 109.017054 -392.928094)
				(mid 108.981373 -393.051524)
				(end 108.884212 -393.135612)
			)
			(xy 108.870496 -393.141708) (xy 108.85424 -393.166854) (xy 108.85424 -393.375388) (xy 108.867956 -393.39901)
			(arc
				(start 108.880148 -393.405868)
				(mid 108.964326 -393.489366)
				(end 108.994702 -393.603988)
			)
			(xy 108.994448 -393.603988) (xy 108.994448 -393.9032)
			(arc
				(start 108.994702 -393.9032)
				(mid 108.961699 -394.022343)
				(end 108.871004 -394.1064)
			)
			(xy 108.85805 -394.11275) (xy 108.843064 -394.137134)
			(arc
				(start 108.843064 -394.19403)
				(mid 108.828335 -394.267986)
				(end 108.786422 -394.330682)
			)
			(arc
				(start 108.691934 -394.425424)
				(mid 108.677928 -394.451415)
				(end 108.680758 -394.480796)
			)
			(xy 108.686854 -394.495274) (xy 108.712 -394.512292)
			(arc
				(start 109.062012 -394.512292)
				(mid 109.101529 -394.518544)
				(end 109.137196 -394.536676)
			)
			(xy 109.1438 -394.541756) (xy 109.15904 -394.546582)
		)
		(stroke
			(width 0)
			(type solid)
		)
		(fill yes)
		(layer "F.Cu")
		(net "GND")
	)
	(gr_poly
		(pts
			(xy 228.322124 -293.559738) (xy 228.329236 -293.552372)
			(arc
				(start 228.381052 -293.500556)
				(mid 228.392163 -293.484022)
				(end 228.396038 -293.464488)
			)
			(xy 228.396038 -280.985976) (xy 228.388418 -280.96718) (xy 228.381052 -280.960068)
			(arc
				(start 228.1682 -280.747216)
				(mid 228.151666 -280.736105)
				(end 228.132132 -280.73223)
			)
			(arc
				(start 224.533206 -280.73223)
				(mid 224.513683 -280.728329)
				(end 224.497138 -280.717244)
			)
			(arc
				(start 224.135696 -280.355802)
				(mid 224.124585 -280.339268)
				(end 224.12071 -280.319734)
			)
			(arc
				(start 224.12071 -278.918924)
				(mid 224.124611 -278.899401)
				(end 224.135696 -278.882856)
			)
			(arc
				(start 224.446846 -278.571706)
				(mid 224.46338 -278.560595)
				(end 224.482914 -278.55672)
			)
			(arc
				(start 225.565716 -278.55672)
				(mid 225.585239 -278.552819)
				(end 225.601784 -278.541734)
			)
			(arc
				(start 225.874326 -278.269192)
				(mid 225.885437 -278.252658)
				(end 225.889312 -278.233124)
			)
			(arc
				(start 225.889312 -278.026368)
				(mid 225.893213 -278.006845)
				(end 225.904298 -277.9903)
			)
			(arc
				(start 226.127056 -277.767542)
				(mid 226.14359 -277.756431)
				(end 226.163124 -277.752556)
			)
			(arc
				(start 226.482148 -277.752556)
				(mid 226.492116 -277.751619)
				(end 226.501706 -277.748746)
			)
			(arc
				(start 226.644708 -277.689564)
				(mid 226.674031 -277.678696)
				(end 226.704144 -277.67026)
			)
			(xy 226.704652 -277.67026) (xy 226.711002 -277.66899) (xy 226.723956 -277.661878) (xy 226.742498 -277.654258)
			(xy 227.28301 -277.654258) (xy 227.301806 -277.646638) (xy 227.308918 -277.639272)
			(arc
				(start 227.324158 -277.624032)
				(mid 227.335269 -277.607498)
				(end 227.339144 -277.587964)
			)
			(xy 227.339144 -277.514304) (xy 227.331524 -277.495508) (xy 227.324158 -277.488396)
			(arc
				(start 227.274628 -277.438866)
				(mid 227.258094 -277.427755)
				(end 227.23856 -277.42388)
			)
			(arc
				(start 226.584002 -277.42388)
				(mid 226.569855 -277.42187)
				(end 226.556824 -277.416006)
			)
			(arc
				(start 226.55657 -277.415752)
				(mid 226.54364 -277.410075)
				(end 226.529646 -277.408132)
			)
			(arc
				(start 226.507802 -277.408132)
				(mid 226.488581 -277.404251)
				(end 226.472242 -277.3934)
			)
			(xy 226.34321 -277.264622) (xy 226.087178 -277.00859) (xy 226.080066 -277.001224) (xy 226.06127 -276.993604)
			(arc
				(start 224.260156 -276.993604)
				(mid 224.240633 -276.997505)
				(end 224.224088 -277.00859)
			)
			(arc
				(start 223.409002 -277.823676)
				(mid 223.392468 -277.834787)
				(end 223.372934 -277.838662)
			)
			(arc
				(start 216.327736 -277.838662)
				(mid 216.302586 -277.845469)
				(end 216.284048 -277.863808)
			)
			(xy 216.23274 -277.95093) (xy 216.232486 -277.977854)
			(arc
				(start 216.23909 -277.989792)
				(mid 216.275093 -278.079543)
				(end 216.28735 -278.175466)
			)
			(arc
				(start 216.28735 -278.175466)
				(mid 216.175609 -278.445233)
				(end 215.905842 -278.556974)
			)
			(arc
				(start 215.905842 -278.556974)
				(mid 215.866259 -278.554968)
				(end 215.827102 -278.548846)
			)
			(xy 215.815926 -278.546306) (xy 215.793574 -278.551894)
			(arc
				(start 215.72347 -278.60879)
				(mid 215.709659 -278.62636)
				(end 215.704674 -278.64816)
			)
			(arc
				(start 215.704674 -283.600906)
				(mid 215.708575 -283.620429)
				(end 215.71966 -283.636974)
			)
			(arc
				(start 215.946482 -283.863796)
				(mid 215.963016 -283.874907)
				(end 215.98255 -283.878782)
			)
			(arc
				(start 219.466668 -283.878782)
				(mid 219.486191 -283.882683)
				(end 219.502736 -283.893768)
			)
			(arc
				(start 219.930218 -284.32125)
				(mid 219.941329 -284.337784)
				(end 219.945204 -284.357318)
			)
			(xy 219.945204 -293.082726) (xy 219.952824 -293.101522) (xy 219.96019 -293.108634)
			(arc
				(start 220.403928 -293.552372)
				(mid 220.420462 -293.563483)
				(end 220.439996 -293.567358)
			)
			(xy 228.303328 -293.567358)
		)
		(stroke
			(width 0)
			(type solid)
		)
		(fill yes)
		(layer "F.Cu")
		(net "P1V25_PEX1_R")
	)
	(gr_poly
		(pts
			(arc
				(start 97.743518 -397.0274)
				(mid 97.763041 -397.023499)
				(end 97.779586 -397.012414)
			)
			(arc
				(start 97.927414 -396.864586)
				(mid 97.938525 -396.848052)
				(end 97.9424 -396.828518)
			)
			(arc
				(start 97.9424 -395.829282)
				(mid 97.938499 -395.809759)
				(end 97.927414 -395.793214)
			)
			(arc
				(start 97.830386 -395.696186)
				(mid 97.813852 -395.685075)
				(end 97.794318 -395.6812)
			)
			(arc
				(start 96.871282 -395.6812)
				(mid 96.851759 -395.677299)
				(end 96.835214 -395.666214)
			)
			(arc
				(start 96.712786 -395.543786)
				(mid 96.701675 -395.527252)
				(end 96.6978 -395.507718)
			)
			(xy 96.6978 -395.496796)
			(arc
				(start 96.683576 -395.482064)
				(mid 96.58417 -395.327907)
				(end 96.549464 -395.1478)
			)
			(arc
				(start 96.549464 -395.1478)
				(mid 96.584204 -394.967706)
				(end 96.683576 -394.813536)
			)
			(arc
				(start 96.683576 -394.813536)
				(mid 96.694089 -394.797386)
				(end 96.6978 -394.778484)
			)
			(arc
				(start 96.6978 -394.501116)
				(mid 96.694056 -394.482227)
				(end 96.683576 -394.466064)
			)
			(arc
				(start 96.683576 -394.466064)
				(mid 96.58417 -394.311907)
				(end 96.549464 -394.1318)
			)
			(arc
				(start 96.549464 -394.1318)
				(mid 96.584204 -393.951706)
				(end 96.683576 -393.797536)
			)
			(arc
				(start 96.683576 -393.797536)
				(mid 96.694089 -393.781386)
				(end 96.6978 -393.762484)
			)
			(arc
				(start 96.6978 -393.485116)
				(mid 96.694056 -393.466227)
				(end 96.683576 -393.450064)
			)
			(arc
				(start 96.683576 -393.450064)
				(mid 96.58417 -393.295907)
				(end 96.549464 -393.1158)
			)
			(arc
				(start 96.549464 -393.1158)
				(mid 96.624069 -392.857708)
				(end 96.825054 -392.679428)
			)
			(arc
				(start 96.825054 -392.679428)
				(mid 96.832579 -392.675072)
				(end 96.839278 -392.669522)
			)
			(xy 96.84258 -392.66622) (xy 96.861122 -392.6586) (xy 96.876362 -392.6586)
			(arc
				(start 96.883982 -392.65606)
				(mid 96.957238 -392.638592)
				(end 97.032318 -392.632692)
			)
			(arc
				(start 97.648268 -392.632692)
				(mid 97.723353 -392.638563)
				(end 97.796604 -392.65606)
			)
			(xy 97.804224 -392.6586)
			(arc
				(start 97.870518 -392.6586)
				(mid 97.890041 -392.654699)
				(end 97.906586 -392.643614)
			)
			(arc
				(start 97.952814 -392.597386)
				(mid 97.963925 -392.580852)
				(end 97.9678 -392.561318)
			)
			(arc
				(start 97.9678 -390.927082)
				(mid 97.971701 -390.907559)
				(end 97.982786 -390.891014)
			)
			(arc
				(start 98.031046 -390.842754)
				(mid 98.042108 -390.826337)
				(end 98.046032 -390.80694)
			)
			(xy 98.046032 -390.796272) (xy 98.075496 -390.7663)
			(arc
				(start 98.086418 -390.7663)
				(mid 98.105775 -390.762467)
				(end 98.122232 -390.751568)
			)
			(arc
				(start 98.206814 -390.666986)
				(mid 98.223348 -390.655875)
				(end 98.242882 -390.652)
			)
			(arc
				(start 99.242118 -390.652)
				(mid 99.261641 -390.648099)
				(end 99.278186 -390.637014)
			)
			(arc
				(start 99.400614 -390.514586)
				(mid 99.411725 -390.498052)
				(end 99.4156 -390.478518)
			)
			(arc
				(start 99.4156 -389.479282)
				(mid 99.411699 -389.459759)
				(end 99.400614 -389.443214)
			)
			(arc
				(start 99.303586 -389.346186)
				(mid 99.287052 -389.335075)
				(end 99.267518 -389.3312)
			)
			(arc
				(start 96.205548 -389.3312)
				(mid 96.169627 -389.346079)
				(end 96.154748 -389.382)
			)
			(arc
				(start 96.154748 -396.556484)
				(mid 96.158532 -396.575978)
				(end 96.16948 -396.592552)
			)
			(arc
				(start 96.589596 -397.012414)
				(mid 96.606013 -397.023476)
				(end 96.62541 -397.0274)
			)
		)
		(stroke
			(width 0)
			(type solid)
		)
		(fill yes)
		(layer "F.Cu")
		(net "P3V3_AUX")
	)
	(gr_poly
		(pts
			(arc
				(start 232.372408 -117.576346)
				(mid 232.391931 -117.572445)
				(end 232.408476 -117.56136)
			)
			(arc
				(start 232.410508 -117.559328)
				(mid 232.421619 -117.542794)
				(end 232.425494 -117.52326)
			)
			(arc
				(start 232.425494 -113.851182)
				(mid 232.421593 -113.831659)
				(end 232.410508 -113.815114)
			)
			(xy 232.330498 -113.735104) (xy 232.323386 -113.727738) (xy 232.30459 -113.720118)
			(arc
				(start 224.908872 -113.720118)
				(mid 224.889349 -113.716217)
				(end 224.872804 -113.705132)
			)
			(arc
				(start 224.338388 -113.170716)
				(mid 224.327277 -113.154182)
				(end 224.323402 -113.134648)
			)
			(xy 224.323402 -109.619796) (xy 224.322386 -109.61878)
			(arc
				(start 224.322386 -104.595676)
				(mid 224.326287 -104.576153)
				(end 224.337372 -104.559608)
			)
			(arc
				(start 224.817432 -104.079548)
				(mid 224.828543 -104.063014)
				(end 224.832418 -104.04348)
			)
			(arc
				(start 224.832418 -103.668576)
				(mid 224.828517 -103.649053)
				(end 224.817432 -103.632508)
			)
			(xy 224.747836 -103.562912) (xy 224.740724 -103.555546) (xy 224.721928 -103.547926) (xy 222.638874 -103.547926)
			(xy 222.5802 -103.6066) (xy 222.5802 -104.0638) (xy 222.5802 -104.234742) (xy 222.471742 -104.3432)
			(xy 222.3008 -104.3432) (xy 221.632272 -104.3432) (xy 221.378272 -104.5972)
			(arc
				(start 221.378272 -106.447336)
				(mid 221.374371 -106.466859)
				(end 221.363286 -106.483404)
			)
			(arc
				(start 221.03588 -106.81081)
				(mid 221.019346 -106.821921)
				(end 220.999812 -106.825796)
			)
			(arc
				(start 219.888562 -106.825796)
				(mid 219.869039 -106.821895)
				(end 219.852494 -106.81081)
			)
			(xy 219.594684 -106.553)
			(arc
				(start 219.205556 -106.163618)
				(mid 219.194445 -106.147084)
				(end 219.19057 -106.12755)
			)
			(arc
				(start 219.19057 -104.959404)
				(mid 219.186669 -104.939881)
				(end 219.175584 -104.923336)
			)
			(xy 219.066364 -104.814116) (xy 219.059252 -104.80675) (xy 219.040456 -104.79913)
			(arc
				(start 218.738196 -104.79913)
				(mid 218.718673 -104.795229)
				(end 218.702128 -104.784144)
			)
			(arc
				(start 218.47937 -104.561386)
				(mid 218.468259 -104.544852)
				(end 218.464384 -104.525318)
			)
			(arc
				(start 218.464384 -104.076246)
				(mid 218.460483 -104.056723)
				(end 218.449398 -104.040178)
			)
			(arc
				(start 218.381072 -103.971852)
				(mid 218.369961 -103.955318)
				(end 218.366086 -103.935784)
			)
			(arc
				(start 218.366086 -103.415592)
				(mid 218.362185 -103.396069)
				(end 218.3511 -103.379524)
			)
			(xy 218.33586 -103.364284) (xy 218.328748 -103.356918) (xy 218.309952 -103.349298)
			(arc
				(start 218.236292 -103.349298)
				(mid 218.216769 -103.353199)
				(end 218.200224 -103.364284)
			)
			(xy 218.150694 -103.413814) (xy 218.143328 -103.420926) (xy 218.135708 -103.439722)
			(arc
				(start 218.135708 -104.223058)
				(mid 218.131807 -104.242581)
				(end 218.120722 -104.259126)
			)
			(xy 218.033854 -104.345994) (xy 218.033854 -104.357424) (xy 217.720418 -104.67086) (xy 217.713052 -104.677972)
			(xy 217.705432 -104.696768) (xy 217.705432 -104.706928) (xy 217.705432 -104.707182) (xy 217.429842 -104.982772)
			(xy 217.422476 -104.989884) (xy 217.414856 -105.00868)
			(arc
				(start 217.414856 -106.444796)
				(mid 217.410955 -106.464319)
				(end 217.39987 -106.480864)
			)
			(arc
				(start 217.08872 -106.792014)
				(mid 217.072186 -106.803125)
				(end 217.052652 -106.807)
			)
			(arc
				(start 216.846404 -106.807)
				(mid 216.826881 -106.810901)
				(end 216.810336 -106.821986)
			)
			(xy 216.281762 -107.35056) (xy 216.274396 -107.357672) (xy 216.266776 -107.376468)
			(arc
				(start 216.266776 -109.189266)
				(mid 216.265814 -109.199104)
				(end 216.262966 -109.20857)
			)
			(arc
				(start 216.258648 -109.218984)
				(mid 216.255799 -109.22845)
				(end 216.254838 -109.238288)
			)
			(arc
				(start 216.254838 -116.732558)
				(mid 216.262605 -116.759555)
				(end 216.28354 -116.778278)
			)
			(arc
				(start 216.28354 -116.778278)
				(mid 216.422503 -116.880865)
				(end 216.51341 -117.027706)
			)
			(xy 216.517474 -117.03812)
			(arc
				(start 217.040714 -117.56136)
				(mid 217.057248 -117.572471)
				(end 217.076782 -117.576346)
			)
		)
		(stroke
			(width 0)
			(type solid)
		)
		(fill yes)
		(layer "F.Cu")
		(net "P12V_NIC3_R")
	)
	(gr_poly
		(pts
			(xy 263.741408 -211.380324) (xy 263.751478 -211.3799) (xy 263.770083 -211.372186) (xy 263.777476 -211.365338)
			(xy 264.675366 -210.467448) (xy 264.682766 -210.460607) (xy 264.701365 -210.452889) (xy 264.711434 -210.452462)
			(xy 267.748258 -210.452462) (xy 267.758323 -210.452028) (xy 267.776908 -210.444294) (xy 267.784326 -210.437476)
			(xy 268.021054 -210.200748) (xy 268.027897 -210.193349) (xy 268.03562 -210.17475) (xy 268.03604 -210.16468)
			(xy 268.03604 -207.292702) (xy 268.035616 -207.282633) (xy 268.027895 -207.264034) (xy 268.021054 -207.256634)
			(xy 267.937488 -207.173068) (xy 267.930092 -207.166216) (xy 267.911493 -207.158475) (xy 267.90142 -207.158082)
			(xy 263.70407 -207.158082) (xy 263.694002 -207.15851) (xy 263.675404 -207.16623) (xy 263.668002 -207.173068)
			(xy 262.878824 -207.962246) (xy 262.871424 -207.969087) (xy 262.852825 -207.976802) (xy 262.842756 -207.977232)
			(xy 260.476238 -207.977232) (xy 260.466173 -207.977667) (xy 260.447588 -207.985401) (xy 260.44017 -207.992218)
			(xy 259.108194 -209.324194) (xy 259.100795 -209.33104) (xy 259.082197 -209.338773) (xy 259.072126 -209.33918)
			(xy 258.692142 -209.33918) (xy 258.682114 -209.339592) (xy 258.663579 -209.347254) (xy 258.649389 -209.361427)
			(xy 258.641704 -209.379952) (xy 258.641342 -209.38998) (xy 258.641342 -210.209384) (xy 260.726936 -210.209384)
			(xy 260.726936 -208.659984) (xy 260.727409 -208.635553) (xy 260.735892 -208.587433) (xy 260.752598 -208.541516)
			(xy 260.77702 -208.499195) (xy 260.808417 -208.461755) (xy 260.845835 -208.430332) (xy 260.888139 -208.405881)
			(xy 260.934045 -208.389143) (xy 260.982159 -208.380626) (xy 261.00659 -208.380076) (xy 262.55599 -208.380076)
			(xy 262.580428 -208.380558) (xy 262.628561 -208.389049) (xy 262.674487 -208.405775) (xy 262.716807 -208.430226)
			(xy 262.754235 -208.461659) (xy 262.785631 -208.499118) (xy 262.810041 -208.541462) (xy 262.826722 -208.587404)
			(xy 262.835166 -208.635545) (xy 262.835644 -208.659984) (xy 262.835644 -209.079084) (xy 266.711682 -209.079084)
			(xy 266.715753 -209.023462) (xy 266.727879 -208.969025) (xy 266.747802 -208.916934) (xy 266.775098 -208.868299)
			(xy 266.809184 -208.824156) (xy 266.849333 -208.785447) (xy 266.894691 -208.752996) (xy 266.944291 -208.727495)
			(xy 266.997075 -208.709488) (xy 267.051918 -208.699358) (xy 267.107652 -208.697321) (xy 267.163089 -208.703421)
			(xy 267.217046 -208.717527) (xy 267.268375 -208.739339) (xy 267.315981 -208.768393) (xy 267.358849 -208.804068)
			(xy 267.396066 -208.845605) (xy 267.426839 -208.892118) (xy 267.450511 -208.942615) (xy 267.466579 -208.996022)
			(xy 267.474699 -209.051198) (xy 267.475208 -209.079084) (xy 267.474699 -209.10697) (xy 267.466579 -209.162146)
			(xy 267.450511 -209.215553) (xy 267.426839 -209.26605) (xy 267.396066 -209.312563) (xy 267.358849 -209.3541)
			(xy 267.315981 -209.389775) (xy 267.268375 -209.418829) (xy 267.217046 -209.440641) (xy 267.163089 -209.454747)
			(xy 267.107652 -209.460847) (xy 267.051918 -209.45881) (xy 266.997075 -209.44868) (xy 266.944291 -209.430673)
			(xy 266.894691 -209.405172) (xy 266.849333 -209.372721) (xy 266.809184 -209.334012) (xy 266.775098 -209.289869)
			(xy 266.747802 -209.241234) (xy 266.727879 -209.189143) (xy 266.715753 -209.134706) (xy 266.711682 -209.079084)
			(xy 262.835644 -209.079084) (xy 262.835644 -210.209384) (xy 262.835062 -210.23381) (xy 262.826587 -210.28192)
			(xy 262.809892 -210.32783) (xy 262.785482 -210.370146) (xy 262.7541 -210.407583) (xy 262.716697 -210.439007)
			(xy 262.674408 -210.463462) (xy 262.628516 -210.480208) (xy 262.580415 -210.488735) (xy 262.55599 -210.489292)
			(xy 261.00659 -210.489292) (xy 260.982155 -210.488761) (xy 260.934028 -210.480269) (xy 260.888109 -210.463545)
			(xy 260.845793 -210.439098) (xy 260.808368 -210.407672) (xy 260.776972 -210.370221) (xy 260.752559 -210.327886)
			(xy 260.735872 -210.281953) (xy 260.727419 -210.233819) (xy 260.726936 -210.209384) (xy 258.641342 -210.209384)
			(xy 258.641342 -210.306412) (xy 258.641769 -210.31648) (xy 258.649491 -210.335078) (xy 258.656328 -210.34248)
			(xy 259.046726 -210.732878) (xy 259.054125 -210.739723) (xy 259.072723 -210.747451) (xy 259.082794 -210.747864)
			(xy 259.852414 -210.747864) (xy 259.862482 -210.748291) (xy 259.881076 -210.756016) (xy 259.888482 -210.76285)
			(xy 260.49097 -211.365338) (xy 260.498369 -211.37218) (xy 260.516968 -211.379899) (xy 260.527038 -211.380324)
		)
		(stroke
			(width 0)
			(type solid)
		)
		(fill yes)
		(layer "F.Cu")
		(net "P3V3_AUX_JTAG")
	)
	(gr_poly
		(pts
			(xy 416.458146 -13.816076) (xy 416.458146 -13.40739) (xy 416.40887 -13.358114)
			(arc
				(start 409.26512 -13.358114)
				(mid 408.198804 -12.916432)
				(end 407.757122 -11.850116)
			)
			(arc
				(start 407.757122 -1.999996)
				(mid 407.320126 -0.944996)
				(end 406.265126 -0.508)
			)
			(arc
				(start 394.264896 -0.508)
				(mid 393.209896 -0.944996)
				(end 392.7729 -1.999996)
			)
			(arc
				(start 392.7729 -11.850116)
				(mid 392.702216 -12.306469)
				(end 392.496802 -12.720066)
			)
			(xy 392.496802 -12.748514) (xy 392.499088 -12.7508)
			(arc
				(start 393.067794 -12.7508)
				(mid 393.226496 -12.312827)
				(end 393.280392 -11.850116)
			)
			(arc
				(start 393.280392 -1.999996)
				(mid 393.568747 -1.303847)
				(end 394.264896 -1.015492)
			)
			(arc
				(start 406.265126 -1.015492)
				(mid 406.961365 -1.303831)
				(end 407.249884 -1.999996)
			)
			(arc
				(start 407.249884 -11.850116)
				(mid 407.840133 -13.275103)
				(end 409.26512 -13.865352)
			)
			(xy 416.40887 -13.865352)
		)
		(stroke
			(width 0)
			(type solid)
		)
		(fill yes)
		(layer "F.Cu")
		(net "GND")
	)
	(gr_poly
		(pts
			(xy 364.096808 -13.358114)
			(arc
				(start 357.26497 -13.358114)
				(mid 356.198654 -12.916432)
				(end 355.756972 -11.850116)
			)
			(arc
				(start 355.756972 -1.999996)
				(mid 355.319976 -0.944996)
				(end 354.264976 -0.508)
			)
			(arc
				(start 330.164948 -0.508)
				(mid 329.109948 -0.944996)
				(end 328.672952 -1.999996)
			)
			(arc
				(start 328.672952 -11.850116)
				(mid 328.570197 -12.397292)
				(end 328.27595 -12.869926)
			)
			(xy 328.27595 -12.876784) (xy 328.28738 -12.888214) (xy 328.885042 -12.888214)
			(arc
				(start 328.90333 -12.869926)
				(mid 329.10994 -12.378512)
				(end 329.180444 -11.850116)
			)
			(arc
				(start 329.180444 -1.999996)
				(mid 329.468799 -1.303847)
				(end 330.164948 -1.015492)
			)
			(arc
				(start 354.264976 -1.015492)
				(mid 354.961125 -1.303847)
				(end 355.24948 -1.999996)
			)
			(arc
				(start 355.24948 -11.850116)
				(mid 355.839893 -13.275118)
				(end 357.26497 -13.865352)
			)
			(xy 364.096808 -13.865352)
		)
		(stroke
			(width 0)
			(type solid)
		)
		(fill yes)
		(layer "F.Cu")
		(net "GND")
	)
	(gr_poly
		(pts
			(xy 390.499092 -13.810996) (xy 390.499092 -13.41247) (xy 390.444736 -13.358114)
			(arc
				(start 383.264918 -13.358114)
				(mid 382.198602 -12.916432)
				(end 381.75692 -11.850116)
			)
			(arc
				(start 381.75692 -1.999996)
				(mid 381.319924 -0.944996)
				(end 380.264924 -0.508)
			)
			(arc
				(start 368.264948 -0.508)
				(mid 367.209948 -0.944996)
				(end 366.772952 -1.999996)
			)
			(arc
				(start 366.772952 -11.850116)
				(mid 366.670132 -12.397459)
				(end 366.375696 -12.87018)
			)
			(xy 366.375696 -12.899644) (xy 366.434878 -12.958826) (xy 366.914684 -12.958826)
			(arc
				(start 367.00333 -12.87018)
				(mid 367.209881 -12.378884)
				(end 367.280444 -11.850624)
			)
			(arc
				(start 367.280444 -1.999996)
				(mid 367.568799 -1.303847)
				(end 368.264948 -1.015492)
			)
			(arc
				(start 380.264924 -1.015492)
				(mid 380.961073 -1.303847)
				(end 381.249428 -1.999996)
			)
			(arc
				(start 381.249428 -11.850116)
				(mid 381.839841 -13.275118)
				(end 383.264918 -13.865352)
			)
			(xy 390.444736 -13.865352)
		)
		(stroke
			(width 0)
			(type solid)
		)
		(fill yes)
		(layer "F.Cu")
		(net "GND")
	)
	(gr_poly
		(pts
			(xy 326.45985 -13.852906) (xy 326.45985 -13.37945) (xy 326.438514 -13.358114)
			(arc
				(start 319.16497 -13.358114)
				(mid 318.098654 -12.916432)
				(end 317.656972 -11.850116)
			)
			(arc
				(start 317.656972 -1.999996)
				(mid 317.219976 -0.944996)
				(end 316.164976 -0.508)
			)
			(arc
				(start 304.165 -0.508)
				(mid 303.11 -0.944996)
				(end 302.673004 -1.999996)
			)
			(arc
				(start 302.673004 -11.850116)
				(mid 302.577528 -12.378214)
				(end 302.30318 -12.839446)
			)
			(xy 302.30318 -12.884912) (xy 302.304196 -12.885928) (xy 302.874426 -12.885928)
			(arc
				(start 302.920908 -12.839446)
				(mid 303.114524 -12.361527)
				(end 303.180496 -11.850116)
			)
			(arc
				(start 303.180496 -1.999996)
				(mid 303.468851 -1.303847)
				(end 304.165 -1.015492)
			)
			(arc
				(start 316.164976 -1.015492)
				(mid 316.861125 -1.303847)
				(end 317.14948 -1.999996)
			)
			(arc
				(start 317.14948 -11.850116)
				(mid 317.739893 -13.275118)
				(end 319.16497 -13.865352)
			)
			(xy 326.438514 -13.865352) (xy 326.447404 -13.865352)
		)
		(stroke
			(width 0)
			(type solid)
		)
		(fill yes)
		(layer "F.Cu")
		(net "GND")
	)
	(gr_poly
		(pts
			(arc
				(start 459.449424 -293.690802)
				(mid 459.468947 -293.686901)
				(end 459.485492 -293.675816)
			)
			(arc
				(start 460.000858 -293.16045)
				(mid 460.011969 -293.143916)
				(end 460.015844 -293.124382)
			)
			(arc
				(start 460.015844 -282.073858)
				(mid 460.011943 -282.054335)
				(end 460.000858 -282.03779)
			)
			(arc
				(start 459.076552 -281.113484)
				(mid 459.060018 -281.102373)
				(end 459.040484 -281.098498)
			)
			(arc
				(start 459.038198 -281.098498)
				(mid 459.018675 -281.094597)
				(end 459.00213 -281.083512)
			)
			(arc
				(start 458.789278 -280.87066)
				(mid 458.772744 -280.859549)
				(end 458.75321 -280.855674)
			)
			(arc
				(start 455.154284 -280.855674)
				(mid 455.134761 -280.851773)
				(end 455.118216 -280.840688)
			)
			(arc
				(start 454.756774 -280.479246)
				(mid 454.745663 -280.462712)
				(end 454.741788 -280.443178)
			)
			(arc
				(start 454.741788 -279.042368)
				(mid 454.745689 -279.022845)
				(end 454.756774 -279.0063)
			)
			(arc
				(start 455.067924 -278.69515)
				(mid 455.084458 -278.684039)
				(end 455.103992 -278.680164)
			)
			(arc
				(start 456.186794 -278.680164)
				(mid 456.206317 -278.676263)
				(end 456.222862 -278.665178)
			)
			(arc
				(start 456.495404 -278.392636)
				(mid 456.506515 -278.376102)
				(end 456.51039 -278.356568)
			)
			(arc
				(start 456.51039 -278.149812)
				(mid 456.514291 -278.130289)
				(end 456.525376 -278.113744)
			)
			(arc
				(start 456.748134 -277.890986)
				(mid 456.764668 -277.879875)
				(end 456.784202 -277.876)
			)
			(arc
				(start 457.103226 -277.876)
				(mid 457.113194 -277.875063)
				(end 457.122784 -277.87219)
			)
			(arc
				(start 457.265786 -277.813008)
				(mid 457.292879 -277.802961)
				(end 457.32065 -277.794974)
			)
			(xy 457.320904 -277.794974) (xy 457.32573 -277.793704) (xy 457.332842 -277.79218) (xy 457.345288 -277.785068)
			(xy 457.352654 -277.777702)
			(arc
				(start 457.893928 -277.777702)
				(mid 457.913451 -277.773801)
				(end 457.929996 -277.762716)
			)
			(arc
				(start 457.945236 -277.747476)
				(mid 457.956347 -277.730942)
				(end 457.960222 -277.711408)
			)
			(arc
				(start 457.960222 -277.647908)
				(mid 457.956321 -277.628385)
				(end 457.945236 -277.61184)
			)
			(xy 457.895706 -277.56231) (xy 457.888594 -277.554944) (xy 457.869798 -277.547324)
			(arc
				(start 457.20508 -277.547324)
				(mid 457.190933 -277.545314)
				(end 457.177902 -277.53945)
			)
			(xy 457.171806 -277.53564) (xy 457.15809 -277.531576)
			(arc
				(start 457.129134 -277.531576)
				(mid 457.109777 -277.527743)
				(end 457.09332 -277.516844)
			)
			(xy 456.964288 -277.388066)
			(arc
				(start 456.708256 -277.132034)
				(mid 456.691722 -277.120923)
				(end 456.672188 -277.117048)
			)
			(arc
				(start 455.053954 -277.117048)
				(mid 455.034431 -277.120949)
				(end 455.017886 -277.132034)
			)
			(arc
				(start 454.061322 -278.088598)
				(mid 454.044788 -278.099709)
				(end 454.025254 -278.103584)
			)
			(arc
				(start 448.676522 -278.103584)
				(mid 448.656999 -278.107485)
				(end 448.640454 -278.11857)
			)
			(arc
				(start 448.397376 -278.361648)
				(mid 448.385128 -278.381678)
				(end 448.383152 -278.405082)
			)
			(xy 448.397376 -278.498046) (xy 448.411346 -278.517604)
			(arc
				(start 448.422014 -278.523446)
				(mid 448.571404 -278.663819)
				(end 448.626484 -278.861266)
			)
			(arc
				(start 448.626484 -278.861266)
				(mid 448.514743 -279.131033)
				(end 448.244976 -279.242774)
			)
			(xy 448.21348 -279.241504) (xy 448.202558 -279.240488) (xy 448.182746 -279.247346)
			(arc
				(start 448.120008 -279.305258)
				(mid 448.1078 -279.322188)
				(end 448.103498 -279.342596)
			)
			(arc
				(start 448.103498 -279.40889)
				(mid 448.107874 -279.429265)
				(end 448.120008 -279.446228)
			)
			(xy 448.182746 -279.50414) (xy 448.202558 -279.510998) (xy 448.21348 -279.509982)
			(arc
				(start 448.244976 -279.508712)
				(mid 448.626484 -279.89022)
				(end 448.244976 -280.271728)
			)
			(xy 448.21348 -280.270458) (xy 448.202558 -280.269442) (xy 448.182746 -280.2763)
			(arc
				(start 448.120008 -280.334212)
				(mid 448.1078 -280.351142)
				(end 448.103498 -280.37155)
			)
			(arc
				(start 448.103498 -283.707332)
				(mid 448.107399 -283.726855)
				(end 448.118484 -283.7434)
			)
			(arc
				(start 448.394074 -284.01899)
				(mid 448.410608 -284.030101)
				(end 448.430142 -284.033976)
			)
			(arc
				(start 451.003162 -284.033976)
				(mid 451.022685 -284.037877)
				(end 451.03923 -284.048962)
			)
			(arc
				(start 452.214234 -285.223966)
				(mid 452.225345 -285.2405)
				(end 452.22922 -285.260034)
			)
			(arc
				(start 452.22922 -293.469568)
				(mid 452.233121 -293.489091)
				(end 452.244206 -293.505636)
			)
			(arc
				(start 452.414386 -293.675816)
				(mid 452.43092 -293.686927)
				(end 452.450454 -293.690802)
			)
		)
		(stroke
			(width 0)
			(type solid)
		)
		(fill yes)
		(layer "F.Cu")
		(net "P1V25_PEX3_R")
	)
	(gr_poly
		(pts
			(xy 464.101942 -398.100042) (xy 464.101441 -398.029227) (xy 464.093428 -397.887824) (xy 464.077428 -397.7471)
			(xy 464.053493 -397.607507) (xy 464.021698 -397.469492) (xy 463.982146 -397.333496) (xy 463.934963 -397.199957)
			(xy 463.880301 -397.0693) (xy 463.818335 -396.941945) (xy 463.749262 -396.8183) (xy 463.673305 -396.698761)
			(xy 463.590707 -396.58371) (xy 463.501732 -396.473517) (xy 463.406666 -396.368533) (xy 463.305812 -396.269097)
			(xy 463.199494 -396.175525) (xy 463.088053 -396.088119) (xy 462.971845 -396.007157) (xy 462.851243 -395.932899)
			(xy 462.726632 -395.865583) (xy 462.598413 -395.805425) (xy 462.466996 -395.752618) (xy 462.332802 -395.707329)
			(xy 462.196261 -395.669706) (xy 462.057809 -395.639867) (xy 461.917892 -395.617909) (xy 461.776956 -395.603903)
			(xy 461.635453 -395.597892) (xy 461.493837 -395.599896) (xy 461.352561 -395.609909) (xy 461.212078 -395.627898)
			(xy 461.072838 -395.653807) (xy 460.935287 -395.687551) (xy 460.799864 -395.729024) (xy 460.667006 -395.778092)
			(xy 460.537136 -395.834597) (xy 460.41067 -395.89836) (xy 460.288015 -395.969175) (xy 460.169562 -396.046816)
			(xy 460.055692 -396.131034) (xy 459.946769 -396.221559) (xy 459.843142 -396.318102) (xy 459.745142 -396.420352)
			(xy 459.653085 -396.527984) (xy 459.567264 -396.640651) (xy 459.487954 -396.757993) (xy 459.415411 -396.879634)
			(xy 459.349865 -397.005184) (xy 459.291527 -397.134241) (xy 459.240585 -397.266393) (xy 459.1972 -397.401214)
			(xy 459.161512 -397.538274) (xy 459.133636 -397.677134) (xy 459.11366 -397.817349) (xy 459.101649 -397.958469)
			(xy 459.097641 -398.100042) (xy 459.539604 -398.100042) (xy 459.543589 -397.971945) (xy 459.555531 -397.844344)
			(xy 459.575383 -397.717732) (xy 459.603067 -397.592599) (xy 459.638478 -397.46943) (xy 459.681477 -397.3487)
			(xy 459.731899 -397.230877) (xy 459.789548 -397.116416) (xy 459.854202 -397.005761) (xy 459.92561 -396.89934)
			(xy 460.003497 -396.797564) (xy 460.08756 -396.700827) (xy 460.177474 -396.609503) (xy 460.272892 -396.523946)
			(xy 460.373445 -396.444486) (xy 460.478743 -396.371431) (xy 460.588379 -396.305064) (xy 460.701929 -396.245642)
			(xy 460.818954 -396.193394) (xy 460.939 -396.148522) (xy 461.061604 -396.1112) (xy 461.186291 -396.081573)
			(xy 461.312579 -396.059755) (xy 461.439979 -396.04583) (xy 461.567998 -396.039853) (xy 461.696142 -396.041846)
			(xy 461.823913 -396.051802) (xy 461.950818 -396.069682) (xy 462.076367 -396.095417) (xy 462.200072 -396.128908)
			(xy 462.321456 -396.170024) (xy 462.440049 -396.218608) (xy 462.555392 -396.27447) (xy 462.667039 -396.337395)
			(xy 462.774558 -396.40714) (xy 462.877534 -396.483434) (xy 462.975566 -396.565982) (xy 463.068277 -396.654465)
			(xy 463.155308 -396.748541) (xy 463.236322 -396.847846) (xy 463.311005 -396.951995) (xy 463.379069 -397.060586)
			(xy 463.440251 -397.173198) (xy 463.494312 -397.289396) (xy 463.541046 -397.408731) (xy 463.58027 -397.530739)
			(xy 463.611832 -397.654951) (xy 463.635612 -397.780884) (xy 463.651516 -397.908052) (xy 463.659484 -398.035963)
			(xy 463.659982 -398.100042) (xy 463.659484 -398.164121) (xy 463.651516 -398.292032) (xy 463.635612 -398.4192)
			(xy 463.611832 -398.545133) (xy 463.58027 -398.669345) (xy 463.541046 -398.791353) (xy 463.494312 -398.910688)
			(xy 463.440251 -399.026886) (xy 463.379069 -399.139498) (xy 463.311005 -399.248089) (xy 463.236322 -399.352238)
			(xy 463.155308 -399.451543) (xy 463.068277 -399.545619) (xy 462.975566 -399.634102) (xy 462.877534 -399.71665)
			(xy 462.774558 -399.792944) (xy 462.667039 -399.862689) (xy 462.555392 -399.925614) (xy 462.440049 -399.981476)
			(xy 462.321456 -400.03006) (xy 462.200072 -400.071176) (xy 462.076367 -400.104667) (xy 461.950818 -400.130402)
			(xy 461.823913 -400.148282) (xy 461.696142 -400.158238) (xy 461.567998 -400.160231) (xy 461.439979 -400.154254)
			(xy 461.312579 -400.140329) (xy 461.186291 -400.118511) (xy 461.061604 -400.088884) (xy 460.939 -400.051562)
			(xy 460.818954 -400.00669) (xy 460.701929 -399.954442) (xy 460.588379 -399.89502) (xy 460.478743 -399.828653)
			(xy 460.373445 -399.755598) (xy 460.272892 -399.676138) (xy 460.177474 -399.590581) (xy 460.08756 -399.499257)
			(xy 460.003497 -399.40252) (xy 459.92561 -399.300744) (xy 459.854202 -399.194323) (xy 459.789548 -399.083668)
			(xy 459.731899 -398.969207) (xy 459.681477 -398.851384) (xy 459.638478 -398.730654) (xy 459.603067 -398.607485)
			(xy 459.575383 -398.482352) (xy 459.555531 -398.35574) (xy 459.543589 -398.228139) (xy 459.539604 -398.100042)
			(xy 459.097641 -398.100042) (xy 459.101649 -398.241615) (xy 459.11366 -398.382735) (xy 459.133636 -398.52295)
			(xy 459.161512 -398.66181) (xy 459.1972 -398.79887) (xy 459.240585 -398.933691) (xy 459.291527 -399.065843)
			(xy 459.349865 -399.1949) (xy 459.415411 -399.32045) (xy 459.487954 -399.442091) (xy 459.567264 -399.559433)
			(xy 459.653085 -399.6721) (xy 459.745142 -399.779732) (xy 459.843142 -399.881982) (xy 459.946769 -399.978525)
			(xy 460.055692 -400.06905) (xy 460.169562 -400.153268) (xy 460.288015 -400.230909) (xy 460.41067 -400.301724)
			(xy 460.537136 -400.365487) (xy 460.667006 -400.421992) (xy 460.799864 -400.47106) (xy 460.935287 -400.512533)
			(xy 461.072838 -400.546277) (xy 461.212078 -400.572186) (xy 461.352561 -400.590175) (xy 461.493837 -400.600188)
			(xy 461.635453 -400.602192) (xy 461.776956 -400.596181) (xy 461.917892 -400.582175) (xy 462.057809 -400.560217)
			(xy 462.196261 -400.530378) (xy 462.332802 -400.492755) (xy 462.466996 -400.447466) (xy 462.598413 -400.394659)
			(xy 462.726632 -400.334501) (xy 462.851243 -400.267185) (xy 462.971845 -400.192927) (xy 463.088053 -400.111965)
			(xy 463.199494 -400.024559) (xy 463.305812 -399.930987) (xy 463.406666 -399.831551) (xy 463.501732 -399.726567)
			(xy 463.590707 -399.616374) (xy 463.673305 -399.501323) (xy 463.749262 -399.381784) (xy 463.818335 -399.258139)
			(xy 463.880301 -399.130784) (xy 463.934963 -399.000127) (xy 463.982146 -398.866588) (xy 464.021698 -398.730592)
			(xy 464.053493 -398.592577) (xy 464.077428 -398.452984) (xy 464.093428 -398.31226) (xy 464.101441 -398.170857)
		)
		(stroke
			(width 0)
			(type solid)
		)
		(fill yes)
		(layer "F.Cu")
		(net "Net_19")
	)
	(gr_poly
		(pts
			(arc
				(start 277.068026 -140.872464)
				(mid 277.087549 -140.868563)
				(end 277.104094 -140.857478)
			)
			(arc
				(start 277.603966 -140.357606)
				(mid 277.6205 -140.346495)
				(end 277.640034 -140.34262)
			)
			(arc
				(start 277.843488 -140.34262)
				(mid 277.860919 -140.339536)
				(end 277.876254 -140.330682)
			)
			(arc
				(start 277.876254 -140.330682)
				(mid 278.047429 -140.23141)
				(end 278.242268 -140.196824)
			)
			(arc
				(start 278.846026 -140.196824)
				(mid 278.881947 -140.181945)
				(end 278.896826 -140.146024)
			)
			(arc
				(start 278.896826 -140.048742)
				(mid 278.892925 -140.029219)
				(end 278.88184 -140.012674)
			)
			(arc
				(start 278.86025 -139.991084)
				(mid 278.843716 -139.979973)
				(end 278.824182 -139.976098)
			)
			(arc
				(start 277.523702 -139.976098)
				(mid 277.504179 -139.972197)
				(end 277.487634 -139.961112)
			)
			(arc
				(start 276.950678 -139.424156)
				(mid 276.934144 -139.413045)
				(end 276.91461 -139.40917)
			)
			(arc
				(start 276.566884 -139.40917)
				(mid 276.547361 -139.405269)
				(end 276.530816 -139.394184)
			)
			(arc
				(start 274.57273 -137.436098)
				(mid 274.556196 -137.424987)
				(end 274.536662 -137.421112)
			)
			(xy 271.830292 -137.421112)
			(arc
				(start 271.827244 -137.421366)
				(mid 271.787308 -137.424926)
				(end 271.747234 -137.426192)
			)
			(arc
				(start 271.747234 -137.426192)
				(mid 271.707159 -137.424936)
				(end 271.667224 -137.421366)
			)
			(xy 271.664176 -137.421112) (xy 271.296892 -137.421112)
			(arc
				(start 271.293844 -137.421366)
				(mid 271.253908 -137.424926)
				(end 271.213834 -137.426192)
			)
			(arc
				(start 271.213834 -137.426192)
				(mid 271.173759 -137.424936)
				(end 271.133824 -137.421366)
			)
			(xy 271.130776 -137.421112)
			(arc
				(start 266.960858 -137.421112)
				(mid 266.941335 -137.417211)
				(end 266.92479 -137.406126)
			)
			(arc
				(start 263.479534 -133.96087)
				(mid 263.468423 -133.944336)
				(end 263.464548 -133.924802)
			)
			(arc
				(start 263.464548 -120.604534)
				(mid 263.460647 -120.585011)
				(end 263.449562 -120.568466)
			)
			(arc
				(start 258.204716 -115.32362)
				(mid 258.188182 -115.312509)
				(end 258.168648 -115.308634)
			)
			(xy 252.16993 -115.308634)
			(arc
				(start 252.164342 -115.303046)
				(mid 252.147808 -115.291935)
				(end 252.128274 -115.28806)
			)
			(arc
				(start 251.19838 -115.28806)
				(mid 251.178857 -115.291961)
				(end 251.162312 -115.303046)
			)
			(xy 251.156724 -115.308634) (xy 250.598178 -115.308634) (xy 250.598178 -115.314222)
			(arc
				(start 248.485406 -115.314222)
				(mid 248.449485 -115.329101)
				(end 248.434606 -115.365022)
			)
			(xy 248.434606 -116.058696) (xy 248.442226 -116.077238) (xy 248.44375 -116.078762)
			(arc
				(start 249.14098 -116.078762)
				(mid 249.160503 -116.082663)
				(end 249.177048 -116.093748)
			)
			(arc
				(start 249.89663 -116.81333)
				(mid 249.907741 -116.829864)
				(end 249.911616 -116.849398)
			)
			(arc
				(start 249.911616 -118.169182)
				(mid 249.915517 -118.188705)
				(end 249.926602 -118.20525)
			)
			(xy 250.598178 -118.876826) (xy 250.598178 -118.87835)
			(arc
				(start 250.757436 -119.037608)
				(mid 250.77397 -119.048719)
				(end 250.793504 -119.052594)
			)
			(arc
				(start 253.82474 -119.052594)
				(mid 253.844263 -119.056495)
				(end 253.860808 -119.06758)
			)
			(arc
				(start 254.668528 -119.8753)
				(mid 254.679639 -119.891834)
				(end 254.683514 -119.911368)
			)
			(arc
				(start 254.683514 -123.902978)
				(mid 254.679613 -123.922501)
				(end 254.668528 -123.939046)
			)
			(arc
				(start 254.357378 -124.250196)
				(mid 254.340844 -124.261307)
				(end 254.32131 -124.265182)
			)
			(arc
				(start 248.167144 -124.265182)
				(mid 248.147621 -124.261281)
				(end 248.131076 -124.250196)
			)
			(arc
				(start 247.647968 -123.767088)
				(mid 247.631434 -123.755977)
				(end 247.6119 -123.752102)
			)
			(arc
				(start 247.222264 -123.752102)
				(mid 247.186343 -123.766981)
				(end 247.171464 -123.802902)
			)
			(arc
				(start 247.171464 -125.918976)
				(mid 247.176198 -125.940391)
				(end 247.189498 -125.957838)
			)
			(xy 247.257824 -126.015242) (xy 247.27916 -126.021084)
			(arc
				(start 247.290336 -126.019052)
				(mid 247.323108 -126.014833)
				(end 247.356122 -126.013464)
			)
			(arc
				(start 247.356122 -126.013464)
				(mid 247.419619 -126.018746)
				(end 247.481344 -126.034546)
			)
			(xy 247.50014 -126.04115) (xy 247.51411 -126.037848) (xy 247.52554 -126.036578) (xy 247.598184 -126.036578)
			(xy 247.729502 -126.036578) (xy 247.904 -126.211076) (xy 247.904 -126.342394)
			(arc
				(start 247.904 -127.150368)
				(mid 247.907901 -127.169891)
				(end 247.918986 -127.186436)
			)
			(arc
				(start 248.137172 -127.404622)
				(mid 248.153706 -127.415733)
				(end 248.17324 -127.419608)
			)
			(arc
				(start 252.676914 -127.419608)
				(mid 252.696437 -127.423509)
				(end 252.712982 -127.434594)
			)
			(arc
				(start 253.62408 -128.345692)
				(mid 253.635191 -128.362226)
				(end 253.639066 -128.38176)
			)
			(arc
				(start 253.639066 -134.193534)
				(mid 253.642967 -134.213057)
				(end 253.654052 -134.229602)
			)
			(arc
				(start 259.405882 -139.981432)
				(mid 259.422416 -139.992543)
				(end 259.44195 -139.996418)
			)
			(arc
				(start 272.243804 -139.996418)
				(mid 272.260806 -139.993488)
				(end 272.275808 -139.984988)
			)
			(arc
				(start 272.275808 -139.984988)
				(mid 272.597118 -139.870686)
				(end 272.918428 -139.984988)
			)
			(xy 272.925286 -139.990576) (xy 272.941542 -139.996418)
			(arc
				(start 272.990056 -139.996418)
				(mid 273.009579 -140.000319)
				(end 273.026124 -140.011404)
			)
			(arc
				(start 273.872198 -140.857478)
				(mid 273.888732 -140.868589)
				(end 273.908266 -140.872464)
			)
		)
		(stroke
			(width 0)
			(type solid)
		)
		(fill yes)
		(layer "F.Cu")
		(net "P3V3_NIC4")
	)
	(gr_poly
		(pts
			(xy 19.004788 -22.717252) (xy 19.014858 -22.71683) (xy 19.033461 -22.709113) (xy 19.040856 -22.702266)
			(xy 19.12366 -22.619462) (xy 19.130505 -22.612063) (xy 19.138232 -22.593465) (xy 19.138646 -22.583394)
			(xy 19.138646 -22.179788) (xy 19.134836 -22.166834) (xy 19.13128 -22.160738) (xy 19.06784 -22.055648)
			(xy 18.946656 -21.842135) (xy 18.83208 -21.625004) (xy 18.72422 -21.40446) (xy 18.623177 -21.180711)
			(xy 18.529047 -20.953967) (xy 18.441918 -20.724441) (xy 18.361873 -20.49235) (xy 18.288986 -20.257913)
			(xy 18.223327 -20.02135) (xy 18.164957 -19.782883) (xy 18.113931 -19.542738) (xy 18.070297 -19.30114)
			(xy 18.034096 -19.058317) (xy 18.019268 -18.936462) (xy 18.00479 -18.90649) (xy 17.736312 -18.638012)
			(xy 17.728915 -18.631162) (xy 17.710317 -18.623422) (xy 17.700244 -18.623026) (xy 15.866872 -18.623026)
			(xy 15.856866 -18.622534) (xy 15.838379 -18.61487) (xy 15.824229 -18.600719) (xy 15.816566 -18.582232)
			(xy 15.816072 -18.572226) (xy 15.816072 -14.525752) (xy 15.815639 -14.515686) (xy 15.80791 -14.497097)
			(xy 15.801086 -14.489684) (xy 15.445994 -14.134592) (xy 15.438584 -14.12791) (xy 15.420148 -14.120331)
			(xy 15.41018 -14.11986) (xy 8.96493 -14.11986) (xy 8.905252 -14.119432) (xy 8.786063 -14.113081)
			(xy 8.726678 -14.10716) (xy 8.723884 -14.106906) (xy 8.061198 -14.106906) (xy 8.051128 -14.106483)
			(xy 8.032523 -14.098769) (xy 8.02513 -14.09192) (xy 7.586472 -13.653262) (xy 7.583678 -13.65123)
			(xy 7.524934 -13.605428) (xy 7.412912 -13.507221) (xy 7.307571 -13.40188) (xy 7.209365 -13.289858)
			(xy 7.163562 -13.231114) (xy 7.16153 -13.22832) (xy 6.762242 -12.829032) (xy 6.754842 -12.822191)
			(xy 6.736243 -12.814473) (xy 6.726174 -12.814046) (xy 6.352032 -12.814046) (xy 6.341968 -12.814483)
			(xy 6.323386 -12.82222) (xy 6.315964 -12.829032) (xy 6.257544 -12.887452) (xy 6.250701 -12.894851)
			(xy 6.242979 -12.91345) (xy 6.242558 -12.92352) (xy 6.242558 -14.384274) (xy 6.242996 -14.394337)
			(xy 6.250736 -14.412916) (xy 6.257544 -14.420342) (xy 6.37032 -14.533118) (xy 6.377716 -14.53997)
			(xy 6.396315 -14.54771) (xy 6.406388 -14.548104) (xy 7.007606 -14.548104) (xy 7.017676 -14.548528)
			(xy 7.036278 -14.556245) (xy 7.043674 -14.56309) (xy 7.240524 -14.75994) (xy 7.247372 -14.767337)
			(xy 7.255104 -14.785936) (xy 7.25551 -14.796008) (xy 7.25551 -15.420086) (xy 11.097768 -15.420086)
			(xy 11.098219 -15.376646) (xy 11.106237 -15.290138) (xy 11.122202 -15.204738) (xy 11.145979 -15.121175)
			(xy 11.177365 -15.040163) (xy 11.216092 -14.962393) (xy 11.261829 -14.888527) (xy 11.314187 -14.819197)
			(xy 11.372719 -14.754993) (xy 11.436924 -14.696464) (xy 11.506257 -14.644109) (xy 11.580124 -14.598374)
			(xy 11.657896 -14.559651) (xy 11.738909 -14.528268) (xy 11.822473 -14.504494) (xy 11.907873 -14.488532)
			(xy 11.994382 -14.480518) (xy 12.037822 -14.480032) (xy 13.89253 -14.480032) (xy 13.934227 -14.480489)
			(xy 14.017292 -14.487905) (xy 14.099374 -14.502648) (xy 14.179827 -14.524604) (xy 14.25802 -14.553598)
			(xy 14.333337 -14.589405) (xy 14.405186 -14.631741) (xy 14.473004 -14.680275) (xy 14.504924 -14.707108)
			(xy 14.511288 -14.712171) (xy 14.526308 -14.718385) (xy 14.534388 -14.7193) (xy 15.415768 -14.7193)
			(xy 15.415768 -16.28902) (xy 15.416711 -16.297461) (xy 15.423468 -16.313034) (xy 15.428976 -16.3195)
			(xy 15.458636 -16.35283) (xy 15.512389 -16.424048) (xy 15.559345 -16.49992) (xy 15.599102 -16.579799)
			(xy 15.631323 -16.663005) (xy 15.655732 -16.748828) (xy 15.672121 -16.836536) (xy 15.680351 -16.925382)
			(xy 15.680351 -17.014609) (xy 15.672122 -17.103455) (xy 15.655734 -17.191164) (xy 15.631326 -17.276987)
			(xy 15.599106 -17.360193) (xy 15.559349 -17.440072) (xy 15.512394 -17.515945) (xy 15.458642 -17.587163)
			(xy 15.428976 -17.620488) (xy 15.422372 -17.6276) (xy 15.415768 -17.645126) (xy 15.415768 -17.67078)
			(xy 15.390114 -17.67078) (xy 15.372588 -17.677384) (xy 15.365476 -17.683988) (xy 15.332161 -17.713684)
			(xy 15.260936 -17.767472) (xy 15.185053 -17.814459) (xy 15.105158 -17.854244) (xy 15.021932 -17.886486)
			(xy 14.936087 -17.910912) (xy 14.848354 -17.927313) (xy 14.759481 -17.935548) (xy 14.670229 -17.935548)
			(xy 14.581356 -17.927313) (xy 14.493623 -17.910912) (xy 14.407778 -17.886486) (xy 14.324552 -17.854244)
			(xy 14.244657 -17.814459) (xy 14.168774 -17.767472) (xy 14.097549 -17.713684) (xy 14.064234 -17.683988)
			(xy 14.05776 -17.678493) (xy 14.042191 -17.67174) (xy 14.033754 -17.67078) (xy 11.583924 -17.67078)
			(xy 11.583924 -16.266922) (xy 11.581919 -16.255374) (xy 11.569061 -16.235801) (xy 11.559286 -16.22933)
			(xy 11.521428 -16.206298) (xy 11.449733 -16.154205) (xy 11.383259 -16.095597) (xy 11.322596 -16.030993)
			(xy 11.268281 -15.960967) (xy 11.220797 -15.886141) (xy 11.180566 -15.807178) (xy 11.147944 -15.724779)
			(xy 11.123221 -15.639676) (xy 11.106617 -15.552625) (xy 11.098279 -15.464397) (xy 11.097768 -15.420086)
			(xy 7.25551 -15.420086) (xy 7.25551 -17.548352) (xy 7.255943 -17.558418) (xy 7.263672 -17.577008)
			(xy 7.270496 -17.58442) (xy 7.549896 -17.86382) (xy 7.557291 -17.870676) (xy 7.575889 -17.878424)
			(xy 7.585964 -17.878806) (xy 9.863582 -17.878806) (xy 9.873645 -17.879244) (xy 9.892228 -17.88698)
			(xy 9.89965 -17.893792) (xy 10.163556 -18.157698) (xy 10.170957 -18.164536) (xy 10.189556 -18.17225)
			(xy 10.199624 -18.172684) (xy 12.832334 -18.172684) (xy 12.842402 -18.173113) (xy 12.860999 -18.180834)
			(xy 12.868402 -18.18767) (xy 13.613638 -18.932906) (xy 13.62049 -18.940302) (xy 13.628232 -18.958901)
			(xy 13.628624 -18.968974) (xy 13.628624 -21.490432) (xy 13.629054 -21.500499) (xy 13.636779 -21.519093)
			(xy 13.64361 -21.5265) (xy 14.08557 -21.96846) (xy 14.09297 -21.9753) (xy 14.111569 -21.983015) (xy 14.121638 -21.983446)
			(xy 16.028416 -21.983446) (xy 16.038484 -21.983873) (xy 16.05708 -21.991597) (xy 16.064484 -21.998432)
			(xy 16.276066 -22.210014) (xy 16.282914 -22.217412) (xy 16.290649 -22.23601) (xy 16.291052 -22.246082)
			(xy 16.291052 -22.584918) (xy 16.29148 -22.594986) (xy 16.299205 -22.61358) (xy 16.306038 -22.620986)
			(xy 16.387318 -22.702266) (xy 16.394716 -22.709113) (xy 16.413314 -22.716847) (xy 16.423386 -22.717252)
		)
		(stroke
			(width 0)
			(type solid)
		)
		(fill yes)
		(layer "F.Cu")
		(net "P12V_SSD0")
	)
	(gr_poly
		(pts
			(arc
				(start 44.965112 -140.872464)
				(mid 44.984635 -140.868563)
				(end 45.00118 -140.857478)
			)
			(xy 45.311314 -140.547344)
			(arc
				(start 45.315124 -140.5382)
				(mid 45.342633 -140.497129)
				(end 45.383704 -140.46962)
			)
			(xy 45.392848 -140.46581)
			(arc
				(start 45.501052 -140.357606)
				(mid 45.517586 -140.346495)
				(end 45.53712 -140.34262)
			)
			(xy 45.65269 -140.34262) (xy 45.6692 -140.336524)
			(arc
				(start 45.676312 -140.330682)
				(mid 45.847487 -140.23141)
				(end 46.042326 -140.196824)
			)
			(arc
				(start 46.646084 -140.196824)
				(mid 46.682005 -140.181945)
				(end 46.696884 -140.146024)
			)
			(arc
				(start 46.696884 -140.048742)
				(mid 46.692983 -140.029219)
				(end 46.681898 -140.012674)
			)
			(arc
				(start 46.660308 -139.991084)
				(mid 46.643774 -139.979973)
				(end 46.62424 -139.976098)
			)
			(arc
				(start 45.32376 -139.976098)
				(mid 45.304237 -139.972197)
				(end 45.287692 -139.961112)
			)
			(arc
				(start 44.750736 -139.424156)
				(mid 44.734202 -139.413045)
				(end 44.714668 -139.40917)
			)
			(arc
				(start 44.366942 -139.40917)
				(mid 44.347419 -139.405269)
				(end 44.330874 -139.394184)
			)
			(arc
				(start 42.372788 -137.436098)
				(mid 42.356254 -137.424987)
				(end 42.33672 -137.421112)
			)
			(xy 39.63035 -137.421112)
			(arc
				(start 39.627302 -137.421366)
				(mid 39.587366 -137.424926)
				(end 39.547292 -137.426192)
			)
			(arc
				(start 39.547292 -137.426192)
				(mid 39.507217 -137.424936)
				(end 39.467282 -137.421366)
			)
			(xy 39.464234 -137.421112) (xy 39.09695 -137.421112)
			(arc
				(start 39.093902 -137.421366)
				(mid 39.053966 -137.424926)
				(end 39.013892 -137.426192)
			)
			(arc
				(start 39.013892 -137.426192)
				(mid 38.973817 -137.424936)
				(end 38.933882 -137.421366)
			)
			(xy 38.930834 -137.421112)
			(arc
				(start 34.760916 -137.421112)
				(mid 34.741393 -137.417211)
				(end 34.724848 -137.406126)
			)
			(arc
				(start 31.279592 -133.96087)
				(mid 31.268481 -133.944336)
				(end 31.264606 -133.924802)
			)
			(arc
				(start 31.264606 -120.604534)
				(mid 31.260705 -120.585011)
				(end 31.24962 -120.568466)
			)
			(arc
				(start 26.004774 -115.32362)
				(mid 25.98824 -115.312509)
				(end 25.968706 -115.308634)
			)
			(xy 19.969988 -115.308634)
			(arc
				(start 19.9644 -115.303046)
				(mid 19.947866 -115.291935)
				(end 19.928332 -115.28806)
			)
			(arc
				(start 18.998438 -115.28806)
				(mid 18.978915 -115.291961)
				(end 18.96237 -115.303046)
			)
			(xy 18.956782 -115.308634) (xy 18.398236 -115.308634) (xy 18.398236 -115.314222)
			(arc
				(start 16.285464 -115.314222)
				(mid 16.249543 -115.329101)
				(end 16.234664 -115.365022)
			)
			(xy 16.234664 -116.058696) (xy 16.242284 -116.077238) (xy 16.243808 -116.078762)
			(arc
				(start 16.941038 -116.078762)
				(mid 16.960561 -116.082663)
				(end 16.977106 -116.093748)
			)
			(arc
				(start 17.696688 -116.81333)
				(mid 17.707799 -116.829864)
				(end 17.711674 -116.849398)
			)
			(arc
				(start 17.711674 -118.169182)
				(mid 17.715575 -118.188705)
				(end 17.72666 -118.20525)
			)
			(xy 18.398236 -118.876826) (xy 18.398236 -118.87835)
			(arc
				(start 18.557494 -119.037608)
				(mid 18.574028 -119.048719)
				(end 18.593562 -119.052594)
			)
			(arc
				(start 21.624798 -119.052594)
				(mid 21.644321 -119.056495)
				(end 21.660866 -119.06758)
			)
			(arc
				(start 22.468586 -119.8753)
				(mid 22.479697 -119.891834)
				(end 22.483572 -119.911368)
			)
			(arc
				(start 22.483572 -123.902978)
				(mid 22.479671 -123.922501)
				(end 22.468586 -123.939046)
			)
			(arc
				(start 22.157436 -124.250196)
				(mid 22.140902 -124.261307)
				(end 22.121368 -124.265182)
			)
			(arc
				(start 15.967202 -124.265182)
				(mid 15.947679 -124.261281)
				(end 15.931134 -124.250196)
			)
			(arc
				(start 15.448026 -123.767088)
				(mid 15.431492 -123.755977)
				(end 15.411958 -123.752102)
			)
			(arc
				(start 15.022068 -123.752102)
				(mid 14.986147 -123.766981)
				(end 14.971268 -123.802902)
			)
			(arc
				(start 14.971268 -125.918976)
				(mid 14.976131 -125.940414)
				(end 14.989556 -125.957838)
			)
			(xy 15.057882 -126.015242) (xy 15.079218 -126.021084)
			(arc
				(start 15.090394 -126.019052)
				(mid 15.123166 -126.014833)
				(end 15.15618 -126.013464)
			)
			(arc
				(start 15.15618 -126.013464)
				(mid 15.219677 -126.018746)
				(end 15.281402 -126.034546)
			)
			(xy 15.300198 -126.04115) (xy 15.314168 -126.037848) (xy 15.325598 -126.036578) (xy 15.398242 -126.036578)
			(xy 15.608808 -126.036578) (xy 15.704058 -126.131828) (xy 15.704058 -126.342394)
			(arc
				(start 15.704058 -127.150368)
				(mid 15.707959 -127.169891)
				(end 15.719044 -127.186436)
			)
			(arc
				(start 15.93723 -127.404622)
				(mid 15.953764 -127.415733)
				(end 15.973298 -127.419608)
			)
			(arc
				(start 20.476972 -127.419608)
				(mid 20.496495 -127.423509)
				(end 20.51304 -127.434594)
			)
			(arc
				(start 21.424138 -128.345692)
				(mid 21.435249 -128.362226)
				(end 21.439124 -128.38176)
			)
			(arc
				(start 21.439124 -134.193534)
				(mid 21.443025 -134.213057)
				(end 21.45411 -134.229602)
			)
			(arc
				(start 27.20594 -139.981432)
				(mid 27.222474 -139.992543)
				(end 27.242008 -139.996418)
			)
			(arc
				(start 35.737292 -139.996418)
				(mid 35.755227 -139.993147)
				(end 35.77082 -139.983718)
			)
			(arc
				(start 35.77082 -139.983718)
				(mid 35.91192 -139.8984)
				(end 36.074096 -139.868656)
			)
			(arc
				(start 36.074096 -139.868656)
				(mid 36.236257 -139.898441)
				(end 36.377372 -139.983718)
			)
			(arc
				(start 36.377372 -139.983718)
				(mid 36.392982 -139.993102)
				(end 36.4109 -139.996418)
			)
			(arc
				(start 40.043862 -139.996418)
				(mid 40.060864 -139.993488)
				(end 40.075866 -139.984988)
			)
			(arc
				(start 40.075866 -139.984988)
				(mid 40.397176 -139.870686)
				(end 40.718486 -139.984988)
			)
			(xy 40.725344 -139.990576) (xy 40.7416 -139.996418)
			(arc
				(start 40.790114 -139.996418)
				(mid 40.809637 -140.000319)
				(end 40.826182 -140.011404)
			)
			(arc
				(start 41.672256 -140.857478)
				(mid 41.68879 -140.868589)
				(end 41.708324 -140.872464)
			)
		)
		(stroke
			(width 0)
			(type solid)
		)
		(fill yes)
		(layer "F.Cu")
		(net "P3V3_NIC0")
	)
	(gr_poly
		(pts
			(arc
				(start 161.064956 -140.872464)
				(mid 161.084147 -140.868699)
				(end 161.100516 -140.857986)
			)
			(xy 161.10077 -140.857732) (xy 161.411158 -140.547344)
			(arc
				(start 161.414968 -140.5382)
				(mid 161.442477 -140.497129)
				(end 161.483548 -140.46962)
			)
			(xy 161.492692 -140.46581) (xy 161.57448 -140.384022) (xy 161.617406 -140.341096) (xy 162.760914 -140.341096)
			(xy 162.796728 -140.305282) (xy 162.796728 -140.146024)
			(arc
				(start 162.796728 -140.048742)
				(mid 162.792827 -140.029219)
				(end 162.781742 -140.012674)
			)
			(xy 162.760152 -139.991084) (xy 162.75304 -139.983718) (xy 162.734244 -139.976098)
			(arc
				(start 161.423604 -139.976098)
				(mid 161.404081 -139.972197)
				(end 161.387536 -139.961112)
			)
			(xy 160.85058 -139.424156) (xy 160.843468 -139.41679) (xy 160.824672 -139.40917)
			(arc
				(start 160.466786 -139.40917)
				(mid 160.447263 -139.405269)
				(end 160.430718 -139.394184)
			)
			(xy 158.472632 -137.436098) (xy 158.46552 -137.428732) (xy 158.446724 -137.421112) (xy 155.730194 -137.421112)
			(xy 155.727146 -137.421366) (xy 155.694888 -137.424414) (xy 155.694634 -137.424414) (xy 155.64739 -137.426192)
			(xy 155.646882 -137.426192) (xy 155.599638 -137.424414) (xy 155.599384 -137.424414) (xy 155.567126 -137.421366)
			(xy 155.564078 -137.421112) (xy 155.196794 -137.421112) (xy 155.193746 -137.421366) (xy 155.161488 -137.424414)
			(xy 155.161234 -137.424414) (xy 155.11399 -137.426192) (xy 155.113482 -137.426192) (xy 155.066238 -137.424414)
			(xy 155.065984 -137.424414) (xy 155.033726 -137.421366) (xy 155.030678 -137.421112)
			(arc
				(start 150.86076 -137.421112)
				(mid 150.841237 -137.417211)
				(end 150.824692 -137.406126)
			)
			(arc
				(start 147.379436 -133.96087)
				(mid 147.368325 -133.944336)
				(end 147.36445 -133.924802)
			)
			(arc
				(start 147.36445 -120.604534)
				(mid 147.360549 -120.585011)
				(end 147.349464 -120.568466)
			)
			(arc
				(start 141.342872 -114.56162)
				(mid 141.326338 -114.550509)
				(end 141.306804 -114.546634)
			)
			(xy 135.561832 -114.546634)
			(arc
				(start 135.556244 -114.541046)
				(mid 135.53971 -114.529935)
				(end 135.520176 -114.52606)
			)
			(arc
				(start 134.590282 -114.52606)
				(mid 134.570759 -114.529961)
				(end 134.554214 -114.541046)
			)
			(xy 134.548626 -114.546634) (xy 133.99008 -114.546634) (xy 133.99008 -114.552222)
			(arc
				(start 131.877308 -114.552222)
				(mid 131.841387 -114.567101)
				(end 131.826508 -114.603022)
			)
			(arc
				(start 131.826508 -115.265962)
				(mid 131.841387 -115.301883)
				(end 131.877308 -115.316762)
			)
			(arc
				(start 132.532882 -115.316762)
				(mid 132.552405 -115.320663)
				(end 132.56895 -115.331748)
			)
			(arc
				(start 133.288532 -116.05133)
				(mid 133.299643 -116.067864)
				(end 133.303518 -116.087398)
			)
			(arc
				(start 133.303518 -117.407182)
				(mid 133.307283 -117.426373)
				(end 133.317996 -117.442742)
			)
			(xy 133.31825 -117.442996)
			(arc
				(start 133.505956 -117.630702)
				(mid 133.517067 -117.647236)
				(end 133.520942 -117.66677)
			)
			(arc
				(start 133.520942 -118.741952)
				(mid 133.524843 -118.761475)
				(end 133.535928 -118.77802)
			)
			(arc
				(start 134.15137 -119.393462)
				(mid 134.167904 -119.404573)
				(end 134.187438 -119.408448)
			)
			(arc
				(start 137.889234 -119.408448)
				(mid 137.908757 -119.412349)
				(end 137.925302 -119.423434)
			)
			(arc
				(start 138.56843 -120.066562)
				(mid 138.579541 -120.083096)
				(end 138.583416 -120.10263)
			)
			(arc
				(start 138.583416 -123.902978)
				(mid 138.579515 -123.922501)
				(end 138.56843 -123.939046)
			)
			(arc
				(start 138.25728 -124.250196)
				(mid 138.240746 -124.261307)
				(end 138.221212 -124.265182)
			)
			(arc
				(start 132.067046 -124.265182)
				(mid 132.047523 -124.261281)
				(end 132.030978 -124.250196)
			)
			(xy 131.54787 -123.767088) (xy 131.540758 -123.759722) (xy 131.521962 -123.752102)
			(arc
				(start 131.121912 -123.752102)
				(mid 131.085991 -123.766981)
				(end 131.071112 -123.802902)
			)
			(arc
				(start 131.071112 -125.918976)
				(mid 131.075975 -125.940414)
				(end 131.0894 -125.957838)
			)
			(xy 131.157726 -126.015242) (xy 131.179062 -126.021084) (xy 131.190238 -126.019052) (xy 131.191 -126.018798)
			(arc
				(start 131.191254 -126.018798)
				(mid 131.223525 -126.014754)
				(end 131.256024 -126.013464)
			)
			(arc
				(start 131.256024 -126.013464)
				(mid 131.321778 -126.019133)
				(end 131.385564 -126.03607)
			)
			(arc
				(start 131.385564 -126.03607)
				(mid 131.399661 -126.038998)
				(end 131.414012 -126.037848)
			)
			(xy 131.425188 -126.036578) (xy 131.498086 -126.036578) (xy 131.752086 -126.036578) (xy 131.803902 -126.088394)
			(xy 131.803902 -126.342394)
			(arc
				(start 131.803902 -127.150368)
				(mid 131.807667 -127.169559)
				(end 131.81838 -127.185928)
			)
			(xy 131.818634 -127.186182) (xy 132.037074 -127.404622)
			(arc
				(start 132.037582 -127.40513)
				(mid 132.053939 -127.415872)
				(end 132.073142 -127.419608)
			)
			(arc
				(start 136.576816 -127.419608)
				(mid 136.596339 -127.423509)
				(end 136.612884 -127.434594)
			)
			(arc
				(start 137.523982 -128.345692)
				(mid 137.535093 -128.362226)
				(end 137.538968 -128.38176)
			)
			(arc
				(start 137.538968 -134.193534)
				(mid 137.542733 -134.212725)
				(end 137.553446 -134.229094)
			)
			(xy 137.5537 -134.229348) (xy 143.305784 -139.981432)
			(arc
				(start 143.306292 -139.98194)
				(mid 143.322649 -139.992682)
				(end 143.341852 -139.996418)
			)
			(arc
				(start 151.827738 -139.996418)
				(mid 151.836904 -139.995584)
				(end 151.845772 -139.993116)
			)
			(xy 151.87041 -139.983718)
			(arc
				(start 151.877268 -139.97813)
				(mid 152.015855 -139.896992)
				(end 152.17394 -139.868656)
			)
			(arc
				(start 152.17394 -139.868656)
				(mid 152.33205 -139.896925)
				(end 152.470612 -139.97813)
			)
			(xy 152.47747 -139.983718)
			(arc
				(start 152.502108 -139.993116)
				(mid 152.510975 -139.99559)
				(end 152.520142 -139.996418)
			)
			(arc
				(start 156.134816 -139.996418)
				(mid 156.143587 -139.995655)
				(end 156.152088 -139.99337)
			)
			(xy 156.174948 -139.985242)
			(arc
				(start 156.181552 -139.980162)
				(mid 156.33002 -139.89864)
				(end 156.49702 -139.870434)
			)
			(arc
				(start 156.49702 -139.870434)
				(mid 156.667696 -139.899932)
				(end 156.818584 -139.984988)
			)
			(xy 156.825696 -139.990576) (xy 156.841698 -139.996418)
			(arc
				(start 156.889958 -139.996418)
				(mid 156.909481 -140.000319)
				(end 156.926026 -140.011404)
			)
			(xy 157.7721 -140.857478)
			(arc
				(start 157.772608 -140.857986)
				(mid 157.788965 -140.868728)
				(end 157.808168 -140.872464)
			)
		)
		(stroke
			(width 0)
			(type solid)
		)
		(fill yes)
		(layer "F.Cu")
		(net "P3V3_NIC2")
	)
	(gr_poly
		(pts
			(arc
				(start 393.265152 -140.872464)
				(mid 393.284343 -140.868699)
				(end 393.300712 -140.857986)
			)
			(xy 393.300966 -140.857732) (xy 393.611354 -140.547344)
			(arc
				(start 393.615164 -140.5382)
				(mid 393.642673 -140.497129)
				(end 393.683744 -140.46962)
			)
			(xy 393.692888 -140.46581) (xy 393.774676 -140.384022) (xy 393.817602 -140.341096) (xy 394.96111 -140.341096)
			(xy 394.996924 -140.305282) (xy 394.996924 -140.146024)
			(arc
				(start 394.996924 -140.048742)
				(mid 394.993023 -140.029219)
				(end 394.981938 -140.012674)
			)
			(xy 394.960348 -139.991084) (xy 394.953236 -139.983718) (xy 394.93444 -139.976098)
			(arc
				(start 393.6238 -139.976098)
				(mid 393.604277 -139.972197)
				(end 393.587732 -139.961112)
			)
			(xy 393.050776 -139.424156) (xy 393.043664 -139.41679) (xy 393.024868 -139.40917)
			(arc
				(start 392.666982 -139.40917)
				(mid 392.647459 -139.405269)
				(end 392.630914 -139.394184)
			)
			(xy 390.672828 -137.436098) (xy 390.665716 -137.428732) (xy 390.64692 -137.421112) (xy 387.93039 -137.421112)
			(xy 387.927342 -137.421366) (xy 387.895084 -137.424414) (xy 387.89483 -137.424414) (xy 387.847586 -137.426192)
			(xy 387.847078 -137.426192) (xy 387.799834 -137.424414) (xy 387.79958 -137.424414) (xy 387.767322 -137.421366)
			(xy 387.764274 -137.421112) (xy 387.39699 -137.421112) (xy 387.393942 -137.421366) (xy 387.361684 -137.424414)
			(xy 387.36143 -137.424414) (xy 387.314186 -137.426192) (xy 387.313678 -137.426192) (xy 387.266434 -137.424414)
			(xy 387.26618 -137.424414) (xy 387.233922 -137.421366) (xy 387.230874 -137.421112)
			(arc
				(start 383.060956 -137.421112)
				(mid 383.041433 -137.417211)
				(end 383.024888 -137.406126)
			)
			(arc
				(start 379.579632 -133.96087)
				(mid 379.568521 -133.944336)
				(end 379.564646 -133.924802)
			)
			(arc
				(start 379.564646 -120.604534)
				(mid 379.560745 -120.585011)
				(end 379.54966 -120.568466)
			)
			(arc
				(start 373.543068 -114.56162)
				(mid 373.526534 -114.550509)
				(end 373.507 -114.546634)
			)
			(xy 367.762028 -114.546634)
			(arc
				(start 367.75644 -114.541046)
				(mid 367.739906 -114.529935)
				(end 367.720372 -114.52606)
			)
			(arc
				(start 366.790478 -114.52606)
				(mid 366.770955 -114.529961)
				(end 366.75441 -114.541046)
			)
			(xy 366.748822 -114.546634) (xy 366.190276 -114.546634) (xy 366.190276 -114.552222)
			(arc
				(start 364.077504 -114.552222)
				(mid 364.041583 -114.567101)
				(end 364.026704 -114.603022)
			)
			(arc
				(start 364.026704 -115.265962)
				(mid 364.041583 -115.301883)
				(end 364.077504 -115.316762)
			)
			(arc
				(start 364.733078 -115.316762)
				(mid 364.752601 -115.320663)
				(end 364.769146 -115.331748)
			)
			(arc
				(start 365.488728 -116.05133)
				(mid 365.499839 -116.067864)
				(end 365.503714 -116.087398)
			)
			(arc
				(start 365.503714 -117.407182)
				(mid 365.507479 -117.426373)
				(end 365.518192 -117.442742)
			)
			(xy 365.518446 -117.442996)
			(arc
				(start 365.706152 -117.630702)
				(mid 365.717263 -117.647236)
				(end 365.721138 -117.66677)
			)
			(arc
				(start 365.721138 -118.741952)
				(mid 365.725039 -118.761475)
				(end 365.736124 -118.77802)
			)
			(arc
				(start 366.351566 -119.393462)
				(mid 366.3681 -119.404573)
				(end 366.387634 -119.408448)
			)
			(arc
				(start 370.08943 -119.408448)
				(mid 370.108953 -119.412349)
				(end 370.125498 -119.423434)
			)
			(arc
				(start 370.768626 -120.066562)
				(mid 370.779737 -120.083096)
				(end 370.783612 -120.10263)
			)
			(arc
				(start 370.783612 -123.902978)
				(mid 370.779711 -123.922501)
				(end 370.768626 -123.939046)
			)
			(arc
				(start 370.457476 -124.250196)
				(mid 370.440942 -124.261307)
				(end 370.421408 -124.265182)
			)
			(arc
				(start 364.267242 -124.265182)
				(mid 364.247719 -124.261281)
				(end 364.231174 -124.250196)
			)
			(xy 363.748066 -123.767088) (xy 363.740954 -123.759722) (xy 363.722158 -123.752102)
			(arc
				(start 363.322108 -123.752102)
				(mid 363.286187 -123.766981)
				(end 363.271308 -123.802902)
			)
			(arc
				(start 363.271308 -125.918976)
				(mid 363.276171 -125.940414)
				(end 363.289596 -125.957838)
			)
			(xy 363.357922 -126.015242) (xy 363.379258 -126.021084) (xy 363.390434 -126.019052) (xy 363.391196 -126.018798)
			(arc
				(start 363.39145 -126.018798)
				(mid 363.423721 -126.014754)
				(end 363.45622 -126.013464)
			)
			(arc
				(start 363.45622 -126.013464)
				(mid 363.521974 -126.019133)
				(end 363.58576 -126.03607)
			)
			(arc
				(start 363.58576 -126.03607)
				(mid 363.599857 -126.038998)
				(end 363.614208 -126.037848)
			)
			(xy 363.625384 -126.036578) (xy 363.698282 -126.036578) (xy 363.893608 -126.036578) (xy 364.004098 -126.147068)
			(xy 364.004098 -126.342394)
			(arc
				(start 364.004098 -127.150368)
				(mid 364.007863 -127.169559)
				(end 364.018576 -127.185928)
			)
			(xy 364.01883 -127.186182) (xy 364.23727 -127.404622)
			(arc
				(start 364.237778 -127.40513)
				(mid 364.254135 -127.415872)
				(end 364.273338 -127.419608)
			)
			(arc
				(start 368.777012 -127.419608)
				(mid 368.796535 -127.423509)
				(end 368.81308 -127.434594)
			)
			(arc
				(start 369.724178 -128.345692)
				(mid 369.735289 -128.362226)
				(end 369.739164 -128.38176)
			)
			(arc
				(start 369.739164 -134.193534)
				(mid 369.742929 -134.212725)
				(end 369.753642 -134.229094)
			)
			(xy 369.753896 -134.229348) (xy 375.50598 -139.981432)
			(arc
				(start 375.506488 -139.98194)
				(mid 375.522845 -139.992682)
				(end 375.542048 -139.996418)
			)
			(arc
				(start 384.027934 -139.996418)
				(mid 384.0371 -139.995584)
				(end 384.045968 -139.993116)
			)
			(xy 384.070606 -139.983718)
			(arc
				(start 384.077464 -139.97813)
				(mid 384.216051 -139.896992)
				(end 384.374136 -139.868656)
			)
			(arc
				(start 384.374136 -139.868656)
				(mid 384.532246 -139.896925)
				(end 384.670808 -139.97813)
			)
			(xy 384.677666 -139.983718)
			(arc
				(start 384.702304 -139.993116)
				(mid 384.711171 -139.99559)
				(end 384.720338 -139.996418)
			)
			(arc
				(start 388.335012 -139.996418)
				(mid 388.343783 -139.995655)
				(end 388.352284 -139.99337)
			)
			(xy 388.375144 -139.985242)
			(arc
				(start 388.381748 -139.980162)
				(mid 388.530216 -139.89864)
				(end 388.697216 -139.870434)
			)
			(arc
				(start 388.697216 -139.870434)
				(mid 388.867892 -139.899932)
				(end 389.01878 -139.984988)
			)
			(xy 389.025892 -139.990576) (xy 389.041894 -139.996418)
			(arc
				(start 389.090154 -139.996418)
				(mid 389.109677 -140.000319)
				(end 389.126222 -140.011404)
			)
			(xy 389.972296 -140.857478)
			(arc
				(start 389.972804 -140.857986)
				(mid 389.989161 -140.868728)
				(end 390.008364 -140.872464)
			)
		)
		(stroke
			(width 0)
			(type solid)
		)
		(fill yes)
		(layer "F.Cu")
		(net "P3V3_NIC6")
	)
	(gr_poly
		(pts
			(xy 200.699878 -378.70003) (xy 200.699377 -378.599976) (xy 200.691371 -378.400029) (xy 200.675372 -378.200562)
			(xy 200.651404 -378.001894) (xy 200.619507 -377.804345) (xy 200.579732 -377.60823) (xy 200.532142 -377.413864)
			(xy 200.476814 -377.221557) (xy 200.413836 -377.031618) (xy 200.343309 -376.844351) (xy 200.265346 -376.660055)
			(xy 200.180072 -376.479026) (xy 200.087623 -376.301554) (xy 199.988148 -376.127923) (xy 199.881805 -375.958411)
			(xy 199.768766 -375.79329) (xy 199.64921 -375.632823) (xy 199.52333 -375.477268) (xy 199.391327 -375.326874)
			(xy 199.253413 -375.181882) (xy 199.109808 -375.042524) (xy 198.960742 -374.909023) (xy 198.806454 -374.781593)
			(xy 198.647192 -374.660438) (xy 198.483209 -374.545752) (xy 198.31477 -374.437719) (xy 198.142143 -374.336511)
			(xy 197.965604 -374.242291) (xy 197.785438 -374.15521) (xy 197.601931 -374.075407) (xy 197.415379 -374.00301)
			(xy 197.22608 -373.938135) (xy 197.034336 -373.880885) (xy 196.840455 -373.831353) (xy 196.644748 -373.789618)
			(xy 196.447528 -373.755746) (xy 196.249111 -373.729793) (xy 196.049814 -373.711798) (xy 195.849956 -373.701792)
			(xy 195.649859 -373.69979) (xy 195.449841 -373.705795) (xy 195.250224 -373.719798) (xy 195.051327 -373.741777)
			(xy 194.853468 -373.771696) (xy 194.656965 -373.809507) (xy 194.462132 -373.85515) (xy 194.269282 -373.908551)
			(xy 194.078722 -373.969626) (xy 193.890759 -374.038275) (xy 193.705692 -374.114391) (xy 193.523819 -374.197849)
			(xy 193.345431 -374.288518) (xy 193.170814 -374.386251) (xy 193.000246 -374.490892) (xy 192.834002 -374.602274)
			(xy 192.672347 -374.720218) (xy 192.51554 -374.844536) (xy 192.363833 -374.975027) (xy 192.217469 -375.111484)
			(xy 192.076681 -375.253688) (xy 191.941695 -375.401411) (xy 191.812728 -375.554416) (xy 191.689985 -375.712458)
			(xy 191.573665 -375.875285) (xy 191.463952 -376.042635) (xy 191.361022 -376.214241) (xy 191.265041 -376.389828)
			(xy 191.176161 -376.569114) (xy 191.094526 -376.751813) (xy 191.020267 -376.937632) (xy 190.953501 -377.126273)
			(xy 190.894336 -377.317434) (xy 190.842866 -377.510809) (xy 190.799175 -377.706089) (xy 190.763332 -377.90296)
			(xy 190.735394 -378.101108) (xy 190.715407 -378.300215) (xy 190.703401 -378.499962) (xy 190.699398 -378.70003)
			(xy 190.700735 -378.766865) (xy 193.488053 -378.766865) (xy 193.488053 -378.633195) (xy 193.496123 -378.49977)
			(xy 193.512235 -378.367075) (xy 193.53633 -378.235596) (xy 193.568319 -378.105811) (xy 193.608086 -377.978194)
			(xy 193.655486 -377.853211) (xy 193.710345 -377.731318) (xy 193.772465 -377.61296) (xy 193.841617 -377.498568)
			(xy 193.917549 -377.38856) (xy 193.999986 -377.283338) (xy 194.088625 -377.183285) (xy 194.183143 -377.088767)
			(xy 194.283196 -377.000128) (xy 194.388418 -376.917691) (xy 194.498426 -376.841759) (xy 194.612818 -376.772607)
			(xy 194.731176 -376.710487) (xy 194.853069 -376.655628) (xy 194.978052 -376.608228) (xy 195.105669 -376.568461)
			(xy 195.235454 -376.536472) (xy 195.366933 -376.512377) (xy 195.499628 -376.496265) (xy 195.633053 -376.488195)
			(xy 195.766723 -376.488195) (xy 195.900148 -376.496265) (xy 196.032843 -376.512377) (xy 196.164322 -376.536472)
			(xy 196.294107 -376.568461) (xy 196.421724 -376.608228) (xy 196.546707 -376.655628) (xy 196.6686 -376.710487)
			(xy 196.786958 -376.772607) (xy 196.90135 -376.841759) (xy 197.011358 -376.917691) (xy 197.11658 -377.000128)
			(xy 197.216633 -377.088767) (xy 197.311151 -377.183285) (xy 197.39979 -377.283338) (xy 197.482227 -377.38856)
			(xy 197.558159 -377.498568) (xy 197.627311 -377.61296) (xy 197.689431 -377.731318) (xy 197.74429 -377.853211)
			(xy 197.79169 -377.978194) (xy 197.831457 -378.105811) (xy 197.863446 -378.235596) (xy 197.887541 -378.367075)
			(xy 197.903653 -378.49977) (xy 197.911723 -378.633195) (xy 197.912228 -378.70003) (xy 197.911723 -378.766865)
			(xy 197.903653 -378.90029) (xy 197.887541 -379.032985) (xy 197.863446 -379.164464) (xy 197.831457 -379.294249)
			(xy 197.79169 -379.421866) (xy 197.74429 -379.546849) (xy 197.689431 -379.668742) (xy 197.627311 -379.7871)
			(xy 197.558159 -379.901492) (xy 197.482227 -380.0115) (xy 197.39979 -380.116722) (xy 197.311151 -380.216775)
			(xy 197.216633 -380.311293) (xy 197.11658 -380.399932) (xy 197.011358 -380.482369) (xy 196.90135 -380.558301)
			(xy 196.786958 -380.627453) (xy 196.6686 -380.689573) (xy 196.546707 -380.744432) (xy 196.421724 -380.791832)
			(xy 196.294107 -380.831599) (xy 196.164322 -380.863588) (xy 196.032843 -380.887683) (xy 195.900148 -380.903795)
			(xy 195.766723 -380.911865) (xy 195.633053 -380.911865) (xy 195.499628 -380.903795) (xy 195.366933 -380.887683)
			(xy 195.235454 -380.863588) (xy 195.105669 -380.831599) (xy 194.978052 -380.791832) (xy 194.853069 -380.744432)
			(xy 194.731176 -380.689573) (xy 194.612818 -380.627453) (xy 194.498426 -380.558301) (xy 194.388418 -380.482369)
			(xy 194.283196 -380.399932) (xy 194.183143 -380.311293) (xy 194.088625 -380.216775) (xy 193.999986 -380.116722)
			(xy 193.917549 -380.0115) (xy 193.841617 -379.901492) (xy 193.772465 -379.7871) (xy 193.710345 -379.668742)
			(xy 193.655486 -379.546849) (xy 193.608086 -379.421866) (xy 193.568319 -379.294249) (xy 193.53633 -379.164464)
			(xy 193.512235 -379.032985) (xy 193.496123 -378.90029) (xy 193.488053 -378.766865) (xy 190.700735 -378.766865)
			(xy 190.703401 -378.900098) (xy 190.715407 -379.099845) (xy 190.735394 -379.298952) (xy 190.763332 -379.4971)
			(xy 190.799175 -379.693971) (xy 190.842866 -379.889251) (xy 190.894336 -380.082626) (xy 190.953501 -380.273787)
			(xy 191.020267 -380.462428) (xy 191.094526 -380.648247) (xy 191.176161 -380.830946) (xy 191.265041 -381.010232)
			(xy 191.361022 -381.185819) (xy 191.463952 -381.357425) (xy 191.573665 -381.524775) (xy 191.689985 -381.687602)
			(xy 191.812728 -381.845644) (xy 191.941695 -381.998649) (xy 192.076681 -382.146372) (xy 192.217469 -382.288576)
			(xy 192.363833 -382.425033) (xy 192.51554 -382.555524) (xy 192.672347 -382.679842) (xy 192.834002 -382.797786)
			(xy 193.000246 -382.909168) (xy 193.170814 -383.013809) (xy 193.345431 -383.111542) (xy 193.523819 -383.202211)
			(xy 193.705692 -383.285669) (xy 193.890759 -383.361785) (xy 194.078722 -383.430434) (xy 194.269282 -383.491509)
			(xy 194.462132 -383.54491) (xy 194.656965 -383.590553) (xy 194.853468 -383.628364) (xy 195.051327 -383.658283)
			(xy 195.250224 -383.680262) (xy 195.449841 -383.694265) (xy 195.649859 -383.70027) (xy 195.849956 -383.698268)
			(xy 196.049814 -383.688262) (xy 196.249111 -383.670267) (xy 196.447528 -383.644314) (xy 196.644748 -383.610442)
			(xy 196.840455 -383.568707) (xy 197.034336 -383.519175) (xy 197.22608 -383.461925) (xy 197.415379 -383.39705)
			(xy 197.601931 -383.324653) (xy 197.785438 -383.24485) (xy 197.965604 -383.157769) (xy 198.142143 -383.063549)
			(xy 198.31477 -382.962341) (xy 198.483209 -382.854308) (xy 198.647192 -382.739622) (xy 198.806454 -382.618467)
			(xy 198.960742 -382.491037) (xy 199.109808 -382.357536) (xy 199.253413 -382.218178) (xy 199.391327 -382.073186)
			(xy 199.52333 -381.922792) (xy 199.64921 -381.767237) (xy 199.768766 -381.60677) (xy 199.881805 -381.441649)
			(xy 199.988148 -381.272137) (xy 200.087623 -381.098506) (xy 200.180072 -380.921034) (xy 200.265346 -380.740005)
			(xy 200.343309 -380.555709) (xy 200.413836 -380.368442) (xy 200.476814 -380.178503) (xy 200.532142 -379.986196)
			(xy 200.579732 -379.79183) (xy 200.619507 -379.595715) (xy 200.651404 -379.398166) (xy 200.675372 -379.199498)
			(xy 200.691371 -379.000031) (xy 200.699377 -378.800084)
		)
		(stroke
			(width 0)
			(type solid)
		)
		(fill yes)
		(layer "F.Cu")
		(net "GND")
	)
	(gr_poly
		(pts
			(xy 213.300056 -98.700082) (xy 213.299555 -98.600028) (xy 213.291549 -98.400081) (xy 213.27555 -98.200614)
			(xy 213.251582 -98.001946) (xy 213.219685 -97.804397) (xy 213.17991 -97.608282) (xy 213.13232 -97.413916)
			(xy 213.076992 -97.221609) (xy 213.014014 -97.03167) (xy 212.943487 -96.844403) (xy 212.865524 -96.660107)
			(xy 212.78025 -96.479078) (xy 212.687801 -96.301606) (xy 212.588326 -96.127975) (xy 212.481983 -95.958463)
			(xy 212.368944 -95.793342) (xy 212.249388 -95.632875) (xy 212.123508 -95.47732) (xy 211.991505 -95.326926)
			(xy 211.853591 -95.181934) (xy 211.709986 -95.042576) (xy 211.56092 -94.909075) (xy 211.406632 -94.781645)
			(xy 211.24737 -94.66049) (xy 211.083387 -94.545804) (xy 210.914948 -94.437771) (xy 210.742321 -94.336563)
			(xy 210.565782 -94.242343) (xy 210.385616 -94.155262) (xy 210.202109 -94.075459) (xy 210.015557 -94.003062)
			(xy 209.826258 -93.938187) (xy 209.634514 -93.880937) (xy 209.440633 -93.831405) (xy 209.244926 -93.78967)
			(xy 209.047706 -93.755798) (xy 208.849289 -93.729845) (xy 208.649992 -93.71185) (xy 208.450134 -93.701844)
			(xy 208.250037 -93.699842) (xy 208.050019 -93.705847) (xy 207.850402 -93.71985) (xy 207.651505 -93.741829)
			(xy 207.453646 -93.771748) (xy 207.257143 -93.809559) (xy 207.06231 -93.855202) (xy 206.86946 -93.908603)
			(xy 206.6789 -93.969678) (xy 206.490937 -94.038327) (xy 206.30587 -94.114443) (xy 206.123997 -94.197901)
			(xy 205.945609 -94.28857) (xy 205.770992 -94.386303) (xy 205.600424 -94.490944) (xy 205.43418 -94.602326)
			(xy 205.272525 -94.72027) (xy 205.115718 -94.844588) (xy 204.964011 -94.975079) (xy 204.817647 -95.111536)
			(xy 204.676859 -95.25374) (xy 204.541873 -95.401463) (xy 204.412906 -95.554468) (xy 204.290163 -95.71251)
			(xy 204.173843 -95.875337) (xy 204.06413 -96.042687) (xy 203.9612 -96.214293) (xy 203.865219 -96.38988)
			(xy 203.776339 -96.569166) (xy 203.694704 -96.751865) (xy 203.620445 -96.937684) (xy 203.553679 -97.126325)
			(xy 203.494514 -97.317486) (xy 203.443044 -97.510861) (xy 203.399353 -97.706141) (xy 203.36351 -97.903012)
			(xy 203.335572 -98.10116) (xy 203.315585 -98.300267) (xy 203.303579 -98.500014) (xy 203.299576 -98.700082)
			(xy 203.300913 -98.766917) (xy 206.088231 -98.766917) (xy 206.088231 -98.633247) (xy 206.096301 -98.499822)
			(xy 206.112413 -98.367127) (xy 206.136508 -98.235648) (xy 206.168497 -98.105863) (xy 206.208264 -97.978246)
			(xy 206.255664 -97.853263) (xy 206.310523 -97.73137) (xy 206.372643 -97.613012) (xy 206.441795 -97.49862)
			(xy 206.517727 -97.388612) (xy 206.600164 -97.28339) (xy 206.688803 -97.183337) (xy 206.783321 -97.088819)
			(xy 206.883374 -97.00018) (xy 206.988596 -96.917743) (xy 207.098604 -96.841811) (xy 207.212996 -96.772659)
			(xy 207.331354 -96.710539) (xy 207.453247 -96.65568) (xy 207.57823 -96.60828) (xy 207.705847 -96.568513)
			(xy 207.835632 -96.536524) (xy 207.967111 -96.512429) (xy 208.099806 -96.496317) (xy 208.233231 -96.488247)
			(xy 208.366901 -96.488247) (xy 208.500326 -96.496317) (xy 208.633021 -96.512429) (xy 208.7645 -96.536524)
			(xy 208.894285 -96.568513) (xy 209.021902 -96.60828) (xy 209.146885 -96.65568) (xy 209.268778 -96.710539)
			(xy 209.387136 -96.772659) (xy 209.501528 -96.841811) (xy 209.611536 -96.917743) (xy 209.716758 -97.00018)
			(xy 209.816811 -97.088819) (xy 209.911329 -97.183337) (xy 209.999968 -97.28339) (xy 210.082405 -97.388612)
			(xy 210.158337 -97.49862) (xy 210.227489 -97.613012) (xy 210.289609 -97.73137) (xy 210.344468 -97.853263)
			(xy 210.391868 -97.978246) (xy 210.431635 -98.105863) (xy 210.463624 -98.235648) (xy 210.487719 -98.367127)
			(xy 210.503831 -98.499822) (xy 210.511901 -98.633247) (xy 210.512406 -98.700082) (xy 210.511901 -98.766917)
			(xy 210.503831 -98.900342) (xy 210.487719 -99.033037) (xy 210.463624 -99.164516) (xy 210.431635 -99.294301)
			(xy 210.391868 -99.421918) (xy 210.344468 -99.546901) (xy 210.289609 -99.668794) (xy 210.227489 -99.787152)
			(xy 210.158337 -99.901544) (xy 210.082405 -100.011552) (xy 209.999968 -100.116774) (xy 209.911329 -100.216827)
			(xy 209.816811 -100.311345) (xy 209.716758 -100.399984) (xy 209.611536 -100.482421) (xy 209.501528 -100.558353)
			(xy 209.387136 -100.627505) (xy 209.268778 -100.689625) (xy 209.146885 -100.744484) (xy 209.021902 -100.791884)
			(xy 208.894285 -100.831651) (xy 208.7645 -100.86364) (xy 208.633021 -100.887735) (xy 208.500326 -100.903847)
			(xy 208.366901 -100.911917) (xy 208.233231 -100.911917) (xy 208.099806 -100.903847) (xy 207.967111 -100.887735)
			(xy 207.835632 -100.86364) (xy 207.705847 -100.831651) (xy 207.57823 -100.791884) (xy 207.453247 -100.744484)
			(xy 207.331354 -100.689625) (xy 207.212996 -100.627505) (xy 207.098604 -100.558353) (xy 206.988596 -100.482421)
			(xy 206.883374 -100.399984) (xy 206.783321 -100.311345) (xy 206.688803 -100.216827) (xy 206.600164 -100.116774)
			(xy 206.517727 -100.011552) (xy 206.441795 -99.901544) (xy 206.372643 -99.787152) (xy 206.310523 -99.668794)
			(xy 206.255664 -99.546901) (xy 206.208264 -99.421918) (xy 206.168497 -99.294301) (xy 206.136508 -99.164516)
			(xy 206.112413 -99.033037) (xy 206.096301 -98.900342) (xy 206.088231 -98.766917) (xy 203.300913 -98.766917)
			(xy 203.303579 -98.90015) (xy 203.315585 -99.099897) (xy 203.335572 -99.299004) (xy 203.36351 -99.497152)
			(xy 203.399353 -99.694023) (xy 203.443044 -99.889303) (xy 203.494514 -100.082678) (xy 203.553679 -100.273839)
			(xy 203.620445 -100.46248) (xy 203.694704 -100.648299) (xy 203.776339 -100.830998) (xy 203.865219 -101.010284)
			(xy 203.9612 -101.185871) (xy 204.06413 -101.357477) (xy 204.173843 -101.524827) (xy 204.290163 -101.687654)
			(xy 204.412906 -101.845696) (xy 204.541873 -101.998701) (xy 204.676859 -102.146424) (xy 204.817647 -102.288628)
			(xy 204.964011 -102.425085) (xy 205.115718 -102.555576) (xy 205.272525 -102.679894) (xy 205.43418 -102.797838)
			(xy 205.600424 -102.90922) (xy 205.770992 -103.013861) (xy 205.945609 -103.111594) (xy 206.123997 -103.202263)
			(xy 206.30587 -103.285721) (xy 206.490937 -103.361837) (xy 206.6789 -103.430486) (xy 206.86946 -103.491561)
			(xy 207.06231 -103.544962) (xy 207.257143 -103.590605) (xy 207.453646 -103.628416) (xy 207.651505 -103.658335)
			(xy 207.850402 -103.680314) (xy 208.050019 -103.694317) (xy 208.250037 -103.700322) (xy 208.450134 -103.69832)
			(xy 208.649992 -103.688314) (xy 208.849289 -103.670319) (xy 209.047706 -103.644366) (xy 209.244926 -103.610494)
			(xy 209.440633 -103.568759) (xy 209.634514 -103.519227) (xy 209.826258 -103.461977) (xy 210.015557 -103.397102)
			(xy 210.202109 -103.324705) (xy 210.385616 -103.244902) (xy 210.565782 -103.157821) (xy 210.742321 -103.063601)
			(xy 210.914948 -102.962393) (xy 211.083387 -102.85436) (xy 211.24737 -102.739674) (xy 211.406632 -102.618519)
			(xy 211.56092 -102.491089) (xy 211.709986 -102.357588) (xy 211.853591 -102.21823) (xy 211.991505 -102.073238)
			(xy 212.123508 -101.922844) (xy 212.249388 -101.767289) (xy 212.368944 -101.606822) (xy 212.481983 -101.441701)
			(xy 212.588326 -101.272189) (xy 212.687801 -101.098558) (xy 212.78025 -100.921086) (xy 212.865524 -100.740057)
			(xy 212.943487 -100.555761) (xy 213.014014 -100.368494) (xy 213.076992 -100.178555) (xy 213.13232 -99.986248)
			(xy 213.17991 -99.791882) (xy 213.219685 -99.595767) (xy 213.251582 -99.398218) (xy 213.27555 -99.19955)
			(xy 213.291549 -99.000083) (xy 213.299555 -98.800136)
		)
		(stroke
			(width 0)
			(type solid)
		)
		(fill yes)
		(layer "F.Cu")
		(net "GND")
	)
	(gr_poly
		(pts
			(xy 264.299954 -98.700082) (xy 264.299453 -98.600028) (xy 264.291447 -98.400081) (xy 264.275448 -98.200614)
			(xy 264.25148 -98.001946) (xy 264.219583 -97.804397) (xy 264.179808 -97.608282) (xy 264.132218 -97.413916)
			(xy 264.07689 -97.221609) (xy 264.013912 -97.03167) (xy 263.943385 -96.844403) (xy 263.865422 -96.660107)
			(xy 263.780148 -96.479078) (xy 263.687699 -96.301606) (xy 263.588224 -96.127975) (xy 263.481881 -95.958463)
			(xy 263.368842 -95.793342) (xy 263.249286 -95.632875) (xy 263.123406 -95.47732) (xy 262.991403 -95.326926)
			(xy 262.853489 -95.181934) (xy 262.709884 -95.042576) (xy 262.560818 -94.909075) (xy 262.40653 -94.781645)
			(xy 262.247268 -94.66049) (xy 262.083285 -94.545804) (xy 261.914846 -94.437771) (xy 261.742219 -94.336563)
			(xy 261.56568 -94.242343) (xy 261.385514 -94.155262) (xy 261.202007 -94.075459) (xy 261.015455 -94.003062)
			(xy 260.826156 -93.938187) (xy 260.634412 -93.880937) (xy 260.440531 -93.831405) (xy 260.244824 -93.78967)
			(xy 260.047604 -93.755798) (xy 259.849187 -93.729845) (xy 259.64989 -93.71185) (xy 259.450032 -93.701844)
			(xy 259.249935 -93.699842) (xy 259.049917 -93.705847) (xy 258.8503 -93.71985) (xy 258.651403 -93.741829)
			(xy 258.453544 -93.771748) (xy 258.257041 -93.809559) (xy 258.062208 -93.855202) (xy 257.869358 -93.908603)
			(xy 257.678798 -93.969678) (xy 257.490835 -94.038327) (xy 257.305768 -94.114443) (xy 257.123895 -94.197901)
			(xy 256.945507 -94.28857) (xy 256.77089 -94.386303) (xy 256.600322 -94.490944) (xy 256.434078 -94.602326)
			(xy 256.272423 -94.72027) (xy 256.115616 -94.844588) (xy 255.963909 -94.975079) (xy 255.817545 -95.111536)
			(xy 255.676757 -95.25374) (xy 255.541771 -95.401463) (xy 255.412804 -95.554468) (xy 255.290061 -95.71251)
			(xy 255.173741 -95.875337) (xy 255.064028 -96.042687) (xy 254.961098 -96.214293) (xy 254.865117 -96.38988)
			(xy 254.776237 -96.569166) (xy 254.694602 -96.751865) (xy 254.620343 -96.937684) (xy 254.553577 -97.126325)
			(xy 254.494412 -97.317486) (xy 254.442942 -97.510861) (xy 254.399251 -97.706141) (xy 254.363408 -97.903012)
			(xy 254.33547 -98.10116) (xy 254.315483 -98.300267) (xy 254.303477 -98.500014) (xy 254.299474 -98.700082)
			(xy 254.300811 -98.766917) (xy 257.088129 -98.766917) (xy 257.088129 -98.633247) (xy 257.096199 -98.499822)
			(xy 257.112311 -98.367127) (xy 257.136406 -98.235648) (xy 257.168395 -98.105863) (xy 257.208162 -97.978246)
			(xy 257.255562 -97.853263) (xy 257.310421 -97.73137) (xy 257.372541 -97.613012) (xy 257.441693 -97.49862)
			(xy 257.517625 -97.388612) (xy 257.600062 -97.28339) (xy 257.688701 -97.183337) (xy 257.783219 -97.088819)
			(xy 257.883272 -97.00018) (xy 257.988494 -96.917743) (xy 258.098502 -96.841811) (xy 258.212894 -96.772659)
			(xy 258.331252 -96.710539) (xy 258.453145 -96.65568) (xy 258.578128 -96.60828) (xy 258.705745 -96.568513)
			(xy 258.83553 -96.536524) (xy 258.967009 -96.512429) (xy 259.099704 -96.496317) (xy 259.233129 -96.488247)
			(xy 259.366799 -96.488247) (xy 259.500224 -96.496317) (xy 259.632919 -96.512429) (xy 259.764398 -96.536524)
			(xy 259.894183 -96.568513) (xy 260.0218 -96.60828) (xy 260.146783 -96.65568) (xy 260.268676 -96.710539)
			(xy 260.387034 -96.772659) (xy 260.501426 -96.841811) (xy 260.611434 -96.917743) (xy 260.716656 -97.00018)
			(xy 260.816709 -97.088819) (xy 260.911227 -97.183337) (xy 260.999866 -97.28339) (xy 261.082303 -97.388612)
			(xy 261.158235 -97.49862) (xy 261.227387 -97.613012) (xy 261.289507 -97.73137) (xy 261.344366 -97.853263)
			(xy 261.391766 -97.978246) (xy 261.431533 -98.105863) (xy 261.463522 -98.235648) (xy 261.487617 -98.367127)
			(xy 261.503729 -98.499822) (xy 261.511799 -98.633247) (xy 261.512304 -98.700082) (xy 261.511799 -98.766917)
			(xy 261.503729 -98.900342) (xy 261.487617 -99.033037) (xy 261.463522 -99.164516) (xy 261.431533 -99.294301)
			(xy 261.391766 -99.421918) (xy 261.344366 -99.546901) (xy 261.289507 -99.668794) (xy 261.227387 -99.787152)
			(xy 261.158235 -99.901544) (xy 261.082303 -100.011552) (xy 260.999866 -100.116774) (xy 260.911227 -100.216827)
			(xy 260.816709 -100.311345) (xy 260.716656 -100.399984) (xy 260.611434 -100.482421) (xy 260.501426 -100.558353)
			(xy 260.387034 -100.627505) (xy 260.268676 -100.689625) (xy 260.146783 -100.744484) (xy 260.0218 -100.791884)
			(xy 259.894183 -100.831651) (xy 259.764398 -100.86364) (xy 259.632919 -100.887735) (xy 259.500224 -100.903847)
			(xy 259.366799 -100.911917) (xy 259.233129 -100.911917) (xy 259.099704 -100.903847) (xy 258.967009 -100.887735)
			(xy 258.83553 -100.86364) (xy 258.705745 -100.831651) (xy 258.578128 -100.791884) (xy 258.453145 -100.744484)
			(xy 258.331252 -100.689625) (xy 258.212894 -100.627505) (xy 258.098502 -100.558353) (xy 257.988494 -100.482421)
			(xy 257.883272 -100.399984) (xy 257.783219 -100.311345) (xy 257.688701 -100.216827) (xy 257.600062 -100.116774)
			(xy 257.517625 -100.011552) (xy 257.441693 -99.901544) (xy 257.372541 -99.787152) (xy 257.310421 -99.668794)
			(xy 257.255562 -99.546901) (xy 257.208162 -99.421918) (xy 257.168395 -99.294301) (xy 257.136406 -99.164516)
			(xy 257.112311 -99.033037) (xy 257.096199 -98.900342) (xy 257.088129 -98.766917) (xy 254.300811 -98.766917)
			(xy 254.303477 -98.90015) (xy 254.315483 -99.099897) (xy 254.33547 -99.299004) (xy 254.363408 -99.497152)
			(xy 254.399251 -99.694023) (xy 254.442942 -99.889303) (xy 254.494412 -100.082678) (xy 254.553577 -100.273839)
			(xy 254.620343 -100.46248) (xy 254.694602 -100.648299) (xy 254.776237 -100.830998) (xy 254.865117 -101.010284)
			(xy 254.961098 -101.185871) (xy 255.064028 -101.357477) (xy 255.173741 -101.524827) (xy 255.290061 -101.687654)
			(xy 255.412804 -101.845696) (xy 255.541771 -101.998701) (xy 255.676757 -102.146424) (xy 255.817545 -102.288628)
			(xy 255.963909 -102.425085) (xy 256.115616 -102.555576) (xy 256.272423 -102.679894) (xy 256.434078 -102.797838)
			(xy 256.600322 -102.90922) (xy 256.77089 -103.013861) (xy 256.945507 -103.111594) (xy 257.123895 -103.202263)
			(xy 257.305768 -103.285721) (xy 257.490835 -103.361837) (xy 257.678798 -103.430486) (xy 257.869358 -103.491561)
			(xy 258.062208 -103.544962) (xy 258.257041 -103.590605) (xy 258.453544 -103.628416) (xy 258.651403 -103.658335)
			(xy 258.8503 -103.680314) (xy 259.049917 -103.694317) (xy 259.249935 -103.700322) (xy 259.450032 -103.69832)
			(xy 259.64989 -103.688314) (xy 259.849187 -103.670319) (xy 260.047604 -103.644366) (xy 260.244824 -103.610494)
			(xy 260.440531 -103.568759) (xy 260.634412 -103.519227) (xy 260.826156 -103.461977) (xy 261.015455 -103.397102)
			(xy 261.202007 -103.324705) (xy 261.385514 -103.244902) (xy 261.56568 -103.157821) (xy 261.742219 -103.063601)
			(xy 261.914846 -102.962393) (xy 262.083285 -102.85436) (xy 262.247268 -102.739674) (xy 262.40653 -102.618519)
			(xy 262.560818 -102.491089) (xy 262.709884 -102.357588) (xy 262.853489 -102.21823) (xy 262.991403 -102.073238)
			(xy 263.123406 -101.922844) (xy 263.249286 -101.767289) (xy 263.368842 -101.606822) (xy 263.481881 -101.441701)
			(xy 263.588224 -101.272189) (xy 263.687699 -101.098558) (xy 263.780148 -100.921086) (xy 263.865422 -100.740057)
			(xy 263.943385 -100.555761) (xy 264.013912 -100.368494) (xy 264.07689 -100.178555) (xy 264.132218 -99.986248)
			(xy 264.179808 -99.791882) (xy 264.219583 -99.595767) (xy 264.25148 -99.398218) (xy 264.275448 -99.19955)
			(xy 264.291447 -99.000083) (xy 264.299453 -98.800136)
		)
		(stroke
			(width 0)
			(type solid)
		)
		(fill yes)
		(layer "F.Cu")
		(net "GND")
	)
	(gr_poly
		(pts
			(xy 276.899878 -378.70003) (xy 276.899377 -378.599976) (xy 276.891371 -378.400029) (xy 276.875372 -378.200562)
			(xy 276.851404 -378.001894) (xy 276.819507 -377.804345) (xy 276.779732 -377.60823) (xy 276.732142 -377.413864)
			(xy 276.676814 -377.221557) (xy 276.613836 -377.031618) (xy 276.543309 -376.844351) (xy 276.465346 -376.660055)
			(xy 276.380072 -376.479026) (xy 276.287623 -376.301554) (xy 276.188148 -376.127923) (xy 276.081805 -375.958411)
			(xy 275.968766 -375.79329) (xy 275.84921 -375.632823) (xy 275.72333 -375.477268) (xy 275.591327 -375.326874)
			(xy 275.453413 -375.181882) (xy 275.309808 -375.042524) (xy 275.160742 -374.909023) (xy 275.006454 -374.781593)
			(xy 274.847192 -374.660438) (xy 274.683209 -374.545752) (xy 274.51477 -374.437719) (xy 274.342143 -374.336511)
			(xy 274.165604 -374.242291) (xy 273.985438 -374.15521) (xy 273.801931 -374.075407) (xy 273.615379 -374.00301)
			(xy 273.42608 -373.938135) (xy 273.234336 -373.880885) (xy 273.040455 -373.831353) (xy 272.844748 -373.789618)
			(xy 272.647528 -373.755746) (xy 272.449111 -373.729793) (xy 272.249814 -373.711798) (xy 272.049956 -373.701792)
			(xy 271.849859 -373.69979) (xy 271.649841 -373.705795) (xy 271.450224 -373.719798) (xy 271.251327 -373.741777)
			(xy 271.053468 -373.771696) (xy 270.856965 -373.809507) (xy 270.662132 -373.85515) (xy 270.469282 -373.908551)
			(xy 270.278722 -373.969626) (xy 270.090759 -374.038275) (xy 269.905692 -374.114391) (xy 269.723819 -374.197849)
			(xy 269.545431 -374.288518) (xy 269.370814 -374.386251) (xy 269.200246 -374.490892) (xy 269.034002 -374.602274)
			(xy 268.872347 -374.720218) (xy 268.71554 -374.844536) (xy 268.563833 -374.975027) (xy 268.417469 -375.111484)
			(xy 268.276681 -375.253688) (xy 268.141695 -375.401411) (xy 268.012728 -375.554416) (xy 267.889985 -375.712458)
			(xy 267.773665 -375.875285) (xy 267.663952 -376.042635) (xy 267.561022 -376.214241) (xy 267.465041 -376.389828)
			(xy 267.376161 -376.569114) (xy 267.294526 -376.751813) (xy 267.220267 -376.937632) (xy 267.153501 -377.126273)
			(xy 267.094336 -377.317434) (xy 267.042866 -377.510809) (xy 266.999175 -377.706089) (xy 266.963332 -377.90296)
			(xy 266.935394 -378.101108) (xy 266.915407 -378.300215) (xy 266.903401 -378.499962) (xy 266.899398 -378.70003)
			(xy 266.900735 -378.766865) (xy 269.688053 -378.766865) (xy 269.688053 -378.633195) (xy 269.696123 -378.49977)
			(xy 269.712235 -378.367075) (xy 269.73633 -378.235596) (xy 269.768319 -378.105811) (xy 269.808086 -377.978194)
			(xy 269.855486 -377.853211) (xy 269.910345 -377.731318) (xy 269.972465 -377.61296) (xy 270.041617 -377.498568)
			(xy 270.117549 -377.38856) (xy 270.199986 -377.283338) (xy 270.288625 -377.183285) (xy 270.383143 -377.088767)
			(xy 270.483196 -377.000128) (xy 270.588418 -376.917691) (xy 270.698426 -376.841759) (xy 270.812818 -376.772607)
			(xy 270.931176 -376.710487) (xy 271.053069 -376.655628) (xy 271.178052 -376.608228) (xy 271.305669 -376.568461)
			(xy 271.435454 -376.536472) (xy 271.566933 -376.512377) (xy 271.699628 -376.496265) (xy 271.833053 -376.488195)
			(xy 271.966723 -376.488195) (xy 272.100148 -376.496265) (xy 272.232843 -376.512377) (xy 272.364322 -376.536472)
			(xy 272.494107 -376.568461) (xy 272.621724 -376.608228) (xy 272.746707 -376.655628) (xy 272.8686 -376.710487)
			(xy 272.986958 -376.772607) (xy 273.10135 -376.841759) (xy 273.211358 -376.917691) (xy 273.31658 -377.000128)
			(xy 273.416633 -377.088767) (xy 273.511151 -377.183285) (xy 273.59979 -377.283338) (xy 273.682227 -377.38856)
			(xy 273.758159 -377.498568) (xy 273.827311 -377.61296) (xy 273.889431 -377.731318) (xy 273.94429 -377.853211)
			(xy 273.99169 -377.978194) (xy 274.031457 -378.105811) (xy 274.063446 -378.235596) (xy 274.087541 -378.367075)
			(xy 274.103653 -378.49977) (xy 274.111723 -378.633195) (xy 274.112228 -378.70003) (xy 274.111723 -378.766865)
			(xy 274.103653 -378.90029) (xy 274.087541 -379.032985) (xy 274.063446 -379.164464) (xy 274.031457 -379.294249)
			(xy 273.99169 -379.421866) (xy 273.94429 -379.546849) (xy 273.889431 -379.668742) (xy 273.827311 -379.7871)
			(xy 273.758159 -379.901492) (xy 273.682227 -380.0115) (xy 273.59979 -380.116722) (xy 273.511151 -380.216775)
			(xy 273.416633 -380.311293) (xy 273.31658 -380.399932) (xy 273.211358 -380.482369) (xy 273.10135 -380.558301)
			(xy 272.986958 -380.627453) (xy 272.8686 -380.689573) (xy 272.746707 -380.744432) (xy 272.621724 -380.791832)
			(xy 272.494107 -380.831599) (xy 272.364322 -380.863588) (xy 272.232843 -380.887683) (xy 272.100148 -380.903795)
			(xy 271.966723 -380.911865) (xy 271.833053 -380.911865) (xy 271.699628 -380.903795) (xy 271.566933 -380.887683)
			(xy 271.435454 -380.863588) (xy 271.305669 -380.831599) (xy 271.178052 -380.791832) (xy 271.053069 -380.744432)
			(xy 270.931176 -380.689573) (xy 270.812818 -380.627453) (xy 270.698426 -380.558301) (xy 270.588418 -380.482369)
			(xy 270.483196 -380.399932) (xy 270.383143 -380.311293) (xy 270.288625 -380.216775) (xy 270.199986 -380.116722)
			(xy 270.117549 -380.0115) (xy 270.041617 -379.901492) (xy 269.972465 -379.7871) (xy 269.910345 -379.668742)
			(xy 269.855486 -379.546849) (xy 269.808086 -379.421866) (xy 269.768319 -379.294249) (xy 269.73633 -379.164464)
			(xy 269.712235 -379.032985) (xy 269.696123 -378.90029) (xy 269.688053 -378.766865) (xy 266.900735 -378.766865)
			(xy 266.903401 -378.900098) (xy 266.915407 -379.099845) (xy 266.935394 -379.298952) (xy 266.963332 -379.4971)
			(xy 266.999175 -379.693971) (xy 267.042866 -379.889251) (xy 267.094336 -380.082626) (xy 267.153501 -380.273787)
			(xy 267.220267 -380.462428) (xy 267.294526 -380.648247) (xy 267.376161 -380.830946) (xy 267.465041 -381.010232)
			(xy 267.561022 -381.185819) (xy 267.663952 -381.357425) (xy 267.773665 -381.524775) (xy 267.889985 -381.687602)
			(xy 268.012728 -381.845644) (xy 268.141695 -381.998649) (xy 268.276681 -382.146372) (xy 268.417469 -382.288576)
			(xy 268.563833 -382.425033) (xy 268.71554 -382.555524) (xy 268.872347 -382.679842) (xy 269.034002 -382.797786)
			(xy 269.200246 -382.909168) (xy 269.370814 -383.013809) (xy 269.545431 -383.111542) (xy 269.723819 -383.202211)
			(xy 269.905692 -383.285669) (xy 270.090759 -383.361785) (xy 270.278722 -383.430434) (xy 270.469282 -383.491509)
			(xy 270.662132 -383.54491) (xy 270.856965 -383.590553) (xy 271.053468 -383.628364) (xy 271.251327 -383.658283)
			(xy 271.450224 -383.680262) (xy 271.649841 -383.694265) (xy 271.849859 -383.70027) (xy 272.049956 -383.698268)
			(xy 272.249814 -383.688262) (xy 272.449111 -383.670267) (xy 272.647528 -383.644314) (xy 272.844748 -383.610442)
			(xy 273.040455 -383.568707) (xy 273.234336 -383.519175) (xy 273.42608 -383.461925) (xy 273.615379 -383.39705)
			(xy 273.801931 -383.324653) (xy 273.985438 -383.24485) (xy 274.165604 -383.157769) (xy 274.342143 -383.063549)
			(xy 274.51477 -382.962341) (xy 274.683209 -382.854308) (xy 274.847192 -382.739622) (xy 275.006454 -382.618467)
			(xy 275.160742 -382.491037) (xy 275.309808 -382.357536) (xy 275.453413 -382.218178) (xy 275.591327 -382.073186)
			(xy 275.72333 -381.922792) (xy 275.84921 -381.767237) (xy 275.968766 -381.60677) (xy 276.081805 -381.441649)
			(xy 276.188148 -381.272137) (xy 276.287623 -381.098506) (xy 276.380072 -380.921034) (xy 276.465346 -380.740005)
			(xy 276.543309 -380.555709) (xy 276.613836 -380.368442) (xy 276.676814 -380.178503) (xy 276.732142 -379.986196)
			(xy 276.779732 -379.79183) (xy 276.819507 -379.595715) (xy 276.851404 -379.398166) (xy 276.875372 -379.199498)
			(xy 276.891371 -379.000031) (xy 276.899377 -378.800084)
		)
		(stroke
			(width 0)
			(type solid)
		)
		(fill yes)
		(layer "F.Cu")
		(net "GND")
	)
	(gr_poly
		(pts
			(xy 157.36443 -364.544864) (xy 157.374497 -364.544435) (xy 157.39309 -364.536709) (xy 157.400498 -364.529878)
			(xy 157.96895 -363.961426) (xy 157.97579 -363.954026) (xy 157.983506 -363.935427) (xy 157.983936 -363.925358)
			(xy 157.983936 -341.909654) (xy 157.984368 -341.899588) (xy 157.992098 -341.880999) (xy 157.998922 -341.873586)
			(xy 159.868616 -340.003892) (xy 159.876016 -339.997049) (xy 159.894614 -339.989321) (xy 159.904684 -339.988906)
			(xy 202.970892 -339.988906) (xy 202.980963 -339.988485) (xy 202.99957 -339.980773) (xy 203.00696 -339.97392)
			(xy 203.853796 -339.127084) (xy 203.86064 -339.119685) (xy 203.868369 -339.101087) (xy 203.868782 -339.091016)
			(xy 203.868782 -331.900022) (xy 203.868344 -331.889959) (xy 203.860608 -331.871376) (xy 203.853796 -331.863954)
			(xy 201.326242 -329.3364) (xy 201.31913 -329.329034) (xy 201.300334 -329.321414) (xy 147.62988 -329.321414)
			(xy 147.619812 -329.321841) (xy 147.601214 -329.329562) (xy 147.593812 -329.3364) (xy 145.28546 -331.644752)
			(xy 145.278094 -331.651864) (xy 145.270474 -331.67066) (xy 145.270474 -338.84362) (xy 200.121774 -338.84362)
			(xy 200.121774 -338.843366) (xy 200.122218 -338.817071) (xy 200.129468 -338.764982) (xy 200.143797 -338.714381)
			(xy 200.164935 -338.666225) (xy 200.192482 -338.621425) (xy 200.225917 -338.58083) (xy 200.244964 -338.562696)
			(xy 200.2524 -338.55512) (xy 200.260929 -338.535706) (xy 200.261474 -338.525104) (xy 200.261474 -338.450936)
			(xy 200.261099 -338.4403) (xy 200.252527 -338.420835) (xy 200.244964 -338.413344) (xy 200.225933 -338.39519)
			(xy 200.192472 -338.354615) (xy 200.164907 -338.309825) (xy 200.143764 -338.261669) (xy 200.129442 -338.211064)
			(xy 200.122214 -338.15897) (xy 200.121774 -338.132674) (xy 200.121774 -338.13242) (xy 200.122274 -338.105168)
			(xy 200.130028 -338.05122) (xy 200.14538 -337.998924) (xy 200.168019 -337.949345) (xy 200.197483 -337.903493)
			(xy 200.233173 -337.8623) (xy 200.274362 -337.826606) (xy 200.320211 -337.797137) (xy 200.369788 -337.774494)
			(xy 200.422083 -337.759136) (xy 200.476031 -337.751377) (xy 200.503282 -337.750912) (xy 200.503536 -337.750912)
			(xy 200.529832 -337.751343) (xy 200.581922 -337.758593) (xy 200.632524 -337.772925) (xy 200.68068 -337.794065)
			(xy 200.725479 -337.821615) (xy 200.766073 -337.855053) (xy 200.784206 -337.874102) (xy 200.791776 -337.881545)
			(xy 200.811195 -337.890069) (xy 200.821798 -337.890612) (xy 200.895966 -337.890612) (xy 200.906601 -337.890226)
			(xy 200.926064 -337.88166) (xy 200.933558 -337.874102) (xy 200.951698 -337.855058) (xy 200.992278 -337.8216)
			(xy 201.037072 -337.794039) (xy 201.085229 -337.772898) (xy 201.135836 -337.758578) (xy 201.187931 -337.751352)
			(xy 201.214228 -337.750912) (xy 201.214482 -337.750912) (xy 201.241735 -337.751372) (xy 201.295687 -337.759127)
			(xy 201.347987 -337.774482) (xy 201.397568 -337.797124) (xy 201.443422 -337.826592) (xy 201.484615 -337.862286)
			(xy 201.520309 -337.90348) (xy 201.549777 -337.949334) (xy 201.572419 -337.998915) (xy 201.587773 -338.051215)
			(xy 201.595528 -338.105167) (xy 201.59599 -338.13242) (xy 201.59599 -338.132674) (xy 201.595517 -338.158968)
			(xy 201.588275 -338.211057) (xy 201.573952 -338.261658) (xy 201.552819 -338.309814) (xy 201.525277 -338.354614)
			(xy 201.491846 -338.395209) (xy 201.4728 -338.413344) (xy 201.465341 -338.4209) (xy 201.456826 -338.44033)
			(xy 201.45629 -338.450936) (xy 201.45629 -338.525104) (xy 201.456709 -338.535735) (xy 201.465252 -338.555199)
			(xy 201.4728 -338.562696) (xy 201.491863 -338.580817) (xy 201.525319 -338.621401) (xy 201.552877 -338.666199)
			(xy 201.574015 -338.71436) (xy 201.588331 -338.76497) (xy 201.595553 -338.817068) (xy 201.59599 -338.843366)
			(xy 201.59599 -338.84362) (xy 201.595541 -338.870873) (xy 201.587781 -338.924823) (xy 201.572422 -338.977119)
			(xy 201.549778 -339.026698) (xy 201.520308 -339.072549) (xy 201.484612 -339.113739) (xy 201.443418 -339.14943)
			(xy 201.397564 -339.178896) (xy 201.347983 -339.201536) (xy 201.295685 -339.216889) (xy 201.241735 -339.224643)
			(xy 201.214482 -339.225128) (xy 201.214228 -339.225128) (xy 201.187934 -339.224642) (xy 201.135847 -339.217401)
			(xy 201.085247 -339.20308) (xy 201.037091 -339.181949) (xy 200.99229 -339.15441) (xy 200.951694 -339.120982)
			(xy 200.933558 -339.101938) (xy 200.925996 -339.094485) (xy 200.906571 -339.085966) (xy 200.895966 -339.085428)
			(xy 200.821798 -339.085428) (xy 200.811166 -339.085837) (xy 200.791701 -339.094386) (xy 200.784206 -339.101938)
			(xy 200.766071 -339.120988) (xy 200.725492 -339.154447) (xy 200.680697 -339.182009) (xy 200.632538 -339.20315)
			(xy 200.58193 -339.217468) (xy 200.529833 -339.224691) (xy 200.503536 -339.225128) (xy 200.503282 -339.225128)
			(xy 200.476031 -339.224639) (xy 200.422085 -339.216881) (xy 200.369791 -339.201524) (xy 200.320215 -339.178882)
			(xy 200.274366 -339.149416) (xy 200.233176 -339.113725) (xy 200.197485 -339.072536) (xy 200.168019 -339.026687)
			(xy 200.145377 -338.977111) (xy 200.13002 -338.924817) (xy 200.122261 -338.870871) (xy 200.121774 -338.84362)
			(xy 145.270474 -338.84362) (xy 145.270474 -357.795576) (xy 145.270036 -357.805639) (xy 145.2623 -357.824221)
			(xy 145.255488 -357.831644) (xy 143.751046 -359.336086) (xy 143.743645 -359.342926) (xy 143.725047 -359.350643)
			(xy 143.714978 -359.351072) (xy 113.889282 -359.351072) (xy 113.885472 -359.347262) (xy 112.15116 -361.081574)
			(xy 112.143761 -361.088417) (xy 112.125162 -361.096141) (xy 112.115092 -361.09656) (xy 102.006654 -361.09656)
			(xy 101.996588 -361.096127) (xy 101.978 -361.088397) (xy 101.970586 -361.081574) (xy 101.837744 -360.948732)
			(xy 101.832664 -360.94543) (xy 101.83241 -360.945176) (xy 101.808255 -360.929451) (xy 101.764539 -360.891889)
			(xy 101.726972 -360.848176) (xy 101.711252 -360.824018) (xy 101.710998 -360.823764) (xy 101.707696 -360.818684)
			(xy 98.287586 -357.398574) (xy 98.280734 -357.391178) (xy 98.272996 -357.372579) (xy 98.2726 -357.362506)
			(xy 98.2726 -339.846666) (xy 98.272171 -339.836599) (xy 98.264447 -339.818003) (xy 98.257614 -339.810598)
			(xy 96.097852 -337.650836) (xy 96.097852 -337.638644) (xy 92.513404 -334.054196) (xy 92.506558 -334.046798)
			(xy 92.498824 -334.0282) (xy 92.498418 -334.018128) (xy 92.498418 -331.086714) (xy 92.49798 -331.07665)
			(xy 92.490245 -331.058067) (xy 92.483432 -331.050646) (xy 91.606878 -330.174092) (xy 91.599766 -330.166726)
			(xy 91.58097 -330.159106) (xy 5.264912 -330.159106) (xy 5.254841 -330.159527) (xy 5.236234 -330.167239)
			(xy 5.228844 -330.174092) (xy 2.516378 -332.886558) (xy 2.509012 -332.89367) (xy 2.501392 -332.912466)
			(xy 2.501392 -339.346794) (xy 2.501814 -339.356865) (xy 2.509526 -339.375472) (xy 2.516378 -339.382862)
			(xy 3.546094 -340.412578) (xy 3.553491 -340.419428) (xy 3.572089 -340.427168) (xy 3.582162 -340.427564)
			(xy 93.154246 -340.427564) (xy 93.164311 -340.427997) (xy 93.182897 -340.435731) (xy 93.190314 -340.44255)
			(xy 94.523814 -341.77605) (xy 94.530662 -341.783447) (xy 94.538392 -341.802046) (xy 94.5388 -341.812118)
			(xy 94.5388 -357.853996) (xy 94.539223 -357.864067) (xy 94.546936 -357.882672) (xy 94.553786 -357.890064)
			(xy 99.995482 -363.33176) (xy 100.002883 -363.338598) (xy 100.021482 -363.346309) (xy 100.03155 -363.346746)
			(xy 105.817416 -363.346746) (xy 105.827484 -363.347173) (xy 105.84608 -363.354897) (xy 105.853484 -363.361732)
			(xy 107.02163 -364.529878) (xy 107.029029 -364.536722) (xy 107.047627 -364.544449) (xy 107.057698 -364.544864)
		)
		(stroke
			(width 0)
			(type solid)
		)
		(fill yes)
		(layer "F.Cu")
		(net "P3V3_AUX")
	)
	(gr_poly
		(pts
			(xy 34.145474 -320.900044) (xy 34.144975 -320.805249) (xy 34.136982 -320.615827) (xy 34.121011 -320.42691)
			(xy 34.097091 -320.238835) (xy 34.065263 -320.051935) (xy 34.025584 -319.866543) (xy 33.978125 -319.682988)
			(xy 33.92297 -319.501598) (xy 33.860218 -319.322694) (xy 33.789979 -319.146594) (xy 33.712379 -318.973612)
			(xy 33.627556 -318.804055) (xy 33.53566 -318.638224) (xy 33.436855 -318.476415) (xy 33.331316 -318.318916)
			(xy 33.219232 -318.166005) (xy 33.100801 -318.017955) (xy 32.976234 -317.87503) (xy 32.845753 -317.737483)
			(xy 32.709589 -317.605559) (xy 32.567985 -317.479492) (xy 32.421192 -317.359507) (xy 32.269471 -317.245817)
			(xy 32.113093 -317.138624) (xy 31.952334 -317.038118) (xy 31.787482 -316.944479) (xy 31.618828 -316.857873)
			(xy 31.446674 -316.778454) (xy 31.271325 -316.706363) (xy 31.093092 -316.641728) (xy 30.912293 -316.584664)
			(xy 30.729249 -316.535272) (xy 30.544286 -316.493641) (xy 30.357732 -316.459845) (xy 30.169919 -316.433943)
			(xy 29.981181 -316.415981) (xy 29.791854 -316.405993) (xy 29.602274 -316.403994) (xy 29.412778 -316.409989)
			(xy 29.223703 -316.423967) (xy 29.035386 -316.445904) (xy 28.848161 -316.47576) (xy 28.662361 -316.513482)
			(xy 28.478317 -316.559003) (xy 28.296355 -316.612243) (xy 28.116799 -316.673106) (xy 27.939969 -316.741484)
			(xy 27.766178 -316.817256) (xy 27.595736 -316.900287) (xy 27.428946 -316.99043) (xy 27.266105 -317.087524)
			(xy 27.107501 -317.191396) (xy 26.953417 -317.301862) (xy 26.804127 -317.418726) (xy 26.659897 -317.541779)
			(xy 26.520982 -317.670803) (xy 26.387629 -317.805568) (xy 26.260077 -317.945836) (xy 26.138551 -318.091356)
			(xy 26.023268 -318.241869) (xy 25.914432 -318.397109) (xy 25.812238 -318.556799) (xy 25.716866 -318.720655)
			(xy 25.628487 -318.888386) (xy 25.547257 -319.059694) (xy 25.473321 -319.234273) (xy 25.406811 -319.411815)
			(xy 25.347844 -319.592002) (xy 25.296526 -319.774515) (xy 25.252947 -319.95903) (xy 25.217186 -320.145217)
			(xy 25.189306 -320.332746) (xy 25.169355 -320.521284) (xy 25.157371 -320.710496) (xy 25.153374 -320.900044)
			(xy 26.880575 -320.900044) (xy 26.884567 -320.751408) (xy 26.896532 -320.603201) (xy 26.916434 -320.455849)
			(xy 26.944217 -320.309779) (xy 26.979801 -320.16541) (xy 27.023083 -320.023159) (xy 27.073937 -319.883437)
			(xy 27.132219 -319.746645) (xy 27.197759 -319.61318) (xy 27.270368 -319.483424) (xy 27.349837 -319.357753)
			(xy 27.435938 -319.236529) (xy 27.528421 -319.120101) (xy 27.62702 -319.008806) (xy 27.731452 -318.902963)
			(xy 27.841414 -318.802878) (xy 27.956589 -318.70884) (xy 28.076646 -318.62112) (xy 28.201239 -318.539971)
			(xy 28.330008 -318.465626) (xy 28.462582 -318.3983) (xy 28.598578 -318.338188) (xy 28.737605 -318.285462)
			(xy 28.879262 -318.240274) (xy 29.02314 -318.202756) (xy 29.168825 -318.173014) (xy 29.315896 -318.151135)
			(xy 29.463929 -318.137182) (xy 29.612498 -318.131195) (xy 29.761174 -318.133191) (xy 29.909529 -318.143164)
			(xy 30.057134 -318.161087) (xy 30.203565 -318.186907) (xy 30.348399 -318.220549) (xy 30.491217 -318.261917)
			(xy 30.63161 -318.310891) (xy 30.769171 -318.367331) (xy 30.903505 -318.431073) (xy 31.034224 -318.501934)
			(xy 31.16095 -318.579709) (xy 31.283319 -318.664174) (xy 31.400978 -318.755086) (xy 31.513587 -318.852182)
			(xy 31.620822 -318.955183) (xy 31.722374 -319.063792) (xy 31.81795 -319.177694) (xy 31.907274 -319.296563)
			(xy 31.990089 -319.420055) (xy 32.066156 -319.547814) (xy 32.135255 -319.679472) (xy 32.197188 -319.81465)
			(xy 32.251776 -319.952956) (xy 32.298861 -320.093994) (xy 32.338308 -320.237355) (xy 32.370003 -320.382627)
			(xy 32.393854 -320.529391) (xy 32.409794 -320.677224) (xy 32.417775 -320.825699) (xy 32.418274 -320.900044)
			(xy 32.417775 -320.974389) (xy 32.409794 -321.122864) (xy 32.393854 -321.270697) (xy 32.370003 -321.417461)
			(xy 32.338308 -321.562733) (xy 32.298861 -321.706094) (xy 32.251776 -321.847132) (xy 32.197188 -321.985438)
			(xy 32.135255 -322.120616) (xy 32.066156 -322.252274) (xy 31.990089 -322.380033) (xy 31.907274 -322.503525)
			(xy 31.81795 -322.622394) (xy 31.722374 -322.736296) (xy 31.620822 -322.844905) (xy 31.513587 -322.947906)
			(xy 31.400978 -323.045002) (xy 31.283319 -323.135914) (xy 31.16095 -323.220379) (xy 31.034224 -323.298154)
			(xy 30.903505 -323.369015) (xy 30.769171 -323.432757) (xy 30.63161 -323.489197) (xy 30.491217 -323.538171)
			(xy 30.348399 -323.579539) (xy 30.203565 -323.613181) (xy 30.057134 -323.639001) (xy 29.909529 -323.656924)
			(xy 29.761174 -323.666897) (xy 29.612498 -323.668893) (xy 29.463929 -323.662906) (xy 29.315896 -323.648953)
			(xy 29.168825 -323.627074) (xy 29.02314 -323.597332) (xy 28.879262 -323.559814) (xy 28.737605 -323.514626)
			(xy 28.598578 -323.4619) (xy 28.462582 -323.401788) (xy 28.330008 -323.334462) (xy 28.201239 -323.260117)
			(xy 28.076646 -323.178968) (xy 27.956589 -323.091248) (xy 27.841414 -322.99721) (xy 27.731452 -322.897125)
			(xy 27.62702 -322.791282) (xy 27.528421 -322.679987) (xy 27.435938 -322.563559) (xy 27.349837 -322.442335)
			(xy 27.270368 -322.316664) (xy 27.197759 -322.186908) (xy 27.132219 -322.053443) (xy 27.073937 -321.916651)
			(xy 27.023083 -321.776929) (xy 26.979801 -321.634678) (xy 26.944217 -321.490309) (xy 26.916434 -321.344239)
			(xy 26.896532 -321.196887) (xy 26.884567 -321.04868) (xy 26.880575 -320.900044) (xy 25.153374 -320.900044)
			(xy 25.157371 -321.089592) (xy 25.169355 -321.278804) (xy 25.189306 -321.467342) (xy 25.217186 -321.654871)
			(xy 25.252947 -321.841058) (xy 25.296526 -322.025573) (xy 25.347844 -322.208086) (xy 25.406811 -322.388273)
			(xy 25.473321 -322.565815) (xy 25.547257 -322.740394) (xy 25.628487 -322.911702) (xy 25.716866 -323.079433)
			(xy 25.812238 -323.243289) (xy 25.914432 -323.402979) (xy 26.023268 -323.558219) (xy 26.138551 -323.708732)
			(xy 26.260077 -323.854252) (xy 26.387629 -323.99452) (xy 26.520982 -324.129285) (xy 26.659897 -324.258309)
			(xy 26.804127 -324.381362) (xy 26.953417 -324.498226) (xy 27.107501 -324.608692) (xy 27.266105 -324.712564)
			(xy 27.428946 -324.809658) (xy 27.595736 -324.899801) (xy 27.766178 -324.982832) (xy 27.939969 -325.058604)
			(xy 28.116799 -325.126982) (xy 28.296355 -325.187845) (xy 28.478317 -325.241085) (xy 28.662361 -325.286606)
			(xy 28.848161 -325.324328) (xy 29.035386 -325.354184) (xy 29.223703 -325.376121) (xy 29.412778 -325.390099)
			(xy 29.602274 -325.396094) (xy 29.791854 -325.394095) (xy 29.981181 -325.384107) (xy 30.169919 -325.366145)
			(xy 30.357732 -325.340243) (xy 30.544286 -325.306447) (xy 30.729249 -325.264816) (xy 30.912293 -325.215424)
			(xy 31.093092 -325.15836) (xy 31.271325 -325.093725) (xy 31.446674 -325.021634) (xy 31.618828 -324.942215)
			(xy 31.787482 -324.855609) (xy 31.952334 -324.76197) (xy 32.113093 -324.661464) (xy 32.269471 -324.554271)
			(xy 32.421192 -324.440581) (xy 32.567985 -324.320596) (xy 32.709589 -324.194529) (xy 32.845753 -324.062605)
			(xy 32.976234 -323.925058) (xy 33.100801 -323.782133) (xy 33.219232 -323.634083) (xy 33.331316 -323.481172)
			(xy 33.436855 -323.323673) (xy 33.53566 -323.161864) (xy 33.627556 -322.996033) (xy 33.712379 -322.826476)
			(xy 33.789979 -322.653494) (xy 33.860218 -322.477394) (xy 33.92297 -322.29849) (xy 33.978125 -322.1171)
			(xy 34.025584 -321.933545) (xy 34.065263 -321.748153) (xy 34.097091 -321.561253) (xy 34.121011 -321.373178)
			(xy 34.136982 -321.184261) (xy 34.144975 -320.994839)
		)
		(stroke
			(width 0)
			(type solid)
		)
		(fill yes)
		(layer "F.Cu")
		(net "GND")
	)
	(gr_poly
		(pts
			(xy 34.145474 -270.89989) (xy 34.144975 -270.805095) (xy 34.136982 -270.615673) (xy 34.121011 -270.426756)
			(xy 34.097091 -270.238681) (xy 34.065263 -270.051781) (xy 34.025584 -269.866389) (xy 33.978125 -269.682834)
			(xy 33.92297 -269.501444) (xy 33.860218 -269.32254) (xy 33.789979 -269.14644) (xy 33.712379 -268.973458)
			(xy 33.627556 -268.803901) (xy 33.53566 -268.63807) (xy 33.436855 -268.476261) (xy 33.331316 -268.318762)
			(xy 33.219232 -268.165851) (xy 33.100801 -268.017801) (xy 32.976234 -267.874876) (xy 32.845753 -267.737329)
			(xy 32.709589 -267.605405) (xy 32.567985 -267.479338) (xy 32.421192 -267.359353) (xy 32.269471 -267.245663)
			(xy 32.113093 -267.13847) (xy 31.952334 -267.037964) (xy 31.787482 -266.944325) (xy 31.618828 -266.857719)
			(xy 31.446674 -266.7783) (xy 31.271325 -266.706209) (xy 31.093092 -266.641574) (xy 30.912293 -266.58451)
			(xy 30.729249 -266.535118) (xy 30.544286 -266.493487) (xy 30.357732 -266.459691) (xy 30.169919 -266.433789)
			(xy 29.981181 -266.415827) (xy 29.791854 -266.405839) (xy 29.602274 -266.40384) (xy 29.412778 -266.409835)
			(xy 29.223703 -266.423813) (xy 29.035386 -266.44575) (xy 28.848161 -266.475606) (xy 28.662361 -266.513328)
			(xy 28.478317 -266.558849) (xy 28.296355 -266.612089) (xy 28.116799 -266.672952) (xy 27.939969 -266.74133)
			(xy 27.766178 -266.817102) (xy 27.595736 -266.900133) (xy 27.428946 -266.990276) (xy 27.266105 -267.08737)
			(xy 27.107501 -267.191242) (xy 26.953417 -267.301708) (xy 26.804127 -267.418572) (xy 26.659897 -267.541625)
			(xy 26.520982 -267.670649) (xy 26.387629 -267.805414) (xy 26.260077 -267.945682) (xy 26.138551 -268.091202)
			(xy 26.023268 -268.241715) (xy 25.914432 -268.396955) (xy 25.812238 -268.556645) (xy 25.716866 -268.720501)
			(xy 25.628487 -268.888232) (xy 25.547257 -269.05954) (xy 25.473321 -269.234119) (xy 25.406811 -269.411661)
			(xy 25.347844 -269.591848) (xy 25.296526 -269.774361) (xy 25.252947 -269.958876) (xy 25.217186 -270.145063)
			(xy 25.189306 -270.332592) (xy 25.169355 -270.52113) (xy 25.157371 -270.710342) (xy 25.153374 -270.89989)
			(xy 26.880575 -270.89989) (xy 26.884567 -270.751254) (xy 26.896532 -270.603047) (xy 26.916434 -270.455695)
			(xy 26.944217 -270.309625) (xy 26.979801 -270.165256) (xy 27.023083 -270.023005) (xy 27.073937 -269.883283)
			(xy 27.132219 -269.746491) (xy 27.197759 -269.613026) (xy 27.270368 -269.48327) (xy 27.349837 -269.357599)
			(xy 27.435938 -269.236375) (xy 27.528421 -269.119947) (xy 27.62702 -269.008652) (xy 27.731452 -268.902809)
			(xy 27.841414 -268.802724) (xy 27.956589 -268.708686) (xy 28.076646 -268.620966) (xy 28.201239 -268.539817)
			(xy 28.330008 -268.465472) (xy 28.462582 -268.398146) (xy 28.598578 -268.338034) (xy 28.737605 -268.285308)
			(xy 28.879262 -268.24012) (xy 29.02314 -268.202602) (xy 29.168825 -268.17286) (xy 29.315896 -268.150981)
			(xy 29.463929 -268.137028) (xy 29.612498 -268.131041) (xy 29.761174 -268.133037) (xy 29.909529 -268.14301)
			(xy 30.057134 -268.160933) (xy 30.203565 -268.186753) (xy 30.348399 -268.220395) (xy 30.491217 -268.261763)
			(xy 30.63161 -268.310737) (xy 30.769171 -268.367177) (xy 30.903505 -268.430919) (xy 31.034224 -268.50178)
			(xy 31.16095 -268.579555) (xy 31.283319 -268.66402) (xy 31.400978 -268.754932) (xy 31.513587 -268.852028)
			(xy 31.620822 -268.955029) (xy 31.722374 -269.063638) (xy 31.81795 -269.17754) (xy 31.907274 -269.296409)
			(xy 31.990089 -269.419901) (xy 32.066156 -269.54766) (xy 32.135255 -269.679318) (xy 32.197188 -269.814496)
			(xy 32.251776 -269.952802) (xy 32.298861 -270.09384) (xy 32.338308 -270.237201) (xy 32.370003 -270.382473)
			(xy 32.393854 -270.529237) (xy 32.409794 -270.67707) (xy 32.417775 -270.825545) (xy 32.418274 -270.89989)
			(xy 32.417775 -270.974235) (xy 32.409794 -271.12271) (xy 32.393854 -271.270543) (xy 32.370003 -271.417307)
			(xy 32.338308 -271.562579) (xy 32.298861 -271.70594) (xy 32.251776 -271.846978) (xy 32.197188 -271.985284)
			(xy 32.135255 -272.120462) (xy 32.066156 -272.25212) (xy 31.990089 -272.379879) (xy 31.907274 -272.503371)
			(xy 31.81795 -272.62224) (xy 31.722374 -272.736142) (xy 31.620822 -272.844751) (xy 31.513587 -272.947752)
			(xy 31.400978 -273.044848) (xy 31.283319 -273.13576) (xy 31.16095 -273.220225) (xy 31.034224 -273.298)
			(xy 30.903505 -273.368861) (xy 30.769171 -273.432603) (xy 30.63161 -273.489043) (xy 30.491217 -273.538017)
			(xy 30.348399 -273.579385) (xy 30.203565 -273.613027) (xy 30.057134 -273.638847) (xy 29.909529 -273.65677)
			(xy 29.761174 -273.666743) (xy 29.612498 -273.668739) (xy 29.463929 -273.662752) (xy 29.315896 -273.648799)
			(xy 29.168825 -273.62692) (xy 29.02314 -273.597178) (xy 28.879262 -273.55966) (xy 28.737605 -273.514472)
			(xy 28.598578 -273.461746) (xy 28.462582 -273.401634) (xy 28.330008 -273.334308) (xy 28.201239 -273.259963)
			(xy 28.076646 -273.178814) (xy 27.956589 -273.091094) (xy 27.841414 -272.997056) (xy 27.731452 -272.896971)
			(xy 27.62702 -272.791128) (xy 27.528421 -272.679833) (xy 27.435938 -272.563405) (xy 27.349837 -272.442181)
			(xy 27.270368 -272.31651) (xy 27.197759 -272.186754) (xy 27.132219 -272.053289) (xy 27.073937 -271.916497)
			(xy 27.023083 -271.776775) (xy 26.979801 -271.634524) (xy 26.944217 -271.490155) (xy 26.916434 -271.344085)
			(xy 26.896532 -271.196733) (xy 26.884567 -271.048526) (xy 26.880575 -270.89989) (xy 25.153374 -270.89989)
			(xy 25.157371 -271.089438) (xy 25.169355 -271.27865) (xy 25.189306 -271.467188) (xy 25.217186 -271.654717)
			(xy 25.252947 -271.840904) (xy 25.296526 -272.025419) (xy 25.347844 -272.207932) (xy 25.406811 -272.388119)
			(xy 25.473321 -272.565661) (xy 25.547257 -272.74024) (xy 25.628487 -272.911548) (xy 25.716866 -273.079279)
			(xy 25.812238 -273.243135) (xy 25.914432 -273.402825) (xy 26.023268 -273.558065) (xy 26.138551 -273.708578)
			(xy 26.260077 -273.854098) (xy 26.387629 -273.994366) (xy 26.520982 -274.129131) (xy 26.659897 -274.258155)
			(xy 26.804127 -274.381208) (xy 26.953417 -274.498072) (xy 27.107501 -274.608538) (xy 27.266105 -274.71241)
			(xy 27.428946 -274.809504) (xy 27.595736 -274.899647) (xy 27.766178 -274.982678) (xy 27.939969 -275.05845)
			(xy 28.116799 -275.126828) (xy 28.296355 -275.187691) (xy 28.478317 -275.240931) (xy 28.662361 -275.286452)
			(xy 28.848161 -275.324174) (xy 29.035386 -275.35403) (xy 29.223703 -275.375967) (xy 29.412778 -275.389945)
			(xy 29.602274 -275.39594) (xy 29.791854 -275.393941) (xy 29.981181 -275.383953) (xy 30.169919 -275.365991)
			(xy 30.357732 -275.340089) (xy 30.544286 -275.306293) (xy 30.729249 -275.264662) (xy 30.912293 -275.21527)
			(xy 31.093092 -275.158206) (xy 31.271325 -275.093571) (xy 31.446674 -275.02148) (xy 31.618828 -274.942061)
			(xy 31.787482 -274.855455) (xy 31.952334 -274.761816) (xy 32.113093 -274.66131) (xy 32.269471 -274.554117)
			(xy 32.421192 -274.440427) (xy 32.567985 -274.320442) (xy 32.709589 -274.194375) (xy 32.845753 -274.062451)
			(xy 32.976234 -273.924904) (xy 33.100801 -273.781979) (xy 33.219232 -273.633929) (xy 33.331316 -273.481018)
			(xy 33.436855 -273.323519) (xy 33.53566 -273.16171) (xy 33.627556 -272.995879) (xy 33.712379 -272.826322)
			(xy 33.789979 -272.65334) (xy 33.860218 -272.47724) (xy 33.92297 -272.298336) (xy 33.978125 -272.116946)
			(xy 34.025584 -271.933391) (xy 34.065263 -271.747999) (xy 34.097091 -271.561099) (xy 34.121011 -271.373024)
			(xy 34.136982 -271.184107) (xy 34.144975 -270.994685)
		)
		(stroke
			(width 0)
			(type solid)
		)
		(fill yes)
		(layer "F.Cu")
		(net "GND")
	)
	(gr_poly
		(pts
			(xy 94.145608 -320.900044) (xy 94.145109 -320.805249) (xy 94.137116 -320.615827) (xy 94.121145 -320.42691)
			(xy 94.097225 -320.238835) (xy 94.065397 -320.051935) (xy 94.025718 -319.866543) (xy 93.978259 -319.682988)
			(xy 93.923104 -319.501598) (xy 93.860352 -319.322694) (xy 93.790113 -319.146594) (xy 93.712513 -318.973612)
			(xy 93.62769 -318.804055) (xy 93.535794 -318.638224) (xy 93.436989 -318.476415) (xy 93.33145 -318.318916)
			(xy 93.219366 -318.166005) (xy 93.100935 -318.017955) (xy 92.976368 -317.87503) (xy 92.845887 -317.737483)
			(xy 92.709723 -317.605559) (xy 92.568119 -317.479492) (xy 92.421326 -317.359507) (xy 92.269605 -317.245817)
			(xy 92.113227 -317.138624) (xy 91.952468 -317.038118) (xy 91.787616 -316.944479) (xy 91.618962 -316.857873)
			(xy 91.446808 -316.778454) (xy 91.271459 -316.706363) (xy 91.093226 -316.641728) (xy 90.912427 -316.584664)
			(xy 90.729383 -316.535272) (xy 90.54442 -316.493641) (xy 90.357866 -316.459845) (xy 90.170053 -316.433943)
			(xy 89.981315 -316.415981) (xy 89.791988 -316.405993) (xy 89.602408 -316.403994) (xy 89.412912 -316.409989)
			(xy 89.223837 -316.423967) (xy 89.03552 -316.445904) (xy 88.848295 -316.47576) (xy 88.662495 -316.513482)
			(xy 88.478451 -316.559003) (xy 88.296489 -316.612243) (xy 88.116933 -316.673106) (xy 87.940103 -316.741484)
			(xy 87.766312 -316.817256) (xy 87.59587 -316.900287) (xy 87.42908 -316.99043) (xy 87.266239 -317.087524)
			(xy 87.107635 -317.191396) (xy 86.953551 -317.301862) (xy 86.804261 -317.418726) (xy 86.660031 -317.541779)
			(xy 86.521116 -317.670803) (xy 86.387763 -317.805568) (xy 86.260211 -317.945836) (xy 86.138685 -318.091356)
			(xy 86.023402 -318.241869) (xy 85.914566 -318.397109) (xy 85.812372 -318.556799) (xy 85.717 -318.720655)
			(xy 85.628621 -318.888386) (xy 85.547391 -319.059694) (xy 85.473455 -319.234273) (xy 85.406945 -319.411815)
			(xy 85.347978 -319.592002) (xy 85.29666 -319.774515) (xy 85.253081 -319.95903) (xy 85.21732 -320.145217)
			(xy 85.18944 -320.332746) (xy 85.169489 -320.521284) (xy 85.157505 -320.710496) (xy 85.153508 -320.900044)
			(xy 86.880709 -320.900044) (xy 86.884701 -320.751408) (xy 86.896666 -320.603201) (xy 86.916568 -320.455849)
			(xy 86.944351 -320.309779) (xy 86.979935 -320.16541) (xy 87.023217 -320.023159) (xy 87.074071 -319.883437)
			(xy 87.132353 -319.746645) (xy 87.197893 -319.61318) (xy 87.270502 -319.483424) (xy 87.349971 -319.357753)
			(xy 87.436072 -319.236529) (xy 87.528555 -319.120101) (xy 87.627154 -319.008806) (xy 87.731586 -318.902963)
			(xy 87.841548 -318.802878) (xy 87.956723 -318.70884) (xy 88.07678 -318.62112) (xy 88.201373 -318.539971)
			(xy 88.330142 -318.465626) (xy 88.462716 -318.3983) (xy 88.598712 -318.338188) (xy 88.737739 -318.285462)
			(xy 88.879396 -318.240274) (xy 89.023274 -318.202756) (xy 89.168959 -318.173014) (xy 89.31603 -318.151135)
			(xy 89.464063 -318.137182) (xy 89.612632 -318.131195) (xy 89.761308 -318.133191) (xy 89.909663 -318.143164)
			(xy 90.057268 -318.161087) (xy 90.203699 -318.186907) (xy 90.348533 -318.220549) (xy 90.491351 -318.261917)
			(xy 90.631744 -318.310891) (xy 90.769305 -318.367331) (xy 90.903639 -318.431073) (xy 91.034358 -318.501934)
			(xy 91.161084 -318.579709) (xy 91.283453 -318.664174) (xy 91.401112 -318.755086) (xy 91.513721 -318.852182)
			(xy 91.620956 -318.955183) (xy 91.722508 -319.063792) (xy 91.818084 -319.177694) (xy 91.907408 -319.296563)
			(xy 91.990223 -319.420055) (xy 92.06629 -319.547814) (xy 92.135389 -319.679472) (xy 92.197322 -319.81465)
			(xy 92.25191 -319.952956) (xy 92.298995 -320.093994) (xy 92.338442 -320.237355) (xy 92.370137 -320.382627)
			(xy 92.393988 -320.529391) (xy 92.409928 -320.677224) (xy 92.417909 -320.825699) (xy 92.418408 -320.900044)
			(xy 92.417909 -320.974389) (xy 92.409928 -321.122864) (xy 92.393988 -321.270697) (xy 92.370137 -321.417461)
			(xy 92.338442 -321.562733) (xy 92.298995 -321.706094) (xy 92.25191 -321.847132) (xy 92.197322 -321.985438)
			(xy 92.135389 -322.120616) (xy 92.06629 -322.252274) (xy 91.990223 -322.380033) (xy 91.907408 -322.503525)
			(xy 91.818084 -322.622394) (xy 91.722508 -322.736296) (xy 91.620956 -322.844905) (xy 91.513721 -322.947906)
			(xy 91.401112 -323.045002) (xy 91.283453 -323.135914) (xy 91.161084 -323.220379) (xy 91.034358 -323.298154)
			(xy 90.903639 -323.369015) (xy 90.769305 -323.432757) (xy 90.631744 -323.489197) (xy 90.491351 -323.538171)
			(xy 90.348533 -323.579539) (xy 90.203699 -323.613181) (xy 90.057268 -323.639001) (xy 89.909663 -323.656924)
			(xy 89.761308 -323.666897) (xy 89.612632 -323.668893) (xy 89.464063 -323.662906) (xy 89.31603 -323.648953)
			(xy 89.168959 -323.627074) (xy 89.023274 -323.597332) (xy 88.879396 -323.559814) (xy 88.737739 -323.514626)
			(xy 88.598712 -323.4619) (xy 88.462716 -323.401788) (xy 88.330142 -323.334462) (xy 88.201373 -323.260117)
			(xy 88.07678 -323.178968) (xy 87.956723 -323.091248) (xy 87.841548 -322.99721) (xy 87.731586 -322.897125)
			(xy 87.627154 -322.791282) (xy 87.528555 -322.679987) (xy 87.436072 -322.563559) (xy 87.349971 -322.442335)
			(xy 87.270502 -322.316664) (xy 87.197893 -322.186908) (xy 87.132353 -322.053443) (xy 87.074071 -321.916651)
			(xy 87.023217 -321.776929) (xy 86.979935 -321.634678) (xy 86.944351 -321.490309) (xy 86.916568 -321.344239)
			(xy 86.896666 -321.196887) (xy 86.884701 -321.04868) (xy 86.880709 -320.900044) (xy 85.153508 -320.900044)
			(xy 85.157505 -321.089592) (xy 85.169489 -321.278804) (xy 85.18944 -321.467342) (xy 85.21732 -321.654871)
			(xy 85.253081 -321.841058) (xy 85.29666 -322.025573) (xy 85.347978 -322.208086) (xy 85.406945 -322.388273)
			(xy 85.473455 -322.565815) (xy 85.547391 -322.740394) (xy 85.628621 -322.911702) (xy 85.717 -323.079433)
			(xy 85.812372 -323.243289) (xy 85.914566 -323.402979) (xy 86.023402 -323.558219) (xy 86.138685 -323.708732)
			(xy 86.260211 -323.854252) (xy 86.387763 -323.99452) (xy 86.521116 -324.129285) (xy 86.660031 -324.258309)
			(xy 86.804261 -324.381362) (xy 86.953551 -324.498226) (xy 87.107635 -324.608692) (xy 87.266239 -324.712564)
			(xy 87.42908 -324.809658) (xy 87.59587 -324.899801) (xy 87.766312 -324.982832) (xy 87.940103 -325.058604)
			(xy 88.116933 -325.126982) (xy 88.296489 -325.187845) (xy 88.478451 -325.241085) (xy 88.662495 -325.286606)
			(xy 88.848295 -325.324328) (xy 89.03552 -325.354184) (xy 89.223837 -325.376121) (xy 89.412912 -325.390099)
			(xy 89.602408 -325.396094) (xy 89.791988 -325.394095) (xy 89.981315 -325.384107) (xy 90.170053 -325.366145)
			(xy 90.357866 -325.340243) (xy 90.54442 -325.306447) (xy 90.729383 -325.264816) (xy 90.912427 -325.215424)
			(xy 91.093226 -325.15836) (xy 91.271459 -325.093725) (xy 91.446808 -325.021634) (xy 91.618962 -324.942215)
			(xy 91.787616 -324.855609) (xy 91.952468 -324.76197) (xy 92.113227 -324.661464) (xy 92.269605 -324.554271)
			(xy 92.421326 -324.440581) (xy 92.568119 -324.320596) (xy 92.709723 -324.194529) (xy 92.845887 -324.062605)
			(xy 92.976368 -323.925058) (xy 93.100935 -323.782133) (xy 93.219366 -323.634083) (xy 93.33145 -323.481172)
			(xy 93.436989 -323.323673) (xy 93.535794 -323.161864) (xy 93.62769 -322.996033) (xy 93.712513 -322.826476)
			(xy 93.790113 -322.653494) (xy 93.860352 -322.477394) (xy 93.923104 -322.29849) (xy 93.978259 -322.1171)
			(xy 94.025718 -321.933545) (xy 94.065397 -321.748153) (xy 94.097225 -321.561253) (xy 94.121145 -321.373178)
			(xy 94.137116 -321.184261) (xy 94.145109 -320.994839)
		)
		(stroke
			(width 0)
			(type solid)
		)
		(fill yes)
		(layer "F.Cu")
		(net "GND")
	)
	(gr_poly
		(pts
			(xy 94.145608 -270.89989) (xy 94.145109 -270.805095) (xy 94.137116 -270.615673) (xy 94.121145 -270.426756)
			(xy 94.097225 -270.238681) (xy 94.065397 -270.051781) (xy 94.025718 -269.866389) (xy 93.978259 -269.682834)
			(xy 93.923104 -269.501444) (xy 93.860352 -269.32254) (xy 93.790113 -269.14644) (xy 93.712513 -268.973458)
			(xy 93.62769 -268.803901) (xy 93.535794 -268.63807) (xy 93.436989 -268.476261) (xy 93.33145 -268.318762)
			(xy 93.219366 -268.165851) (xy 93.100935 -268.017801) (xy 92.976368 -267.874876) (xy 92.845887 -267.737329)
			(xy 92.709723 -267.605405) (xy 92.568119 -267.479338) (xy 92.421326 -267.359353) (xy 92.269605 -267.245663)
			(xy 92.113227 -267.13847) (xy 91.952468 -267.037964) (xy 91.787616 -266.944325) (xy 91.618962 -266.857719)
			(xy 91.446808 -266.7783) (xy 91.271459 -266.706209) (xy 91.093226 -266.641574) (xy 90.912427 -266.58451)
			(xy 90.729383 -266.535118) (xy 90.54442 -266.493487) (xy 90.357866 -266.459691) (xy 90.170053 -266.433789)
			(xy 89.981315 -266.415827) (xy 89.791988 -266.405839) (xy 89.602408 -266.40384) (xy 89.412912 -266.409835)
			(xy 89.223837 -266.423813) (xy 89.03552 -266.44575) (xy 88.848295 -266.475606) (xy 88.662495 -266.513328)
			(xy 88.478451 -266.558849) (xy 88.296489 -266.612089) (xy 88.116933 -266.672952) (xy 87.940103 -266.74133)
			(xy 87.766312 -266.817102) (xy 87.59587 -266.900133) (xy 87.42908 -266.990276) (xy 87.266239 -267.08737)
			(xy 87.107635 -267.191242) (xy 86.953551 -267.301708) (xy 86.804261 -267.418572) (xy 86.660031 -267.541625)
			(xy 86.521116 -267.670649) (xy 86.387763 -267.805414) (xy 86.260211 -267.945682) (xy 86.138685 -268.091202)
			(xy 86.023402 -268.241715) (xy 85.914566 -268.396955) (xy 85.812372 -268.556645) (xy 85.717 -268.720501)
			(xy 85.628621 -268.888232) (xy 85.547391 -269.05954) (xy 85.473455 -269.234119) (xy 85.406945 -269.411661)
			(xy 85.347978 -269.591848) (xy 85.29666 -269.774361) (xy 85.253081 -269.958876) (xy 85.21732 -270.145063)
			(xy 85.18944 -270.332592) (xy 85.169489 -270.52113) (xy 85.157505 -270.710342) (xy 85.153508 -270.89989)
			(xy 86.880709 -270.89989) (xy 86.884701 -270.751254) (xy 86.896666 -270.603047) (xy 86.916568 -270.455695)
			(xy 86.944351 -270.309625) (xy 86.979935 -270.165256) (xy 87.023217 -270.023005) (xy 87.074071 -269.883283)
			(xy 87.132353 -269.746491) (xy 87.197893 -269.613026) (xy 87.270502 -269.48327) (xy 87.349971 -269.357599)
			(xy 87.436072 -269.236375) (xy 87.528555 -269.119947) (xy 87.627154 -269.008652) (xy 87.731586 -268.902809)
			(xy 87.841548 -268.802724) (xy 87.956723 -268.708686) (xy 88.07678 -268.620966) (xy 88.201373 -268.539817)
			(xy 88.330142 -268.465472) (xy 88.462716 -268.398146) (xy 88.598712 -268.338034) (xy 88.737739 -268.285308)
			(xy 88.879396 -268.24012) (xy 89.023274 -268.202602) (xy 89.168959 -268.17286) (xy 89.31603 -268.150981)
			(xy 89.464063 -268.137028) (xy 89.612632 -268.131041) (xy 89.761308 -268.133037) (xy 89.909663 -268.14301)
			(xy 90.057268 -268.160933) (xy 90.203699 -268.186753) (xy 90.348533 -268.220395) (xy 90.491351 -268.261763)
			(xy 90.631744 -268.310737) (xy 90.769305 -268.367177) (xy 90.903639 -268.430919) (xy 91.034358 -268.50178)
			(xy 91.161084 -268.579555) (xy 91.283453 -268.66402) (xy 91.401112 -268.754932) (xy 91.513721 -268.852028)
			(xy 91.620956 -268.955029) (xy 91.722508 -269.063638) (xy 91.818084 -269.17754) (xy 91.907408 -269.296409)
			(xy 91.990223 -269.419901) (xy 92.06629 -269.54766) (xy 92.135389 -269.679318) (xy 92.197322 -269.814496)
			(xy 92.25191 -269.952802) (xy 92.298995 -270.09384) (xy 92.338442 -270.237201) (xy 92.370137 -270.382473)
			(xy 92.393988 -270.529237) (xy 92.409928 -270.67707) (xy 92.417909 -270.825545) (xy 92.418408 -270.89989)
			(xy 92.417909 -270.974235) (xy 92.409928 -271.12271) (xy 92.393988 -271.270543) (xy 92.370137 -271.417307)
			(xy 92.338442 -271.562579) (xy 92.298995 -271.70594) (xy 92.25191 -271.846978) (xy 92.197322 -271.985284)
			(xy 92.135389 -272.120462) (xy 92.06629 -272.25212) (xy 91.990223 -272.379879) (xy 91.907408 -272.503371)
			(xy 91.818084 -272.62224) (xy 91.722508 -272.736142) (xy 91.620956 -272.844751) (xy 91.513721 -272.947752)
			(xy 91.401112 -273.044848) (xy 91.283453 -273.13576) (xy 91.161084 -273.220225) (xy 91.034358 -273.298)
			(xy 90.903639 -273.368861) (xy 90.769305 -273.432603) (xy 90.631744 -273.489043) (xy 90.491351 -273.538017)
			(xy 90.348533 -273.579385) (xy 90.203699 -273.613027) (xy 90.057268 -273.638847) (xy 89.909663 -273.65677)
			(xy 89.761308 -273.666743) (xy 89.612632 -273.668739) (xy 89.464063 -273.662752) (xy 89.31603 -273.648799)
			(xy 89.168959 -273.62692) (xy 89.023274 -273.597178) (xy 88.879396 -273.55966) (xy 88.737739 -273.514472)
			(xy 88.598712 -273.461746) (xy 88.462716 -273.401634) (xy 88.330142 -273.334308) (xy 88.201373 -273.259963)
			(xy 88.07678 -273.178814) (xy 87.956723 -273.091094) (xy 87.841548 -272.997056) (xy 87.731586 -272.896971)
			(xy 87.627154 -272.791128) (xy 87.528555 -272.679833) (xy 87.436072 -272.563405) (xy 87.349971 -272.442181)
			(xy 87.270502 -272.31651) (xy 87.197893 -272.186754) (xy 87.132353 -272.053289) (xy 87.074071 -271.916497)
			(xy 87.023217 -271.776775) (xy 86.979935 -271.634524) (xy 86.944351 -271.490155) (xy 86.916568 -271.344085)
			(xy 86.896666 -271.196733) (xy 86.884701 -271.048526) (xy 86.880709 -270.89989) (xy 85.153508 -270.89989)
			(xy 85.157505 -271.089438) (xy 85.169489 -271.27865) (xy 85.18944 -271.467188) (xy 85.21732 -271.654717)
			(xy 85.253081 -271.840904) (xy 85.29666 -272.025419) (xy 85.347978 -272.207932) (xy 85.406945 -272.388119)
			(xy 85.473455 -272.565661) (xy 85.547391 -272.74024) (xy 85.628621 -272.911548) (xy 85.717 -273.079279)
			(xy 85.812372 -273.243135) (xy 85.914566 -273.402825) (xy 86.023402 -273.558065) (xy 86.138685 -273.708578)
			(xy 86.260211 -273.854098) (xy 86.387763 -273.994366) (xy 86.521116 -274.129131) (xy 86.660031 -274.258155)
			(xy 86.804261 -274.381208) (xy 86.953551 -274.498072) (xy 87.107635 -274.608538) (xy 87.266239 -274.71241)
			(xy 87.42908 -274.809504) (xy 87.59587 -274.899647) (xy 87.766312 -274.982678) (xy 87.940103 -275.05845)
			(xy 88.116933 -275.126828) (xy 88.296489 -275.187691) (xy 88.478451 -275.240931) (xy 88.662495 -275.286452)
			(xy 88.848295 -275.324174) (xy 89.03552 -275.35403) (xy 89.223837 -275.375967) (xy 89.412912 -275.389945)
			(xy 89.602408 -275.39594) (xy 89.791988 -275.393941) (xy 89.981315 -275.383953) (xy 90.170053 -275.365991)
			(xy 90.357866 -275.340089) (xy 90.54442 -275.306293) (xy 90.729383 -275.264662) (xy 90.912427 -275.21527)
			(xy 91.093226 -275.158206) (xy 91.271459 -275.093571) (xy 91.446808 -275.02148) (xy 91.618962 -274.942061)
			(xy 91.787616 -274.855455) (xy 91.952468 -274.761816) (xy 92.113227 -274.66131) (xy 92.269605 -274.554117)
			(xy 92.421326 -274.440427) (xy 92.568119 -274.320442) (xy 92.709723 -274.194375) (xy 92.845887 -274.062451)
			(xy 92.976368 -273.924904) (xy 93.100935 -273.781979) (xy 93.219366 -273.633929) (xy 93.33145 -273.481018)
			(xy 93.436989 -273.323519) (xy 93.535794 -273.16171) (xy 93.62769 -272.995879) (xy 93.712513 -272.826322)
			(xy 93.790113 -272.65334) (xy 93.860352 -272.47724) (xy 93.923104 -272.298336) (xy 93.978259 -272.116946)
			(xy 94.025718 -271.933391) (xy 94.065397 -271.747999) (xy 94.097225 -271.561099) (xy 94.121145 -271.373024)
			(xy 94.137116 -271.184107) (xy 94.145109 -270.994685)
		)
		(stroke
			(width 0)
			(type solid)
		)
		(fill yes)
		(layer "F.Cu")
		(net "GND")
	)
	(gr_poly
		(pts
			(xy 150.245572 -320.900044) (xy 150.245073 -320.805249) (xy 150.23708 -320.615827) (xy 150.221109 -320.42691)
			(xy 150.197189 -320.238835) (xy 150.165361 -320.051935) (xy 150.125682 -319.866543) (xy 150.078223 -319.682988)
			(xy 150.023068 -319.501598) (xy 149.960316 -319.322694) (xy 149.890077 -319.146594) (xy 149.812477 -318.973612)
			(xy 149.727654 -318.804055) (xy 149.635758 -318.638224) (xy 149.536953 -318.476415) (xy 149.431414 -318.318916)
			(xy 149.31933 -318.166005) (xy 149.200899 -318.017955) (xy 149.076332 -317.87503) (xy 148.945851 -317.737483)
			(xy 148.809687 -317.605559) (xy 148.668083 -317.479492) (xy 148.52129 -317.359507) (xy 148.369569 -317.245817)
			(xy 148.213191 -317.138624) (xy 148.052432 -317.038118) (xy 147.88758 -316.944479) (xy 147.718926 -316.857873)
			(xy 147.546772 -316.778454) (xy 147.371423 -316.706363) (xy 147.19319 -316.641728) (xy 147.012391 -316.584664)
			(xy 146.829347 -316.535272) (xy 146.644384 -316.493641) (xy 146.45783 -316.459845) (xy 146.270017 -316.433943)
			(xy 146.081279 -316.415981) (xy 145.891952 -316.405993) (xy 145.702372 -316.403994) (xy 145.512876 -316.409989)
			(xy 145.323801 -316.423967) (xy 145.135484 -316.445904) (xy 144.948259 -316.47576) (xy 144.762459 -316.513482)
			(xy 144.578415 -316.559003) (xy 144.396453 -316.612243) (xy 144.216897 -316.673106) (xy 144.040067 -316.741484)
			(xy 143.866276 -316.817256) (xy 143.695834 -316.900287) (xy 143.529044 -316.99043) (xy 143.366203 -317.087524)
			(xy 143.207599 -317.191396) (xy 143.053515 -317.301862) (xy 142.904225 -317.418726) (xy 142.759995 -317.541779)
			(xy 142.62108 -317.670803) (xy 142.487727 -317.805568) (xy 142.360175 -317.945836) (xy 142.238649 -318.091356)
			(xy 142.123366 -318.241869) (xy 142.01453 -318.397109) (xy 141.912336 -318.556799) (xy 141.816964 -318.720655)
			(xy 141.728585 -318.888386) (xy 141.647355 -319.059694) (xy 141.573419 -319.234273) (xy 141.506909 -319.411815)
			(xy 141.447942 -319.592002) (xy 141.396624 -319.774515) (xy 141.353045 -319.95903) (xy 141.317284 -320.145217)
			(xy 141.289404 -320.332746) (xy 141.269453 -320.521284) (xy 141.257469 -320.710496) (xy 141.253472 -320.900044)
			(xy 142.980673 -320.900044) (xy 142.984665 -320.751408) (xy 142.99663 -320.603201) (xy 143.016532 -320.455849)
			(xy 143.044315 -320.309779) (xy 143.079899 -320.16541) (xy 143.123181 -320.023159) (xy 143.174035 -319.883437)
			(xy 143.232317 -319.746645) (xy 143.297857 -319.61318) (xy 143.370466 -319.483424) (xy 143.449935 -319.357753)
			(xy 143.536036 -319.236529) (xy 143.628519 -319.120101) (xy 143.727118 -319.008806) (xy 143.83155 -318.902963)
			(xy 143.941512 -318.802878) (xy 144.056687 -318.70884) (xy 144.176744 -318.62112) (xy 144.301337 -318.539971)
			(xy 144.430106 -318.465626) (xy 144.56268 -318.3983) (xy 144.698676 -318.338188) (xy 144.837703 -318.285462)
			(xy 144.97936 -318.240274) (xy 145.123238 -318.202756) (xy 145.268923 -318.173014) (xy 145.415994 -318.151135)
			(xy 145.564027 -318.137182) (xy 145.712596 -318.131195) (xy 145.861272 -318.133191) (xy 146.009627 -318.143164)
			(xy 146.157232 -318.161087) (xy 146.303663 -318.186907) (xy 146.448497 -318.220549) (xy 146.591315 -318.261917)
			(xy 146.731708 -318.310891) (xy 146.869269 -318.367331) (xy 147.003603 -318.431073) (xy 147.134322 -318.501934)
			(xy 147.261048 -318.579709) (xy 147.383417 -318.664174) (xy 147.501076 -318.755086) (xy 147.613685 -318.852182)
			(xy 147.72092 -318.955183) (xy 147.822472 -319.063792) (xy 147.918048 -319.177694) (xy 148.007372 -319.296563)
			(xy 148.090187 -319.420055) (xy 148.166254 -319.547814) (xy 148.235353 -319.679472) (xy 148.297286 -319.81465)
			(xy 148.351874 -319.952956) (xy 148.398959 -320.093994) (xy 148.438406 -320.237355) (xy 148.470101 -320.382627)
			(xy 148.493952 -320.529391) (xy 148.509892 -320.677224) (xy 148.517873 -320.825699) (xy 148.518372 -320.900044)
			(xy 148.517873 -320.974389) (xy 148.509892 -321.122864) (xy 148.493952 -321.270697) (xy 148.470101 -321.417461)
			(xy 148.438406 -321.562733) (xy 148.398959 -321.706094) (xy 148.351874 -321.847132) (xy 148.297286 -321.985438)
			(xy 148.235353 -322.120616) (xy 148.166254 -322.252274) (xy 148.090187 -322.380033) (xy 148.007372 -322.503525)
			(xy 147.918048 -322.622394) (xy 147.822472 -322.736296) (xy 147.72092 -322.844905) (xy 147.613685 -322.947906)
			(xy 147.501076 -323.045002) (xy 147.383417 -323.135914) (xy 147.261048 -323.220379) (xy 147.134322 -323.298154)
			(xy 147.003603 -323.369015) (xy 146.869269 -323.432757) (xy 146.731708 -323.489197) (xy 146.591315 -323.538171)
			(xy 146.448497 -323.579539) (xy 146.303663 -323.613181) (xy 146.157232 -323.639001) (xy 146.009627 -323.656924)
			(xy 145.861272 -323.666897) (xy 145.712596 -323.668893) (xy 145.564027 -323.662906) (xy 145.415994 -323.648953)
			(xy 145.268923 -323.627074) (xy 145.123238 -323.597332) (xy 144.97936 -323.559814) (xy 144.837703 -323.514626)
			(xy 144.698676 -323.4619) (xy 144.56268 -323.401788) (xy 144.430106 -323.334462) (xy 144.301337 -323.260117)
			(xy 144.176744 -323.178968) (xy 144.056687 -323.091248) (xy 143.941512 -322.99721) (xy 143.83155 -322.897125)
			(xy 143.727118 -322.791282) (xy 143.628519 -322.679987) (xy 143.536036 -322.563559) (xy 143.449935 -322.442335)
			(xy 143.370466 -322.316664) (xy 143.297857 -322.186908) (xy 143.232317 -322.053443) (xy 143.174035 -321.916651)
			(xy 143.123181 -321.776929) (xy 143.079899 -321.634678) (xy 143.044315 -321.490309) (xy 143.016532 -321.344239)
			(xy 142.99663 -321.196887) (xy 142.984665 -321.04868) (xy 142.980673 -320.900044) (xy 141.253472 -320.900044)
			(xy 141.257469 -321.089592) (xy 141.269453 -321.278804) (xy 141.289404 -321.467342) (xy 141.317284 -321.654871)
			(xy 141.353045 -321.841058) (xy 141.396624 -322.025573) (xy 141.447942 -322.208086) (xy 141.506909 -322.388273)
			(xy 141.573419 -322.565815) (xy 141.647355 -322.740394) (xy 141.728585 -322.911702) (xy 141.816964 -323.079433)
			(xy 141.912336 -323.243289) (xy 142.01453 -323.402979) (xy 142.123366 -323.558219) (xy 142.238649 -323.708732)
			(xy 142.360175 -323.854252) (xy 142.487727 -323.99452) (xy 142.62108 -324.129285) (xy 142.759995 -324.258309)
			(xy 142.904225 -324.381362) (xy 143.053515 -324.498226) (xy 143.207599 -324.608692) (xy 143.366203 -324.712564)
			(xy 143.529044 -324.809658) (xy 143.695834 -324.899801) (xy 143.866276 -324.982832) (xy 144.040067 -325.058604)
			(xy 144.216897 -325.126982) (xy 144.396453 -325.187845) (xy 144.578415 -325.241085) (xy 144.762459 -325.286606)
			(xy 144.948259 -325.324328) (xy 145.135484 -325.354184) (xy 145.323801 -325.376121) (xy 145.512876 -325.390099)
			(xy 145.702372 -325.396094) (xy 145.891952 -325.394095) (xy 146.081279 -325.384107) (xy 146.270017 -325.366145)
			(xy 146.45783 -325.340243) (xy 146.644384 -325.306447) (xy 146.829347 -325.264816) (xy 147.012391 -325.215424)
			(xy 147.19319 -325.15836) (xy 147.371423 -325.093725) (xy 147.546772 -325.021634) (xy 147.718926 -324.942215)
			(xy 147.88758 -324.855609) (xy 148.052432 -324.76197) (xy 148.213191 -324.661464) (xy 148.369569 -324.554271)
			(xy 148.52129 -324.440581) (xy 148.668083 -324.320596) (xy 148.809687 -324.194529) (xy 148.945851 -324.062605)
			(xy 149.076332 -323.925058) (xy 149.200899 -323.782133) (xy 149.31933 -323.634083) (xy 149.431414 -323.481172)
			(xy 149.536953 -323.323673) (xy 149.635758 -323.161864) (xy 149.727654 -322.996033) (xy 149.812477 -322.826476)
			(xy 149.890077 -322.653494) (xy 149.960316 -322.477394) (xy 150.023068 -322.29849) (xy 150.078223 -322.1171)
			(xy 150.125682 -321.933545) (xy 150.165361 -321.748153) (xy 150.197189 -321.561253) (xy 150.221109 -321.373178)
			(xy 150.23708 -321.184261) (xy 150.245073 -320.994839)
		)
		(stroke
			(width 0)
			(type solid)
		)
		(fill yes)
		(layer "F.Cu")
		(net "GND")
	)
	(gr_poly
		(pts
			(xy 150.245572 -270.89989) (xy 150.245073 -270.805095) (xy 150.23708 -270.615673) (xy 150.221109 -270.426756)
			(xy 150.197189 -270.238681) (xy 150.165361 -270.051781) (xy 150.125682 -269.866389) (xy 150.078223 -269.682834)
			(xy 150.023068 -269.501444) (xy 149.960316 -269.32254) (xy 149.890077 -269.14644) (xy 149.812477 -268.973458)
			(xy 149.727654 -268.803901) (xy 149.635758 -268.63807) (xy 149.536953 -268.476261) (xy 149.431414 -268.318762)
			(xy 149.31933 -268.165851) (xy 149.200899 -268.017801) (xy 149.076332 -267.874876) (xy 148.945851 -267.737329)
			(xy 148.809687 -267.605405) (xy 148.668083 -267.479338) (xy 148.52129 -267.359353) (xy 148.369569 -267.245663)
			(xy 148.213191 -267.13847) (xy 148.052432 -267.037964) (xy 147.88758 -266.944325) (xy 147.718926 -266.857719)
			(xy 147.546772 -266.7783) (xy 147.371423 -266.706209) (xy 147.19319 -266.641574) (xy 147.012391 -266.58451)
			(xy 146.829347 -266.535118) (xy 146.644384 -266.493487) (xy 146.45783 -266.459691) (xy 146.270017 -266.433789)
			(xy 146.081279 -266.415827) (xy 145.891952 -266.405839) (xy 145.702372 -266.40384) (xy 145.512876 -266.409835)
			(xy 145.323801 -266.423813) (xy 145.135484 -266.44575) (xy 144.948259 -266.475606) (xy 144.762459 -266.513328)
			(xy 144.578415 -266.558849) (xy 144.396453 -266.612089) (xy 144.216897 -266.672952) (xy 144.040067 -266.74133)
			(xy 143.866276 -266.817102) (xy 143.695834 -266.900133) (xy 143.529044 -266.990276) (xy 143.366203 -267.08737)
			(xy 143.207599 -267.191242) (xy 143.053515 -267.301708) (xy 142.904225 -267.418572) (xy 142.759995 -267.541625)
			(xy 142.62108 -267.670649) (xy 142.487727 -267.805414) (xy 142.360175 -267.945682) (xy 142.238649 -268.091202)
			(xy 142.123366 -268.241715) (xy 142.01453 -268.396955) (xy 141.912336 -268.556645) (xy 141.816964 -268.720501)
			(xy 141.728585 -268.888232) (xy 141.647355 -269.05954) (xy 141.573419 -269.234119) (xy 141.506909 -269.411661)
			(xy 141.447942 -269.591848) (xy 141.396624 -269.774361) (xy 141.353045 -269.958876) (xy 141.317284 -270.145063)
			(xy 141.289404 -270.332592) (xy 141.269453 -270.52113) (xy 141.257469 -270.710342) (xy 141.253472 -270.89989)
			(xy 142.980673 -270.89989) (xy 142.984665 -270.751254) (xy 142.99663 -270.603047) (xy 143.016532 -270.455695)
			(xy 143.044315 -270.309625) (xy 143.079899 -270.165256) (xy 143.123181 -270.023005) (xy 143.174035 -269.883283)
			(xy 143.232317 -269.746491) (xy 143.297857 -269.613026) (xy 143.370466 -269.48327) (xy 143.449935 -269.357599)
			(xy 143.536036 -269.236375) (xy 143.628519 -269.119947) (xy 143.727118 -269.008652) (xy 143.83155 -268.902809)
			(xy 143.941512 -268.802724) (xy 144.056687 -268.708686) (xy 144.176744 -268.620966) (xy 144.301337 -268.539817)
			(xy 144.430106 -268.465472) (xy 144.56268 -268.398146) (xy 144.698676 -268.338034) (xy 144.837703 -268.285308)
			(xy 144.97936 -268.24012) (xy 145.123238 -268.202602) (xy 145.268923 -268.17286) (xy 145.415994 -268.150981)
			(xy 145.564027 -268.137028) (xy 145.712596 -268.131041) (xy 145.861272 -268.133037) (xy 146.009627 -268.14301)
			(xy 146.157232 -268.160933) (xy 146.303663 -268.186753) (xy 146.448497 -268.220395) (xy 146.591315 -268.261763)
			(xy 146.731708 -268.310737) (xy 146.869269 -268.367177) (xy 147.003603 -268.430919) (xy 147.134322 -268.50178)
			(xy 147.261048 -268.579555) (xy 147.383417 -268.66402) (xy 147.501076 -268.754932) (xy 147.613685 -268.852028)
			(xy 147.72092 -268.955029) (xy 147.822472 -269.063638) (xy 147.918048 -269.17754) (xy 148.007372 -269.296409)
			(xy 148.090187 -269.419901) (xy 148.166254 -269.54766) (xy 148.235353 -269.679318) (xy 148.297286 -269.814496)
			(xy 148.351874 -269.952802) (xy 148.398959 -270.09384) (xy 148.438406 -270.237201) (xy 148.470101 -270.382473)
			(xy 148.493952 -270.529237) (xy 148.509892 -270.67707) (xy 148.517873 -270.825545) (xy 148.518372 -270.89989)
			(xy 148.517873 -270.974235) (xy 148.509892 -271.12271) (xy 148.493952 -271.270543) (xy 148.470101 -271.417307)
			(xy 148.438406 -271.562579) (xy 148.398959 -271.70594) (xy 148.351874 -271.846978) (xy 148.297286 -271.985284)
			(xy 148.235353 -272.120462) (xy 148.166254 -272.25212) (xy 148.090187 -272.379879) (xy 148.007372 -272.503371)
			(xy 147.918048 -272.62224) (xy 147.822472 -272.736142) (xy 147.72092 -272.844751) (xy 147.613685 -272.947752)
			(xy 147.501076 -273.044848) (xy 147.383417 -273.13576) (xy 147.261048 -273.220225) (xy 147.134322 -273.298)
			(xy 147.003603 -273.368861) (xy 146.869269 -273.432603) (xy 146.731708 -273.489043) (xy 146.591315 -273.538017)
			(xy 146.448497 -273.579385) (xy 146.303663 -273.613027) (xy 146.157232 -273.638847) (xy 146.009627 -273.65677)
			(xy 145.861272 -273.666743) (xy 145.712596 -273.668739) (xy 145.564027 -273.662752) (xy 145.415994 -273.648799)
			(xy 145.268923 -273.62692) (xy 145.123238 -273.597178) (xy 144.97936 -273.55966) (xy 144.837703 -273.514472)
			(xy 144.698676 -273.461746) (xy 144.56268 -273.401634) (xy 144.430106 -273.334308) (xy 144.301337 -273.259963)
			(xy 144.176744 -273.178814) (xy 144.056687 -273.091094) (xy 143.941512 -272.997056) (xy 143.83155 -272.896971)
			(xy 143.727118 -272.791128) (xy 143.628519 -272.679833) (xy 143.536036 -272.563405) (xy 143.449935 -272.442181)
			(xy 143.370466 -272.31651) (xy 143.297857 -272.186754) (xy 143.232317 -272.053289) (xy 143.174035 -271.916497)
			(xy 143.123181 -271.776775) (xy 143.079899 -271.634524) (xy 143.044315 -271.490155) (xy 143.016532 -271.344085)
			(xy 142.99663 -271.196733) (xy 142.984665 -271.048526) (xy 142.980673 -270.89989) (xy 141.253472 -270.89989)
			(xy 141.257469 -271.089438) (xy 141.269453 -271.27865) (xy 141.289404 -271.467188) (xy 141.317284 -271.654717)
			(xy 141.353045 -271.840904) (xy 141.396624 -272.025419) (xy 141.447942 -272.207932) (xy 141.506909 -272.388119)
			(xy 141.573419 -272.565661) (xy 141.647355 -272.74024) (xy 141.728585 -272.911548) (xy 141.816964 -273.079279)
			(xy 141.912336 -273.243135) (xy 142.01453 -273.402825) (xy 142.123366 -273.558065) (xy 142.238649 -273.708578)
			(xy 142.360175 -273.854098) (xy 142.487727 -273.994366) (xy 142.62108 -274.129131) (xy 142.759995 -274.258155)
			(xy 142.904225 -274.381208) (xy 143.053515 -274.498072) (xy 143.207599 -274.608538) (xy 143.366203 -274.71241)
			(xy 143.529044 -274.809504) (xy 143.695834 -274.899647) (xy 143.866276 -274.982678) (xy 144.040067 -275.05845)
			(xy 144.216897 -275.126828) (xy 144.396453 -275.187691) (xy 144.578415 -275.240931) (xy 144.762459 -275.286452)
			(xy 144.948259 -275.324174) (xy 145.135484 -275.35403) (xy 145.323801 -275.375967) (xy 145.512876 -275.389945)
			(xy 145.702372 -275.39594) (xy 145.891952 -275.393941) (xy 146.081279 -275.383953) (xy 146.270017 -275.365991)
			(xy 146.45783 -275.340089) (xy 146.644384 -275.306293) (xy 146.829347 -275.264662) (xy 147.012391 -275.21527)
			(xy 147.19319 -275.158206) (xy 147.371423 -275.093571) (xy 147.546772 -275.02148) (xy 147.718926 -274.942061)
			(xy 147.88758 -274.855455) (xy 148.052432 -274.761816) (xy 148.213191 -274.66131) (xy 148.369569 -274.554117)
			(xy 148.52129 -274.440427) (xy 148.668083 -274.320442) (xy 148.809687 -274.194375) (xy 148.945851 -274.062451)
			(xy 149.076332 -273.924904) (xy 149.200899 -273.781979) (xy 149.31933 -273.633929) (xy 149.431414 -273.481018)
			(xy 149.536953 -273.323519) (xy 149.635758 -273.16171) (xy 149.727654 -272.995879) (xy 149.812477 -272.826322)
			(xy 149.890077 -272.65334) (xy 149.960316 -272.47724) (xy 150.023068 -272.298336) (xy 150.078223 -272.116946)
			(xy 150.125682 -271.933391) (xy 150.165361 -271.747999) (xy 150.197189 -271.561099) (xy 150.221109 -271.373024)
			(xy 150.23708 -271.184107) (xy 150.245073 -270.994685)
		)
		(stroke
			(width 0)
			(type solid)
		)
		(fill yes)
		(layer "F.Cu")
		(net "GND")
	)
	(gr_poly
		(pts
			(xy 210.245452 -320.900044) (xy 210.244953 -320.805249) (xy 210.23696 -320.615827) (xy 210.220989 -320.42691)
			(xy 210.197069 -320.238835) (xy 210.165241 -320.051935) (xy 210.125562 -319.866543) (xy 210.078103 -319.682988)
			(xy 210.022948 -319.501598) (xy 209.960196 -319.322694) (xy 209.889957 -319.146594) (xy 209.812357 -318.973612)
			(xy 209.727534 -318.804055) (xy 209.635638 -318.638224) (xy 209.536833 -318.476415) (xy 209.431294 -318.318916)
			(xy 209.31921 -318.166005) (xy 209.200779 -318.017955) (xy 209.076212 -317.87503) (xy 208.945731 -317.737483)
			(xy 208.809567 -317.605559) (xy 208.667963 -317.479492) (xy 208.52117 -317.359507) (xy 208.369449 -317.245817)
			(xy 208.213071 -317.138624) (xy 208.052312 -317.038118) (xy 207.88746 -316.944479) (xy 207.718806 -316.857873)
			(xy 207.546652 -316.778454) (xy 207.371303 -316.706363) (xy 207.19307 -316.641728) (xy 207.012271 -316.584664)
			(xy 206.829227 -316.535272) (xy 206.644264 -316.493641) (xy 206.45771 -316.459845) (xy 206.269897 -316.433943)
			(xy 206.081159 -316.415981) (xy 205.891832 -316.405993) (xy 205.702252 -316.403994) (xy 205.512756 -316.409989)
			(xy 205.323681 -316.423967) (xy 205.135364 -316.445904) (xy 204.948139 -316.47576) (xy 204.762339 -316.513482)
			(xy 204.578295 -316.559003) (xy 204.396333 -316.612243) (xy 204.216777 -316.673106) (xy 204.039947 -316.741484)
			(xy 203.866156 -316.817256) (xy 203.695714 -316.900287) (xy 203.528924 -316.99043) (xy 203.366083 -317.087524)
			(xy 203.207479 -317.191396) (xy 203.053395 -317.301862) (xy 202.904105 -317.418726) (xy 202.759875 -317.541779)
			(xy 202.62096 -317.670803) (xy 202.487607 -317.805568) (xy 202.360055 -317.945836) (xy 202.238529 -318.091356)
			(xy 202.123246 -318.241869) (xy 202.01441 -318.397109) (xy 201.912216 -318.556799) (xy 201.816844 -318.720655)
			(xy 201.728465 -318.888386) (xy 201.647235 -319.059694) (xy 201.573299 -319.234273) (xy 201.506789 -319.411815)
			(xy 201.447822 -319.592002) (xy 201.396504 -319.774515) (xy 201.352925 -319.95903) (xy 201.317164 -320.145217)
			(xy 201.289284 -320.332746) (xy 201.269333 -320.521284) (xy 201.257349 -320.710496) (xy 201.253352 -320.900044)
			(xy 202.980553 -320.900044) (xy 202.984545 -320.751408) (xy 202.99651 -320.603201) (xy 203.016412 -320.455849)
			(xy 203.044195 -320.309779) (xy 203.079779 -320.16541) (xy 203.123061 -320.023159) (xy 203.173915 -319.883437)
			(xy 203.232197 -319.746645) (xy 203.297737 -319.61318) (xy 203.370346 -319.483424) (xy 203.449815 -319.357753)
			(xy 203.535916 -319.236529) (xy 203.628399 -319.120101) (xy 203.726998 -319.008806) (xy 203.83143 -318.902963)
			(xy 203.941392 -318.802878) (xy 204.056567 -318.70884) (xy 204.176624 -318.62112) (xy 204.301217 -318.539971)
			(xy 204.429986 -318.465626) (xy 204.56256 -318.3983) (xy 204.698556 -318.338188) (xy 204.837583 -318.285462)
			(xy 204.97924 -318.240274) (xy 205.123118 -318.202756) (xy 205.268803 -318.173014) (xy 205.415874 -318.151135)
			(xy 205.563907 -318.137182) (xy 205.712476 -318.131195) (xy 205.861152 -318.133191) (xy 206.009507 -318.143164)
			(xy 206.157112 -318.161087) (xy 206.303543 -318.186907) (xy 206.448377 -318.220549) (xy 206.591195 -318.261917)
			(xy 206.731588 -318.310891) (xy 206.869149 -318.367331) (xy 207.003483 -318.431073) (xy 207.134202 -318.501934)
			(xy 207.260928 -318.579709) (xy 207.383297 -318.664174) (xy 207.500956 -318.755086) (xy 207.613565 -318.852182)
			(xy 207.7208 -318.955183) (xy 207.822352 -319.063792) (xy 207.917928 -319.177694) (xy 208.007252 -319.296563)
			(xy 208.090067 -319.420055) (xy 208.166134 -319.547814) (xy 208.235233 -319.679472) (xy 208.297166 -319.81465)
			(xy 208.351754 -319.952956) (xy 208.398839 -320.093994) (xy 208.438286 -320.237355) (xy 208.469981 -320.382627)
			(xy 208.493832 -320.529391) (xy 208.509772 -320.677224) (xy 208.517753 -320.825699) (xy 208.518252 -320.900044)
			(xy 208.517753 -320.974389) (xy 208.509772 -321.122864) (xy 208.493832 -321.270697) (xy 208.469981 -321.417461)
			(xy 208.438286 -321.562733) (xy 208.398839 -321.706094) (xy 208.351754 -321.847132) (xy 208.297166 -321.985438)
			(xy 208.235233 -322.120616) (xy 208.166134 -322.252274) (xy 208.090067 -322.380033) (xy 208.007252 -322.503525)
			(xy 207.917928 -322.622394) (xy 207.822352 -322.736296) (xy 207.7208 -322.844905) (xy 207.613565 -322.947906)
			(xy 207.500956 -323.045002) (xy 207.383297 -323.135914) (xy 207.260928 -323.220379) (xy 207.134202 -323.298154)
			(xy 207.003483 -323.369015) (xy 206.869149 -323.432757) (xy 206.731588 -323.489197) (xy 206.591195 -323.538171)
			(xy 206.448377 -323.579539) (xy 206.303543 -323.613181) (xy 206.157112 -323.639001) (xy 206.009507 -323.656924)
			(xy 205.861152 -323.666897) (xy 205.712476 -323.668893) (xy 205.563907 -323.662906) (xy 205.415874 -323.648953)
			(xy 205.268803 -323.627074) (xy 205.123118 -323.597332) (xy 204.97924 -323.559814) (xy 204.837583 -323.514626)
			(xy 204.698556 -323.4619) (xy 204.56256 -323.401788) (xy 204.429986 -323.334462) (xy 204.301217 -323.260117)
			(xy 204.176624 -323.178968) (xy 204.056567 -323.091248) (xy 203.941392 -322.99721) (xy 203.83143 -322.897125)
			(xy 203.726998 -322.791282) (xy 203.628399 -322.679987) (xy 203.535916 -322.563559) (xy 203.449815 -322.442335)
			(xy 203.370346 -322.316664) (xy 203.297737 -322.186908) (xy 203.232197 -322.053443) (xy 203.173915 -321.916651)
			(xy 203.123061 -321.776929) (xy 203.079779 -321.634678) (xy 203.044195 -321.490309) (xy 203.016412 -321.344239)
			(xy 202.99651 -321.196887) (xy 202.984545 -321.04868) (xy 202.980553 -320.900044) (xy 201.253352 -320.900044)
			(xy 201.257349 -321.089592) (xy 201.269333 -321.278804) (xy 201.289284 -321.467342) (xy 201.317164 -321.654871)
			(xy 201.352925 -321.841058) (xy 201.396504 -322.025573) (xy 201.447822 -322.208086) (xy 201.506789 -322.388273)
			(xy 201.573299 -322.565815) (xy 201.647235 -322.740394) (xy 201.728465 -322.911702) (xy 201.816844 -323.079433)
			(xy 201.912216 -323.243289) (xy 202.01441 -323.402979) (xy 202.123246 -323.558219) (xy 202.238529 -323.708732)
			(xy 202.360055 -323.854252) (xy 202.487607 -323.99452) (xy 202.62096 -324.129285) (xy 202.759875 -324.258309)
			(xy 202.904105 -324.381362) (xy 203.053395 -324.498226) (xy 203.207479 -324.608692) (xy 203.366083 -324.712564)
			(xy 203.528924 -324.809658) (xy 203.695714 -324.899801) (xy 203.866156 -324.982832) (xy 204.039947 -325.058604)
			(xy 204.216777 -325.126982) (xy 204.396333 -325.187845) (xy 204.578295 -325.241085) (xy 204.762339 -325.286606)
			(xy 204.948139 -325.324328) (xy 205.135364 -325.354184) (xy 205.323681 -325.376121) (xy 205.512756 -325.390099)
			(xy 205.702252 -325.396094) (xy 205.891832 -325.394095) (xy 206.081159 -325.384107) (xy 206.269897 -325.366145)
			(xy 206.45771 -325.340243) (xy 206.644264 -325.306447) (xy 206.829227 -325.264816) (xy 207.012271 -325.215424)
			(xy 207.19307 -325.15836) (xy 207.371303 -325.093725) (xy 207.546652 -325.021634) (xy 207.718806 -324.942215)
			(xy 207.88746 -324.855609) (xy 208.052312 -324.76197) (xy 208.213071 -324.661464) (xy 208.369449 -324.554271)
			(xy 208.52117 -324.440581) (xy 208.667963 -324.320596) (xy 208.809567 -324.194529) (xy 208.945731 -324.062605)
			(xy 209.076212 -323.925058) (xy 209.200779 -323.782133) (xy 209.31921 -323.634083) (xy 209.431294 -323.481172)
			(xy 209.536833 -323.323673) (xy 209.635638 -323.161864) (xy 209.727534 -322.996033) (xy 209.812357 -322.826476)
			(xy 209.889957 -322.653494) (xy 209.960196 -322.477394) (xy 210.022948 -322.29849) (xy 210.078103 -322.1171)
			(xy 210.125562 -321.933545) (xy 210.165241 -321.748153) (xy 210.197069 -321.561253) (xy 210.220989 -321.373178)
			(xy 210.23696 -321.184261) (xy 210.244953 -320.994839)
		)
		(stroke
			(width 0)
			(type solid)
		)
		(fill yes)
		(layer "F.Cu")
		(net "GND")
	)
	(gr_poly
		(pts
			(xy 210.245452 -270.89989) (xy 210.244953 -270.805095) (xy 210.23696 -270.615673) (xy 210.220989 -270.426756)
			(xy 210.197069 -270.238681) (xy 210.165241 -270.051781) (xy 210.125562 -269.866389) (xy 210.078103 -269.682834)
			(xy 210.022948 -269.501444) (xy 209.960196 -269.32254) (xy 209.889957 -269.14644) (xy 209.812357 -268.973458)
			(xy 209.727534 -268.803901) (xy 209.635638 -268.63807) (xy 209.536833 -268.476261) (xy 209.431294 -268.318762)
			(xy 209.31921 -268.165851) (xy 209.200779 -268.017801) (xy 209.076212 -267.874876) (xy 208.945731 -267.737329)
			(xy 208.809567 -267.605405) (xy 208.667963 -267.479338) (xy 208.52117 -267.359353) (xy 208.369449 -267.245663)
			(xy 208.213071 -267.13847) (xy 208.052312 -267.037964) (xy 207.88746 -266.944325) (xy 207.718806 -266.857719)
			(xy 207.546652 -266.7783) (xy 207.371303 -266.706209) (xy 207.19307 -266.641574) (xy 207.012271 -266.58451)
			(xy 206.829227 -266.535118) (xy 206.644264 -266.493487) (xy 206.45771 -266.459691) (xy 206.269897 -266.433789)
			(xy 206.081159 -266.415827) (xy 205.891832 -266.405839) (xy 205.702252 -266.40384) (xy 205.512756 -266.409835)
			(xy 205.323681 -266.423813) (xy 205.135364 -266.44575) (xy 204.948139 -266.475606) (xy 204.762339 -266.513328)
			(xy 204.578295 -266.558849) (xy 204.396333 -266.612089) (xy 204.216777 -266.672952) (xy 204.039947 -266.74133)
			(xy 203.866156 -266.817102) (xy 203.695714 -266.900133) (xy 203.528924 -266.990276) (xy 203.366083 -267.08737)
			(xy 203.207479 -267.191242) (xy 203.053395 -267.301708) (xy 202.904105 -267.418572) (xy 202.759875 -267.541625)
			(xy 202.62096 -267.670649) (xy 202.487607 -267.805414) (xy 202.360055 -267.945682) (xy 202.238529 -268.091202)
			(xy 202.123246 -268.241715) (xy 202.01441 -268.396955) (xy 201.912216 -268.556645) (xy 201.816844 -268.720501)
			(xy 201.728465 -268.888232) (xy 201.647235 -269.05954) (xy 201.573299 -269.234119) (xy 201.506789 -269.411661)
			(xy 201.447822 -269.591848) (xy 201.396504 -269.774361) (xy 201.352925 -269.958876) (xy 201.317164 -270.145063)
			(xy 201.289284 -270.332592) (xy 201.269333 -270.52113) (xy 201.257349 -270.710342) (xy 201.253352 -270.89989)
			(xy 202.980553 -270.89989) (xy 202.984545 -270.751254) (xy 202.99651 -270.603047) (xy 203.016412 -270.455695)
			(xy 203.044195 -270.309625) (xy 203.079779 -270.165256) (xy 203.123061 -270.023005) (xy 203.173915 -269.883283)
			(xy 203.232197 -269.746491) (xy 203.297737 -269.613026) (xy 203.370346 -269.48327) (xy 203.449815 -269.357599)
			(xy 203.535916 -269.236375) (xy 203.628399 -269.119947) (xy 203.726998 -269.008652) (xy 203.83143 -268.902809)
			(xy 203.941392 -268.802724) (xy 204.056567 -268.708686) (xy 204.176624 -268.620966) (xy 204.301217 -268.539817)
			(xy 204.429986 -268.465472) (xy 204.56256 -268.398146) (xy 204.698556 -268.338034) (xy 204.837583 -268.285308)
			(xy 204.97924 -268.24012) (xy 205.123118 -268.202602) (xy 205.268803 -268.17286) (xy 205.415874 -268.150981)
			(xy 205.563907 -268.137028) (xy 205.712476 -268.131041) (xy 205.861152 -268.133037) (xy 206.009507 -268.14301)
			(xy 206.157112 -268.160933) (xy 206.303543 -268.186753) (xy 206.448377 -268.220395) (xy 206.591195 -268.261763)
			(xy 206.731588 -268.310737) (xy 206.869149 -268.367177) (xy 207.003483 -268.430919) (xy 207.134202 -268.50178)
			(xy 207.260928 -268.579555) (xy 207.383297 -268.66402) (xy 207.500956 -268.754932) (xy 207.613565 -268.852028)
			(xy 207.7208 -268.955029) (xy 207.822352 -269.063638) (xy 207.917928 -269.17754) (xy 208.007252 -269.296409)
			(xy 208.090067 -269.419901) (xy 208.166134 -269.54766) (xy 208.235233 -269.679318) (xy 208.297166 -269.814496)
			(xy 208.351754 -269.952802) (xy 208.398839 -270.09384) (xy 208.438286 -270.237201) (xy 208.469981 -270.382473)
			(xy 208.493832 -270.529237) (xy 208.509772 -270.67707) (xy 208.517753 -270.825545) (xy 208.518252 -270.89989)
			(xy 208.517753 -270.974235) (xy 208.509772 -271.12271) (xy 208.493832 -271.270543) (xy 208.469981 -271.417307)
			(xy 208.438286 -271.562579) (xy 208.398839 -271.70594) (xy 208.351754 -271.846978) (xy 208.297166 -271.985284)
			(xy 208.235233 -272.120462) (xy 208.166134 -272.25212) (xy 208.090067 -272.379879) (xy 208.007252 -272.503371)
			(xy 207.917928 -272.62224) (xy 207.822352 -272.736142) (xy 207.7208 -272.844751) (xy 207.613565 -272.947752)
			(xy 207.500956 -273.044848) (xy 207.383297 -273.13576) (xy 207.260928 -273.220225) (xy 207.134202 -273.298)
			(xy 207.003483 -273.368861) (xy 206.869149 -273.432603) (xy 206.731588 -273.489043) (xy 206.591195 -273.538017)
			(xy 206.448377 -273.579385) (xy 206.303543 -273.613027) (xy 206.157112 -273.638847) (xy 206.009507 -273.65677)
			(xy 205.861152 -273.666743) (xy 205.712476 -273.668739) (xy 205.563907 -273.662752) (xy 205.415874 -273.648799)
			(xy 205.268803 -273.62692) (xy 205.123118 -273.597178) (xy 204.97924 -273.55966) (xy 204.837583 -273.514472)
			(xy 204.698556 -273.461746) (xy 204.56256 -273.401634) (xy 204.429986 -273.334308) (xy 204.301217 -273.259963)
			(xy 204.176624 -273.178814) (xy 204.056567 -273.091094) (xy 203.941392 -272.997056) (xy 203.83143 -272.896971)
			(xy 203.726998 -272.791128) (xy 203.628399 -272.679833) (xy 203.535916 -272.563405) (xy 203.449815 -272.442181)
			(xy 203.370346 -272.31651) (xy 203.297737 -272.186754) (xy 203.232197 -272.053289) (xy 203.173915 -271.916497)
			(xy 203.123061 -271.776775) (xy 203.079779 -271.634524) (xy 203.044195 -271.490155) (xy 203.016412 -271.344085)
			(xy 202.99651 -271.196733) (xy 202.984545 -271.048526) (xy 202.980553 -270.89989) (xy 201.253352 -270.89989)
			(xy 201.257349 -271.089438) (xy 201.269333 -271.27865) (xy 201.289284 -271.467188) (xy 201.317164 -271.654717)
			(xy 201.352925 -271.840904) (xy 201.396504 -272.025419) (xy 201.447822 -272.207932) (xy 201.506789 -272.388119)
			(xy 201.573299 -272.565661) (xy 201.647235 -272.74024) (xy 201.728465 -272.911548) (xy 201.816844 -273.079279)
			(xy 201.912216 -273.243135) (xy 202.01441 -273.402825) (xy 202.123246 -273.558065) (xy 202.238529 -273.708578)
			(xy 202.360055 -273.854098) (xy 202.487607 -273.994366) (xy 202.62096 -274.129131) (xy 202.759875 -274.258155)
			(xy 202.904105 -274.381208) (xy 203.053395 -274.498072) (xy 203.207479 -274.608538) (xy 203.366083 -274.71241)
			(xy 203.528924 -274.809504) (xy 203.695714 -274.899647) (xy 203.866156 -274.982678) (xy 204.039947 -275.05845)
			(xy 204.216777 -275.126828) (xy 204.396333 -275.187691) (xy 204.578295 -275.240931) (xy 204.762339 -275.286452)
			(xy 204.948139 -275.324174) (xy 205.135364 -275.35403) (xy 205.323681 -275.375967) (xy 205.512756 -275.389945)
			(xy 205.702252 -275.39594) (xy 205.891832 -275.393941) (xy 206.081159 -275.383953) (xy 206.269897 -275.365991)
			(xy 206.45771 -275.340089) (xy 206.644264 -275.306293) (xy 206.829227 -275.264662) (xy 207.012271 -275.21527)
			(xy 207.19307 -275.158206) (xy 207.371303 -275.093571) (xy 207.546652 -275.02148) (xy 207.718806 -274.942061)
			(xy 207.88746 -274.855455) (xy 208.052312 -274.761816) (xy 208.213071 -274.66131) (xy 208.369449 -274.554117)
			(xy 208.52117 -274.440427) (xy 208.667963 -274.320442) (xy 208.809567 -274.194375) (xy 208.945731 -274.062451)
			(xy 209.076212 -273.924904) (xy 209.200779 -273.781979) (xy 209.31921 -273.633929) (xy 209.431294 -273.481018)
			(xy 209.536833 -273.323519) (xy 209.635638 -273.16171) (xy 209.727534 -272.995879) (xy 209.812357 -272.826322)
			(xy 209.889957 -272.65334) (xy 209.960196 -272.47724) (xy 210.022948 -272.298336) (xy 210.078103 -272.116946)
			(xy 210.125562 -271.933391) (xy 210.165241 -271.747999) (xy 210.197069 -271.561099) (xy 210.220989 -271.373024)
			(xy 210.23696 -271.184107) (xy 210.244953 -270.994685)
		)
		(stroke
			(width 0)
			(type solid)
		)
		(fill yes)
		(layer "F.Cu")
		(net "GND")
	)
	(gr_poly
		(pts
			(xy 266.34567 -320.900044) (xy 266.345171 -320.805249) (xy 266.337178 -320.615827) (xy 266.321207 -320.42691)
			(xy 266.297287 -320.238835) (xy 266.265459 -320.051935) (xy 266.22578 -319.866543) (xy 266.178321 -319.682988)
			(xy 266.123166 -319.501598) (xy 266.060414 -319.322694) (xy 265.990175 -319.146594) (xy 265.912575 -318.973612)
			(xy 265.827752 -318.804055) (xy 265.735856 -318.638224) (xy 265.637051 -318.476415) (xy 265.531512 -318.318916)
			(xy 265.419428 -318.166005) (xy 265.300997 -318.017955) (xy 265.17643 -317.87503) (xy 265.045949 -317.737483)
			(xy 264.909785 -317.605559) (xy 264.768181 -317.479492) (xy 264.621388 -317.359507) (xy 264.469667 -317.245817)
			(xy 264.313289 -317.138624) (xy 264.15253 -317.038118) (xy 263.987678 -316.944479) (xy 263.819024 -316.857873)
			(xy 263.64687 -316.778454) (xy 263.471521 -316.706363) (xy 263.293288 -316.641728) (xy 263.112489 -316.584664)
			(xy 262.929445 -316.535272) (xy 262.744482 -316.493641) (xy 262.557928 -316.459845) (xy 262.370115 -316.433943)
			(xy 262.181377 -316.415981) (xy 261.99205 -316.405993) (xy 261.80247 -316.403994) (xy 261.612974 -316.409989)
			(xy 261.423899 -316.423967) (xy 261.235582 -316.445904) (xy 261.048357 -316.47576) (xy 260.862557 -316.513482)
			(xy 260.678513 -316.559003) (xy 260.496551 -316.612243) (xy 260.316995 -316.673106) (xy 260.140165 -316.741484)
			(xy 259.966374 -316.817256) (xy 259.795932 -316.900287) (xy 259.629142 -316.99043) (xy 259.466301 -317.087524)
			(xy 259.307697 -317.191396) (xy 259.153613 -317.301862) (xy 259.004323 -317.418726) (xy 258.860093 -317.541779)
			(xy 258.721178 -317.670803) (xy 258.587825 -317.805568) (xy 258.460273 -317.945836) (xy 258.338747 -318.091356)
			(xy 258.223464 -318.241869) (xy 258.114628 -318.397109) (xy 258.012434 -318.556799) (xy 257.917062 -318.720655)
			(xy 257.828683 -318.888386) (xy 257.747453 -319.059694) (xy 257.673517 -319.234273) (xy 257.607007 -319.411815)
			(xy 257.54804 -319.592002) (xy 257.496722 -319.774515) (xy 257.453143 -319.95903) (xy 257.417382 -320.145217)
			(xy 257.389502 -320.332746) (xy 257.369551 -320.521284) (xy 257.357567 -320.710496) (xy 257.35357 -320.900044)
			(xy 259.080771 -320.900044) (xy 259.084763 -320.751408) (xy 259.096728 -320.603201) (xy 259.11663 -320.455849)
			(xy 259.144413 -320.309779) (xy 259.179997 -320.16541) (xy 259.223279 -320.023159) (xy 259.274133 -319.883437)
			(xy 259.332415 -319.746645) (xy 259.397955 -319.61318) (xy 259.470564 -319.483424) (xy 259.550033 -319.357753)
			(xy 259.636134 -319.236529) (xy 259.728617 -319.120101) (xy 259.827216 -319.008806) (xy 259.931648 -318.902963)
			(xy 260.04161 -318.802878) (xy 260.156785 -318.70884) (xy 260.276842 -318.62112) (xy 260.401435 -318.539971)
			(xy 260.530204 -318.465626) (xy 260.662778 -318.3983) (xy 260.798774 -318.338188) (xy 260.937801 -318.285462)
			(xy 261.079458 -318.240274) (xy 261.223336 -318.202756) (xy 261.369021 -318.173014) (xy 261.516092 -318.151135)
			(xy 261.664125 -318.137182) (xy 261.812694 -318.131195) (xy 261.96137 -318.133191) (xy 262.109725 -318.143164)
			(xy 262.25733 -318.161087) (xy 262.403761 -318.186907) (xy 262.548595 -318.220549) (xy 262.691413 -318.261917)
			(xy 262.831806 -318.310891) (xy 262.969367 -318.367331) (xy 263.103701 -318.431073) (xy 263.23442 -318.501934)
			(xy 263.361146 -318.579709) (xy 263.483515 -318.664174) (xy 263.601174 -318.755086) (xy 263.713783 -318.852182)
			(xy 263.821018 -318.955183) (xy 263.92257 -319.063792) (xy 264.018146 -319.177694) (xy 264.10747 -319.296563)
			(xy 264.190285 -319.420055) (xy 264.266352 -319.547814) (xy 264.335451 -319.679472) (xy 264.397384 -319.81465)
			(xy 264.451972 -319.952956) (xy 264.499057 -320.093994) (xy 264.538504 -320.237355) (xy 264.570199 -320.382627)
			(xy 264.59405 -320.529391) (xy 264.60999 -320.677224) (xy 264.617971 -320.825699) (xy 264.61847 -320.900044)
			(xy 264.617971 -320.974389) (xy 264.60999 -321.122864) (xy 264.59405 -321.270697) (xy 264.570199 -321.417461)
			(xy 264.538504 -321.562733) (xy 264.499057 -321.706094) (xy 264.451972 -321.847132) (xy 264.397384 -321.985438)
			(xy 264.335451 -322.120616) (xy 264.266352 -322.252274) (xy 264.190285 -322.380033) (xy 264.10747 -322.503525)
			(xy 264.018146 -322.622394) (xy 263.92257 -322.736296) (xy 263.821018 -322.844905) (xy 263.713783 -322.947906)
			(xy 263.601174 -323.045002) (xy 263.483515 -323.135914) (xy 263.361146 -323.220379) (xy 263.23442 -323.298154)
			(xy 263.103701 -323.369015) (xy 262.969367 -323.432757) (xy 262.831806 -323.489197) (xy 262.691413 -323.538171)
			(xy 262.548595 -323.579539) (xy 262.403761 -323.613181) (xy 262.25733 -323.639001) (xy 262.109725 -323.656924)
			(xy 261.96137 -323.666897) (xy 261.812694 -323.668893) (xy 261.664125 -323.662906) (xy 261.516092 -323.648953)
			(xy 261.369021 -323.627074) (xy 261.223336 -323.597332) (xy 261.079458 -323.559814) (xy 260.937801 -323.514626)
			(xy 260.798774 -323.4619) (xy 260.662778 -323.401788) (xy 260.530204 -323.334462) (xy 260.401435 -323.260117)
			(xy 260.276842 -323.178968) (xy 260.156785 -323.091248) (xy 260.04161 -322.99721) (xy 259.931648 -322.897125)
			(xy 259.827216 -322.791282) (xy 259.728617 -322.679987) (xy 259.636134 -322.563559) (xy 259.550033 -322.442335)
			(xy 259.470564 -322.316664) (xy 259.397955 -322.186908) (xy 259.332415 -322.053443) (xy 259.274133 -321.916651)
			(xy 259.223279 -321.776929) (xy 259.179997 -321.634678) (xy 259.144413 -321.490309) (xy 259.11663 -321.344239)
			(xy 259.096728 -321.196887) (xy 259.084763 -321.04868) (xy 259.080771 -320.900044) (xy 257.35357 -320.900044)
			(xy 257.357567 -321.089592) (xy 257.369551 -321.278804) (xy 257.389502 -321.467342) (xy 257.417382 -321.654871)
			(xy 257.453143 -321.841058) (xy 257.496722 -322.025573) (xy 257.54804 -322.208086) (xy 257.607007 -322.388273)
			(xy 257.673517 -322.565815) (xy 257.747453 -322.740394) (xy 257.828683 -322.911702) (xy 257.917062 -323.079433)
			(xy 258.012434 -323.243289) (xy 258.114628 -323.402979) (xy 258.223464 -323.558219) (xy 258.338747 -323.708732)
			(xy 258.460273 -323.854252) (xy 258.587825 -323.99452) (xy 258.721178 -324.129285) (xy 258.860093 -324.258309)
			(xy 259.004323 -324.381362) (xy 259.153613 -324.498226) (xy 259.307697 -324.608692) (xy 259.466301 -324.712564)
			(xy 259.629142 -324.809658) (xy 259.795932 -324.899801) (xy 259.966374 -324.982832) (xy 260.140165 -325.058604)
			(xy 260.316995 -325.126982) (xy 260.496551 -325.187845) (xy 260.678513 -325.241085) (xy 260.862557 -325.286606)
			(xy 261.048357 -325.324328) (xy 261.235582 -325.354184) (xy 261.423899 -325.376121) (xy 261.612974 -325.390099)
			(xy 261.80247 -325.396094) (xy 261.99205 -325.394095) (xy 262.181377 -325.384107) (xy 262.370115 -325.366145)
			(xy 262.557928 -325.340243) (xy 262.744482 -325.306447) (xy 262.929445 -325.264816) (xy 263.112489 -325.215424)
			(xy 263.293288 -325.15836) (xy 263.471521 -325.093725) (xy 263.64687 -325.021634) (xy 263.819024 -324.942215)
			(xy 263.987678 -324.855609) (xy 264.15253 -324.76197) (xy 264.313289 -324.661464) (xy 264.469667 -324.554271)
			(xy 264.621388 -324.440581) (xy 264.768181 -324.320596) (xy 264.909785 -324.194529) (xy 265.045949 -324.062605)
			(xy 265.17643 -323.925058) (xy 265.300997 -323.782133) (xy 265.419428 -323.634083) (xy 265.531512 -323.481172)
			(xy 265.637051 -323.323673) (xy 265.735856 -323.161864) (xy 265.827752 -322.996033) (xy 265.912575 -322.826476)
			(xy 265.990175 -322.653494) (xy 266.060414 -322.477394) (xy 266.123166 -322.29849) (xy 266.178321 -322.1171)
			(xy 266.22578 -321.933545) (xy 266.265459 -321.748153) (xy 266.297287 -321.561253) (xy 266.321207 -321.373178)
			(xy 266.337178 -321.184261) (xy 266.345171 -320.994839)
		)
		(stroke
			(width 0)
			(type solid)
		)
		(fill yes)
		(layer "F.Cu")
		(net "GND")
	)
	(gr_poly
		(pts
			(xy 266.34567 -270.89989) (xy 266.345171 -270.805095) (xy 266.337178 -270.615673) (xy 266.321207 -270.426756)
			(xy 266.297287 -270.238681) (xy 266.265459 -270.051781) (xy 266.22578 -269.866389) (xy 266.178321 -269.682834)
			(xy 266.123166 -269.501444) (xy 266.060414 -269.32254) (xy 265.990175 -269.14644) (xy 265.912575 -268.973458)
			(xy 265.827752 -268.803901) (xy 265.735856 -268.63807) (xy 265.637051 -268.476261) (xy 265.531512 -268.318762)
			(xy 265.419428 -268.165851) (xy 265.300997 -268.017801) (xy 265.17643 -267.874876) (xy 265.045949 -267.737329)
			(xy 264.909785 -267.605405) (xy 264.768181 -267.479338) (xy 264.621388 -267.359353) (xy 264.469667 -267.245663)
			(xy 264.313289 -267.13847) (xy 264.15253 -267.037964) (xy 263.987678 -266.944325) (xy 263.819024 -266.857719)
			(xy 263.64687 -266.7783) (xy 263.471521 -266.706209) (xy 263.293288 -266.641574) (xy 263.112489 -266.58451)
			(xy 262.929445 -266.535118) (xy 262.744482 -266.493487) (xy 262.557928 -266.459691) (xy 262.370115 -266.433789)
			(xy 262.181377 -266.415827) (xy 261.99205 -266.405839) (xy 261.80247 -266.40384) (xy 261.612974 -266.409835)
			(xy 261.423899 -266.423813) (xy 261.235582 -266.44575) (xy 261.048357 -266.475606) (xy 260.862557 -266.513328)
			(xy 260.678513 -266.558849) (xy 260.496551 -266.612089) (xy 260.316995 -266.672952) (xy 260.140165 -266.74133)
			(xy 259.966374 -266.817102) (xy 259.795932 -266.900133) (xy 259.629142 -266.990276) (xy 259.466301 -267.08737)
			(xy 259.307697 -267.191242) (xy 259.153613 -267.301708) (xy 259.004323 -267.418572) (xy 258.860093 -267.541625)
			(xy 258.721178 -267.670649) (xy 258.587825 -267.805414) (xy 258.460273 -267.945682) (xy 258.338747 -268.091202)
			(xy 258.223464 -268.241715) (xy 258.114628 -268.396955) (xy 258.012434 -268.556645) (xy 257.917062 -268.720501)
			(xy 257.828683 -268.888232) (xy 257.747453 -269.05954) (xy 257.673517 -269.234119) (xy 257.607007 -269.411661)
			(xy 257.54804 -269.591848) (xy 257.496722 -269.774361) (xy 257.453143 -269.958876) (xy 257.417382 -270.145063)
			(xy 257.389502 -270.332592) (xy 257.369551 -270.52113) (xy 257.357567 -270.710342) (xy 257.35357 -270.89989)
			(xy 259.080771 -270.89989) (xy 259.084763 -270.751254) (xy 259.096728 -270.603047) (xy 259.11663 -270.455695)
			(xy 259.144413 -270.309625) (xy 259.179997 -270.165256) (xy 259.223279 -270.023005) (xy 259.274133 -269.883283)
			(xy 259.332415 -269.746491) (xy 259.397955 -269.613026) (xy 259.470564 -269.48327) (xy 259.550033 -269.357599)
			(xy 259.636134 -269.236375) (xy 259.728617 -269.119947) (xy 259.827216 -269.008652) (xy 259.931648 -268.902809)
			(xy 260.04161 -268.802724) (xy 260.156785 -268.708686) (xy 260.276842 -268.620966) (xy 260.401435 -268.539817)
			(xy 260.530204 -268.465472) (xy 260.662778 -268.398146) (xy 260.798774 -268.338034) (xy 260.937801 -268.285308)
			(xy 261.079458 -268.24012) (xy 261.223336 -268.202602) (xy 261.369021 -268.17286) (xy 261.516092 -268.150981)
			(xy 261.664125 -268.137028) (xy 261.812694 -268.131041) (xy 261.96137 -268.133037) (xy 262.109725 -268.14301)
			(xy 262.25733 -268.160933) (xy 262.403761 -268.186753) (xy 262.548595 -268.220395) (xy 262.691413 -268.261763)
			(xy 262.831806 -268.310737) (xy 262.969367 -268.367177) (xy 263.103701 -268.430919) (xy 263.23442 -268.50178)
			(xy 263.361146 -268.579555) (xy 263.483515 -268.66402) (xy 263.601174 -268.754932) (xy 263.713783 -268.852028)
			(xy 263.821018 -268.955029) (xy 263.92257 -269.063638) (xy 264.018146 -269.17754) (xy 264.10747 -269.296409)
			(xy 264.190285 -269.419901) (xy 264.266352 -269.54766) (xy 264.335451 -269.679318) (xy 264.397384 -269.814496)
			(xy 264.451972 -269.952802) (xy 264.499057 -270.09384) (xy 264.538504 -270.237201) (xy 264.570199 -270.382473)
			(xy 264.59405 -270.529237) (xy 264.60999 -270.67707) (xy 264.617971 -270.825545) (xy 264.61847 -270.89989)
			(xy 264.617971 -270.974235) (xy 264.60999 -271.12271) (xy 264.59405 -271.270543) (xy 264.570199 -271.417307)
			(xy 264.538504 -271.562579) (xy 264.499057 -271.70594) (xy 264.451972 -271.846978) (xy 264.397384 -271.985284)
			(xy 264.335451 -272.120462) (xy 264.266352 -272.25212) (xy 264.190285 -272.379879) (xy 264.10747 -272.503371)
			(xy 264.018146 -272.62224) (xy 263.92257 -272.736142) (xy 263.821018 -272.844751) (xy 263.713783 -272.947752)
			(xy 263.601174 -273.044848) (xy 263.483515 -273.13576) (xy 263.361146 -273.220225) (xy 263.23442 -273.298)
			(xy 263.103701 -273.368861) (xy 262.969367 -273.432603) (xy 262.831806 -273.489043) (xy 262.691413 -273.538017)
			(xy 262.548595 -273.579385) (xy 262.403761 -273.613027) (xy 262.25733 -273.638847) (xy 262.109725 -273.65677)
			(xy 261.96137 -273.666743) (xy 261.812694 -273.668739) (xy 261.664125 -273.662752) (xy 261.516092 -273.648799)
			(xy 261.369021 -273.62692) (xy 261.223336 -273.597178) (xy 261.079458 -273.55966) (xy 260.937801 -273.514472)
			(xy 260.798774 -273.461746) (xy 260.662778 -273.401634) (xy 260.530204 -273.334308) (xy 260.401435 -273.259963)
			(xy 260.276842 -273.178814) (xy 260.156785 -273.091094) (xy 260.04161 -272.997056) (xy 259.931648 -272.896971)
			(xy 259.827216 -272.791128) (xy 259.728617 -272.679833) (xy 259.636134 -272.563405) (xy 259.550033 -272.442181)
			(xy 259.470564 -272.31651) (xy 259.397955 -272.186754) (xy 259.332415 -272.053289) (xy 259.274133 -271.916497)
			(xy 259.223279 -271.776775) (xy 259.179997 -271.634524) (xy 259.144413 -271.490155) (xy 259.11663 -271.344085)
			(xy 259.096728 -271.196733) (xy 259.084763 -271.048526) (xy 259.080771 -270.89989) (xy 257.35357 -270.89989)
			(xy 257.357567 -271.089438) (xy 257.369551 -271.27865) (xy 257.389502 -271.467188) (xy 257.417382 -271.654717)
			(xy 257.453143 -271.840904) (xy 257.496722 -272.025419) (xy 257.54804 -272.207932) (xy 257.607007 -272.388119)
			(xy 257.673517 -272.565661) (xy 257.747453 -272.74024) (xy 257.828683 -272.911548) (xy 257.917062 -273.079279)
			(xy 258.012434 -273.243135) (xy 258.114628 -273.402825) (xy 258.223464 -273.558065) (xy 258.338747 -273.708578)
			(xy 258.460273 -273.854098) (xy 258.587825 -273.994366) (xy 258.721178 -274.129131) (xy 258.860093 -274.258155)
			(xy 259.004323 -274.381208) (xy 259.153613 -274.498072) (xy 259.307697 -274.608538) (xy 259.466301 -274.71241)
			(xy 259.629142 -274.809504) (xy 259.795932 -274.899647) (xy 259.966374 -274.982678) (xy 260.140165 -275.05845)
			(xy 260.316995 -275.126828) (xy 260.496551 -275.187691) (xy 260.678513 -275.240931) (xy 260.862557 -275.286452)
			(xy 261.048357 -275.324174) (xy 261.235582 -275.35403) (xy 261.423899 -275.375967) (xy 261.612974 -275.389945)
			(xy 261.80247 -275.39594) (xy 261.99205 -275.393941) (xy 262.181377 -275.383953) (xy 262.370115 -275.365991)
			(xy 262.557928 -275.340089) (xy 262.744482 -275.306293) (xy 262.929445 -275.264662) (xy 263.112489 -275.21527)
			(xy 263.293288 -275.158206) (xy 263.471521 -275.093571) (xy 263.64687 -275.02148) (xy 263.819024 -274.942061)
			(xy 263.987678 -274.855455) (xy 264.15253 -274.761816) (xy 264.313289 -274.66131) (xy 264.469667 -274.554117)
			(xy 264.621388 -274.440427) (xy 264.768181 -274.320442) (xy 264.909785 -274.194375) (xy 265.045949 -274.062451)
			(xy 265.17643 -273.924904) (xy 265.300997 -273.781979) (xy 265.419428 -273.633929) (xy 265.531512 -273.481018)
			(xy 265.637051 -273.323519) (xy 265.735856 -273.16171) (xy 265.827752 -272.995879) (xy 265.912575 -272.826322)
			(xy 265.990175 -272.65334) (xy 266.060414 -272.47724) (xy 266.123166 -272.298336) (xy 266.178321 -272.116946)
			(xy 266.22578 -271.933391) (xy 266.265459 -271.747999) (xy 266.297287 -271.561099) (xy 266.321207 -271.373024)
			(xy 266.337178 -271.184107) (xy 266.345171 -270.994685)
		)
		(stroke
			(width 0)
			(type solid)
		)
		(fill yes)
		(layer "F.Cu")
		(net "GND")
	)
	(gr_poly
		(pts
			(xy 326.34555 -320.900044) (xy 326.345051 -320.805249) (xy 326.337058 -320.615827) (xy 326.321087 -320.42691)
			(xy 326.297167 -320.238835) (xy 326.265339 -320.051935) (xy 326.22566 -319.866543) (xy 326.178201 -319.682988)
			(xy 326.123046 -319.501598) (xy 326.060294 -319.322694) (xy 325.990055 -319.146594) (xy 325.912455 -318.973612)
			(xy 325.827632 -318.804055) (xy 325.735736 -318.638224) (xy 325.636931 -318.476415) (xy 325.531392 -318.318916)
			(xy 325.419308 -318.166005) (xy 325.300877 -318.017955) (xy 325.17631 -317.87503) (xy 325.045829 -317.737483)
			(xy 324.909665 -317.605559) (xy 324.768061 -317.479492) (xy 324.621268 -317.359507) (xy 324.469547 -317.245817)
			(xy 324.313169 -317.138624) (xy 324.15241 -317.038118) (xy 323.987558 -316.944479) (xy 323.818904 -316.857873)
			(xy 323.64675 -316.778454) (xy 323.471401 -316.706363) (xy 323.293168 -316.641728) (xy 323.112369 -316.584664)
			(xy 322.929325 -316.535272) (xy 322.744362 -316.493641) (xy 322.557808 -316.459845) (xy 322.369995 -316.433943)
			(xy 322.181257 -316.415981) (xy 321.99193 -316.405993) (xy 321.80235 -316.403994) (xy 321.612854 -316.409989)
			(xy 321.423779 -316.423967) (xy 321.235462 -316.445904) (xy 321.048237 -316.47576) (xy 320.862437 -316.513482)
			(xy 320.678393 -316.559003) (xy 320.496431 -316.612243) (xy 320.316875 -316.673106) (xy 320.140045 -316.741484)
			(xy 319.966254 -316.817256) (xy 319.795812 -316.900287) (xy 319.629022 -316.99043) (xy 319.466181 -317.087524)
			(xy 319.307577 -317.191396) (xy 319.153493 -317.301862) (xy 319.004203 -317.418726) (xy 318.859973 -317.541779)
			(xy 318.721058 -317.670803) (xy 318.587705 -317.805568) (xy 318.460153 -317.945836) (xy 318.338627 -318.091356)
			(xy 318.223344 -318.241869) (xy 318.114508 -318.397109) (xy 318.012314 -318.556799) (xy 317.916942 -318.720655)
			(xy 317.828563 -318.888386) (xy 317.747333 -319.059694) (xy 317.673397 -319.234273) (xy 317.606887 -319.411815)
			(xy 317.54792 -319.592002) (xy 317.496602 -319.774515) (xy 317.453023 -319.95903) (xy 317.417262 -320.145217)
			(xy 317.389382 -320.332746) (xy 317.369431 -320.521284) (xy 317.357447 -320.710496) (xy 317.35345 -320.900044)
			(xy 319.080651 -320.900044) (xy 319.084643 -320.751408) (xy 319.096608 -320.603201) (xy 319.11651 -320.455849)
			(xy 319.144293 -320.309779) (xy 319.179877 -320.16541) (xy 319.223159 -320.023159) (xy 319.274013 -319.883437)
			(xy 319.332295 -319.746645) (xy 319.397835 -319.61318) (xy 319.470444 -319.483424) (xy 319.549913 -319.357753)
			(xy 319.636014 -319.236529) (xy 319.728497 -319.120101) (xy 319.827096 -319.008806) (xy 319.931528 -318.902963)
			(xy 320.04149 -318.802878) (xy 320.156665 -318.70884) (xy 320.276722 -318.62112) (xy 320.401315 -318.539971)
			(xy 320.530084 -318.465626) (xy 320.662658 -318.3983) (xy 320.798654 -318.338188) (xy 320.937681 -318.285462)
			(xy 321.079338 -318.240274) (xy 321.223216 -318.202756) (xy 321.368901 -318.173014) (xy 321.515972 -318.151135)
			(xy 321.664005 -318.137182) (xy 321.812574 -318.131195) (xy 321.96125 -318.133191) (xy 322.109605 -318.143164)
			(xy 322.25721 -318.161087) (xy 322.403641 -318.186907) (xy 322.548475 -318.220549) (xy 322.691293 -318.261917)
			(xy 322.831686 -318.310891) (xy 322.969247 -318.367331) (xy 323.103581 -318.431073) (xy 323.2343 -318.501934)
			(xy 323.361026 -318.579709) (xy 323.483395 -318.664174) (xy 323.601054 -318.755086) (xy 323.713663 -318.852182)
			(xy 323.820898 -318.955183) (xy 323.92245 -319.063792) (xy 324.018026 -319.177694) (xy 324.10735 -319.296563)
			(xy 324.190165 -319.420055) (xy 324.266232 -319.547814) (xy 324.335331 -319.679472) (xy 324.397264 -319.81465)
			(xy 324.451852 -319.952956) (xy 324.498937 -320.093994) (xy 324.538384 -320.237355) (xy 324.570079 -320.382627)
			(xy 324.59393 -320.529391) (xy 324.60987 -320.677224) (xy 324.617851 -320.825699) (xy 324.61835 -320.900044)
			(xy 324.617851 -320.974389) (xy 324.60987 -321.122864) (xy 324.59393 -321.270697) (xy 324.570079 -321.417461)
			(xy 324.538384 -321.562733) (xy 324.498937 -321.706094) (xy 324.451852 -321.847132) (xy 324.397264 -321.985438)
			(xy 324.335331 -322.120616) (xy 324.266232 -322.252274) (xy 324.190165 -322.380033) (xy 324.10735 -322.503525)
			(xy 324.018026 -322.622394) (xy 323.92245 -322.736296) (xy 323.820898 -322.844905) (xy 323.713663 -322.947906)
			(xy 323.601054 -323.045002) (xy 323.483395 -323.135914) (xy 323.361026 -323.220379) (xy 323.2343 -323.298154)
			(xy 323.103581 -323.369015) (xy 322.969247 -323.432757) (xy 322.831686 -323.489197) (xy 322.691293 -323.538171)
			(xy 322.548475 -323.579539) (xy 322.403641 -323.613181) (xy 322.25721 -323.639001) (xy 322.109605 -323.656924)
			(xy 321.96125 -323.666897) (xy 321.812574 -323.668893) (xy 321.664005 -323.662906) (xy 321.515972 -323.648953)
			(xy 321.368901 -323.627074) (xy 321.223216 -323.597332) (xy 321.079338 -323.559814) (xy 320.937681 -323.514626)
			(xy 320.798654 -323.4619) (xy 320.662658 -323.401788) (xy 320.530084 -323.334462) (xy 320.401315 -323.260117)
			(xy 320.276722 -323.178968) (xy 320.156665 -323.091248) (xy 320.04149 -322.99721) (xy 319.931528 -322.897125)
			(xy 319.827096 -322.791282) (xy 319.728497 -322.679987) (xy 319.636014 -322.563559) (xy 319.549913 -322.442335)
			(xy 319.470444 -322.316664) (xy 319.397835 -322.186908) (xy 319.332295 -322.053443) (xy 319.274013 -321.916651)
			(xy 319.223159 -321.776929) (xy 319.179877 -321.634678) (xy 319.144293 -321.490309) (xy 319.11651 -321.344239)
			(xy 319.096608 -321.196887) (xy 319.084643 -321.04868) (xy 319.080651 -320.900044) (xy 317.35345 -320.900044)
			(xy 317.357447 -321.089592) (xy 317.369431 -321.278804) (xy 317.389382 -321.467342) (xy 317.417262 -321.654871)
			(xy 317.453023 -321.841058) (xy 317.496602 -322.025573) (xy 317.54792 -322.208086) (xy 317.606887 -322.388273)
			(xy 317.673397 -322.565815) (xy 317.747333 -322.740394) (xy 317.828563 -322.911702) (xy 317.916942 -323.079433)
			(xy 318.012314 -323.243289) (xy 318.114508 -323.402979) (xy 318.223344 -323.558219) (xy 318.338627 -323.708732)
			(xy 318.460153 -323.854252) (xy 318.587705 -323.99452) (xy 318.721058 -324.129285) (xy 318.859973 -324.258309)
			(xy 319.004203 -324.381362) (xy 319.153493 -324.498226) (xy 319.307577 -324.608692) (xy 319.466181 -324.712564)
			(xy 319.629022 -324.809658) (xy 319.795812 -324.899801) (xy 319.966254 -324.982832) (xy 320.140045 -325.058604)
			(xy 320.316875 -325.126982) (xy 320.496431 -325.187845) (xy 320.678393 -325.241085) (xy 320.862437 -325.286606)
			(xy 321.048237 -325.324328) (xy 321.235462 -325.354184) (xy 321.423779 -325.376121) (xy 321.612854 -325.390099)
			(xy 321.80235 -325.396094) (xy 321.99193 -325.394095) (xy 322.181257 -325.384107) (xy 322.369995 -325.366145)
			(xy 322.557808 -325.340243) (xy 322.744362 -325.306447) (xy 322.929325 -325.264816) (xy 323.112369 -325.215424)
			(xy 323.293168 -325.15836) (xy 323.471401 -325.093725) (xy 323.64675 -325.021634) (xy 323.818904 -324.942215)
			(xy 323.987558 -324.855609) (xy 324.15241 -324.76197) (xy 324.313169 -324.661464) (xy 324.469547 -324.554271)
			(xy 324.621268 -324.440581) (xy 324.768061 -324.320596) (xy 324.909665 -324.194529) (xy 325.045829 -324.062605)
			(xy 325.17631 -323.925058) (xy 325.300877 -323.782133) (xy 325.419308 -323.634083) (xy 325.531392 -323.481172)
			(xy 325.636931 -323.323673) (xy 325.735736 -323.161864) (xy 325.827632 -322.996033) (xy 325.912455 -322.826476)
			(xy 325.990055 -322.653494) (xy 326.060294 -322.477394) (xy 326.123046 -322.29849) (xy 326.178201 -322.1171)
			(xy 326.22566 -321.933545) (xy 326.265339 -321.748153) (xy 326.297167 -321.561253) (xy 326.321087 -321.373178)
			(xy 326.337058 -321.184261) (xy 326.345051 -320.994839)
		)
		(stroke
			(width 0)
			(type solid)
		)
		(fill yes)
		(layer "F.Cu")
		(net "GND")
	)
	(gr_poly
		(pts
			(xy 326.34555 -270.89989) (xy 326.345051 -270.805095) (xy 326.337058 -270.615673) (xy 326.321087 -270.426756)
			(xy 326.297167 -270.238681) (xy 326.265339 -270.051781) (xy 326.22566 -269.866389) (xy 326.178201 -269.682834)
			(xy 326.123046 -269.501444) (xy 326.060294 -269.32254) (xy 325.990055 -269.14644) (xy 325.912455 -268.973458)
			(xy 325.827632 -268.803901) (xy 325.735736 -268.63807) (xy 325.636931 -268.476261) (xy 325.531392 -268.318762)
			(xy 325.419308 -268.165851) (xy 325.300877 -268.017801) (xy 325.17631 -267.874876) (xy 325.045829 -267.737329)
			(xy 324.909665 -267.605405) (xy 324.768061 -267.479338) (xy 324.621268 -267.359353) (xy 324.469547 -267.245663)
			(xy 324.313169 -267.13847) (xy 324.15241 -267.037964) (xy 323.987558 -266.944325) (xy 323.818904 -266.857719)
			(xy 323.64675 -266.7783) (xy 323.471401 -266.706209) (xy 323.293168 -266.641574) (xy 323.112369 -266.58451)
			(xy 322.929325 -266.535118) (xy 322.744362 -266.493487) (xy 322.557808 -266.459691) (xy 322.369995 -266.433789)
			(xy 322.181257 -266.415827) (xy 321.99193 -266.405839) (xy 321.80235 -266.40384) (xy 321.612854 -266.409835)
			(xy 321.423779 -266.423813) (xy 321.235462 -266.44575) (xy 321.048237 -266.475606) (xy 320.862437 -266.513328)
			(xy 320.678393 -266.558849) (xy 320.496431 -266.612089) (xy 320.316875 -266.672952) (xy 320.140045 -266.74133)
			(xy 319.966254 -266.817102) (xy 319.795812 -266.900133) (xy 319.629022 -266.990276) (xy 319.466181 -267.08737)
			(xy 319.307577 -267.191242) (xy 319.153493 -267.301708) (xy 319.004203 -267.418572) (xy 318.859973 -267.541625)
			(xy 318.721058 -267.670649) (xy 318.587705 -267.805414) (xy 318.460153 -267.945682) (xy 318.338627 -268.091202)
			(xy 318.223344 -268.241715) (xy 318.114508 -268.396955) (xy 318.012314 -268.556645) (xy 317.916942 -268.720501)
			(xy 317.828563 -268.888232) (xy 317.747333 -269.05954) (xy 317.673397 -269.234119) (xy 317.606887 -269.411661)
			(xy 317.54792 -269.591848) (xy 317.496602 -269.774361) (xy 317.453023 -269.958876) (xy 317.417262 -270.145063)
			(xy 317.389382 -270.332592) (xy 317.369431 -270.52113) (xy 317.357447 -270.710342) (xy 317.35345 -270.89989)
			(xy 319.080651 -270.89989) (xy 319.084643 -270.751254) (xy 319.096608 -270.603047) (xy 319.11651 -270.455695)
			(xy 319.144293 -270.309625) (xy 319.179877 -270.165256) (xy 319.223159 -270.023005) (xy 319.274013 -269.883283)
			(xy 319.332295 -269.746491) (xy 319.397835 -269.613026) (xy 319.470444 -269.48327) (xy 319.549913 -269.357599)
			(xy 319.636014 -269.236375) (xy 319.728497 -269.119947) (xy 319.827096 -269.008652) (xy 319.931528 -268.902809)
			(xy 320.04149 -268.802724) (xy 320.156665 -268.708686) (xy 320.276722 -268.620966) (xy 320.401315 -268.539817)
			(xy 320.530084 -268.465472) (xy 320.662658 -268.398146) (xy 320.798654 -268.338034) (xy 320.937681 -268.285308)
			(xy 321.079338 -268.24012) (xy 321.223216 -268.202602) (xy 321.368901 -268.17286) (xy 321.515972 -268.150981)
			(xy 321.664005 -268.137028) (xy 321.812574 -268.131041) (xy 321.96125 -268.133037) (xy 322.109605 -268.14301)
			(xy 322.25721 -268.160933) (xy 322.403641 -268.186753) (xy 322.548475 -268.220395) (xy 322.691293 -268.261763)
			(xy 322.831686 -268.310737) (xy 322.969247 -268.367177) (xy 323.103581 -268.430919) (xy 323.2343 -268.50178)
			(xy 323.361026 -268.579555) (xy 323.483395 -268.66402) (xy 323.601054 -268.754932) (xy 323.713663 -268.852028)
			(xy 323.820898 -268.955029) (xy 323.92245 -269.063638) (xy 324.018026 -269.17754) (xy 324.10735 -269.296409)
			(xy 324.190165 -269.419901) (xy 324.266232 -269.54766) (xy 324.335331 -269.679318) (xy 324.397264 -269.814496)
			(xy 324.451852 -269.952802) (xy 324.498937 -270.09384) (xy 324.538384 -270.237201) (xy 324.570079 -270.382473)
			(xy 324.59393 -270.529237) (xy 324.60987 -270.67707) (xy 324.617851 -270.825545) (xy 324.61835 -270.89989)
			(xy 324.617851 -270.974235) (xy 324.60987 -271.12271) (xy 324.59393 -271.270543) (xy 324.570079 -271.417307)
			(xy 324.538384 -271.562579) (xy 324.498937 -271.70594) (xy 324.451852 -271.846978) (xy 324.397264 -271.985284)
			(xy 324.335331 -272.120462) (xy 324.266232 -272.25212) (xy 324.190165 -272.379879) (xy 324.10735 -272.503371)
			(xy 324.018026 -272.62224) (xy 323.92245 -272.736142) (xy 323.820898 -272.844751) (xy 323.713663 -272.947752)
			(xy 323.601054 -273.044848) (xy 323.483395 -273.13576) (xy 323.361026 -273.220225) (xy 323.2343 -273.298)
			(xy 323.103581 -273.368861) (xy 322.969247 -273.432603) (xy 322.831686 -273.489043) (xy 322.691293 -273.538017)
			(xy 322.548475 -273.579385) (xy 322.403641 -273.613027) (xy 322.25721 -273.638847) (xy 322.109605 -273.65677)
			(xy 321.96125 -273.666743) (xy 321.812574 -273.668739) (xy 321.664005 -273.662752) (xy 321.515972 -273.648799)
			(xy 321.368901 -273.62692) (xy 321.223216 -273.597178) (xy 321.079338 -273.55966) (xy 320.937681 -273.514472)
			(xy 320.798654 -273.461746) (xy 320.662658 -273.401634) (xy 320.530084 -273.334308) (xy 320.401315 -273.259963)
			(xy 320.276722 -273.178814) (xy 320.156665 -273.091094) (xy 320.04149 -272.997056) (xy 319.931528 -272.896971)
			(xy 319.827096 -272.791128) (xy 319.728497 -272.679833) (xy 319.636014 -272.563405) (xy 319.549913 -272.442181)
			(xy 319.470444 -272.31651) (xy 319.397835 -272.186754) (xy 319.332295 -272.053289) (xy 319.274013 -271.916497)
			(xy 319.223159 -271.776775) (xy 319.179877 -271.634524) (xy 319.144293 -271.490155) (xy 319.11651 -271.344085)
			(xy 319.096608 -271.196733) (xy 319.084643 -271.048526) (xy 319.080651 -270.89989) (xy 317.35345 -270.89989)
			(xy 317.357447 -271.089438) (xy 317.369431 -271.27865) (xy 317.389382 -271.467188) (xy 317.417262 -271.654717)
			(xy 317.453023 -271.840904) (xy 317.496602 -272.025419) (xy 317.54792 -272.207932) (xy 317.606887 -272.388119)
			(xy 317.673397 -272.565661) (xy 317.747333 -272.74024) (xy 317.828563 -272.911548) (xy 317.916942 -273.079279)
			(xy 318.012314 -273.243135) (xy 318.114508 -273.402825) (xy 318.223344 -273.558065) (xy 318.338627 -273.708578)
			(xy 318.460153 -273.854098) (xy 318.587705 -273.994366) (xy 318.721058 -274.129131) (xy 318.859973 -274.258155)
			(xy 319.004203 -274.381208) (xy 319.153493 -274.498072) (xy 319.307577 -274.608538) (xy 319.466181 -274.71241)
			(xy 319.629022 -274.809504) (xy 319.795812 -274.899647) (xy 319.966254 -274.982678) (xy 320.140045 -275.05845)
			(xy 320.316875 -275.126828) (xy 320.496431 -275.187691) (xy 320.678393 -275.240931) (xy 320.862437 -275.286452)
			(xy 321.048237 -275.324174) (xy 321.235462 -275.35403) (xy 321.423779 -275.375967) (xy 321.612854 -275.389945)
			(xy 321.80235 -275.39594) (xy 321.99193 -275.393941) (xy 322.181257 -275.383953) (xy 322.369995 -275.365991)
			(xy 322.557808 -275.340089) (xy 322.744362 -275.306293) (xy 322.929325 -275.264662) (xy 323.112369 -275.21527)
			(xy 323.293168 -275.158206) (xy 323.471401 -275.093571) (xy 323.64675 -275.02148) (xy 323.818904 -274.942061)
			(xy 323.987558 -274.855455) (xy 324.15241 -274.761816) (xy 324.313169 -274.66131) (xy 324.469547 -274.554117)
			(xy 324.621268 -274.440427) (xy 324.768061 -274.320442) (xy 324.909665 -274.194375) (xy 325.045829 -274.062451)
			(xy 325.17631 -273.924904) (xy 325.300877 -273.781979) (xy 325.419308 -273.633929) (xy 325.531392 -273.481018)
			(xy 325.636931 -273.323519) (xy 325.735736 -273.16171) (xy 325.827632 -272.995879) (xy 325.912455 -272.826322)
			(xy 325.990055 -272.65334) (xy 326.060294 -272.47724) (xy 326.123046 -272.298336) (xy 326.178201 -272.116946)
			(xy 326.22566 -271.933391) (xy 326.265339 -271.747999) (xy 326.297167 -271.561099) (xy 326.321087 -271.373024)
			(xy 326.337058 -271.184107) (xy 326.345051 -270.994685)
		)
		(stroke
			(width 0)
			(type solid)
		)
		(fill yes)
		(layer "F.Cu")
		(net "GND")
	)
	(gr_poly
		(pts
			(xy 382.445514 -320.900044) (xy 382.445015 -320.805249) (xy 382.437022 -320.615827) (xy 382.421051 -320.42691)
			(xy 382.397131 -320.238835) (xy 382.365303 -320.051935) (xy 382.325624 -319.866543) (xy 382.278165 -319.682988)
			(xy 382.22301 -319.501598) (xy 382.160258 -319.322694) (xy 382.090019 -319.146594) (xy 382.012419 -318.973612)
			(xy 381.927596 -318.804055) (xy 381.8357 -318.638224) (xy 381.736895 -318.476415) (xy 381.631356 -318.318916)
			(xy 381.519272 -318.166005) (xy 381.400841 -318.017955) (xy 381.276274 -317.87503) (xy 381.145793 -317.737483)
			(xy 381.009629 -317.605559) (xy 380.868025 -317.479492) (xy 380.721232 -317.359507) (xy 380.569511 -317.245817)
			(xy 380.413133 -317.138624) (xy 380.252374 -317.038118) (xy 380.087522 -316.944479) (xy 379.918868 -316.857873)
			(xy 379.746714 -316.778454) (xy 379.571365 -316.706363) (xy 379.393132 -316.641728) (xy 379.212333 -316.584664)
			(xy 379.029289 -316.535272) (xy 378.844326 -316.493641) (xy 378.657772 -316.459845) (xy 378.469959 -316.433943)
			(xy 378.281221 -316.415981) (xy 378.091894 -316.405993) (xy 377.902314 -316.403994) (xy 377.712818 -316.409989)
			(xy 377.523743 -316.423967) (xy 377.335426 -316.445904) (xy 377.148201 -316.47576) (xy 376.962401 -316.513482)
			(xy 376.778357 -316.559003) (xy 376.596395 -316.612243) (xy 376.416839 -316.673106) (xy 376.240009 -316.741484)
			(xy 376.066218 -316.817256) (xy 375.895776 -316.900287) (xy 375.728986 -316.99043) (xy 375.566145 -317.087524)
			(xy 375.407541 -317.191396) (xy 375.253457 -317.301862) (xy 375.104167 -317.418726) (xy 374.959937 -317.541779)
			(xy 374.821022 -317.670803) (xy 374.687669 -317.805568) (xy 374.560117 -317.945836) (xy 374.438591 -318.091356)
			(xy 374.323308 -318.241869) (xy 374.214472 -318.397109) (xy 374.112278 -318.556799) (xy 374.016906 -318.720655)
			(xy 373.928527 -318.888386) (xy 373.847297 -319.059694) (xy 373.773361 -319.234273) (xy 373.706851 -319.411815)
			(xy 373.647884 -319.592002) (xy 373.596566 -319.774515) (xy 373.552987 -319.95903) (xy 373.517226 -320.145217)
			(xy 373.489346 -320.332746) (xy 373.469395 -320.521284) (xy 373.457411 -320.710496) (xy 373.453414 -320.900044)
			(xy 375.180615 -320.900044) (xy 375.184607 -320.751408) (xy 375.196572 -320.603201) (xy 375.216474 -320.455849)
			(xy 375.244257 -320.309779) (xy 375.279841 -320.16541) (xy 375.323123 -320.023159) (xy 375.373977 -319.883437)
			(xy 375.432259 -319.746645) (xy 375.497799 -319.61318) (xy 375.570408 -319.483424) (xy 375.649877 -319.357753)
			(xy 375.735978 -319.236529) (xy 375.828461 -319.120101) (xy 375.92706 -319.008806) (xy 376.031492 -318.902963)
			(xy 376.141454 -318.802878) (xy 376.256629 -318.70884) (xy 376.376686 -318.62112) (xy 376.501279 -318.539971)
			(xy 376.630048 -318.465626) (xy 376.762622 -318.3983) (xy 376.898618 -318.338188) (xy 377.037645 -318.285462)
			(xy 377.179302 -318.240274) (xy 377.32318 -318.202756) (xy 377.468865 -318.173014) (xy 377.615936 -318.151135)
			(xy 377.763969 -318.137182) (xy 377.912538 -318.131195) (xy 378.061214 -318.133191) (xy 378.209569 -318.143164)
			(xy 378.357174 -318.161087) (xy 378.503605 -318.186907) (xy 378.648439 -318.220549) (xy 378.791257 -318.261917)
			(xy 378.93165 -318.310891) (xy 379.069211 -318.367331) (xy 379.203545 -318.431073) (xy 379.334264 -318.501934)
			(xy 379.46099 -318.579709) (xy 379.583359 -318.664174) (xy 379.701018 -318.755086) (xy 379.813627 -318.852182)
			(xy 379.920862 -318.955183) (xy 380.022414 -319.063792) (xy 380.11799 -319.177694) (xy 380.207314 -319.296563)
			(xy 380.290129 -319.420055) (xy 380.366196 -319.547814) (xy 380.435295 -319.679472) (xy 380.497228 -319.81465)
			(xy 380.551816 -319.952956) (xy 380.598901 -320.093994) (xy 380.638348 -320.237355) (xy 380.670043 -320.382627)
			(xy 380.693894 -320.529391) (xy 380.709834 -320.677224) (xy 380.717815 -320.825699) (xy 380.718314 -320.900044)
			(xy 380.717815 -320.974389) (xy 380.709834 -321.122864) (xy 380.693894 -321.270697) (xy 380.670043 -321.417461)
			(xy 380.638348 -321.562733) (xy 380.598901 -321.706094) (xy 380.551816 -321.847132) (xy 380.497228 -321.985438)
			(xy 380.435295 -322.120616) (xy 380.366196 -322.252274) (xy 380.290129 -322.380033) (xy 380.207314 -322.503525)
			(xy 380.11799 -322.622394) (xy 380.022414 -322.736296) (xy 379.920862 -322.844905) (xy 379.813627 -322.947906)
			(xy 379.701018 -323.045002) (xy 379.583359 -323.135914) (xy 379.46099 -323.220379) (xy 379.334264 -323.298154)
			(xy 379.203545 -323.369015) (xy 379.069211 -323.432757) (xy 378.93165 -323.489197) (xy 378.791257 -323.538171)
			(xy 378.648439 -323.579539) (xy 378.503605 -323.613181) (xy 378.357174 -323.639001) (xy 378.209569 -323.656924)
			(xy 378.061214 -323.666897) (xy 377.912538 -323.668893) (xy 377.763969 -323.662906) (xy 377.615936 -323.648953)
			(xy 377.468865 -323.627074) (xy 377.32318 -323.597332) (xy 377.179302 -323.559814) (xy 377.037645 -323.514626)
			(xy 376.898618 -323.4619) (xy 376.762622 -323.401788) (xy 376.630048 -323.334462) (xy 376.501279 -323.260117)
			(xy 376.376686 -323.178968) (xy 376.256629 -323.091248) (xy 376.141454 -322.99721) (xy 376.031492 -322.897125)
			(xy 375.92706 -322.791282) (xy 375.828461 -322.679987) (xy 375.735978 -322.563559) (xy 375.649877 -322.442335)
			(xy 375.570408 -322.316664) (xy 375.497799 -322.186908) (xy 375.432259 -322.053443) (xy 375.373977 -321.916651)
			(xy 375.323123 -321.776929) (xy 375.279841 -321.634678) (xy 375.244257 -321.490309) (xy 375.216474 -321.344239)
			(xy 375.196572 -321.196887) (xy 375.184607 -321.04868) (xy 375.180615 -320.900044) (xy 373.453414 -320.900044)
			(xy 373.457411 -321.089592) (xy 373.469395 -321.278804) (xy 373.489346 -321.467342) (xy 373.517226 -321.654871)
			(xy 373.552987 -321.841058) (xy 373.596566 -322.025573) (xy 373.647884 -322.208086) (xy 373.706851 -322.388273)
			(xy 373.773361 -322.565815) (xy 373.847297 -322.740394) (xy 373.928527 -322.911702) (xy 374.016906 -323.079433)
			(xy 374.112278 -323.243289) (xy 374.214472 -323.402979) (xy 374.323308 -323.558219) (xy 374.438591 -323.708732)
			(xy 374.560117 -323.854252) (xy 374.687669 -323.99452) (xy 374.821022 -324.129285) (xy 374.959937 -324.258309)
			(xy 375.104167 -324.381362) (xy 375.253457 -324.498226) (xy 375.407541 -324.608692) (xy 375.566145 -324.712564)
			(xy 375.728986 -324.809658) (xy 375.895776 -324.899801) (xy 376.066218 -324.982832) (xy 376.240009 -325.058604)
			(xy 376.416839 -325.126982) (xy 376.596395 -325.187845) (xy 376.778357 -325.241085) (xy 376.962401 -325.286606)
			(xy 377.148201 -325.324328) (xy 377.335426 -325.354184) (xy 377.523743 -325.376121) (xy 377.712818 -325.390099)
			(xy 377.902314 -325.396094) (xy 378.091894 -325.394095) (xy 378.281221 -325.384107) (xy 378.469959 -325.366145)
			(xy 378.657772 -325.340243) (xy 378.844326 -325.306447) (xy 379.029289 -325.264816) (xy 379.212333 -325.215424)
			(xy 379.393132 -325.15836) (xy 379.571365 -325.093725) (xy 379.746714 -325.021634) (xy 379.918868 -324.942215)
			(xy 380.087522 -324.855609) (xy 380.252374 -324.76197) (xy 380.413133 -324.661464) (xy 380.569511 -324.554271)
			(xy 380.721232 -324.440581) (xy 380.868025 -324.320596) (xy 381.009629 -324.194529) (xy 381.145793 -324.062605)
			(xy 381.276274 -323.925058) (xy 381.400841 -323.782133) (xy 381.519272 -323.634083) (xy 381.631356 -323.481172)
			(xy 381.736895 -323.323673) (xy 381.8357 -323.161864) (xy 381.927596 -322.996033) (xy 382.012419 -322.826476)
			(xy 382.090019 -322.653494) (xy 382.160258 -322.477394) (xy 382.22301 -322.29849) (xy 382.278165 -322.1171)
			(xy 382.325624 -321.933545) (xy 382.365303 -321.748153) (xy 382.397131 -321.561253) (xy 382.421051 -321.373178)
			(xy 382.437022 -321.184261) (xy 382.445015 -320.994839)
		)
		(stroke
			(width 0)
			(type solid)
		)
		(fill yes)
		(layer "F.Cu")
		(net "GND")
	)
	(gr_poly
		(pts
			(xy 382.445514 -270.89989) (xy 382.445015 -270.805095) (xy 382.437022 -270.615673) (xy 382.421051 -270.426756)
			(xy 382.397131 -270.238681) (xy 382.365303 -270.051781) (xy 382.325624 -269.866389) (xy 382.278165 -269.682834)
			(xy 382.22301 -269.501444) (xy 382.160258 -269.32254) (xy 382.090019 -269.14644) (xy 382.012419 -268.973458)
			(xy 381.927596 -268.803901) (xy 381.8357 -268.63807) (xy 381.736895 -268.476261) (xy 381.631356 -268.318762)
			(xy 381.519272 -268.165851) (xy 381.400841 -268.017801) (xy 381.276274 -267.874876) (xy 381.145793 -267.737329)
			(xy 381.009629 -267.605405) (xy 380.868025 -267.479338) (xy 380.721232 -267.359353) (xy 380.569511 -267.245663)
			(xy 380.413133 -267.13847) (xy 380.252374 -267.037964) (xy 380.087522 -266.944325) (xy 379.918868 -266.857719)
			(xy 379.746714 -266.7783) (xy 379.571365 -266.706209) (xy 379.393132 -266.641574) (xy 379.212333 -266.58451)
			(xy 379.029289 -266.535118) (xy 378.844326 -266.493487) (xy 378.657772 -266.459691) (xy 378.469959 -266.433789)
			(xy 378.281221 -266.415827) (xy 378.091894 -266.405839) (xy 377.902314 -266.40384) (xy 377.712818 -266.409835)
			(xy 377.523743 -266.423813) (xy 377.335426 -266.44575) (xy 377.148201 -266.475606) (xy 376.962401 -266.513328)
			(xy 376.778357 -266.558849) (xy 376.596395 -266.612089) (xy 376.416839 -266.672952) (xy 376.240009 -266.74133)
			(xy 376.066218 -266.817102) (xy 375.895776 -266.900133) (xy 375.728986 -266.990276) (xy 375.566145 -267.08737)
			(xy 375.407541 -267.191242) (xy 375.253457 -267.301708) (xy 375.104167 -267.418572) (xy 374.959937 -267.541625)
			(xy 374.821022 -267.670649) (xy 374.687669 -267.805414) (xy 374.560117 -267.945682) (xy 374.438591 -268.091202)
			(xy 374.323308 -268.241715) (xy 374.214472 -268.396955) (xy 374.112278 -268.556645) (xy 374.016906 -268.720501)
			(xy 373.928527 -268.888232) (xy 373.847297 -269.05954) (xy 373.773361 -269.234119) (xy 373.706851 -269.411661)
			(xy 373.647884 -269.591848) (xy 373.596566 -269.774361) (xy 373.552987 -269.958876) (xy 373.517226 -270.145063)
			(xy 373.489346 -270.332592) (xy 373.469395 -270.52113) (xy 373.457411 -270.710342) (xy 373.453414 -270.89989)
			(xy 375.180615 -270.89989) (xy 375.184607 -270.751254) (xy 375.196572 -270.603047) (xy 375.216474 -270.455695)
			(xy 375.244257 -270.309625) (xy 375.279841 -270.165256) (xy 375.323123 -270.023005) (xy 375.373977 -269.883283)
			(xy 375.432259 -269.746491) (xy 375.497799 -269.613026) (xy 375.570408 -269.48327) (xy 375.649877 -269.357599)
			(xy 375.735978 -269.236375) (xy 375.828461 -269.119947) (xy 375.92706 -269.008652) (xy 376.031492 -268.902809)
			(xy 376.141454 -268.802724) (xy 376.256629 -268.708686) (xy 376.376686 -268.620966) (xy 376.501279 -268.539817)
			(xy 376.630048 -268.465472) (xy 376.762622 -268.398146) (xy 376.898618 -268.338034) (xy 377.037645 -268.285308)
			(xy 377.179302 -268.24012) (xy 377.32318 -268.202602) (xy 377.468865 -268.17286) (xy 377.615936 -268.150981)
			(xy 377.763969 -268.137028) (xy 377.912538 -268.131041) (xy 378.061214 -268.133037) (xy 378.209569 -268.14301)
			(xy 378.357174 -268.160933) (xy 378.503605 -268.186753) (xy 378.648439 -268.220395) (xy 378.791257 -268.261763)
			(xy 378.93165 -268.310737) (xy 379.069211 -268.367177) (xy 379.203545 -268.430919) (xy 379.334264 -268.50178)
			(xy 379.46099 -268.579555) (xy 379.583359 -268.66402) (xy 379.701018 -268.754932) (xy 379.813627 -268.852028)
			(xy 379.920862 -268.955029) (xy 380.022414 -269.063638) (xy 380.11799 -269.17754) (xy 380.207314 -269.296409)
			(xy 380.290129 -269.419901) (xy 380.366196 -269.54766) (xy 380.435295 -269.679318) (xy 380.497228 -269.814496)
			(xy 380.551816 -269.952802) (xy 380.598901 -270.09384) (xy 380.638348 -270.237201) (xy 380.670043 -270.382473)
			(xy 380.693894 -270.529237) (xy 380.709834 -270.67707) (xy 380.717815 -270.825545) (xy 380.718314 -270.89989)
			(xy 380.717815 -270.974235) (xy 380.709834 -271.12271) (xy 380.693894 -271.270543) (xy 380.670043 -271.417307)
			(xy 380.638348 -271.562579) (xy 380.598901 -271.70594) (xy 380.551816 -271.846978) (xy 380.497228 -271.985284)
			(xy 380.435295 -272.120462) (xy 380.366196 -272.25212) (xy 380.290129 -272.379879) (xy 380.207314 -272.503371)
			(xy 380.11799 -272.62224) (xy 380.022414 -272.736142) (xy 379.920862 -272.844751) (xy 379.813627 -272.947752)
			(xy 379.701018 -273.044848) (xy 379.583359 -273.13576) (xy 379.46099 -273.220225) (xy 379.334264 -273.298)
			(xy 379.203545 -273.368861) (xy 379.069211 -273.432603) (xy 378.93165 -273.489043) (xy 378.791257 -273.538017)
			(xy 378.648439 -273.579385) (xy 378.503605 -273.613027) (xy 378.357174 -273.638847) (xy 378.209569 -273.65677)
			(xy 378.061214 -273.666743) (xy 377.912538 -273.668739) (xy 377.763969 -273.662752) (xy 377.615936 -273.648799)
			(xy 377.468865 -273.62692) (xy 377.32318 -273.597178) (xy 377.179302 -273.55966) (xy 377.037645 -273.514472)
			(xy 376.898618 -273.461746) (xy 376.762622 -273.401634) (xy 376.630048 -273.334308) (xy 376.501279 -273.259963)
			(xy 376.376686 -273.178814) (xy 376.256629 -273.091094) (xy 376.141454 -272.997056) (xy 376.031492 -272.896971)
			(xy 375.92706 -272.791128) (xy 375.828461 -272.679833) (xy 375.735978 -272.563405) (xy 375.649877 -272.442181)
			(xy 375.570408 -272.31651) (xy 375.497799 -272.186754) (xy 375.432259 -272.053289) (xy 375.373977 -271.916497)
			(xy 375.323123 -271.776775) (xy 375.279841 -271.634524) (xy 375.244257 -271.490155) (xy 375.216474 -271.344085)
			(xy 375.196572 -271.196733) (xy 375.184607 -271.048526) (xy 375.180615 -270.89989) (xy 373.453414 -270.89989)
			(xy 373.457411 -271.089438) (xy 373.469395 -271.27865) (xy 373.489346 -271.467188) (xy 373.517226 -271.654717)
			(xy 373.552987 -271.840904) (xy 373.596566 -272.025419) (xy 373.647884 -272.207932) (xy 373.706851 -272.388119)
			(xy 373.773361 -272.565661) (xy 373.847297 -272.74024) (xy 373.928527 -272.911548) (xy 374.016906 -273.079279)
			(xy 374.112278 -273.243135) (xy 374.214472 -273.402825) (xy 374.323308 -273.558065) (xy 374.438591 -273.708578)
			(xy 374.560117 -273.854098) (xy 374.687669 -273.994366) (xy 374.821022 -274.129131) (xy 374.959937 -274.258155)
			(xy 375.104167 -274.381208) (xy 375.253457 -274.498072) (xy 375.407541 -274.608538) (xy 375.566145 -274.71241)
			(xy 375.728986 -274.809504) (xy 375.895776 -274.899647) (xy 376.066218 -274.982678) (xy 376.240009 -275.05845)
			(xy 376.416839 -275.126828) (xy 376.596395 -275.187691) (xy 376.778357 -275.240931) (xy 376.962401 -275.286452)
			(xy 377.148201 -275.324174) (xy 377.335426 -275.35403) (xy 377.523743 -275.375967) (xy 377.712818 -275.389945)
			(xy 377.902314 -275.39594) (xy 378.091894 -275.393941) (xy 378.281221 -275.383953) (xy 378.469959 -275.365991)
			(xy 378.657772 -275.340089) (xy 378.844326 -275.306293) (xy 379.029289 -275.264662) (xy 379.212333 -275.21527)
			(xy 379.393132 -275.158206) (xy 379.571365 -275.093571) (xy 379.746714 -275.02148) (xy 379.918868 -274.942061)
			(xy 380.087522 -274.855455) (xy 380.252374 -274.761816) (xy 380.413133 -274.66131) (xy 380.569511 -274.554117)
			(xy 380.721232 -274.440427) (xy 380.868025 -274.320442) (xy 381.009629 -274.194375) (xy 381.145793 -274.062451)
			(xy 381.276274 -273.924904) (xy 381.400841 -273.781979) (xy 381.519272 -273.633929) (xy 381.631356 -273.481018)
			(xy 381.736895 -273.323519) (xy 381.8357 -273.16171) (xy 381.927596 -272.995879) (xy 382.012419 -272.826322)
			(xy 382.090019 -272.65334) (xy 382.160258 -272.47724) (xy 382.22301 -272.298336) (xy 382.278165 -272.116946)
			(xy 382.325624 -271.933391) (xy 382.365303 -271.747999) (xy 382.397131 -271.561099) (xy 382.421051 -271.373024)
			(xy 382.437022 -271.184107) (xy 382.445015 -270.994685)
		)
		(stroke
			(width 0)
			(type solid)
		)
		(fill yes)
		(layer "F.Cu")
		(net "GND")
	)
	(gr_poly
		(pts
			(xy 442.445648 -320.900044) (xy 442.445149 -320.805249) (xy 442.437156 -320.615827) (xy 442.421185 -320.42691)
			(xy 442.397265 -320.238835) (xy 442.365437 -320.051935) (xy 442.325758 -319.866543) (xy 442.278299 -319.682988)
			(xy 442.223144 -319.501598) (xy 442.160392 -319.322694) (xy 442.090153 -319.146594) (xy 442.012553 -318.973612)
			(xy 441.92773 -318.804055) (xy 441.835834 -318.638224) (xy 441.737029 -318.476415) (xy 441.63149 -318.318916)
			(xy 441.519406 -318.166005) (xy 441.400975 -318.017955) (xy 441.276408 -317.87503) (xy 441.145927 -317.737483)
			(xy 441.009763 -317.605559) (xy 440.868159 -317.479492) (xy 440.721366 -317.359507) (xy 440.569645 -317.245817)
			(xy 440.413267 -317.138624) (xy 440.252508 -317.038118) (xy 440.087656 -316.944479) (xy 439.919002 -316.857873)
			(xy 439.746848 -316.778454) (xy 439.571499 -316.706363) (xy 439.393266 -316.641728) (xy 439.212467 -316.584664)
			(xy 439.029423 -316.535272) (xy 438.84446 -316.493641) (xy 438.657906 -316.459845) (xy 438.470093 -316.433943)
			(xy 438.281355 -316.415981) (xy 438.092028 -316.405993) (xy 437.902448 -316.403994) (xy 437.712952 -316.409989)
			(xy 437.523877 -316.423967) (xy 437.33556 -316.445904) (xy 437.148335 -316.47576) (xy 436.962535 -316.513482)
			(xy 436.778491 -316.559003) (xy 436.596529 -316.612243) (xy 436.416973 -316.673106) (xy 436.240143 -316.741484)
			(xy 436.066352 -316.817256) (xy 435.89591 -316.900287) (xy 435.72912 -316.99043) (xy 435.566279 -317.087524)
			(xy 435.407675 -317.191396) (xy 435.253591 -317.301862) (xy 435.104301 -317.418726) (xy 434.960071 -317.541779)
			(xy 434.821156 -317.670803) (xy 434.687803 -317.805568) (xy 434.560251 -317.945836) (xy 434.438725 -318.091356)
			(xy 434.323442 -318.241869) (xy 434.214606 -318.397109) (xy 434.112412 -318.556799) (xy 434.01704 -318.720655)
			(xy 433.928661 -318.888386) (xy 433.847431 -319.059694) (xy 433.773495 -319.234273) (xy 433.706985 -319.411815)
			(xy 433.648018 -319.592002) (xy 433.5967 -319.774515) (xy 433.553121 -319.95903) (xy 433.51736 -320.145217)
			(xy 433.48948 -320.332746) (xy 433.469529 -320.521284) (xy 433.457545 -320.710496) (xy 433.453548 -320.900044)
			(xy 435.180749 -320.900044) (xy 435.184741 -320.751408) (xy 435.196706 -320.603201) (xy 435.216608 -320.455849)
			(xy 435.244391 -320.309779) (xy 435.279975 -320.16541) (xy 435.323257 -320.023159) (xy 435.374111 -319.883437)
			(xy 435.432393 -319.746645) (xy 435.497933 -319.61318) (xy 435.570542 -319.483424) (xy 435.650011 -319.357753)
			(xy 435.736112 -319.236529) (xy 435.828595 -319.120101) (xy 435.927194 -319.008806) (xy 436.031626 -318.902963)
			(xy 436.141588 -318.802878) (xy 436.256763 -318.70884) (xy 436.37682 -318.62112) (xy 436.501413 -318.539971)
			(xy 436.630182 -318.465626) (xy 436.762756 -318.3983) (xy 436.898752 -318.338188) (xy 437.037779 -318.285462)
			(xy 437.179436 -318.240274) (xy 437.323314 -318.202756) (xy 437.468999 -318.173014) (xy 437.61607 -318.151135)
			(xy 437.764103 -318.137182) (xy 437.912672 -318.131195) (xy 438.061348 -318.133191) (xy 438.209703 -318.143164)
			(xy 438.357308 -318.161087) (xy 438.503739 -318.186907) (xy 438.648573 -318.220549) (xy 438.791391 -318.261917)
			(xy 438.931784 -318.310891) (xy 439.069345 -318.367331) (xy 439.203679 -318.431073) (xy 439.334398 -318.501934)
			(xy 439.461124 -318.579709) (xy 439.583493 -318.664174) (xy 439.701152 -318.755086) (xy 439.813761 -318.852182)
			(xy 439.920996 -318.955183) (xy 440.022548 -319.063792) (xy 440.118124 -319.177694) (xy 440.207448 -319.296563)
			(xy 440.290263 -319.420055) (xy 440.36633 -319.547814) (xy 440.435429 -319.679472) (xy 440.497362 -319.81465)
			(xy 440.55195 -319.952956) (xy 440.599035 -320.093994) (xy 440.638482 -320.237355) (xy 440.670177 -320.382627)
			(xy 440.694028 -320.529391) (xy 440.709968 -320.677224) (xy 440.717949 -320.825699) (xy 440.718448 -320.900044)
			(xy 440.717949 -320.974389) (xy 440.709968 -321.122864) (xy 440.694028 -321.270697) (xy 440.670177 -321.417461)
			(xy 440.638482 -321.562733) (xy 440.599035 -321.706094) (xy 440.55195 -321.847132) (xy 440.497362 -321.985438)
			(xy 440.435429 -322.120616) (xy 440.36633 -322.252274) (xy 440.290263 -322.380033) (xy 440.207448 -322.503525)
			(xy 440.118124 -322.622394) (xy 440.022548 -322.736296) (xy 439.920996 -322.844905) (xy 439.813761 -322.947906)
			(xy 439.701152 -323.045002) (xy 439.583493 -323.135914) (xy 439.461124 -323.220379) (xy 439.334398 -323.298154)
			(xy 439.203679 -323.369015) (xy 439.069345 -323.432757) (xy 438.931784 -323.489197) (xy 438.791391 -323.538171)
			(xy 438.648573 -323.579539) (xy 438.503739 -323.613181) (xy 438.357308 -323.639001) (xy 438.209703 -323.656924)
			(xy 438.061348 -323.666897) (xy 437.912672 -323.668893) (xy 437.764103 -323.662906) (xy 437.61607 -323.648953)
			(xy 437.468999 -323.627074) (xy 437.323314 -323.597332) (xy 437.179436 -323.559814) (xy 437.037779 -323.514626)
			(xy 436.898752 -323.4619) (xy 436.762756 -323.401788) (xy 436.630182 -323.334462) (xy 436.501413 -323.260117)
			(xy 436.37682 -323.178968) (xy 436.256763 -323.091248) (xy 436.141588 -322.99721) (xy 436.031626 -322.897125)
			(xy 435.927194 -322.791282) (xy 435.828595 -322.679987) (xy 435.736112 -322.563559) (xy 435.650011 -322.442335)
			(xy 435.570542 -322.316664) (xy 435.497933 -322.186908) (xy 435.432393 -322.053443) (xy 435.374111 -321.916651)
			(xy 435.323257 -321.776929) (xy 435.279975 -321.634678) (xy 435.244391 -321.490309) (xy 435.216608 -321.344239)
			(xy 435.196706 -321.196887) (xy 435.184741 -321.04868) (xy 435.180749 -320.900044) (xy 433.453548 -320.900044)
			(xy 433.457545 -321.089592) (xy 433.469529 -321.278804) (xy 433.48948 -321.467342) (xy 433.51736 -321.654871)
			(xy 433.553121 -321.841058) (xy 433.5967 -322.025573) (xy 433.648018 -322.208086) (xy 433.706985 -322.388273)
			(xy 433.773495 -322.565815) (xy 433.847431 -322.740394) (xy 433.928661 -322.911702) (xy 434.01704 -323.079433)
			(xy 434.112412 -323.243289) (xy 434.214606 -323.402979) (xy 434.323442 -323.558219) (xy 434.438725 -323.708732)
			(xy 434.560251 -323.854252) (xy 434.687803 -323.99452) (xy 434.821156 -324.129285) (xy 434.960071 -324.258309)
			(xy 435.104301 -324.381362) (xy 435.253591 -324.498226) (xy 435.407675 -324.608692) (xy 435.566279 -324.712564)
			(xy 435.72912 -324.809658) (xy 435.89591 -324.899801) (xy 436.066352 -324.982832) (xy 436.240143 -325.058604)
			(xy 436.416973 -325.126982) (xy 436.596529 -325.187845) (xy 436.778491 -325.241085) (xy 436.962535 -325.286606)
			(xy 437.148335 -325.324328) (xy 437.33556 -325.354184) (xy 437.523877 -325.376121) (xy 437.712952 -325.390099)
			(xy 437.902448 -325.396094) (xy 438.092028 -325.394095) (xy 438.281355 -325.384107) (xy 438.470093 -325.366145)
			(xy 438.657906 -325.340243) (xy 438.84446 -325.306447) (xy 439.029423 -325.264816) (xy 439.212467 -325.215424)
			(xy 439.393266 -325.15836) (xy 439.571499 -325.093725) (xy 439.746848 -325.021634) (xy 439.919002 -324.942215)
			(xy 440.087656 -324.855609) (xy 440.252508 -324.76197) (xy 440.413267 -324.661464) (xy 440.569645 -324.554271)
			(xy 440.721366 -324.440581) (xy 440.868159 -324.320596) (xy 441.009763 -324.194529) (xy 441.145927 -324.062605)
			(xy 441.276408 -323.925058) (xy 441.400975 -323.782133) (xy 441.519406 -323.634083) (xy 441.63149 -323.481172)
			(xy 441.737029 -323.323673) (xy 441.835834 -323.161864) (xy 441.92773 -322.996033) (xy 442.012553 -322.826476)
			(xy 442.090153 -322.653494) (xy 442.160392 -322.477394) (xy 442.223144 -322.29849) (xy 442.278299 -322.1171)
			(xy 442.325758 -321.933545) (xy 442.365437 -321.748153) (xy 442.397265 -321.561253) (xy 442.421185 -321.373178)
			(xy 442.437156 -321.184261) (xy 442.445149 -320.994839)
		)
		(stroke
			(width 0)
			(type solid)
		)
		(fill yes)
		(layer "F.Cu")
		(net "GND")
	)
	(gr_poly
		(pts
			(xy 442.445648 -270.89989) (xy 442.445149 -270.805095) (xy 442.437156 -270.615673) (xy 442.421185 -270.426756)
			(xy 442.397265 -270.238681) (xy 442.365437 -270.051781) (xy 442.325758 -269.866389) (xy 442.278299 -269.682834)
			(xy 442.223144 -269.501444) (xy 442.160392 -269.32254) (xy 442.090153 -269.14644) (xy 442.012553 -268.973458)
			(xy 441.92773 -268.803901) (xy 441.835834 -268.63807) (xy 441.737029 -268.476261) (xy 441.63149 -268.318762)
			(xy 441.519406 -268.165851) (xy 441.400975 -268.017801) (xy 441.276408 -267.874876) (xy 441.145927 -267.737329)
			(xy 441.009763 -267.605405) (xy 440.868159 -267.479338) (xy 440.721366 -267.359353) (xy 440.569645 -267.245663)
			(xy 440.413267 -267.13847) (xy 440.252508 -267.037964) (xy 440.087656 -266.944325) (xy 439.919002 -266.857719)
			(xy 439.746848 -266.7783) (xy 439.571499 -266.706209) (xy 439.393266 -266.641574) (xy 439.212467 -266.58451)
			(xy 439.029423 -266.535118) (xy 438.84446 -266.493487) (xy 438.657906 -266.459691) (xy 438.470093 -266.433789)
			(xy 438.281355 -266.415827) (xy 438.092028 -266.405839) (xy 437.902448 -266.40384) (xy 437.712952 -266.409835)
			(xy 437.523877 -266.423813) (xy 437.33556 -266.44575) (xy 437.148335 -266.475606) (xy 436.962535 -266.513328)
			(xy 436.778491 -266.558849) (xy 436.596529 -266.612089) (xy 436.416973 -266.672952) (xy 436.240143 -266.74133)
			(xy 436.066352 -266.817102) (xy 435.89591 -266.900133) (xy 435.72912 -266.990276) (xy 435.566279 -267.08737)
			(xy 435.407675 -267.191242) (xy 435.253591 -267.301708) (xy 435.104301 -267.418572) (xy 434.960071 -267.541625)
			(xy 434.821156 -267.670649) (xy 434.687803 -267.805414) (xy 434.560251 -267.945682) (xy 434.438725 -268.091202)
			(xy 434.323442 -268.241715) (xy 434.214606 -268.396955) (xy 434.112412 -268.556645) (xy 434.01704 -268.720501)
			(xy 433.928661 -268.888232) (xy 433.847431 -269.05954) (xy 433.773495 -269.234119) (xy 433.706985 -269.411661)
			(xy 433.648018 -269.591848) (xy 433.5967 -269.774361) (xy 433.553121 -269.958876) (xy 433.51736 -270.145063)
			(xy 433.48948 -270.332592) (xy 433.469529 -270.52113) (xy 433.457545 -270.710342) (xy 433.453548 -270.89989)
			(xy 435.180749 -270.89989) (xy 435.184741 -270.751254) (xy 435.196706 -270.603047) (xy 435.216608 -270.455695)
			(xy 435.244391 -270.309625) (xy 435.279975 -270.165256) (xy 435.323257 -270.023005) (xy 435.374111 -269.883283)
			(xy 435.432393 -269.746491) (xy 435.497933 -269.613026) (xy 435.570542 -269.48327) (xy 435.650011 -269.357599)
			(xy 435.736112 -269.236375) (xy 435.828595 -269.119947) (xy 435.927194 -269.008652) (xy 436.031626 -268.902809)
			(xy 436.141588 -268.802724) (xy 436.256763 -268.708686) (xy 436.37682 -268.620966) (xy 436.501413 -268.539817)
			(xy 436.630182 -268.465472) (xy 436.762756 -268.398146) (xy 436.898752 -268.338034) (xy 437.037779 -268.285308)
			(xy 437.179436 -268.24012) (xy 437.323314 -268.202602) (xy 437.468999 -268.17286) (xy 437.61607 -268.150981)
			(xy 437.764103 -268.137028) (xy 437.912672 -268.131041) (xy 438.061348 -268.133037) (xy 438.209703 -268.14301)
			(xy 438.357308 -268.160933) (xy 438.503739 -268.186753) (xy 438.648573 -268.220395) (xy 438.791391 -268.261763)
			(xy 438.931784 -268.310737) (xy 439.069345 -268.367177) (xy 439.203679 -268.430919) (xy 439.334398 -268.50178)
			(xy 439.461124 -268.579555) (xy 439.583493 -268.66402) (xy 439.701152 -268.754932) (xy 439.813761 -268.852028)
			(xy 439.920996 -268.955029) (xy 440.022548 -269.063638) (xy 440.118124 -269.17754) (xy 440.207448 -269.296409)
			(xy 440.290263 -269.419901) (xy 440.36633 -269.54766) (xy 440.435429 -269.679318) (xy 440.497362 -269.814496)
			(xy 440.55195 -269.952802) (xy 440.599035 -270.09384) (xy 440.638482 -270.237201) (xy 440.670177 -270.382473)
			(xy 440.694028 -270.529237) (xy 440.709968 -270.67707) (xy 440.717949 -270.825545) (xy 440.718448 -270.89989)
			(xy 440.717949 -270.974235) (xy 440.709968 -271.12271) (xy 440.694028 -271.270543) (xy 440.670177 -271.417307)
			(xy 440.638482 -271.562579) (xy 440.599035 -271.70594) (xy 440.55195 -271.846978) (xy 440.497362 -271.985284)
			(xy 440.435429 -272.120462) (xy 440.36633 -272.25212) (xy 440.290263 -272.379879) (xy 440.207448 -272.503371)
			(xy 440.118124 -272.62224) (xy 440.022548 -272.736142) (xy 439.920996 -272.844751) (xy 439.813761 -272.947752)
			(xy 439.701152 -273.044848) (xy 439.583493 -273.13576) (xy 439.461124 -273.220225) (xy 439.334398 -273.298)
			(xy 439.203679 -273.368861) (xy 439.069345 -273.432603) (xy 438.931784 -273.489043) (xy 438.791391 -273.538017)
			(xy 438.648573 -273.579385) (xy 438.503739 -273.613027) (xy 438.357308 -273.638847) (xy 438.209703 -273.65677)
			(xy 438.061348 -273.666743) (xy 437.912672 -273.668739) (xy 437.764103 -273.662752) (xy 437.61607 -273.648799)
			(xy 437.468999 -273.62692) (xy 437.323314 -273.597178) (xy 437.179436 -273.55966) (xy 437.037779 -273.514472)
			(xy 436.898752 -273.461746) (xy 436.762756 -273.401634) (xy 436.630182 -273.334308) (xy 436.501413 -273.259963)
			(xy 436.37682 -273.178814) (xy 436.256763 -273.091094) (xy 436.141588 -272.997056) (xy 436.031626 -272.896971)
			(xy 435.927194 -272.791128) (xy 435.828595 -272.679833) (xy 435.736112 -272.563405) (xy 435.650011 -272.442181)
			(xy 435.570542 -272.31651) (xy 435.497933 -272.186754) (xy 435.432393 -272.053289) (xy 435.374111 -271.916497)
			(xy 435.323257 -271.776775) (xy 435.279975 -271.634524) (xy 435.244391 -271.490155) (xy 435.216608 -271.344085)
			(xy 435.196706 -271.196733) (xy 435.184741 -271.048526) (xy 435.180749 -270.89989) (xy 433.453548 -270.89989)
			(xy 433.457545 -271.089438) (xy 433.469529 -271.27865) (xy 433.48948 -271.467188) (xy 433.51736 -271.654717)
			(xy 433.553121 -271.840904) (xy 433.5967 -272.025419) (xy 433.648018 -272.207932) (xy 433.706985 -272.388119)
			(xy 433.773495 -272.565661) (xy 433.847431 -272.74024) (xy 433.928661 -272.911548) (xy 434.01704 -273.079279)
			(xy 434.112412 -273.243135) (xy 434.214606 -273.402825) (xy 434.323442 -273.558065) (xy 434.438725 -273.708578)
			(xy 434.560251 -273.854098) (xy 434.687803 -273.994366) (xy 434.821156 -274.129131) (xy 434.960071 -274.258155)
			(xy 435.104301 -274.381208) (xy 435.253591 -274.498072) (xy 435.407675 -274.608538) (xy 435.566279 -274.71241)
			(xy 435.72912 -274.809504) (xy 435.89591 -274.899647) (xy 436.066352 -274.982678) (xy 436.240143 -275.05845)
			(xy 436.416973 -275.126828) (xy 436.596529 -275.187691) (xy 436.778491 -275.240931) (xy 436.962535 -275.286452)
			(xy 437.148335 -275.324174) (xy 437.33556 -275.35403) (xy 437.523877 -275.375967) (xy 437.712952 -275.389945)
			(xy 437.902448 -275.39594) (xy 438.092028 -275.393941) (xy 438.281355 -275.383953) (xy 438.470093 -275.365991)
			(xy 438.657906 -275.340089) (xy 438.84446 -275.306293) (xy 439.029423 -275.264662) (xy 439.212467 -275.21527)
			(xy 439.393266 -275.158206) (xy 439.571499 -275.093571) (xy 439.746848 -275.02148) (xy 439.919002 -274.942061)
			(xy 440.087656 -274.855455) (xy 440.252508 -274.761816) (xy 440.413267 -274.66131) (xy 440.569645 -274.554117)
			(xy 440.721366 -274.440427) (xy 440.868159 -274.320442) (xy 441.009763 -274.194375) (xy 441.145927 -274.062451)
			(xy 441.276408 -273.924904) (xy 441.400975 -273.781979) (xy 441.519406 -273.633929) (xy 441.63149 -273.481018)
			(xy 441.737029 -273.323519) (xy 441.835834 -273.16171) (xy 441.92773 -272.995879) (xy 442.012553 -272.826322)
			(xy 442.090153 -272.65334) (xy 442.160392 -272.47724) (xy 442.223144 -272.298336) (xy 442.278299 -272.116946)
			(xy 442.325758 -271.933391) (xy 442.365437 -271.747999) (xy 442.397265 -271.561099) (xy 442.421185 -271.373024)
			(xy 442.437156 -271.184107) (xy 442.445149 -270.994685)
		)
		(stroke
			(width 0)
			(type solid)
		)
		(fill yes)
		(layer "F.Cu")
		(net "GND")
	)
	(gr_poly
		(pts
			(arc
				(start 111.426244 -397.678148)
				(mid 111.445631 -397.674198)
				(end 111.462058 -397.663162)
			)
			(arc
				(start 112.042702 -397.082518)
				(mid 112.053764 -397.066101)
				(end 112.057688 -397.046704)
			)
			(arc
				(start 112.057688 -396.46479)
				(mid 112.058625 -396.454822)
				(end 112.061498 -396.445232)
			)
			(arc
				(start 112.068864 -396.42796)
				(mid 112.071737 -396.41837)
				(end 112.072674 -396.408402)
			)
			(arc
				(start 112.072674 -394.498068)
				(mid 112.076575 -394.478545)
				(end 112.08766 -394.462)
			)
			(xy 112.097566 -394.452094)
			(arc
				(start 112.098074 -394.451586)
				(mid 112.108816 -394.435229)
				(end 112.112552 -394.416026)
			)
			(xy 112.112552 -393.30503) (xy 112.104932 -393.286234) (xy 112.097566 -393.279122)
			(arc
				(start 109.926374 -391.10793)
				(mid 109.90984 -391.096819)
				(end 109.890306 -391.092944)
			)
			(arc
				(start 107.31119 -391.092944)
				(mid 107.292882 -391.097249)
				(end 107.277408 -391.10793)
			)
			(xy 107.220512 -391.16508)
			(arc
				(start 107.138216 -391.247376)
				(mid 107.12421 -391.273367)
				(end 107.12704 -391.302748)
			)
			(xy 107.133136 -391.317226) (xy 107.158536 -391.334244)
			(arc
				(start 108.160566 -391.334244)
				(mid 108.17401 -391.332293)
				(end 108.186474 -391.326878)
			)
			(arc
				(start 108.186474 -391.326878)
				(mid 108.280622 -391.286739)
				(end 108.382054 -391.27303)
			)
			(arc
				(start 108.382054 -391.27303)
				(mid 108.561947 -391.318106)
				(end 108.6993 -391.442702)
			)
			(arc
				(start 108.6993 -391.442702)
				(mid 108.713596 -391.456974)
				(end 108.73232 -391.464546)
			)
			(arc
				(start 108.73232 -391.464546)
				(mid 108.786625 -391.483649)
				(end 108.832904 -391.517886)
			)
			(arc
				(start 109.367828 -392.05281)
				(mid 109.391998 -392.082103)
				(end 109.409992 -392.115548)
			)
			(arc
				(start 109.84103 -393.156186)
				(mid 109.851905 -393.192431)
				(end 109.855508 -393.2301)
			)
			(arc
				(start 109.855508 -393.371832)
				(mid 109.870387 -393.407753)
				(end 109.906308 -393.422632)
			)
			(arc
				(start 109.990636 -393.422632)
				(mid 110.026646 -393.437495)
				(end 110.041436 -393.473432)
			)
			(arc
				(start 110.041436 -394.006832)
				(mid 110.026557 -394.042753)
				(end 109.990636 -394.057632)
			)
			(arc
				(start 109.88294 -394.057632)
				(mid 109.847019 -394.072511)
				(end 109.83214 -394.108432)
			)
			(arc
				(start 109.83214 -394.217906)
				(mid 109.817411 -394.291862)
				(end 109.775498 -394.354558)
			)
			(arc
				(start 109.619796 -394.510514)
				(mid 109.60887 -394.52696)
				(end 109.605064 -394.546328)
			)
			(arc
				(start 109.605064 -395.453362)
				(mid 109.608897 -395.472719)
				(end 109.619796 -395.489176)
			)
			(arc
				(start 109.927898 -395.797278)
				(mid 109.944315 -395.80834)
				(end 109.963712 -395.812264)
			)
			(arc
				(start 110.76178 -395.812264)
				(mid 110.851852 -395.84952)
				(end 110.889288 -395.939518)
			)
			(arc
				(start 110.889288 -396.853918)
				(mid 110.851926 -396.94399)
				(end 110.76178 -396.981172)
			)
			(arc
				(start 109.74578 -396.981172)
				(mid 109.655708 -396.943916)
				(end 109.618272 -396.853918)
			)
			(arc
				(start 109.618272 -396.05585)
				(mid 109.614439 -396.036493)
				(end 109.60354 -396.020036)
			)
			(xy 109.274864 -395.691106) (xy 109.264196 -395.67993) (xy 109.2581 -395.672564) (xy 109.242352 -395.663928)
			(xy 109.157262 -395.651736) (xy 109.139482 -395.655546)
			(arc
				(start 109.131608 -395.660626)
				(mid 109.098307 -395.675971)
				(end 109.062012 -395.6812)
			)
			(arc
				(start 108.046012 -395.6812)
				(mid 107.95594 -395.643944)
				(end 107.918504 -395.553946)
			)
			(arc
				(start 107.918504 -395.51864)
				(mid 107.90361 -395.482809)
				(end 107.867704 -395.46784)
			)
			(arc
				(start 107.485434 -395.46784)
				(mid 107.411434 -395.453009)
				(end 107.348782 -395.410944)
			)
			(arc
				(start 107.221782 -395.283944)
				(mid 107.179836 -395.221262)
				(end 107.16514 -395.147292)
			)
			(arc
				(start 107.16514 -394.591794)
				(mid 107.179869 -394.517838)
				(end 107.221782 -394.455142)
			)
			(arc
				(start 107.45216 -394.224764)
				(mid 107.514827 -394.182735)
				(end 107.588812 -394.167868)
			)
			(arc
				(start 108.185204 -394.167868)
				(mid 108.2212 -394.153064)
				(end 108.236004 -394.117068)
			)
			(arc
				(start 108.236004 -393.487148)
				(mid 108.250883 -393.451227)
				(end 108.286804 -393.436348)
			)
			(arc
				(start 108.416852 -393.436348)
				(mid 108.452773 -393.421469)
				(end 108.467652 -393.385548)
			)
			(arc
				(start 108.467652 -393.146788)
				(mid 108.452773 -393.110867)
				(end 108.416852 -393.095988)
			)
			(arc
				(start 108.04906 -393.095988)
				(mid 108.013139 -393.110867)
				(end 107.99826 -393.146788)
			)
			(xy 107.99826 -393.155932)
			(arc
				(start 107.730798 -393.155932)
				(mid 107.570322 -393.089091)
				(end 107.504738 -392.928094)
			)
			(xy 107.504992 -392.928094)
			(arc
				(start 107.504992 -392.705844)
				(mid 107.490024 -392.670087)
				(end 107.454192 -392.655044)
			)
			(arc
				(start 107.270804 -392.655044)
				(mid 107.25736 -392.656995)
				(end 107.244896 -392.66241)
			)
			(xy 107.237276 -392.666728) (xy 107.231434 -392.67003)
			(arc
				(start 107.22102 -392.68019)
				(mid 107.204603 -392.691252)
				(end 107.185206 -392.695176)
			)
			(xy 107.174538 -392.695176)
			(arc
				(start 107.166918 -392.697716)
				(mid 107.108846 -392.71162)
				(end 107.049316 -392.716258)
			)
			(arc
				(start 107.049316 -392.716258)
				(mid 107.026159 -392.71557)
				(end 107.003088 -392.713464)
			)
			(xy 106.991404 -392.71194) (xy 106.96956 -392.71956)
			(arc
				(start 106.618532 -393.070588)
				(mid 106.607421 -393.087122)
				(end 106.603546 -393.106656)
			)
			(arc
				(start 106.603546 -395.68374)
				(mid 106.607447 -395.703263)
				(end 106.618532 -395.719808)
			)
			(arc
				(start 107.092242 -396.193518)
				(mid 107.098644 -396.201221)
				(end 107.103418 -396.210028)
			)
			(xy 107.114594 -396.236952) (xy 107.121706 -396.244064)
			(arc
				(start 108.540804 -397.663162)
				(mid 108.557338 -397.674273)
				(end 108.576872 -397.678148)
			)
		)
		(stroke
			(width 0)
			(type solid)
		)
		(fill yes)
		(layer "F.Cu")
		(net "GND")
	)
	(gr_poly
		(pts
			(arc
				(start 87.765128 -263.124188)
				(mid 89.649808 -262.899043)
				(end 91.534488 -263.124188)
			)
			(xy 91.546426 -263.125712) (xy 104.412288 -263.125712) (xy 107.066334 -260.471666)
			(arc
				(start 110.84306 -260.471666)
				(mid 110.846961 -260.452143)
				(end 110.858046 -260.435598)
			)
			(arc
				(start 111.946436 -259.347208)
				(mid 111.96297 -259.336097)
				(end 111.982504 -259.332222)
			)
			(arc
				(start 112.237266 -259.332222)
				(mid 112.261773 -259.32578)
				(end 112.280192 -259.308346)
			)
			(xy 112.333024 -259.224526) (xy 112.334294 -259.198364)
			(arc
				(start 112.328452 -259.186426)
				(mid 112.300206 -259.105754)
				(end 112.290606 -259.020818)
			)
			(arc
				(start 112.290606 -259.020564)
				(mid 112.672114 -258.639056)
				(end 113.053622 -259.020564)
			)
			(arc
				(start 113.053622 -259.020818)
				(mid 113.044046 -259.105759)
				(end 113.015776 -259.186426)
			)
			(xy 113.009934 -259.198364) (xy 113.011204 -259.224526)
			(arc
				(start 113.064036 -259.308346)
				(mid 113.082413 -259.325854)
				(end 113.106962 -259.332222)
			)
			(arc
				(start 113.909856 -259.332222)
				(mid 113.929379 -259.328321)
				(end 113.945924 -259.317236)
			)
			(arc
				(start 114.321844 -258.941316)
				(mid 114.332955 -258.924782)
				(end 114.33683 -258.905248)
			)
			(arc
				(start 114.33683 -257.101086)
				(mid 114.332929 -257.081563)
				(end 114.321844 -257.065018)
			)
			(arc
				(start 114.060478 -256.803652)
				(mid 114.043944 -256.792541)
				(end 114.02441 -256.788666)
			)
			(arc
				(start 104.65943 -256.788666)
				(mid 104.639907 -256.792567)
				(end 104.623362 -256.803652)
			)
			(arc
				(start 103.004874 -258.42214)
				(mid 102.98834 -258.433251)
				(end 102.968806 -258.437126)
			)
			(arc
				(start 87.114126 -258.437126)
				(mid 87.093528 -258.441489)
				(end 87.076534 -258.45389)
			)
			(xy 87.018876 -258.517644) (xy 87.012272 -258.537964) (xy 87.013288 -258.548632)
			(arc
				(start 87.015066 -258.586224)
				(mid 86.633558 -258.967732)
				(end 86.25205 -258.586224)
			)
			(xy 86.253828 -258.548632) (xy 86.254844 -258.537964) (xy 86.24824 -258.517644)
			(arc
				(start 86.190582 -258.45389)
				(mid 86.173436 -258.44152)
				(end 86.152736 -258.437126)
			)
			(arc
				(start 86.143338 -258.437126)
				(mid 86.107417 -258.452005)
				(end 86.092538 -258.487926)
			)
			(xy 86.092538 -258.497578)
			(arc
				(start 86.096094 -258.506468)
				(mid 86.116033 -258.575188)
				(end 86.122764 -258.646422)
			)
			(arc
				(start 86.122764 -258.646676)
				(mid 85.741256 -259.028184)
				(end 85.359748 -258.646676)
			)
			(arc
				(start 85.359748 -258.646422)
				(mid 85.362187 -258.603607)
				(end 85.3694 -258.561332)
			)
			(xy 85.37194 -258.550156) (xy 85.36686 -258.527296)
			(arc
				(start 85.309964 -258.456176)
				(mid 85.292317 -258.442154)
				(end 85.27034 -258.437126)
			)
			(arc
				(start 85.258656 -258.437126)
				(mid 85.222735 -258.452005)
				(end 85.207856 -258.487926)
			)
			(xy 85.207856 -258.49199)
			(arc
				(start 85.208618 -258.496054)
				(mid 85.212417 -258.526939)
				(end 85.213698 -258.55803)
			)
			(arc
				(start 85.213698 -258.55803)
				(mid 84.83219 -258.939538)
				(end 84.450682 -258.55803)
			)
			(xy 84.450936 -258.54279) (xy 84.451444 -258.532376) (xy 84.444332 -258.513072)
			(arc
				(start 84.386166 -258.45262)
				(mid 84.369458 -258.441133)
				(end 84.34959 -258.437126)
			)
			(arc
				(start 53.405786 -258.437126)
				(mid 53.386263 -258.433225)
				(end 53.369718 -258.42214)
			)
			(arc
				(start 47.563278 -252.615954)
				(mid 47.552167 -252.59942)
				(end 47.548292 -252.579886)
			)
			(arc
				(start 47.548292 -210.603592)
				(mid 47.544391 -210.584069)
				(end 47.533306 -210.567524)
			)
			(xy 12.828016 -175.862234) (xy 12.824968 -175.85944) (xy 12.824968 -168.33723) (xy 12.486894 -167.999156)
			(xy 8.795766 -167.999156) (xy 8.472678 -168.322244) (xy 8.472678 -173.49851) (xy 7.926578 -174.04461)
			(arc
				(start 7.926578 -179.800758)
				(mid 7.930479 -179.820281)
				(end 7.941564 -179.836826)
			)
			(arc
				(start 8.095234 -179.990496)
				(mid 8.111768 -180.001607)
				(end 8.131302 -180.005482)
			)
			(arc
				(start 12.21105 -180.005482)
				(mid 12.230573 -180.009383)
				(end 12.247118 -180.020468)
			)
			(arc
				(start 19.093688 -186.867038)
				(mid 21.587685 -188.572423)
				(end 23.29307 -191.06642)
			)
			(arc
				(start 42.849038 -210.622388)
				(mid 42.860149 -210.638922)
				(end 42.864024 -210.658456)
			)
			(arc
				(start 42.864024 -256.697988)
				(mid 42.867925 -256.717511)
				(end 42.87901 -256.734056)
			)
			(arc
				(start 49.25568 -263.110726)
				(mid 49.272214 -263.121837)
				(end 49.291748 -263.125712)
			)
			(xy 87.75319 -263.125712)
		)
		(stroke
			(width 0)
			(type solid)
		)
		(fill yes)
		(layer "F.Cu")
		(net "P5V_AUX")
	)
	(gr_poly
		(pts
			(xy 105.285794 -335.193132) (xy 105.295783 -335.192597) (xy 105.314219 -335.184888) (xy 105.321608 -335.178146)
			(xy 105.596182 -334.903572) (xy 105.60299 -334.896226) (xy 105.610715 -334.877763) (xy 105.611168 -334.867758)
			(xy 105.611168 -328.294746) (xy 105.610734 -328.284681) (xy 105.603003 -328.266094) (xy 105.596182 -328.258678)
			(xy 105.121456 -327.783698) (xy 105.112994 -327.776147) (xy 105.091632 -327.768617) (xy 105.080308 -327.76922)
			(xy 105.079546 -327.76922) (xy 105.0686 -327.770412) (xy 105.046615 -327.771684) (xy 105.035604 -327.77176)
			(xy 105.009036 -327.771281) (xy 104.956417 -327.763871) (xy 104.905335 -327.749235) (xy 104.856776 -327.727656)
			(xy 104.811679 -327.699551) (xy 104.791002 -327.68286) (xy 104.784144 -327.677272) (xy 104.760014 -327.668382)
			(xy 104.755728 -327.666853) (xy 104.746783 -327.665186) (xy 104.742234 -327.66508) (xy 102.069392 -327.66508)
			(xy 102.059322 -327.665504) (xy 102.040718 -327.673218) (xy 102.033324 -327.680066) (xy 101.714554 -327.99909)
			(xy 101.707736 -328.006432) (xy 101.699992 -328.024895) (xy 101.699568 -328.034904) (xy 101.699568 -328.218292)
			(xy 103.1908 -328.218292) (xy 103.194871 -328.16267) (xy 103.206997 -328.108233) (xy 103.22692 -328.056142)
			(xy 103.254216 -328.007507) (xy 103.288302 -327.963364) (xy 103.328451 -327.924655) (xy 103.373809 -327.892204)
			(xy 103.423409 -327.866703) (xy 103.476193 -327.848696) (xy 103.531036 -327.838566) (xy 103.58677 -327.836529)
			(xy 103.642207 -327.842629) (xy 103.696164 -327.856735) (xy 103.747493 -327.878547) (xy 103.795099 -327.907601)
			(xy 103.837967 -327.943276) (xy 103.875184 -327.984813) (xy 103.905957 -328.031326) (xy 103.929629 -328.081823)
			(xy 103.945697 -328.13523) (xy 103.953817 -328.190406) (xy 103.954326 -328.218292) (xy 103.953817 -328.246178)
			(xy 103.945697 -328.301354) (xy 103.929629 -328.354761) (xy 103.905957 -328.405258) (xy 103.875184 -328.451771)
			(xy 103.837967 -328.493308) (xy 103.795099 -328.528983) (xy 103.747493 -328.558037) (xy 103.696164 -328.579849)
			(xy 103.642207 -328.593955) (xy 103.58677 -328.600055) (xy 103.531036 -328.598018) (xy 103.476193 -328.587888)
			(xy 103.423409 -328.569881) (xy 103.373809 -328.54438) (xy 103.328451 -328.511929) (xy 103.288302 -328.47322)
			(xy 103.254216 -328.429077) (xy 103.22692 -328.380442) (xy 103.206997 -328.328351) (xy 103.194871 -328.273914)
			(xy 103.1908 -328.218292) (xy 101.699568 -328.218292) (xy 101.699568 -328.596244) (xy 101.699784 -328.602823)
			(xy 101.703138 -328.615547) (xy 101.706172 -328.62139) (xy 101.720904 -328.647552) (xy 101.729032 -328.656188)
			(xy 101.73462 -328.65949) (xy 101.757246 -328.674645) (xy 101.798363 -328.710348) (xy 101.833989 -328.751533)
			(xy 101.863398 -328.797364) (xy 101.885995 -328.846911) (xy 101.901319 -328.899165) (xy 101.90906 -328.953068)
			(xy 101.909061 -329.007523) (xy 101.901321 -329.061426) (xy 101.885998 -329.113681) (xy 101.863403 -329.163228)
			(xy 101.833994 -329.20906) (xy 101.79837 -329.250246) (xy 101.757253 -329.28595) (xy 101.73462 -329.301094)
			(xy 101.729032 -329.304396) (xy 101.720904 -329.313032) (xy 101.706172 -329.339194) (xy 101.703071 -329.34501)
			(xy 101.699716 -329.357751) (xy 101.699568 -329.36434) (xy 101.699568 -330.250038) (xy 104.609898 -330.250038)
			(xy 104.613969 -330.194416) (xy 104.626095 -330.139979) (xy 104.646018 -330.087888) (xy 104.673314 -330.039253)
			(xy 104.7074 -329.99511) (xy 104.747549 -329.956401) (xy 104.792907 -329.92395) (xy 104.842507 -329.898449)
			(xy 104.895291 -329.880442) (xy 104.950134 -329.870312) (xy 105.005868 -329.868275) (xy 105.061305 -329.874375)
			(xy 105.115262 -329.888481) (xy 105.166591 -329.910293) (xy 105.214197 -329.939347) (xy 105.257065 -329.975022)
			(xy 105.294282 -330.016559) (xy 105.325055 -330.063072) (xy 105.348727 -330.113569) (xy 105.364795 -330.166976)
			(xy 105.372915 -330.222152) (xy 105.373424 -330.250038) (xy 105.372915 -330.277924) (xy 105.364795 -330.3331)
			(xy 105.348727 -330.386507) (xy 105.325055 -330.437004) (xy 105.294282 -330.483517) (xy 105.257065 -330.525054)
			(xy 105.214197 -330.560729) (xy 105.166591 -330.589783) (xy 105.115262 -330.611595) (xy 105.061305 -330.625701)
			(xy 105.005868 -330.631801) (xy 104.950134 -330.629764) (xy 104.895291 -330.619634) (xy 104.842507 -330.601627)
			(xy 104.792907 -330.576126) (xy 104.747549 -330.543675) (xy 104.7074 -330.504966) (xy 104.673314 -330.460823)
			(xy 104.646018 -330.412188) (xy 104.626095 -330.360097) (xy 104.613969 -330.30566) (xy 104.609898 -330.250038)
			(xy 101.699568 -330.250038) (xy 101.699568 -331.545692) (xy 104.614978 -331.545692) (xy 104.619049 -331.49007)
			(xy 104.631175 -331.435633) (xy 104.651098 -331.383542) (xy 104.678394 -331.334907) (xy 104.71248 -331.290764)
			(xy 104.752629 -331.252055) (xy 104.797987 -331.219604) (xy 104.847587 -331.194103) (xy 104.900371 -331.176096)
			(xy 104.955214 -331.165966) (xy 105.010948 -331.163929) (xy 105.066385 -331.170029) (xy 105.120342 -331.184135)
			(xy 105.171671 -331.205947) (xy 105.219277 -331.235001) (xy 105.262145 -331.270676) (xy 105.299362 -331.312213)
			(xy 105.330135 -331.358726) (xy 105.353807 -331.409223) (xy 105.369875 -331.46263) (xy 105.377995 -331.517806)
			(xy 105.378504 -331.545692) (xy 105.377995 -331.573578) (xy 105.369875 -331.628754) (xy 105.353807 -331.682161)
			(xy 105.330135 -331.732658) (xy 105.299362 -331.779171) (xy 105.262145 -331.820708) (xy 105.219277 -331.856383)
			(xy 105.171671 -331.885437) (xy 105.120342 -331.907249) (xy 105.066385 -331.921355) (xy 105.010948 -331.927455)
			(xy 104.955214 -331.925418) (xy 104.900371 -331.915288) (xy 104.847587 -331.897281) (xy 104.797987 -331.87178)
			(xy 104.752629 -331.839329) (xy 104.71248 -331.80062) (xy 104.678394 -331.756477) (xy 104.651098 -331.707842)
			(xy 104.631175 -331.655751) (xy 104.619049 -331.601314) (xy 104.614978 -331.545692) (xy 101.699568 -331.545692)
			(xy 101.699568 -331.563726) (xy 101.700047 -331.574475) (xy 101.708863 -331.594081) (xy 101.716586 -331.601572)
			(xy 101.78161 -331.659484) (xy 101.80193 -331.665834) (xy 101.812852 -331.664564) (xy 101.823798 -331.663372)
			(xy 101.845783 -331.6621) (xy 101.856794 -331.662024) (xy 101.884045 -331.662487) (xy 101.937992 -331.670242)
			(xy 101.990286 -331.685597) (xy 102.039863 -331.708237) (xy 102.085713 -331.737702) (xy 102.126903 -331.773393)
			(xy 102.162594 -331.814582) (xy 102.19206 -331.860432) (xy 102.214701 -331.910008) (xy 102.230056 -331.962302)
			(xy 102.237813 -332.016249) (xy 102.237813 -332.070751) (xy 102.230056 -332.124698) (xy 102.214701 -332.176992)
			(xy 102.19206 -332.226568) (xy 102.162594 -332.272418) (xy 102.126903 -332.313607) (xy 102.085713 -332.349298)
			(xy 102.039863 -332.378763) (xy 101.990286 -332.401403) (xy 101.937992 -332.416758) (xy 101.884045 -332.424513)
			(xy 101.856794 -332.42504) (xy 101.845783 -332.424962) (xy 101.823798 -332.423692) (xy 101.812852 -332.4225)
			(xy 101.80193 -332.42123) (xy 101.78161 -332.42758) (xy 101.716586 -332.485492) (xy 101.708964 -332.493057)
			(xy 101.700162 -332.512616) (xy 101.699568 -332.523338) (xy 101.699568 -332.862174) (xy 104.620312 -332.862174)
			(xy 104.624383 -332.806552) (xy 104.636509 -332.752115) (xy 104.656432 -332.700024) (xy 104.683728 -332.651389)
			(xy 104.717814 -332.607246) (xy 104.757963 -332.568537) (xy 104.803321 -332.536086) (xy 104.852921 -332.510585)
			(xy 104.905705 -332.492578) (xy 104.960548 -332.482448) (xy 105.016282 -332.480411) (xy 105.071719 -332.486511)
			(xy 105.125676 -332.500617) (xy 105.177005 -332.522429) (xy 105.224611 -332.551483) (xy 105.267479 -332.587158)
			(xy 105.304696 -332.628695) (xy 105.335469 -332.675208) (xy 105.359141 -332.725705) (xy 105.375209 -332.779112)
			(xy 105.383329 -332.834288) (xy 105.383838 -332.862174) (xy 105.383329 -332.89006) (xy 105.375209 -332.945236)
			(xy 105.359141 -332.998643) (xy 105.335469 -333.04914) (xy 105.304696 -333.095653) (xy 105.267479 -333.13719)
			(xy 105.224611 -333.172865) (xy 105.177005 -333.201919) (xy 105.125676 -333.223731) (xy 105.071719 -333.237837)
			(xy 105.016282 -333.243937) (xy 104.960548 -333.2419) (xy 104.905705 -333.23177) (xy 104.852921 -333.213763)
			(xy 104.803321 -333.188262) (xy 104.757963 -333.155811) (xy 104.717814 -333.117102) (xy 104.683728 -333.072959)
			(xy 104.656432 -333.024324) (xy 104.636509 -332.972233) (xy 104.624383 -332.917796) (xy 104.620312 -332.862174)
			(xy 101.699568 -332.862174) (xy 101.699568 -334.28559) (xy 101.699988 -334.295662) (xy 101.707697 -334.314272)
			(xy 101.714554 -334.321658) (xy 102.09657 -334.703674) (xy 102.103971 -334.710512) (xy 102.12257 -334.718225)
			(xy 102.132638 -334.71866) (xy 102.97668 -334.71866) (xy 102.986668 -334.718125) (xy 103.005102 -334.710412)
			(xy 103.012494 -334.703674) (xy 103.090218 -334.62595) (xy 103.09703 -334.618606) (xy 103.104757 -334.600143)
			(xy 103.105204 -334.590136) (xy 103.105204 -333.683356) (xy 103.105635 -333.673289) (xy 103.113361 -333.654697)
			(xy 103.12019 -333.647288) (xy 103.170736 -333.596742) (xy 103.178135 -333.589897) (xy 103.196733 -333.582169)
			(xy 103.206804 -333.581756) (xy 104.176068 -333.581756) (xy 104.186131 -333.582193) (xy 104.204713 -333.589931)
			(xy 104.212136 -333.596742) (xy 104.282748 -333.667354) (xy 104.283002 -333.667608) (xy 104.28605 -333.670656)
			(xy 104.286304 -333.67091) (xy 104.33177 -333.716376) (xy 104.332024 -333.71663) (xy 104.335072 -333.719678)
			(xy 104.335326 -333.719932) (xy 104.405938 -333.790544) (xy 104.412784 -333.797942) (xy 104.420512 -333.816541)
			(xy 104.420924 -333.826612) (xy 104.420924 -335.010506) (xy 104.421349 -335.020575) (xy 104.429067 -335.039176)
			(xy 104.43591 -335.046574) (xy 104.567482 -335.178146) (xy 104.574882 -335.184986) (xy 104.593481 -335.192699)
			(xy 104.60355 -335.193132)
		)
		(stroke
			(width 0)
			(type solid)
		)
		(fill yes)
		(layer "F.Cu")
		(net "PEX_REF_CLK_BUFFER_EN_N")
	)
	(gr_poly
		(pts
			(arc
				(start 250.414536 -82.792824)
				(mid 250.429191 -82.788072)
				(end 250.441714 -82.779108)
			)
			(arc
				(start 251.02947 -82.191352)
				(mid 251.046004 -82.180241)
				(end 251.065538 -82.176366)
			)
			(arc
				(start 251.563124 -82.176366)
				(mid 251.579789 -82.173555)
				(end 251.59462 -82.165444)
			)
			(arc
				(start 251.59462 -82.165444)
				(mid 251.686519 -82.114866)
				(end 251.789946 -82.097372)
			)
			(xy 252.226318 -82.097372) (xy 252.232668 -82.095594) (xy 252.251972 -82.091022)
			(arc
				(start 252.252226 -82.091022)
				(mid 252.284196 -82.08622)
				(end 252.316488 -82.084672)
			)
			(arc
				(start 252.927866 -82.084672)
				(mid 252.960157 -82.086227)
				(end 252.992128 -82.091022)
			)
			(xy 252.992382 -82.091022) (xy 253.011686 -82.095594) (xy 253.018036 -82.097372) (xy 254.396748 -82.097372)
			(xy 254.425958 -82.06867)
			(arc
				(start 254.426466 -82.047842)
				(mid 254.434589 -81.97792)
				(end 254.455422 -81.910682)
			)
			(xy 254.455422 -81.910428)
			(arc
				(start 254.455676 -81.90992)
				(mid 254.459109 -81.8857)
				(end 254.45085 -81.862676)
			)
			(arc
				(start 254.408178 -81.799176)
				(mid 254.389963 -81.78246)
				(end 254.366014 -81.776316)
			)
			(arc
				(start 254.113538 -81.776316)
				(mid 254.039582 -81.761587)
				(end 253.976886 -81.719674)
			)
			(xy 253.334774 -81.077816)
			(arc
				(start 253.281688 -81.02473)
				(mid 253.265271 -81.013668)
				(end 253.245874 -81.009744)
			)
			(arc
				(start 252.723904 -81.009744)
				(mid 252.711316 -81.011393)
				(end 252.69952 -81.016094)
			)
			(xy 252.686566 -81.023206) (xy 252.678184 -81.030826)
			(arc
				(start 252.674628 -81.035652)
				(mid 252.362208 -81.198207)
				(end 252.049788 -81.035652)
			)
			(xy 252.046232 -81.030826) (xy 252.03785 -81.023206)
			(arc
				(start 252.024896 -81.016094)
				(mid 252.013105 -81.011373)
				(end 252.000512 -81.009744)
			)
			(arc
				(start 251.906278 -81.009744)
				(mid 251.888314 -81.026331)
				(end 251.880116 -81.049368)
			)
			(xy 251.880116 -81.189322) (xy 251.850652 -81.21904) (xy 251.275088 -81.21904) (xy 251.245624 -81.189322)
			(arc
				(start 251.245624 -81.049368)
				(mid 251.237434 -81.026326)
				(end 251.219462 -81.009744)
			)
			(arc
				(start 250.983496 -81.009744)
				(mid 250.90954 -80.995015)
				(end 250.846844 -80.953102)
			)
			(xy 250.54814 -80.654652)
			(arc
				(start 250.523502 -80.630014)
				(mid 250.515802 -80.623606)
				(end 250.506992 -80.618838)
			)
			(xy 250.406408 -80.577182)
			(arc
				(start 250.304554 -80.535272)
				(mid 250.295099 -80.532314)
				(end 250.28525 -80.531208)
			)
			(arc
				(start 249.054112 -80.531208)
				(mid 249.036467 -80.535707)
				(end 249.0216 -80.546194)
			)
			(xy 248.836688 -80.731106) (xy 248.834656 -80.74025)
			(arc
				(start 248.834656 -82.098642)
				(mid 248.797384 -82.188624)
				(end 248.707402 -82.225896)
			)
			(arc
				(start 247.488202 -82.225896)
				(mid 247.39822 -82.188624)
				(end 247.360948 -82.098642)
			)
			(arc
				(start 247.360948 -80.600042)
				(mid 247.39822 -80.51006)
				(end 247.488202 -80.472788)
			)
			(xy 248.540778 -80.472788) (xy 248.549922 -80.470756) (xy 248.59234 -80.428338)
			(arc
				(start 248.81967 -80.201262)
				(mid 248.857517 -80.171768)
				(end 248.901458 -80.152494)
			)
			(xy 248.911618 -80.149446) (xy 248.927366 -80.136238)
			(arc
				(start 248.96572 -80.061308)
				(mid 248.971044 -80.041632)
				(end 248.96826 -80.02143)
			)
			(xy 248.96826 -80.021176) (xy 248.96572 -80.013556)
			(arc
				(start 248.96572 -80.013302)
				(mid 248.96225 -79.996187)
				(end 248.961148 -79.978758)
			)
			(arc
				(start 248.961148 -78.480158)
				(mid 248.99842 -78.390176)
				(end 249.088402 -78.352904)
			)
			(arc
				(start 249.465084 -78.352904)
				(mid 249.488126 -78.344714)
				(end 249.504708 -78.326742)
			)
			(arc
				(start 249.504708 -78.279244)
				(mid 249.519437 -78.205288)
				(end 249.56135 -78.142592)
			)
			(arc
				(start 249.68835 -78.015592)
				(mid 249.721767 -77.988873)
				(end 249.760232 -77.970126)
			)
			(arc
				(start 249.760232 -77.970126)
				(mid 249.792127 -77.961629)
				(end 249.825002 -77.958696)
			)
			(arc
				(start 250.683522 -77.958696)
				(mid 250.716395 -77.961643)
				(end 250.748292 -77.970126)
			)
			(arc
				(start 250.748292 -77.970126)
				(mid 250.786777 -77.988841)
				(end 250.820174 -78.015592)
			)
			(arc
				(start 250.96597 -78.161388)
				(mid 251.007916 -78.22407)
				(end 251.022612 -78.29804)
			)
			(arc
				(start 251.022612 -79.417672)
				(mid 251.024261 -79.43026)
				(end 251.028962 -79.442056)
			)
			(xy 251.036328 -79.455264) (xy 251.043694 -79.4639)
			(arc
				(start 251.048774 -79.467202)
				(mid 251.100705 -79.51121)
				(end 251.144024 -79.563722)
			)
			(xy 251.15139 -79.57439) (xy 251.173234 -79.58582)
			(arc
				(start 251.219462 -79.58582)
				(mid 251.237356 -79.569339)
				(end 251.245624 -79.54645)
			)
			(arc
				(start 251.245624 -79.427832)
				(mid 251.260503 -79.391911)
				(end 251.296424 -79.377032)
			)
			(arc
				(start 251.829316 -79.377032)
				(mid 251.865402 -79.391821)
				(end 251.880116 -79.427832)
			)
			(arc
				(start 251.880116 -79.59598)
				(mid 251.896584 -79.628575)
				(end 251.930662 -79.6417)
			)
			(xy 251.94006 -79.6417)
			(arc
				(start 251.94006 -79.688944)
				(mid 251.94825 -79.711986)
				(end 251.966222 -79.728568)
			)
			(xy 252.254512 -79.728568) (xy 252.280674 -79.710026)
			(arc
				(start 252.286008 -79.694786)
				(mid 252.368648 -79.58602)
				(end 252.49886 -79.544672)
			)
			(arc
				(start 252.715776 -79.544672)
				(mid 252.751697 -79.559551)
				(end 252.766576 -79.595472)
			)
			(xy 252.766576 -79.604616)
			(arc
				(start 253.24562 -79.604616)
				(mid 253.278215 -79.588148)
				(end 253.29134 -79.55407)
			)
			(xy 253.29134 -79.544672)
			(arc
				(start 253.558294 -79.544672)
				(mid 253.718995 -79.610972)
				(end 253.785116 -79.771748)
			)
			(arc
				(start 253.785116 -79.98333)
				(mid 253.789017 -80.002853)
				(end 253.800102 -80.019398)
			)
			(xy 254.174244 -80.39354) (xy 254.197866 -80.400906)
			(arc
				(start 254.210566 -80.39862)
				(mid 254.245466 -80.393703)
				(end 254.28067 -80.392016)
			)
			(arc
				(start 254.28067 -80.392016)
				(mid 254.550437 -80.503757)
				(end 254.662178 -80.773524)
			)
			(arc
				(start 254.662178 -80.773524)
				(mid 254.660503 -80.80873)
				(end 254.655574 -80.843628)
			)
			(xy 254.653288 -80.856328) (xy 254.660654 -80.87995)
			(arc
				(start 254.78486 -81.004156)
				(mid 254.79256 -81.010564)
				(end 254.80137 -81.015332)
			)
			(arc
				(start 255.57607 -81.336134)
				(mid 255.58566 -81.339007)
				(end 255.595628 -81.339944)
			)
			(arc
				(start 255.874774 -81.339944)
				(mid 255.894131 -81.336111)
				(end 255.910588 -81.325212)
			)
			(arc
				(start 256.123948 -81.111852)
				(mid 256.135059 -81.095318)
				(end 256.138934 -81.075784)
			)
			(xy 256.138934 -80.269334) (xy 256.131314 -80.250538) (xy 256.123948 -80.243426)
			(arc
				(start 255.568704 -79.688182)
				(mid 255.552287 -79.67712)
				(end 255.53289 -79.673196)
			)
			(arc
				(start 255.364996 -79.673196)
				(mid 255.276601 -79.660767)
				(end 255.19507 -79.624428)
			)
			(xy 255.189228 -79.620872)
			(arc
				(start 255.1684 -79.614522)
				(mid 255.161234 -79.612983)
				(end 255.153922 -79.61249)
			)
			(arc
				(start 254.588772 -79.61249)
				(mid 254.569249 -79.608589)
				(end 254.552704 -79.597504)
			)
			(arc
				(start 252.163072 -77.207872)
				(mid 252.146538 -77.196761)
				(end 252.127004 -77.192886)
			)
			(xy 248.05259 -77.192886) (xy 248.033794 -77.200506) (xy 248.026682 -77.207872)
			(arc
				(start 246.620284 -78.61427)
				(mid 246.609173 -78.630804)
				(end 246.605298 -78.650338)
			)
			(arc
				(start 246.605298 -82.357976)
				(mid 246.609199 -82.377499)
				(end 246.620284 -82.394044)
			)
			(arc
				(start 247.00484 -82.7786)
				(mid 247.021374 -82.789711)
				(end 247.040908 -82.793586)
			)
			(xy 250.406154 -82.793586)
		)
		(stroke
			(width 0)
			(type solid)
		)
		(fill yes)
		(layer "F.Cu")
		(net "GND")
	)
	(gr_poly
		(pts
			(arc
				(start 232.828338 -143.532098)
				(mid 232.847529 -143.528333)
				(end 232.863898 -143.51762)
			)
			(xy 232.864152 -143.517366)
			(arc
				(start 233.760518 -142.621)
				(mid 233.771629 -142.604466)
				(end 233.775504 -142.584932)
			)
			(arc
				(start 233.775504 -141.855952)
				(mid 233.779405 -141.836429)
				(end 233.79049 -141.819884)
			)
			(arc
				(start 235.86186 -139.748514)
				(mid 235.872971 -139.73198)
				(end 235.876846 -139.712446)
			)
			(xy 235.876846 -134.751064) (xy 235.869226 -134.732268) (xy 235.86186 -134.725156)
			(arc
				(start 235.139992 -134.003288)
				(mid 235.123458 -133.992177)
				(end 235.103924 -133.988302)
			)
			(xy 230.431848 -133.988302) (xy 230.413052 -133.995922) (xy 230.40594 -134.003288)
			(arc
				(start 230.107998 -134.30123)
				(mid 230.096887 -134.317764)
				(end 230.093012 -134.337298)
			)
			(arc
				(start 230.093012 -136.328658)
				(mid 230.096913 -136.348181)
				(end 230.107998 -136.364726)
			)
			(arc
				(start 230.482902 -136.73963)
				(mid 230.494013 -136.756164)
				(end 230.497888 -136.775698)
			)
			(arc
				(start 230.497888 -137.8712)
				(mid 230.495424 -137.88683)
				(end 230.488236 -137.900918)
			)
			(xy 230.48341 -137.907522) (xy 230.478584 -137.922508)
			(arc
				(start 230.478584 -138.680952)
				(mid 230.482485 -138.700475)
				(end 230.49357 -138.71702)
			)
			(arc
				(start 230.666036 -138.889486)
				(mid 230.677147 -138.90602)
				(end 230.681022 -138.925554)
			)
			(arc
				(start 230.681022 -139.131294)
				(mid 230.684923 -139.150817)
				(end 230.696008 -139.167362)
			)
			(arc
				(start 230.724964 -139.196318)
				(mid 230.794504 -139.300253)
				(end 230.818944 -139.422886)
			)
			(arc
				(start 230.818944 -141.81963)
				(mid 230.822508 -141.838322)
				(end 230.83266 -141.854428)
			)
			(arc
				(start 230.853488 -141.876272)
				(mid 230.867942 -141.887015)
				(end 230.885238 -141.89202)
			)
			(xy 230.89235 -141.892782) (xy 230.903272 -141.894052) (xy 230.9241 -141.887448) (xy 230.989124 -141.82979)
			(xy 230.99014 -141.828774)
			(arc
				(start 230.990394 -141.828774)
				(mid 231.002264 -141.811895)
				(end 231.006396 -141.79169)
			)
			(arc
				(start 231.006396 -141.567408)
				(mid 231.030294 -141.447267)
				(end 231.098344 -141.345412)
			)
			(xy 231.757982 -140.68552)
			(arc
				(start 231.75976 -140.683742)
				(mid 231.769611 -140.66784)
				(end 231.772968 -140.649452)
			)
			(xy 231.772968 -140.050774) (xy 231.768904 -140.03655) (xy 231.76484 -140.030454)
			(arc
				(start 231.761284 -140.024612)
				(mid 231.719636 -139.929151)
				(end 231.705404 -139.825984)
			)
			(arc
				(start 231.705404 -139.819126)
				(mid 231.750908 -139.644918)
				(end 231.871266 -139.511024)
			)
			(arc
				(start 231.871266 -139.511024)
				(mid 231.887498 -139.492803)
				(end 231.893364 -139.469114)
			)
			(arc
				(start 231.893364 -139.3698)
				(mid 231.874764 -139.3509)
				(end 231.849168 -139.343892)
			)
			(xy 231.735376 -139.343892) (xy 231.71404 -139.343892) (xy 231.684576 -139.31392) (xy 231.684576 -138.738864)
			(xy 231.71404 -138.708892) (xy 231.732836 -138.708892)
			(arc
				(start 231.849168 -138.708892)
				(mid 231.874802 -138.70195)
				(end 231.893364 -138.682984)
			)
			(arc
				(start 231.893364 -138.447018)
				(mid 231.908195 -138.373018)
				(end 231.95026 -138.310366)
			)
			(arc
				(start 232.278428 -137.981944)
				(mid 232.284836 -137.974244)
				(end 232.289604 -137.965434)
			)
			(arc
				(start 232.36809 -137.775188)
				(mid 232.370939 -137.765722)
				(end 232.3719 -137.755884)
			)
			(arc
				(start 232.3719 -136.520936)
				(mid 232.368067 -136.501579)
				(end 232.357168 -136.485122)
			)
			(arc
				(start 232.185464 -136.313418)
				(mid 232.16893 -136.302307)
				(end 232.149396 -136.298432)
			)
			(arc
				(start 230.80472 -136.298432)
				(mid 230.714558 -136.261086)
				(end 230.677212 -136.170924)
			)
			(arc
				(start 230.677212 -134.951724)
				(mid 230.714558 -134.861562)
				(end 230.80472 -134.824216)
			)
			(arc
				(start 232.30332 -134.824216)
				(mid 232.393482 -134.861562)
				(end 232.430828 -134.951724)
			)
			(arc
				(start 232.430828 -135.990584)
				(mid 232.434729 -136.010107)
				(end 232.445814 -136.026652)
			)
			(arc
				(start 232.7021 -136.283192)
				(mid 232.743354 -136.344366)
				(end 232.758742 -136.416542)
			)
			(arc
				(start 232.758742 -136.416542)
				(mid 232.788471 -136.46201)
				(end 232.842308 -136.454642)
			)
			(arc
				(start 232.842308 -136.454642)
				(mid 232.85992 -136.442141)
				(end 232.879392 -136.432798)
			)
			(arc
				(start 232.879392 -136.432798)
				(mid 232.901617 -136.426552)
				(end 232.924604 -136.424416)
			)
			(arc
				(start 234.423204 -136.424416)
				(mid 234.513366 -136.461762)
				(end 234.550712 -136.551924)
			)
			(arc
				(start 234.550712 -136.92759)
				(mid 234.553796 -136.945021)
				(end 234.56265 -136.960356)
			)
			(arc
				(start 234.569254 -136.968484)
				(mid 234.637474 -136.985016)
				(end 234.695238 -137.024872)
			)
			(arc
				(start 234.822238 -137.151872)
				(mid 234.864184 -137.214554)
				(end 234.87888 -137.288524)
			)
			(arc
				(start 234.87888 -138.11885)
				(mid 234.864151 -138.192806)
				(end 234.822238 -138.255502)
			)
			(arc
				(start 234.682538 -138.395202)
				(mid 234.619856 -138.437148)
				(end 234.545886 -138.451844)
			)
			(arc
				(start 233.485944 -138.451844)
				(mid 233.4735 -138.453392)
				(end 233.461814 -138.45794)
			)
			(xy 233.448352 -138.465306) (xy 233.439462 -138.472926)
			(arc
				(start 233.43616 -138.478006)
				(mid 233.393817 -138.528373)
				(end 233.34345 -138.570716)
			)
			(xy 233.33837 -138.574018) (xy 233.33075 -138.582908)
			(arc
				(start 233.323384 -138.59637)
				(mid 233.318835 -138.608056)
				(end 233.317288 -138.6205)
			)
			(arc
				(start 233.317288 -138.682476)
				(mid 233.33591 -138.701719)
				(end 233.361738 -138.708892)
			)
			(xy 233.475784 -138.708892) (xy 233.496612 -138.708892) (xy 233.526584 -138.738864) (xy 233.526584 -138.757152)
			(xy 233.526584 -139.293092) (xy 233.526584 -139.31392) (xy 233.496612 -139.343892) (xy 233.478324 -139.343892)
			(arc
				(start 233.312208 -139.343892)
				(mid 233.277564 -139.357538)
				(end 233.261408 -139.391136)
			)
			(xy 233.261408 -139.403836)
			(arc
				(start 233.219244 -139.403836)
				(mid 233.19361 -139.410778)
				(end 233.175048 -139.429744)
			)
			(xy 233.175048 -139.718034) (xy 233.193336 -139.743942)
			(arc
				(start 233.208576 -139.74953)
				(mid 233.317555 -139.832099)
				(end 233.358944 -139.962382)
			)
			(xy 233.358944 -140.179044) (xy 233.358944 -140.20038) (xy 233.328972 -140.229844) (xy 233.328718 -140.229844)
			(xy 233.299 -140.259816)
			(arc
				(start 233.299 -140.704316)
				(mid 233.312646 -140.73896)
				(end 233.346244 -140.755116)
			)
			(xy 233.358944 -140.755116)
			(arc
				(start 233.358944 -141.022578)
				(mid 233.290213 -141.185014)
				(end 233.125772 -141.248638)
			)
			(xy 233.12501 -141.248384) (xy 232.907586 -141.248384) (xy 232.897172 -141.250416)
			(arc
				(start 232.795572 -141.352016)
				(mid 232.784646 -141.368462)
				(end 232.78084 -141.38783)
			)
			(arc
				(start 232.78084 -141.412214)
				(mid 232.766009 -141.486214)
				(end 232.723944 -141.548866)
			)
			(xy 232.611168 -141.661896) (xy 232.603802 -141.685518)
			(arc
				(start 232.606088 -141.698218)
				(mid 232.611005 -141.733118)
				(end 232.612692 -141.768322)
			)
			(arc
				(start 232.612692 -141.768322)
				(mid 232.528871 -142.006924)
				(end 232.314242 -142.140686)
			)
			(xy 232.307384 -142.14221) (xy 232.29443 -142.149068)
			(arc
				(start 231.910382 -142.53337)
				(mid 231.904097 -142.541081)
				(end 231.89946 -142.54988)
			)
			(xy 231.663748 -143.11884)
			(arc
				(start 231.662224 -143.123158)
				(mid 231.66037 -143.130808)
				(end 231.659684 -143.138652)
			)
			(arc
				(start 231.659684 -143.265398)
				(mid 231.653294 -143.329082)
				(end 231.63403 -143.390112)
			)
			(xy 231.62895 -143.40205) (xy 231.630982 -143.42745) (xy 231.684576 -143.508984)
			(arc
				(start 231.690164 -143.516096)
				(mid 231.706461 -143.52771)
				(end 231.725978 -143.532098)
			)
			(xy 231.726994 -143.532098)
		)
		(stroke
			(width 0)
			(type solid)
		)
		(fill yes)
		(layer "F.Cu")
		(net "GND")
	)
	(gr_poly
		(pts
			(arc
				(start 235.636562 -413.132016)
				(mid 235.655753 -413.128251)
				(end 235.672122 -413.117538)
			)
			(xy 236.812328 -411.977332)
			(arc
				(start 236.812836 -411.976824)
				(mid 236.823578 -411.960467)
				(end 236.827314 -411.941264)
			)
			(arc
				(start 236.827314 -402.776436)
				(mid 236.831215 -402.756913)
				(end 236.8423 -402.740368)
			)
			(arc
				(start 238.886238 -400.69643)
				(mid 238.902772 -400.685319)
				(end 238.922306 -400.681444)
			)
			(arc
				(start 242.916964 -400.681444)
				(mid 242.936155 -400.677679)
				(end 242.952524 -400.666966)
			)
			(xy 243.86286 -399.75663)
			(arc
				(start 243.863368 -399.756122)
				(mid 243.87411 -399.739765)
				(end 243.877846 -399.720562)
			)
			(arc
				(start 243.877846 -392.486896)
				(mid 243.880294 -392.471568)
				(end 243.887244 -392.457686)
			)
			(xy 243.891816 -392.451082) (xy 243.896388 -392.43635)
			(arc
				(start 243.896388 -391.97026)
				(mid 243.900289 -391.950737)
				(end 243.911374 -391.934192)
			)
			(arc
				(start 245.02999 -390.815576)
				(mid 245.046524 -390.804465)
				(end 245.066058 -390.80059)
			)
			(arc
				(start 259.092954 -390.80059)
				(mid 259.112145 -390.796825)
				(end 259.128514 -390.786112)
			)
			(xy 262.060944 -387.853682)
			(arc
				(start 262.061452 -387.853174)
				(mid 262.072194 -387.836817)
				(end 262.07593 -387.817614)
			)
			(arc
				(start 262.07593 -379.165866)
				(mid 262.072029 -379.146343)
				(end 262.060944 -379.129798)
			)
			(xy 261.987538 -379.056392) (xy 261.980426 -379.049026) (xy 261.96163 -379.041406)
			(arc
				(start 258.970272 -379.041406)
				(mid 258.934351 -379.056285)
				(end 258.919472 -379.092206)
			)
			(arc
				(start 258.919472 -379.297438)
				(mid 258.896977 -379.36976)
				(end 258.83743 -379.416564)
			)
			(xy 258.831588 -379.41885) (xy 258.82219 -379.4252) (xy 258.815586 -379.432312)
			(arc
				(start 258.811268 -379.436884)
				(mid 258.68634 -379.521868)
				(end 258.538218 -379.551692)
			)
			(arc
				(start 258.538218 -379.551692)
				(mid 258.385485 -379.519873)
				(end 258.25831 -379.429518)
			)
			(arc
				(start 258.239006 -379.416564)
				(mid 258.179459 -379.36976)
				(end 258.156964 -379.297438)
			)
			(arc
				(start 258.156964 -379.08865)
				(mid 258.140813 -379.055115)
				(end 258.106164 -379.041406)
			)
			(arc
				(start 249.373644 -379.041406)
				(mid 249.337723 -379.056285)
				(end 249.322844 -379.092206)
			)
			(arc
				(start 249.322844 -379.297438)
				(mid 249.300349 -379.36976)
				(end 249.240802 -379.416564)
			)
			(xy 249.23496 -379.41885) (xy 249.225562 -379.4252) (xy 249.218958 -379.432312)
			(arc
				(start 249.21464 -379.436884)
				(mid 249.089712 -379.521868)
				(end 248.94159 -379.551692)
			)
			(arc
				(start 248.94159 -379.551692)
				(mid 248.788857 -379.519873)
				(end 248.661682 -379.429518)
			)
			(arc
				(start 248.642378 -379.416564)
				(mid 248.582831 -379.36976)
				(end 248.560336 -379.297438)
			)
			(arc
				(start 248.560336 -379.08865)
				(mid 248.544185 -379.055115)
				(end 248.509536 -379.041406)
			)
			(xy 243.1415 -379.041406) (xy 243.140484 -379.042422)
			(arc
				(start 240.581688 -379.042422)
				(mid 240.562165 -379.046323)
				(end 240.54562 -379.057408)
			)
			(arc
				(start 239.903 -379.700028)
				(mid 239.886466 -379.711139)
				(end 239.866932 -379.715014)
			)
			(arc
				(start 239.849152 -379.715014)
				(mid 239.813231 -379.729893)
				(end 239.798352 -379.765814)
			)
			(arc
				(start 239.798352 -380.563628)
				(mid 239.786921 -380.656063)
				(end 239.753394 -380.742952)
			)
			(xy 239.747552 -380.754382)
			(arc
				(start 239.747552 -381.122428)
				(mid 239.710206 -381.21259)
				(end 239.620044 -381.249936)
			)
			(arc
				(start 239.213644 -381.249936)
				(mid 239.123482 -381.21259)
				(end 239.086136 -381.122428)
			)
			(xy 239.086136 -380.754382)
			(arc
				(start 239.080294 -380.742952)
				(mid 239.04681 -380.656052)
				(end 239.035336 -380.563628)
			)
			(arc
				(start 239.035336 -379.765814)
				(mid 239.020457 -379.729893)
				(end 238.984536 -379.715014)
			)
			(arc
				(start 237.06963 -379.715014)
				(mid 237.050107 -379.711113)
				(end 237.033562 -379.700028)
			)
			(arc
				(start 232.94086 -375.607326)
				(mid 232.929749 -375.590792)
				(end 232.925874 -375.571258)
			)
			(arc
				(start 232.925874 -372.098062)
				(mid 232.921973 -372.078539)
				(end 232.910888 -372.061994)
			)
			(arc
				(start 232.189274 -371.34038)
				(mid 232.178163 -371.323846)
				(end 232.174288 -371.304312)
			)
			(arc
				(start 232.174288 -371.057424)
				(mid 232.170387 -371.037901)
				(end 232.159302 -371.021356)
			)
			(xy 232.119932 -370.981986) (xy 232.118408 -370.981986)
			(arc
				(start 232.015284 -370.878862)
				(mid 232.004173 -370.862328)
				(end 232.000298 -370.842794)
			)
			(arc
				(start 232.000298 -368.92992)
				(mid 231.991311 -368.90107)
				(end 231.967532 -368.882422)
			)
			(xy 231.967532 -367.293906) (xy 231.932988 -367.259362) (xy 228.637592 -367.259362) (xy 228.6 -367.296954)
			(xy 228.6 -368.099594) (xy 228.599492 -368.106198)
			(arc
				(start 228.599492 -370.828062)
				(mid 228.595591 -370.847585)
				(end 228.584506 -370.86413)
			)
			(xy 228.431344 -371.017292) (xy 228.423978 -371.024404) (xy 228.416358 -371.0432)
			(arc
				(start 228.416358 -371.446552)
				(mid 228.412457 -371.466075)
				(end 228.401372 -371.48262)
			)
			(xy 227.137722 -372.74627) (xy 227.130356 -372.753382) (xy 227.122736 -372.772178)
			(arc
				(start 227.122736 -374.248426)
				(mid 227.118835 -374.267949)
				(end 227.10775 -374.284494)
			)
			(arc
				(start 225.693224 -375.69902)
				(mid 225.67669 -375.710131)
				(end 225.657156 -375.714006)
			)
			(arc
				(start 223.582484 -375.714006)
				(mid 223.562961 -375.710105)
				(end 223.546416 -375.69902)
			)
			(arc
				(start 221.539816 -373.69242)
				(mid 221.528705 -373.675886)
				(end 221.52483 -373.656352)
			)
			(arc
				(start 221.52483 -371.070124)
				(mid 221.520929 -371.050601)
				(end 221.509844 -371.034056)
			)
			(arc
				(start 221.337632 -370.861844)
				(mid 221.326521 -370.84531)
				(end 221.322646 -370.825776)
			)
			(xy 221.322646 -367.34369) (xy 221.241112 -367.262156) (xy 217.935048 -367.262156) (xy 217.90152 -367.295684)
			(arc
				(start 217.90152 -370.80063)
				(mid 217.897619 -370.820153)
				(end 217.886534 -370.836698)
			)
			(arc
				(start 216.72931 -371.993922)
				(mid 216.712776 -372.005033)
				(end 216.693242 -372.008908)
			)
			(arc
				(start 210.338924 -372.008908)
				(mid 210.319401 -372.005007)
				(end 210.302856 -371.993922)
			)
			(arc
				(start 210.054698 -371.745764)
				(mid 210.043587 -371.72923)
				(end 210.039712 -371.709696)
			)
			(arc
				(start 210.039712 -371.274086)
				(mid 210.035811 -371.254563)
				(end 210.024726 -371.238018)
			)
			(arc
				(start 209.98688 -371.200172)
				(mid 209.971628 -371.189615)
				(end 209.953606 -371.185186)
			)
			(arc
				(start 209.475324 -371.185186)
				(mid 209.455801 -371.181285)
				(end 209.439256 -371.1702)
			)
			(arc
				(start 208.832196 -370.56314)
				(mid 208.821085 -370.546606)
				(end 208.81721 -370.527072)
			)
			(arc
				(start 208.81721 -370.468144)
				(mid 208.802331 -370.432223)
				(end 208.76641 -370.417344)
			)
			(arc
				(start 208.220056 -370.417344)
				(mid 208.200533 -370.413443)
				(end 208.183988 -370.402358)
			)
			(arc
				(start 208.098898 -370.317268)
				(mid 208.087787 -370.300734)
				(end 208.083912 -370.2812)
			)
			(xy 208.083912 -370.266976) (xy 208.025492 -370.208556) (xy 208.025492 -367.384584) (xy 207.917288 -367.276634)
			(xy 204.763624 -367.276634) (xy 204.667866 -367.372392) (xy 204.667866 -370.867686) (xy 204.80909 -371.00891)
			(arc
				(start 204.80909 -372.890796)
				(mid 204.816119 -372.916579)
				(end 204.835252 -372.935246)
			)
			(arc
				(start 204.949552 -372.935246)
				(mid 205.034392 -372.903591)
				(end 205.124304 -372.892828)
			)
			(arc
				(start 205.124304 -372.892828)
				(mid 205.394071 -373.004569)
				(end 205.505812 -373.274336)
			)
			(arc
				(start 205.505812 -373.274844)
				(mid 205.490619 -373.38118)
				(end 205.446376 -373.47906)
			)
			(xy 205.444598 -373.482108) (xy 205.444598 -374.239536) (xy 204.921612 -374.762522) (xy 204.920088 -374.766332)
			(arc
				(start 204.920088 -387.060948)
				(mid 204.923853 -387.080139)
				(end 204.934566 -387.096508)
			)
			(arc
				(start 207.491838 -389.65378)
				(mid 207.502949 -389.670314)
				(end 207.506824 -389.689848)
			)
			(arc
				(start 207.506824 -411.710124)
				(mid 207.510589 -411.729315)
				(end 207.521302 -411.745684)
			)
			(xy 208.892648 -413.11703)
			(arc
				(start 208.893156 -413.117538)
				(mid 208.909513 -413.12828)
				(end 208.928716 -413.132016)
			)
		)
		(stroke
			(width 0)
			(type solid)
		)
		(fill yes)
		(layer "F.Cu")
		(net "P12V_STBY")
	)
	(gr_poly
		(pts
			(arc
				(start 135.98906 -201.182478)
				(mid 136.024981 -201.167599)
				(end 136.03986 -201.131678)
			)
			(arc
				(start 136.03986 -200.680828)
				(mid 136.037942 -200.667253)
				(end 136.032494 -200.654666)
			)
			(arc
				(start 136.032494 -200.654666)
				(mid 135.998187 -200.575004)
				(end 135.98652 -200.489058)
			)
			(arc
				(start 135.98652 -199.384412)
				(mid 135.98257 -199.365025)
				(end 135.971534 -199.348598)
			)
			(arc
				(start 135.815578 -199.192642)
				(mid 135.746204 -199.088677)
				(end 135.721852 -198.966074)
			)
			(arc
				(start 135.721852 -198.435468)
				(mid 135.704656 -198.416999)
				(end 135.680704 -198.409052)
			)
			(xy 135.669274 -198.409052) (xy 135.639556 -198.379588) (xy 135.639556 -197.82536) (xy 135.639556 -197.804024)
			(xy 135.669528 -197.77456)
			(arc
				(start 135.807704 -197.77456)
				(mid 135.831657 -197.766615)
				(end 135.848852 -197.748144)
			)
			(arc
				(start 135.848852 -197.704202)
				(mid 135.844902 -197.684815)
				(end 135.833866 -197.668388)
			)
			(arc
				(start 135.657844 -197.492112)
				(mid 135.615898 -197.42943)
				(end 135.601202 -197.35546)
			)
			(xy 135.600948 -197.334378) (xy 135.57123 -197.30466)
			(arc
				(start 135.382508 -197.30466)
				(mid 135.29616 -197.265569)
				(end 135.260588 -197.17766)
			)
			(xy 135.260588 -196.821552)
			(arc
				(start 135.260588 -196.466206)
				(mid 135.29795 -196.376134)
				(end 135.388096 -196.338952)
			)
			(xy 136.055608 -196.338952) (xy 136.066022 -196.33692) (xy 136.1567 -196.246242) (xy 136.16432 -196.22643)
			(xy 136.163812 -196.215508)
			(arc
				(start 136.163304 -196.196712)
				(mid 136.275045 -195.926945)
				(end 136.544812 -195.815204)
			)
			(arc
				(start 136.544812 -195.815204)
				(mid 136.593076 -195.818269)
				(end 136.64057 -195.827396)
			)
			(arc
				(start 136.649968 -195.818252)
				(mid 136.712635 -195.776223)
				(end 136.78662 -195.761356)
			)
			(arc
				(start 137.28954 -195.761356)
				(mid 137.308897 -195.757523)
				(end 137.325354 -195.746624)
			)
			(arc
				(start 137.56894 -195.503038)
				(mid 137.579866 -195.486592)
				(end 137.583672 -195.467224)
			)
			(arc
				(start 137.583672 -194.350894)
				(mid 137.579839 -194.331537)
				(end 137.56894 -194.31508)
			)
			(arc
				(start 137.244582 -193.990722)
				(mid 137.228048 -193.979611)
				(end 137.208514 -193.975736)
			)
			(arc
				(start 135.926576 -193.975736)
				(mid 135.836414 -193.93839)
				(end 135.799068 -193.848228)
			)
			(arc
				(start 135.799068 -192.629028)
				(mid 135.836414 -192.538866)
				(end 135.926576 -192.50152)
			)
			(arc
				(start 137.348976 -192.50152)
				(mid 137.439138 -192.538866)
				(end 137.476484 -192.629028)
			)
			(arc
				(start 137.476484 -193.654426)
				(mid 137.480385 -193.673949)
				(end 137.49147 -193.690494)
			)
			(arc
				(start 137.913872 -194.11315)
				(mid 137.935236 -194.138437)
				(end 137.951972 -194.166998)
			)
			(xy 137.95629 -194.176142) (xy 137.971022 -194.18935) (xy 138.047222 -194.216782) (xy 138.066526 -194.21602)
			(arc
				(start 138.075416 -194.21221)
				(mid 138.10038 -194.204123)
				(end 138.12647 -194.201288)
			)
			(arc
				(start 139.549124 -194.201288)
				(mid 139.639286 -194.238634)
				(end 139.676632 -194.328796)
			)
			(arc
				(start 139.676632 -195.379848)
				(mid 139.680533 -195.399371)
				(end 139.691618 -195.415916)
			)
			(arc
				(start 139.750546 -195.475098)
				(mid 139.792492 -195.53778)
				(end 139.807188 -195.61175)
			)
			(arc
				(start 139.807188 -196.557392)
				(mid 139.792459 -196.631348)
				(end 139.750546 -196.694044)
			)
			(arc
				(start 139.486132 -196.958458)
				(mid 139.42345 -197.000404)
				(end 139.34948 -197.0151)
			)
			(arc
				(start 137.852404 -197.0151)
				(mid 137.816483 -197.029979)
				(end 137.801604 -197.0659)
			)
			(xy 137.801604 -197.118478)
			(arc
				(start 137.801604 -197.177406)
				(mid 137.764242 -197.267478)
				(end 137.674096 -197.30466)
			)
			(arc
				(start 137.254488 -197.30466)
				(mid 137.230535 -197.312605)
				(end 137.21334 -197.331076)
			)
			(arc
				(start 137.21334 -197.748144)
				(mid 137.230536 -197.766613)
				(end 137.254488 -197.77456)
			)
			(xy 137.392664 -197.77456) (xy 137.422636 -197.804024) (xy 137.422636 -197.82282) (xy 137.422636 -198.358252)
			(xy 137.422636 -198.379588) (xy 137.392664 -198.409052)
			(arc
				(start 137.38479 -198.409052)
				(mid 137.365238 -198.413071)
				(end 137.348722 -198.424292)
			)
			(xy 137.34796 -198.425054) (xy 137.34034 -198.443342) (xy 137.34034 -198.511922) (xy 137.34415 -198.52513)
			(arc
				(start 137.347706 -198.530972)
				(mid 137.393856 -198.649878)
				(end 137.398252 -198.777352)
			)
			(arc
				(start 137.398252 -198.777352)
				(mid 137.380341 -198.852433)
				(end 137.347706 -198.922386)
			)
			(arc
				(start 137.347706 -198.922386)
				(mid 137.342224 -198.934963)
				(end 137.34034 -198.948548)
			)
			(arc
				(start 137.34034 -199.398382)
				(mid 137.330039 -199.479214)
				(end 137.2997 -199.554846)
			)
			(arc
				(start 137.299954 -199.556116)
				(mid 137.302269 -199.568532)
				(end 137.307574 -199.579992)
			)
			(arc
				(start 137.353802 -199.652382)
				(mid 137.372228 -199.669713)
				(end 137.396728 -199.676004)
			)
			(arc
				(start 137.4521 -199.676004)
				(mid 137.538448 -199.715095)
				(end 137.57402 -199.803004)
			)
			(arc
				(start 137.57402 -200.168002)
				(mid 137.574982 -200.17784)
				(end 137.57783 -200.187306)
			)
			(xy 137.588244 -200.21296)
			(arc
				(start 137.594594 -200.219818)
				(mid 137.673398 -200.344191)
				(end 137.70102 -200.488804)
			)
			(arc
				(start 137.70102 -201.131678)
				(mid 137.715899 -201.167599)
				(end 137.75182 -201.182478)
			)
			(arc
				(start 137.866628 -201.182478)
				(mid 137.885819 -201.178713)
				(end 137.902188 -201.168)
			)
			(xy 137.902442 -201.167746) (xy 137.922 -201.148188)
			(arc
				(start 137.922508 -201.14768)
				(mid 137.93325 -201.131323)
				(end 137.936986 -201.11212)
			)
			(arc
				(start 137.936986 -199.163432)
				(mid 137.940887 -199.143909)
				(end 137.951972 -199.127364)
			)
			(arc
				(start 138.203686 -198.87565)
				(mid 138.214797 -198.859116)
				(end 138.218672 -198.839582)
			)
			(xy 138.218672 -198.749412) (xy 138.217402 -198.743824) (xy 138.213846 -198.727568) (xy 138.213592 -198.727314)
			(arc
				(start 138.20902 -198.717154)
				(mid 138.177842 -198.624285)
				(end 138.16711 -198.526908)
			)
			(arc
				(start 138.16711 -198.5264)
				(mid 138.243981 -198.272433)
				(end 138.448796 -198.103744)
			)
			(xy 138.44905 -198.103744) (xy 138.458448 -198.09968)
			(arc
				(start 138.750548 -197.80758)
				(mid 138.767082 -197.796469)
				(end 138.786616 -197.792594)
			)
			(xy 140.075666 -197.792594)
			(arc
				(start 140.084302 -197.791832)
				(mid 140.098792 -197.787)
				(end 140.111226 -197.778116)
			)
			(arc
				(start 140.80998 -197.079362)
				(mid 140.821091 -197.062828)
				(end 140.824966 -197.043294)
			)
			(arc
				(start 140.824966 -193.43624)
				(mid 140.821065 -193.416717)
				(end 140.80998 -193.400172)
			)
			(xy 138.873484 -191.463676) (xy 138.866372 -191.45631) (xy 138.847576 -191.44869)
			(arc
				(start 134.921498 -191.44869)
				(mid 134.901975 -191.452591)
				(end 134.88543 -191.463676)
			)
			(xy 134.356602 -191.992504) (xy 134.349236 -191.999616) (xy 134.341616 -192.018412)
			(arc
				(start 134.341616 -200.151746)
				(mid 134.345381 -200.170937)
				(end 134.356094 -200.187306)
			)
			(xy 134.356348 -200.18756)
			(arc
				(start 134.452614 -200.283826)
				(mid 134.458899 -200.291537)
				(end 134.463536 -200.300336)
			)
			(arc
				(start 134.470648 -200.317354)
				(mid 134.475209 -200.325987)
				(end 134.481316 -200.33361)
			)
			(xy 134.482078 -200.334372) (xy 134.482332 -200.334626) (xy 135.011668 -200.863962) (xy 135.02767 -200.871328)
			(arc
				(start 135.03656 -200.87209)
				(mid 135.241621 -200.955666)
				(end 135.365744 -201.139044)
			)
			(arc
				(start 135.365744 -201.139298)
				(mid 135.384167 -201.165051)
				(end 135.414258 -201.174858)
			)
			(arc
				(start 135.859266 -201.174858)
				(mid 135.869512 -201.17585)
				(end 135.879332 -201.178922)
			)
			(xy 135.88746 -201.182478)
		)
		(stroke
			(width 0)
			(type solid)
		)
		(fill yes)
		(layer "F.Cu")
		(net "GND")
	)
	(gr_poly
		(pts
			(arc
				(start 243.556028 -94.44736)
				(mid 243.575551 -94.443459)
				(end 243.592096 -94.432374)
			)
			(arc
				(start 244.182646 -93.841824)
				(mid 244.193757 -93.82529)
				(end 244.197632 -93.805756)
			)
			(arc
				(start 244.197632 -90.551)
				(mid 244.193731 -90.531477)
				(end 244.182646 -90.514932)
			)
			(arc
				(start 243.653564 -89.98585)
				(mid 243.63703 -89.974739)
				(end 243.617496 -89.970864)
			)
			(arc
				(start 242.863116 -89.970864)
				(mid 242.843593 -89.966963)
				(end 242.827048 -89.955878)
			)
			(arc
				(start 238.016288 -89.955878)
				(mid 238.00632 -89.956815)
				(end 237.99673 -89.959688)
			)
			(arc
				(start 237.968028 -89.971626)
				(mid 237.959362 -89.976288)
				(end 237.951772 -89.982548)
			)
			(arc
				(start 237.70717 -90.22715)
				(mid 237.696059 -90.243684)
				(end 237.692184 -90.263218)
			)
			(arc
				(start 237.692184 -90.744802)
				(mid 237.688283 -90.764325)
				(end 237.677198 -90.78087)
			)
			(arc
				(start 237.66399 -90.794078)
				(mid 237.649283 -90.826302)
				(end 237.659164 -90.860372)
			)
			(arc
				(start 237.659164 -90.860372)
				(mid 237.71581 -90.968494)
				(end 237.735364 -91.088972)
			)
			(xy 237.734602 -91.110816) (xy 237.734094 -91.121484) (xy 237.740952 -91.140788)
			(arc
				(start 237.799118 -91.202256)
				(mid 237.815912 -91.213933)
				(end 237.835948 -91.218004)
			)
			(arc
				(start 238.709454 -91.218004)
				(mid 238.773611 -91.22449)
				(end 238.835184 -91.243658)
			)
			(xy 238.844582 -91.247976)
			(arc
				(start 239.454436 -91.247976)
				(mid 239.490522 -91.262765)
				(end 239.505236 -91.298776)
			)
			(xy 239.505236 -91.456764)
			(arc
				(start 239.507522 -91.456764)
				(mid 239.557504 -91.389958)
				(end 239.620806 -91.335606)
			)
			(arc
				(start 239.620806 -91.335606)
				(mid 239.637038 -91.317385)
				(end 239.642904 -91.293696)
			)
			(arc
				(start 239.642904 -91.01836)
				(mid 239.657735 -90.94436)
				(end 239.6998 -90.881708)
			)
			(arc
				(start 239.827054 -90.754454)
				(mid 239.889736 -90.712508)
				(end 239.963706 -90.697812)
			)
			(arc
				(start 240.748058 -90.697812)
				(mid 240.822014 -90.712541)
				(end 240.88471 -90.754454)
			)
			(arc
				(start 241.04346 -90.913204)
				(mid 241.068167 -90.943301)
				(end 241.086386 -90.97772)
			)
			(xy 241.092228 -90.992452) (xy 241.117628 -91.009724)
			(arc
				(start 241.414808 -91.009724)
				(mid 241.50488 -91.04698)
				(end 241.542316 -91.136978)
			)
			(arc
				(start 241.542316 -92.051378)
				(mid 241.504954 -92.14145)
				(end 241.414808 -92.178632)
			)
			(arc
				(start 240.398808 -92.178632)
				(mid 240.308736 -92.141376)
				(end 240.2713 -92.051378)
			)
			(arc
				(start 240.2713 -92.00007)
				(mid 240.262919 -91.972119)
				(end 240.240566 -91.953334)
			)
			(xy 240.14049 -91.910408) (xy 240.111026 -91.915742)
			(arc
				(start 240.09985 -91.92641)
				(mid 239.978307 -92.004496)
				(end 239.836452 -92.03182)
			)
			(arc
				(start 239.836452 -92.03182)
				(mid 239.706345 -92.008857)
				(end 239.59185 -91.94292)
			)
			(arc
				(start 239.59185 -91.94292)
				(mid 239.575543 -91.933823)
				(end 239.557052 -91.931236)
			)
			(arc
				(start 239.525302 -91.932506)
				(mid 239.507852 -91.936346)
				(end 239.49279 -91.945968)
			)
			(arc
				(start 239.49279 -91.945968)
				(mid 239.420966 -91.991022)
				(end 239.337596 -92.00642)
			)
			(arc
				(start 239.038384 -92.00642)
				(mid 238.980223 -91.999148)
				(end 238.925862 -91.97721)
			)
			(xy 238.92002 -91.973908) (xy 238.907828 -91.97086)
			(arc
				(start 238.821214 -91.97086)
				(mid 238.698599 -91.946377)
				(end 238.594646 -91.87688)
			)
			(arc
				(start 238.591598 -91.873832)
				(mid 238.575152 -91.862906)
				(end 238.555784 -91.8591)
			)
			(arc
				(start 237.78972 -91.8591)
				(mid 237.770363 -91.862933)
				(end 237.753906 -91.873832)
			)
			(arc
				(start 237.634526 -91.993212)
				(mid 237.600958 -92.022474)
				(end 237.56366 -92.046806)
			)
			(xy 237.550452 -92.053918) (xy 237.536736 -92.079318)
			(arc
				(start 237.542832 -92.18549)
				(mid 237.552158 -92.211935)
				(end 237.574074 -92.229432)
			)
			(xy 237.712758 -92.286836) (xy 237.726474 -92.288614)
			(arc
				(start 237.733078 -92.287598)
				(mid 237.76069 -92.284551)
				(end 237.78845 -92.283534)
			)
			(arc
				(start 237.78845 -92.283534)
				(mid 237.900149 -92.300174)
				(end 238.002064 -92.348812)
			)
			(arc
				(start 238.002064 -92.348812)
				(mid 238.01894 -92.356303)
				(end 238.03737 -92.357194)
			)
			(arc
				(start 238.068612 -92.352876)
				(mid 238.085588 -92.347398)
				(end 238.0996 -92.336366)
			)
			(arc
				(start 238.0996 -92.336366)
				(mid 238.176396 -92.28069)
				(end 238.269272 -92.261436)
			)
			(arc
				(start 238.568484 -92.261436)
				(mid 238.72932 -92.327106)
				(end 238.796068 -92.487496)
			)
			(arc
				(start 238.796068 -92.704412)
				(mid 238.781189 -92.740333)
				(end 238.745268 -92.755212)
			)
			(xy 238.736124 -92.755212)
			(arc
				(start 238.736124 -93.173296)
				(mid 238.751003 -93.209217)
				(end 238.786924 -93.224096)
			)
			(arc
				(start 239.010952 -93.224096)
				(mid 239.046873 -93.209217)
				(end 239.061752 -93.173296)
			)
			(arc
				(start 239.061752 -93.064584)
				(mid 239.076631 -93.028663)
				(end 239.112552 -93.013784)
			)
			(arc
				(start 239.645444 -93.013784)
				(mid 239.68153 -93.028573)
				(end 239.696244 -93.064584)
			)
			(xy 239.696244 -93.209618) (xy 239.712246 -93.23451)
			(arc
				(start 239.725708 -93.24086)
				(mid 239.754837 -93.257755)
				(end 239.780572 -93.279468)
			)
			(arc
				(start 239.837468 -93.33611)
				(mid 239.853885 -93.347172)
				(end 239.873282 -93.351096)
			)
			(arc
				(start 241.855244 -93.351096)
				(mid 241.874631 -93.347146)
				(end 241.891058 -93.33611)
			)
			(arc
				(start 241.956336 -93.270832)
				(mid 241.967262 -93.254386)
				(end 241.971068 -93.235018)
			)
			(arc
				(start 241.971068 -92.43695)
				(mid 242.00843 -92.346878)
				(end 242.098576 -92.309696)
			)
			(arc
				(start 243.114576 -92.309696)
				(mid 243.204648 -92.346952)
				(end 243.242084 -92.43695)
			)
			(arc
				(start 243.242084 -93.35135)
				(mid 243.204722 -93.441422)
				(end 243.114576 -93.478604)
			)
			(arc
				(start 242.316508 -93.478604)
				(mid 242.297121 -93.482554)
				(end 242.280694 -93.49359)
			)
			(arc
				(start 242.092988 -93.681042)
				(mid 242.030306 -93.722988)
				(end 241.956336 -93.737684)
			)
			(arc
				(start 239.77219 -93.737684)
				(mid 239.738277 -93.734776)
				(end 239.705388 -93.726)
			)
			(arc
				(start 239.705388 -93.726)
				(mid 239.681449 -93.723291)
				(end 239.658906 -93.731842)
			)
			(arc
				(start 239.658906 -93.731842)
				(mid 239.596877 -93.762119)
				(end 239.528604 -93.772228)
			)
			(arc
				(start 239.229392 -93.772228)
				(mid 239.106537 -93.736915)
				(end 239.022382 -93.640656)
			)
			(xy 239.016032 -93.62694) (xy 238.991394 -93.611192) (xy 238.807244 -93.611192) (xy 238.782098 -93.627194)
			(arc
				(start 238.776002 -93.64091)
				(mid 238.691935 -93.738104)
				(end 238.568484 -93.773752)
			)
			(arc
				(start 238.269272 -93.773752)
				(mid 238.108436 -93.708082)
				(end 238.041688 -93.547692)
			)
			(arc
				(start 238.041688 -93.330776)
				(mid 238.056567 -93.294855)
				(end 238.092488 -93.279976)
			)
			(xy 238.101632 -93.279976)
			(arc
				(start 238.101632 -93.099382)
				(mid 238.09519 -93.074875)
				(end 238.077756 -93.056456)
			)
			(xy 237.993428 -93.003624) (xy 237.967266 -93.002354)
			(arc
				(start 237.955328 -93.007942)
				(mid 237.874081 -93.03671)
				(end 237.78845 -93.04655)
			)
			(arc
				(start 237.78845 -93.04655)
				(mid 237.617198 -93.005985)
				(end 237.48238 -92.89288)
			)
			(xy 237.478316 -92.887292) (xy 237.467394 -92.87891)
			(arc
				(start 237.199932 -92.768166)
				(mid 237.175595 -92.764483)
				(end 237.152434 -92.772738)
			)
			(xy 237.141766 -92.77985) (xy 237.129828 -92.801948)
			(arc
				(start 237.129828 -93.334332)
				(mid 237.144707 -93.370253)
				(end 237.180628 -93.385132)
			)
			(arc
				(start 237.247938 -93.385132)
				(mid 237.517705 -93.496873)
				(end 237.629446 -93.76664)
			)
			(arc
				(start 237.629446 -93.76664)
				(mid 237.562016 -93.983211)
				(end 237.383574 -94.123256)
			)
			(xy 237.371382 -94.127828) (xy 237.354872 -94.147132)
			(arc
				(start 237.334298 -94.243144)
				(mid 237.334557 -94.265625)
				(end 237.344458 -94.285816)
			)
			(xy 237.346236 -94.287848) (xy 237.490762 -94.432374)
			(arc
				(start 237.49127 -94.432882)
				(mid 237.507627 -94.443624)
				(end 237.52683 -94.44736)
			)
		)
		(stroke
			(width 0)
			(type solid)
		)
		(fill yes)
		(layer "F.Cu")
		(net "GND")
	)
	(gr_poly
		(pts
			(xy 102.060248 -323.636894) (xy 102.070314 -323.636462) (xy 102.088905 -323.628735) (xy 102.096316 -323.621908)
			(xy 102.123748 -323.594476) (xy 102.130596 -323.587079) (xy 102.13833 -323.56848) (xy 102.138734 -323.558408)
			(xy 102.138734 -322.73875) (xy 102.139167 -322.728685) (xy 102.146898 -322.710096) (xy 102.15372 -322.702682)
			(xy 102.255828 -322.600574) (xy 102.263224 -322.593724) (xy 102.281823 -322.585988) (xy 102.291896 -322.585588)
			(xy 103.238554 -322.585588) (xy 103.24862 -322.58602) (xy 103.267212 -322.593747) (xy 103.274622 -322.600574)
			(xy 103.362506 -322.688458) (xy 103.369343 -322.69586) (xy 103.377055 -322.714458) (xy 103.377492 -322.724526)
			(xy 103.377492 -323.586094) (xy 103.377979 -323.596103) (xy 103.385637 -323.614598) (xy 103.39979 -323.628755)
			(xy 103.418283 -323.636418) (xy 103.428292 -323.636894) (xy 117.292628 -323.636894) (xy 117.302696 -323.636466)
			(xy 117.321292 -323.628743) (xy 117.328696 -323.621908) (xy 117.503956 -323.446648) (xy 117.510799 -323.439249)
			(xy 117.518521 -323.42065) (xy 117.518942 -323.41058) (xy 117.518942 -322.141088) (xy 117.518452 -322.131079)
			(xy 117.510792 -322.112584) (xy 117.496641 -322.098425) (xy 117.478151 -322.090753) (xy 117.468142 -322.090288)
			(xy 116.764054 -322.090288) (xy 116.747592 -322.089811) (xy 116.715737 -322.081492) (xy 116.68705 -322.065337)
			(xy 116.6749 -322.05422) (xy 116.667545 -322.047569) (xy 116.649244 -322.039986) (xy 116.63934 -322.039488)
			(xy 116.233194 -322.039488) (xy 116.20373 -322.068444) (xy 116.203222 -322.089272) (xy 116.202081 -322.119993)
			(xy 116.192971 -322.180792) (xy 116.176218 -322.239943) (xy 116.152094 -322.29649) (xy 116.120988 -322.349518)
			(xy 116.083404 -322.398169) (xy 116.061998 -322.420234) (xy 115.68811 -322.794122) (xy 115.665394 -322.816143)
			(xy 115.615202 -322.854662) (xy 115.560411 -322.886296) (xy 115.501957 -322.910504) (xy 115.440843 -322.926872)
			(xy 115.378114 -322.935118) (xy 115.34648 -322.9356) (xy 115.31485 -322.935082) (xy 115.252133 -322.926822)
			(xy 115.191029 -322.910447) (xy 115.132586 -322.886237) (xy 115.077803 -322.854605) (xy 115.027617 -322.816094)
			(xy 114.982887 -322.771362) (xy 114.944379 -322.721174) (xy 114.912751 -322.666389) (xy 114.888544 -322.607944)
			(xy 114.872172 -322.54684) (xy 114.863916 -322.484122) (xy 114.863372 -322.452492) (xy 114.863889 -322.42086)
			(xy 114.872144 -322.358137) (xy 114.888513 -322.297027) (xy 114.912714 -322.238576) (xy 114.944335 -322.183781)
			(xy 114.982835 -322.133581) (xy 115.00485 -322.110862) (xy 115.222528 -321.893438) (xy 115.229215 -321.886029)
			(xy 115.236807 -321.867593) (xy 115.23726 -321.857624) (xy 115.23726 -321.150234) (xy 115.237755 -321.133523)
			(xy 115.246409 -321.10124) (xy 115.263135 -321.072304) (xy 115.286791 -321.048692) (xy 115.315757 -321.032019)
			(xy 115.348056 -321.023424) (xy 115.364768 -321.02298) (xy 116.075968 -321.02298) (xy 116.092428 -321.023461)
			(xy 116.124277 -321.031788) (xy 116.152954 -321.047952) (xy 116.165122 -321.059048) (xy 116.172482 -321.065688)
			(xy 116.190782 -321.073253) (xy 116.200682 -321.07378) (xy 116.63934 -321.07378) (xy 116.649235 -321.073253)
			(xy 116.667518 -321.06566) (xy 116.6749 -321.059048) (xy 116.687057 -321.047936) (xy 116.715734 -321.03176)
			(xy 116.74759 -321.023441) (xy 116.764054 -321.02298) (xy 117.468142 -321.02298) (xy 117.478143 -321.022484)
			(xy 117.496617 -321.014817) (xy 117.510752 -321.000665) (xy 117.518397 -320.982181) (xy 117.518942 -320.97218)
			(xy 117.518942 -320.667888) (xy 117.518452 -320.657879) (xy 117.510792 -320.639384) (xy 117.496641 -320.625225)
			(xy 117.478151 -320.617553) (xy 117.468142 -320.617088) (xy 116.764054 -320.617088) (xy 116.747375 -320.616538)
			(xy 116.715155 -320.607896) (xy 116.686268 -320.591212) (xy 116.66268 -320.567623) (xy 116.645999 -320.538734)
			(xy 116.63736 -320.506513) (xy 116.6368 -320.489834) (xy 116.6368 -319.6844) (xy 116.636398 -319.675118)
			(xy 116.629756 -319.657786) (xy 116.623846 -319.650618) (xy 116.604867 -319.628502) (xy 116.571789 -319.580521)
			(xy 116.544726 -319.528907) (xy 116.524073 -319.47441) (xy 116.51013 -319.417824) (xy 116.503099 -319.359971)
			(xy 116.502688 -319.330832) (xy 116.502688 -318.915034) (xy 116.503222 -318.882428) (xy 116.511991 -318.817809)
			(xy 116.529375 -318.754957) (xy 116.555057 -318.695015) (xy 116.588571 -318.639074) (xy 116.629307 -318.588151)
			(xy 116.652548 -318.565276) (xy 116.660422 -318.55791) (xy 116.668296 -318.539114) (xy 116.694966 -318.512444)
			(xy 116.710968 -318.512444) (xy 116.724684 -318.508634) (xy 116.73078 -318.504824) (xy 116.75962 -318.487591)
			(xy 116.821053 -318.4604) (xy 116.885664 -318.441994) (xy 116.952205 -318.432729) (xy 116.985796 -318.43218)
			(xy 117.017425 -318.43267) (xy 117.08015 -318.440868) (xy 117.141269 -318.457179) (xy 117.170708 -318.468756)
			(xy 117.180106 -318.47282) (xy 117.200426 -318.47282) (xy 117.285516 -318.43726) (xy 117.29974 -318.422782)
			(xy 117.30355 -318.413384) (xy 117.314601 -318.387755) (xy 117.343048 -318.33974) (xy 117.378177 -318.296373)
			(xy 117.419239 -318.258576) (xy 117.465362 -318.227153) (xy 117.49024 -318.214502) (xy 117.503702 -318.207898)
			(xy 117.518942 -318.183514) (xy 117.518942 -318.067182) (xy 117.503702 -318.042798) (xy 117.49024 -318.036194)
			(xy 117.466431 -318.024133) (xy 117.422141 -317.994352) (xy 117.382432 -317.95869) (xy 117.348078 -317.917843)
			(xy 117.319751 -317.872609) (xy 117.298003 -317.823869) (xy 117.283257 -317.772575) (xy 117.275801 -317.719726)
			(xy 117.275356 -317.69304) (xy 117.27575 -317.66832) (xy 117.282137 -317.619296) (xy 117.294796 -317.571505)
			(xy 117.313516 -317.525747) (xy 117.325394 -317.504064) (xy 117.332252 -317.492126) (xy 117.331998 -317.465456)
			(xy 117.280944 -317.377572) (xy 117.276163 -317.370083) (xy 117.262557 -317.358677) (xy 117.245878 -317.352592)
			(xy 117.237002 -317.352172) (xy 117.002306 -317.352172) (xy 116.985623 -317.351628) (xy 116.953393 -317.342995)
			(xy 116.924496 -317.326314) (xy 116.900901 -317.302723) (xy 116.884215 -317.273829) (xy 116.875575 -317.241601)
			(xy 116.875052 -317.224918) (xy 116.875052 -316.513718) (xy 116.875492 -316.498589) (xy 116.882618 -316.469182)
			(xy 116.896452 -316.442272) (xy 116.91622 -316.419364) (xy 116.940816 -316.40174) (xy 116.968863 -316.390386)
			(xy 116.983764 -316.387734) (xy 117.002814 -316.38494) (xy 117.027452 -316.356492) (xy 117.027452 -316.238128)
			(xy 117.028021 -316.20816) (xy 117.037357 -316.148955) (xy 117.055836 -316.091938) (xy 117.083003 -316.038513)
			(xy 117.118189 -315.989992) (xy 117.138958 -315.96838) (xy 117.387116 -315.720222) (xy 117.410059 -315.698174)
			(xy 117.461892 -315.66127) (xy 117.49024 -315.646816) (xy 117.503702 -315.640466) (xy 117.518942 -315.616082)
			(xy 117.518942 -309.803292) (xy 117.518453 -309.793282) (xy 117.510794 -309.774786) (xy 117.496643 -309.760625)
			(xy 117.478151 -309.752954) (xy 117.468142 -309.752492) (xy 117.449854 -309.752492) (xy 117.436138 -309.756302)
			(xy 117.430042 -309.760112) (xy 117.401202 -309.777345) (xy 117.339769 -309.804537) (xy 117.275158 -309.822945)
			(xy 117.208618 -309.832212) (xy 117.175026 -309.832756) (xy 117.141436 -309.832194) (xy 117.074898 -309.82292)
			(xy 117.010287 -309.804519) (xy 116.948847 -309.777346) (xy 116.92001 -309.760112) (xy 116.913914 -309.756302)
			(xy 116.900198 -309.752492) (xy 116.887244 -309.752492) (xy 116.85778 -309.72252) (xy 116.85778 -309.714646)
			(xy 116.841778 -309.69966) (xy 116.818553 -309.676779) (xy 116.777849 -309.625851) (xy 116.744373 -309.569905)
			(xy 116.718735 -309.509962) (xy 116.701403 -309.447112) (xy 116.69269 -309.382501) (xy 116.692172 -309.349902)
			(xy 116.692172 -308.744366) (xy 116.691678 -308.734365) (xy 116.684011 -308.71589) (xy 116.669858 -308.701754)
			(xy 116.651374 -308.69411) (xy 116.641372 -308.693566) (xy 116.364004 -308.693566) (xy 116.353993 -308.694053)
			(xy 116.335494 -308.70171) (xy 116.321332 -308.715862) (xy 116.31366 -308.734356) (xy 116.313204 -308.744366)
			(xy 116.313204 -309.349902) (xy 116.312682 -309.382498) (xy 116.303944 -309.447102) (xy 116.286598 -309.509945)
			(xy 116.26096 -309.569884) (xy 116.227497 -309.625833) (xy 116.186814 -309.676773) (xy 116.163598 -309.69966)
			(xy 116.155724 -309.707026) (xy 116.147596 -309.725822) (xy 116.12118 -309.752492) (xy 116.105178 -309.752492)
			(xy 116.091462 -309.756302) (xy 116.085366 -309.760112) (xy 116.056525 -309.77734) (xy 115.99509 -309.804523)
			(xy 115.930479 -309.82292) (xy 115.86394 -309.832177) (xy 115.83035 -309.832756) (xy 115.796761 -309.832189)
			(xy 115.730228 -309.822905) (xy 115.665622 -309.804496) (xy 115.604189 -309.777315) (xy 115.575334 -309.760112)
			(xy 115.569238 -309.756302) (xy 115.555522 -309.752492) (xy 115.542568 -309.752492) (xy 115.513104 -309.72252)
			(xy 115.513104 -309.714646) (xy 115.497102 -309.69966) (xy 115.473876 -309.67678) (xy 115.43317 -309.625852)
			(xy 115.399693 -309.569907) (xy 115.374053 -309.509963) (xy 115.35672 -309.447113) (xy 115.348007 -309.382501)
			(xy 115.347496 -309.349902) (xy 115.347496 -308.744366) (xy 115.347002 -308.734363) (xy 115.339336 -308.715884)
			(xy 115.325184 -308.701742) (xy 115.306699 -308.694091) (xy 115.296696 -308.693566) (xy 113.928144 -308.693566)
			(xy 113.91808 -308.694001) (xy 113.899496 -308.701737) (xy 113.892076 -308.708552) (xy 113.863882 -308.736746)
			(xy 113.857034 -308.744143) (xy 113.849303 -308.762742) (xy 113.848896 -308.772814) (xy 113.848896 -318.72301)
			(xy 113.848471 -318.733079) (xy 113.840753 -318.751681) (xy 113.83391 -318.759078) (xy 113.497106 -319.095882)
			(xy 113.489708 -319.102731) (xy 113.471111 -319.110471) (xy 113.461038 -319.110868) (xy 99.891596 -319.110868)
			(xy 99.881525 -319.111291) (xy 99.862919 -319.119003) (xy 99.855528 -319.125854) (xy 99.726496 -319.254886)
			(xy 99.719664 -319.262289) (xy 99.711961 -319.280888) (xy 99.71151 -319.290954) (xy 99.71151 -320.489834)
			(xy 115.23726 -320.489834) (xy 115.23726 -318.921638) (xy 115.237765 -318.890005) (xy 115.246009 -318.827278)
			(xy 115.262372 -318.766164) (xy 115.286576 -318.707711) (xy 115.318206 -318.652918) (xy 115.356719 -318.602725)
			(xy 115.378738 -318.580008) (xy 115.385596 -318.57315) (xy 115.393978 -318.565022) (xy 115.40998 -318.550036)
			(xy 115.40998 -318.541908) (xy 115.439444 -318.512444) (xy 115.452398 -318.512444) (xy 115.466114 -318.50838)
			(xy 115.47221 -318.50457) (xy 115.50106 -318.487343) (xy 115.562485 -318.460102) (xy 115.62709 -318.441628)
			(xy 115.693629 -318.432274) (xy 115.727226 -318.431672) (xy 115.760826 -318.432259) (xy 115.827374 -318.441585)
			(xy 115.891986 -318.460053) (xy 115.953411 -318.487307) (xy 115.982242 -318.50457) (xy 115.988338 -318.50838)
			(xy 116.002054 -318.512444) (xy 116.044472 -318.512444) (xy 116.044472 -318.53886) (xy 116.0526 -318.557656)
			(xy 116.060474 -318.565022) (xy 116.083696 -318.587903) (xy 116.124375 -318.638847) (xy 116.157836 -318.694797)
			(xy 116.183472 -318.754737) (xy 116.200817 -318.81758) (xy 116.209557 -318.882184) (xy 116.21008 -318.91478)
			(xy 116.209919 -318.934168) (xy 116.206864 -318.972823) (xy 116.203984 -318.991996) (xy 116.203476 -318.99606)
			(xy 116.203476 -320.489834) (xy 116.202986 -320.506543) (xy 116.19432 -320.538818) (xy 116.177588 -320.567745)
			(xy 116.153933 -320.591351) (xy 116.124971 -320.608022) (xy 116.092678 -320.616621) (xy 116.075968 -320.617088)
			(xy 115.364768 -320.617088) (xy 115.348071 -320.616594) (xy 115.315814 -320.607954) (xy 115.286886 -320.591269)
			(xy 115.263254 -320.567675) (xy 115.246524 -320.538774) (xy 115.237833 -320.50653) (xy 115.23726 -320.489834)
			(xy 99.71151 -320.489834) (xy 99.71151 -323.358256) (xy 99.711944 -323.368321) (xy 99.719673 -323.38691)
			(xy 99.726496 -323.394324) (xy 99.95408 -323.621908) (xy 99.961483 -323.628741) (xy 99.980081 -323.636445)
			(xy 99.990148 -323.636894)
		)
		(stroke
			(width 0)
			(type solid)
		)
		(fill yes)
		(layer "F.Cu")
		(net "P0V8_SERDES_VDDA_PEX0")
	)
	(gr_poly
		(pts
			(arc
				(start 107.446318 -357.3018)
				(mid 107.465841 -357.297899)
				(end 107.482386 -357.286814)
			)
			(arc
				(start 108.697014 -356.072186)
				(mid 108.708125 -356.055652)
				(end 108.712 -356.036118)
			)
			(arc
				(start 108.712 -349.753682)
				(mid 108.708099 -349.734159)
				(end 108.697014 -349.717614)
			)
			(xy 108.279184 -349.299784) (xy 108.243878 -349.296228)
			(arc
				(start 108.228638 -349.30588)
				(mid 108.129651 -349.351235)
				(end 108.021882 -349.36684)
			)
			(arc
				(start 108.021882 -349.36684)
				(mid 107.752115 -349.255099)
				(end 107.640374 -348.985332)
			)
			(arc
				(start 107.640374 -348.985332)
				(mid 107.655917 -348.877545)
				(end 107.701334 -348.778576)
			)
			(xy 107.710986 -348.763336) (xy 107.70743 -348.72803)
			(arc
				(start 107.355386 -348.375986)
				(mid 107.344275 -348.359452)
				(end 107.3404 -348.339918)
			)
			(arc
				(start 107.3404 -344.648282)
				(mid 107.336499 -344.628759)
				(end 107.325414 -344.612214)
			)
			(arc
				(start 106.948986 -344.235786)
				(mid 106.932452 -344.224675)
				(end 106.912918 -344.2208)
			)
			(arc
				(start 106.108246 -344.2208)
				(mid 106.082612 -344.227742)
				(end 106.06405 -344.246708)
			)
			(arc
				(start 106.06405 -344.246708)
				(mid 106.020661 -344.313127)
				(end 105.968546 -344.372946)
			)
			(arc
				(start 105.678986 -344.66276)
				(mid 105.667924 -344.679177)
				(end 105.664 -344.698574)
			)
			(arc
				(start 105.664 -347.171518)
				(mid 105.667901 -347.191041)
				(end 105.678986 -347.207586)
			)
			(arc
				(start 106.182414 -347.711014)
				(mid 106.193525 -347.727548)
				(end 106.1974 -347.747082)
			)
			(arc
				(start 106.1974 -347.901514)
				(mid 106.201582 -347.921698)
				(end 106.213402 -347.938598)
			)
			(xy 106.27487 -347.99651) (xy 106.294174 -348.003622) (xy 106.304842 -348.003114)
			(arc
				(start 106.32694 -348.002352)
				(mid 106.708448 -348.38386)
				(end 106.32694 -348.765368)
			)
			(xy 106.304842 -348.764606) (xy 106.294174 -348.764098) (xy 106.27487 -348.77121)
			(arc
				(start 106.213402 -348.829122)
				(mid 106.201532 -348.846001)
				(end 106.1974 -348.866206)
			)
			(arc
				(start 106.1974 -350.041718)
				(mid 106.193499 -350.061241)
				(end 106.182414 -350.077786)
			)
			(arc
				(start 105.653586 -350.606614)
				(mid 105.637052 -350.617725)
				(end 105.617518 -350.6216)
			)
			(arc
				(start 105.385362 -350.6216)
				(mid 105.360219 -350.628258)
				(end 105.341674 -350.646492)
			)
			(arc
				(start 105.341674 -350.646492)
				(mid 105.012998 -350.834499)
				(end 104.684322 -350.646492)
			)
			(arc
				(start 104.684322 -350.646492)
				(mid 104.665773 -350.628265)
				(end 104.640634 -350.6216)
			)
			(arc
				(start 104.051862 -350.6216)
				(mid 104.027355 -350.628042)
				(end 104.008936 -350.645476)
			)
			(arc
				(start 104.008936 -350.645476)
				(mid 103.685848 -350.82407)
				(end 103.36276 -350.645476)
			)
			(arc
				(start 103.36276 -350.645476)
				(mid 103.344383 -350.627968)
				(end 103.319834 -350.6216)
			)
			(arc
				(start 102.738682 -350.6216)
				(mid 102.713929 -350.628181)
				(end 102.695502 -350.645984)
			)
			(arc
				(start 102.695502 -350.645984)
				(mid 102.369366 -350.829339)
				(end 102.04323 -350.645984)
			)
			(arc
				(start 102.04323 -350.645984)
				(mid 102.024821 -350.62815)
				(end 102.00005 -350.6216)
			)
			(arc
				(start 99.639882 -350.6216)
				(mid 99.620359 -350.625501)
				(end 99.603814 -350.636586)
			)
			(arc
				(start 99.227386 -351.013014)
				(mid 99.216275 -351.029548)
				(end 99.2124 -351.049082)
			)
			(arc
				(start 99.2124 -354.689918)
				(mid 99.216301 -354.709441)
				(end 99.227386 -354.725986)
			)
			(arc
				(start 99.578414 -355.077014)
				(mid 99.594948 -355.088125)
				(end 99.614482 -355.092)
			)
			(arc
				(start 100.435918 -355.092)
				(mid 100.455441 -355.088099)
				(end 100.471986 -355.077014)
			)
			(arc
				(start 100.59416 -354.95484)
				(mid 100.605086 -354.938394)
				(end 100.608892 -354.919026)
			)
			(arc
				(start 100.608892 -354.350574)
				(mid 100.605059 -354.331217)
				(end 100.59416 -354.31476)
			)
			(arc
				(start 100.090986 -353.811586)
				(mid 100.079875 -353.795052)
				(end 100.076 -353.775518)
			)
			(arc
				(start 100.076 -353.643946)
				(mid 100.07205 -353.624559)
				(end 100.061014 -353.608132)
			)
			(arc
				(start 100.014278 -353.561142)
				(mid 100.003216 -353.544725)
				(end 99.999292 -353.525328)
			)
			(arc
				(start 99.999292 -352.772472)
				(mid 100.003242 -352.753085)
				(end 100.014278 -352.736658)
			)
			(arc
				(start 100.061014 -352.689668)
				(mid 100.072076 -352.673251)
				(end 100.076 -352.653854)
			)
			(arc
				(start 100.076 -352.471482)
				(mid 100.079901 -352.451959)
				(end 100.090986 -352.435414)
			)
			(arc
				(start 100.518214 -352.008186)
				(mid 100.534748 -351.997075)
				(end 100.554282 -351.9932)
			)
			(arc
				(start 101.922834 -351.9932)
				(mid 101.945233 -351.987995)
				(end 101.962966 -351.973388)
			)
			(xy 102.019354 -351.900236) (xy 102.02418 -351.87763)
			(arc
				(start 102.021132 -351.865946)
				(mid 102.011851 -351.818209)
				(end 102.008686 -351.76968)
			)
			(arc
				(start 102.008686 -351.76968)
				(mid 102.390194 -351.388172)
				(end 102.771702 -351.76968)
			)
			(arc
				(start 102.771702 -351.76968)
				(mid 102.76857 -351.818214)
				(end 102.759256 -351.865946)
			)
			(xy 102.756208 -351.87763) (xy 102.761034 -351.900236)
			(arc
				(start 102.817422 -351.973388)
				(mid 102.835197 -351.987908)
				(end 102.857554 -351.9932)
			)
			(arc
				(start 104.546908 -351.9932)
				(mid 104.569467 -351.987916)
				(end 104.587294 -351.973134)
			)
			(xy 104.643682 -351.899474) (xy 104.648 -351.87636)
			(arc
				(start 104.644952 -351.86493)
				(mid 104.634878 -351.815087)
				(end 104.63149 -351.764346)
			)
			(arc
				(start 104.63149 -351.764346)
				(mid 105.012998 -351.382838)
				(end 105.394506 -351.764346)
			)
			(arc
				(start 105.394506 -351.764346)
				(mid 105.39115 -351.815091)
				(end 105.381044 -351.86493)
			)
			(xy 105.377996 -351.87636) (xy 105.382314 -351.899474)
			(arc
				(start 105.438702 -351.973134)
				(mid 105.456551 -351.987872)
				(end 105.479088 -351.9932)
			)
			(arc
				(start 107.065318 -351.9932)
				(mid 107.084841 -351.997101)
				(end 107.101386 -352.008186)
			)
			(arc
				(start 107.452414 -352.359214)
				(mid 107.463525 -352.375748)
				(end 107.4674 -352.395282)
			)
			(xy 107.4674 -352.547936) (xy 107.467908 -352.54819)
			(arc
				(start 107.467908 -353.525328)
				(mid 107.463958 -353.544715)
				(end 107.452922 -353.561142)
			)
			(arc
				(start 107.155742 -353.858322)
				(mid 107.139325 -353.869384)
				(end 107.119928 -353.873308)
			)
			(xy 106.17581 -353.873308) (xy 106.172508 -353.87661)
			(arc
				(start 106.172508 -354.558092)
				(mid 106.187297 -354.594178)
				(end 106.223308 -354.608892)
			)
			(arc
				(start 106.738928 -354.608892)
				(mid 106.758315 -354.612842)
				(end 106.774742 -354.623878)
			)
			(arc
				(start 106.796332 -354.645214)
				(mid 106.812749 -354.656276)
				(end 106.832146 -354.6602)
			)
			(arc
				(start 106.862118 -354.6602)
				(mid 106.881641 -354.664101)
				(end 106.898186 -354.675186)
			)
			(arc
				(start 106.995214 -354.772214)
				(mid 107.006325 -354.788748)
				(end 107.0102 -354.808282)
			)
			(xy 107.0102 -354.859336) (xy 107.010708 -354.85959) (xy 107.010708 -355.65461) (xy 107.0102 -355.654864)
			(arc
				(start 107.0102 -355.782118)
				(mid 107.006299 -355.801641)
				(end 106.995214 -355.818186)
			)
			(xy 106.815636 -355.997764) (xy 106.809032 -356.02545)
			(arc
				(start 106.813604 -356.039166)
				(mid 106.828047 -356.098211)
				(end 106.832908 -356.1588)
			)
			(arc
				(start 106.832908 -356.1588)
				(mid 106.721167 -356.428567)
				(end 106.4514 -356.540308)
			)
			(arc
				(start 106.4514 -356.540308)
				(mid 106.181723 -356.428657)
				(end 106.069892 -356.159054)
			)
			(xy 106.069892 -356.148894) (xy 106.062272 -356.130352)
			(arc
				(start 106.004106 -356.07244)
				(mid 105.98766 -356.061514)
				(end 105.968292 -356.057708)
			)
			(arc
				(start 103.906574 -356.057708)
				(mid 103.887217 -356.061541)
				(end 103.87076 -356.07244)
			)
			(arc
				(start 103.773986 -356.169214)
				(mid 103.762875 -356.185748)
				(end 103.759 -356.205282)
			)
			(arc
				(start 103.759 -357.153718)
				(mid 103.762901 -357.173241)
				(end 103.773986 -357.189786)
			)
			(arc
				(start 103.871014 -357.286814)
				(mid 103.887548 -357.297925)
				(end 103.907082 -357.3018)
			)
		)
		(stroke
			(width 0)
			(type solid)
		)
		(fill yes)
		(layer "F.Cu")
		(net "P3V3_CLK_BUFFER_9ZXL0451E_S3_VZX3P3")
	)
	(gr_poly
		(pts
			(arc
				(start 381.037592 -233.522012)
				(mid 381.073513 -233.507133)
				(end 381.088392 -233.471212)
			)
			(arc
				(start 381.088392 -233.027728)
				(mid 381.086474 -233.014153)
				(end 381.081026 -233.001566)
			)
			(arc
				(start 381.081026 -233.001566)
				(mid 381.046753 -232.922026)
				(end 381.035052 -232.836212)
			)
			(arc
				(start 381.035052 -232.145078)
				(mid 381.031219 -232.125721)
				(end 381.02032 -232.109264)
			)
			(arc
				(start 380.864364 -231.953308)
				(mid 380.794824 -231.849373)
				(end 380.770384 -231.72674)
			)
			(arc
				(start 380.770384 -230.782368)
				(mid 380.751784 -230.763468)
				(end 380.726188 -230.75646)
			)
			(xy 380.71806 -230.75646) (xy 380.688596 -230.726742) (xy 380.688596 -230.151432) (xy 380.71806 -230.12146)
			(xy 380.736856 -230.12146)
			(arc
				(start 380.76632 -230.12146)
				(mid 380.794507 -230.112923)
				(end 380.81331 -230.090218)
			)
			(xy 380.819406 -230.07574) (xy 380.81331 -230.045768)
			(arc
				(start 380.70663 -229.938834)
				(mid 380.664684 -229.876152)
				(end 380.649988 -229.802182)
			)
			(arc
				(start 380.649988 -229.702868)
				(mid 380.635109 -229.666947)
				(end 380.599188 -229.652068)
			)
			(xy 380.52121 -229.652068)
			(arc
				(start 380.436882 -229.652068)
				(mid 380.34681 -229.614706)
				(end 380.309628 -229.52456)
			)
			(xy 380.309628 -229.169468) (xy 380.309374 -229.169468)
			(arc
				(start 380.309374 -228.81336)
				(mid 380.34663 -228.723288)
				(end 380.436628 -228.685852)
			)
			(arc
				(start 381.03175 -228.685852)
				(mid 381.051273 -228.681951)
				(end 381.067818 -228.670866)
			)
			(xy 381.167386 -228.571298) (xy 381.175006 -228.547676)
			(arc
				(start 381.17272 -228.53523)
				(mid 381.168177 -228.501583)
				(end 381.166624 -228.467666)
			)
			(arc
				(start 381.166624 -228.467666)
				(mid 381.278365 -228.197899)
				(end 381.548132 -228.086158)
			)
			(arc
				(start 381.548132 -228.086158)
				(mid 381.573587 -228.086957)
				(end 381.598932 -228.08946)
			)
			(arc
				(start 381.598932 -228.08946)
				(mid 381.744651 -228.140556)
				(end 381.858266 -228.245162)
			)
			(xy 381.861568 -228.249988) (xy 381.870204 -228.257608)
			(arc
				(start 381.883666 -228.26472)
				(mid 381.895229 -228.269238)
				(end 381.907542 -228.270816)
			)
			(arc
				(start 382.176274 -228.270816)
				(mid 382.195661 -228.266866)
				(end 382.212088 -228.25583)
			)
			(arc
				(start 382.438148 -228.02977)
				(mid 382.449074 -228.013324)
				(end 382.45288 -227.993956)
			)
			(arc
				(start 382.45288 -226.480624)
				(mid 382.449047 -226.461267)
				(end 382.438148 -226.44481)
			)
			(arc
				(start 382.33096 -226.337622)
				(mid 382.314543 -226.32656)
				(end 382.295146 -226.322636)
			)
			(arc
				(start 380.975362 -226.322636)
				(mid 380.88538 -226.285364)
				(end 380.848108 -226.195382)
			)
			(arc
				(start 380.848108 -224.976182)
				(mid 380.88538 -224.8862)
				(end 380.975362 -224.848928)
			)
			(arc
				(start 382.397762 -224.848928)
				(mid 382.487744 -224.8862)
				(end 382.525016 -224.976182)
			)
			(arc
				(start 382.525016 -225.963734)
				(mid 382.528966 -225.983121)
				(end 382.540002 -225.999548)
			)
			(arc
				(start 382.78308 -226.24288)
				(mid 382.825109 -226.305547)
				(end 382.839976 -226.379532)
			)
			(arc
				(start 382.839976 -228.095048)
				(mid 382.825145 -228.169048)
				(end 382.78308 -228.2317)
			)
			(arc
				(start 382.43383 -228.581204)
				(mid 382.419848 -228.60708)
				(end 382.422654 -228.636322)
			)
			(arc
				(start 382.429766 -228.654102)
				(mid 382.448427 -228.677105)
				(end 382.476756 -228.685852)
			)
			(xy 382.599946 -228.685852)
			(arc
				(start 382.722882 -228.685852)
				(mid 382.812954 -228.723214)
				(end 382.850136 -228.81336)
			)
			(arc
				(start 382.850136 -228.934772)
				(mid 382.858126 -228.958357)
				(end 382.876298 -228.975412)
			)
			(arc
				(start 384.173222 -228.975412)
				(mid 384.192579 -228.971579)
				(end 384.209036 -228.96068)
			)
			(arc
				(start 384.355848 -228.813868)
				(mid 384.366774 -228.797422)
				(end 384.37058 -228.778054)
			)
			(arc
				(start 384.37058 -228.048566)
				(mid 384.353569 -228.030326)
				(end 384.32994 -228.022404)
			)
			(arc
				(start 383.17551 -228.022404)
				(mid 383.085528 -227.985132)
				(end 383.048256 -227.89515)
			)
			(arc
				(start 383.048256 -226.67595)
				(mid 383.085528 -226.585968)
				(end 383.17551 -226.548696)
			)
			(arc
				(start 384.59791 -226.548696)
				(mid 384.687892 -226.585968)
				(end 384.725164 -226.67595)
			)
			(xy 384.725164 -227.78339) (xy 384.72872 -227.79609)
			(arc
				(start 384.732022 -227.801932)
				(mid 384.75111 -227.848264)
				(end 384.757676 -227.897944)
			)
			(arc
				(start 384.757676 -228.879146)
				(mid 384.742845 -228.953146)
				(end 384.70078 -229.015798)
			)
			(arc
				(start 384.410966 -229.305612)
				(mid 384.348299 -229.347641)
				(end 384.274314 -229.362508)
			)
			(arc
				(start 382.876298 -229.362508)
				(mid 382.858058 -229.379519)
				(end 382.850136 -229.403148)
			)
			(xy 382.850136 -229.465632) (xy 382.85039 -229.465632)
			(arc
				(start 382.85039 -229.52456)
				(mid 382.813134 -229.614632)
				(end 382.723136 -229.652068)
			)
			(arc
				(start 382.306576 -229.652068)
				(mid 382.280942 -229.65901)
				(end 382.26238 -229.677976)
			)
			(arc
				(start 382.26238 -230.095552)
				(mid 382.28098 -230.114452)
				(end 382.306576 -230.12146)
			)
			(xy 382.420368 -230.12146) (xy 382.441704 -230.12146) (xy 382.471168 -230.151432)
			(arc
				(start 382.471168 -230.70566)
				(mid 382.456289 -230.741581)
				(end 382.420368 -230.75646)
			)
			(xy 382.418844 -230.75646) (xy 382.38938 -230.785924) (xy 382.38938 -230.859076) (xy 382.392936 -230.872284)
			(arc
				(start 382.396492 -230.878126)
				(mid 382.442642 -230.997032)
				(end 382.447038 -231.124506)
			)
			(arc
				(start 382.447038 -231.124506)
				(mid 382.429127 -231.199587)
				(end 382.396492 -231.26954)
			)
			(arc
				(start 382.396492 -231.26954)
				(mid 382.391162 -231.282138)
				(end 382.38938 -231.295702)
			)
			(arc
				(start 382.38938 -231.816656)
				(mid 382.385071 -231.868785)
				(end 382.372362 -231.919526)
			)
			(xy 382.374394 -231.930194)
			(arc
				(start 382.430528 -232.003092)
				(mid 382.448171 -232.017646)
				(end 382.470406 -232.022904)
			)
			(arc
				(start 382.495298 -232.022904)
				(mid 382.58537 -232.060266)
				(end 382.622552 -232.150412)
			)
			(arc
				(start 382.622552 -232.525062)
				(mid 382.626433 -232.544283)
				(end 382.637284 -232.560622)
			)
			(arc
				(start 382.637284 -232.560622)
				(mid 382.720367 -232.687296)
				(end 382.749552 -232.835958)
			)
			(arc
				(start 382.749552 -233.470196)
				(mid 382.764431 -233.506117)
				(end 382.800352 -233.520996)
			)
			(arc
				(start 382.902206 -233.520996)
				(mid 382.921397 -233.517231)
				(end 382.937766 -233.506518)
			)
			(xy 382.93802 -233.506264) (xy 382.970786 -233.473498)
			(arc
				(start 382.971294 -233.47299)
				(mid 382.982036 -233.456633)
				(end 382.985772 -233.43743)
			)
			(arc
				(start 382.985772 -231.510586)
				(mid 382.989673 -231.491063)
				(end 383.000758 -231.474518)
			)
			(xy 383.252472 -231.222804)
			(arc
				(start 383.25298 -231.222296)
				(mid 383.263722 -231.205939)
				(end 383.267458 -231.186736)
			)
			(arc
				(start 383.267458 -231.097074)
				(mid 383.266205 -231.085604)
				(end 383.262378 -231.074722)
			)
			(arc
				(start 383.262378 -231.074722)
				(mid 383.227658 -230.976792)
				(end 383.215896 -230.873554)
			)
			(arc
				(start 383.215896 -230.873554)
				(mid 383.292855 -230.619533)
				(end 383.497836 -230.450898)
			)
			(xy 383.507234 -230.446834)
			(arc
				(start 383.799334 -230.154734)
				(mid 383.815868 -230.143623)
				(end 383.835402 -230.139748)
			)
			(xy 385.124452 -230.139748)
			(arc
				(start 385.132834 -230.138986)
				(mid 385.147489 -230.134234)
				(end 385.160012 -230.12527)
			)
			(arc
				(start 385.858766 -229.426516)
				(mid 385.869877 -229.409982)
				(end 385.873752 -229.390448)
			)
			(xy 385.873752 -225.773234) (xy 385.866132 -225.754438) (xy 385.858766 -225.747326)
			(arc
				(start 383.92227 -223.81083)
				(mid 383.905736 -223.799719)
				(end 383.886202 -223.795844)
			)
			(xy 380.673356 -223.795844) (xy 380.65456 -223.803464) (xy 380.647448 -223.81083)
			(arc
				(start 380.111 -224.347278)
				(mid 380.099889 -224.363812)
				(end 380.096014 -224.383346)
			)
			(xy 380.096014 -227.213414)
			(arc
				(start 380.100586 -227.22332)
				(mid 380.137785 -227.416027)
				(end 380.083314 -227.604574)
			)
			(arc
				(start 380.081282 -227.607876)
				(mid 380.015124 -227.693864)
				(end 379.929136 -227.760022)
			)
			(xy 379.923294 -227.763578)
			(arc
				(start 379.531118 -228.155754)
				(mid 379.520007 -228.172288)
				(end 379.516132 -228.191822)
			)
			(arc
				(start 379.516132 -232.645712)
				(mid 379.519897 -232.664903)
				(end 379.53061 -232.681272)
			)
			(xy 379.530864 -232.681526) (xy 379.922278 -233.07294) (xy 379.951996 -233.078782)
			(arc
				(start 379.966474 -233.07294)
				(mid 380.03735 -233.051666)
				(end 380.111 -233.044492)
			)
			(arc
				(start 380.111 -233.044492)
				(mid 380.379146 -233.154622)
				(end 380.492508 -233.421428)
			)
			(xy 380.492508 -233.431588) (xy 380.500382 -233.449876)
			(arc
				(start 380.558294 -233.50728)
				(mid 380.57474 -233.518206)
				(end 380.594108 -233.522012)
			)
		)
		(stroke
			(width 0)
			(type solid)
		)
		(fill yes)
		(layer "F.Cu")
		(net "GND")
	)
	(gr_poly
		(pts
			(arc
				(start 208.660238 -367.94948)
				(mid 208.679761 -367.945579)
				(end 208.696306 -367.934494)
			)
			(arc
				(start 208.837276 -367.793524)
				(mid 208.848387 -367.77699)
				(end 208.852262 -367.757456)
			)
			(arc
				(start 208.852262 -366.451388)
				(mid 208.856163 -366.431865)
				(end 208.867248 -366.41532)
			)
			(arc
				(start 209.028792 -366.253776)
				(mid 209.039903 -366.237242)
				(end 209.043778 -366.217708)
			)
			(arc
				(start 209.043778 -366.063022)
				(mid 209.047679 -366.043499)
				(end 209.058764 -366.026954)
			)
			(arc
				(start 209.831432 -365.254286)
				(mid 209.847966 -365.243175)
				(end 209.8675 -365.2393)
			)
			(arc
				(start 213.984078 -365.2393)
				(mid 214.003601 -365.235399)
				(end 214.020146 -365.224314)
			)
			(arc
				(start 214.304118 -364.940342)
				(mid 214.320652 -364.929231)
				(end 214.340186 -364.925356)
			)
			(arc
				(start 215.591644 -364.925356)
				(mid 215.611167 -364.929257)
				(end 215.627712 -364.940342)
			)
			(xy 215.694768 -365.007398)
			(arc
				(start 215.704928 -365.011208)
				(mid 215.767102 -365.042749)
				(end 215.82126 -365.086646)
			)
			(arc
				(start 216.86647 -366.131856)
				(mid 216.910349 -366.186026)
				(end 216.941908 -366.248188)
			)
			(xy 216.945718 -366.258348)
			(arc
				(start 217.625422 -366.938052)
				(mid 217.641956 -366.949163)
				(end 217.66149 -366.953038)
			)
			(arc
				(start 221.550484 -366.953038)
				(mid 221.570007 -366.956939)
				(end 221.586552 -366.968024)
			)
			(arc
				(start 221.66834 -367.049812)
				(mid 221.679451 -367.066346)
				(end 221.683326 -367.08588)
			)
			(arc
				(start 221.683326 -367.77803)
				(mid 221.687227 -367.797553)
				(end 221.698312 -367.814098)
			)
			(arc
				(start 221.746064 -367.86185)
				(mid 221.762598 -367.872961)
				(end 221.782132 -367.876836)
			)
			(arc
				(start 222.06839 -367.876836)
				(mid 222.087913 -367.872935)
				(end 222.104458 -367.86185)
			)
			(arc
				(start 222.140018 -367.82629)
				(mid 222.151129 -367.809756)
				(end 222.155004 -367.790222)
			)
			(arc
				(start 222.155004 -367.010442)
				(mid 222.158905 -366.990919)
				(end 222.16999 -366.974374)
			)
			(arc
				(start 223.594422 -365.549942)
				(mid 223.610956 -365.538831)
				(end 223.63049 -365.534956)
			)
			(arc
				(start 226.862132 -365.534956)
				(mid 226.881655 -365.538857)
				(end 226.8982 -365.549942)
			)
			(arc
				(start 228.245924 -366.897666)
				(mid 228.262458 -366.908777)
				(end 228.281992 -366.912652)
			)
			(arc
				(start 232.25125 -366.912652)
				(mid 232.270773 -366.916553)
				(end 232.287318 -366.927638)
			)
			(arc
				(start 232.347516 -366.987836)
				(mid 232.358627 -367.00437)
				(end 232.362502 -367.023904)
			)
			(arc
				(start 232.362502 -367.537238)
				(mid 232.358601 -367.556761)
				(end 232.347516 -367.573306)
			)
			(xy 232.347008 -367.573814) (xy 232.339388 -367.592356)
			(arc
				(start 232.339388 -367.820194)
				(mid 232.343289 -367.839717)
				(end 232.354374 -367.856262)
			)
			(xy 232.360978 -367.862866)
			(arc
				(start 232.707688 -367.862866)
				(mid 232.727348 -367.859014)
				(end 232.74401 -367.84788)
			)
			(xy 232.749852 -367.841784)
			(arc
				(start 232.749852 -366.861344)
				(mid 232.758928 -366.784427)
				(end 232.785666 -366.711738)
			)
			(arc
				(start 232.785666 -366.711738)
				(mid 232.789821 -366.700511)
				(end 232.791254 -366.688624)
			)
			(arc
				(start 232.791254 -366.536986)
				(mid 232.795155 -366.517463)
				(end 232.80624 -366.500918)
			)
			(arc
				(start 233.33075 -365.976662)
				(mid 233.347284 -365.965551)
				(end 233.366818 -365.961676)
			)
			(arc
				(start 234.312968 -365.961676)
				(mid 234.332491 -365.965577)
				(end 234.349036 -365.976662)
			)
			(arc
				(start 235.752894 -367.38052)
				(mid 235.769428 -367.391631)
				(end 235.788962 -367.395506)
			)
			(arc
				(start 240.540032 -367.395506)
				(mid 240.575953 -367.380627)
				(end 240.590832 -367.344706)
			)
			(xy 240.590832 -366.970056)
			(arc
				(start 240.588546 -366.96269)
				(mid 240.571247 -366.887874)
				(end 240.565432 -366.811306)
			)
			(arc
				(start 240.565432 -366.811306)
				(mid 240.571268 -366.734741)
				(end 240.588546 -366.659922)
			)
			(xy 240.590832 -366.652556)
			(arc
				(start 240.590832 -366.227106)
				(mid 240.628014 -366.137214)
				(end 240.717832 -366.099852)
			)
			(arc
				(start 241.42954 -366.099852)
				(mid 241.519612 -366.137108)
				(end 241.557048 -366.227106)
			)
			(arc
				(start 241.557048 -366.252252)
				(mid 241.571927 -366.288173)
				(end 241.607848 -366.303052)
			)
			(arc
				(start 241.98453 -366.303052)
				(mid 242.34392 -366.451916)
				(end 242.492784 -366.811306)
			)
			(arc
				(start 242.492784 -366.811814)
				(mid 242.440728 -367.035626)
				(end 242.295426 -367.213642)
			)
			(xy 242.282726 -367.223548) (xy 242.273328 -367.25479)
			(arc
				(start 242.30965 -367.361216)
				(mid 242.328169 -367.38603)
				(end 242.357656 -367.395506)
			)
			(arc
				(start 245.30177 -367.395506)
				(mid 245.321293 -367.399407)
				(end 245.337838 -367.410492)
			)
			(arc
				(start 245.384066 -367.45672)
				(mid 245.4006 -367.467831)
				(end 245.420134 -367.471706)
			)
			(arc
				(start 247.184164 -367.471706)
				(mid 247.220085 -367.456827)
				(end 247.234964 -367.420906)
			)
			(xy 247.234964 -367.034318)
			(arc
				(start 247.232678 -367.026952)
				(mid 247.215379 -366.952136)
				(end 247.209564 -366.875568)
			)
			(arc
				(start 247.209564 -366.875568)
				(mid 247.2154 -366.799003)
				(end 247.232678 -366.724184)
			)
			(xy 247.234964 -366.716818)
			(arc
				(start 247.234964 -366.291368)
				(mid 247.27231 -366.201206)
				(end 247.362472 -366.16386)
			)
			(arc
				(start 248.073672 -366.16386)
				(mid 248.163834 -366.201206)
				(end 248.20118 -366.291368)
			)
			(arc
				(start 248.20118 -366.31626)
				(mid 248.216059 -366.352181)
				(end 248.25198 -366.36706)
			)
			(arc
				(start 248.649236 -366.36706)
				(mid 249.008805 -366.515999)
				(end 249.157744 -366.875568)
			)
			(arc
				(start 249.157744 -366.875568)
				(mid 249.101985 -367.107083)
				(end 248.946924 -367.28781)
			)
			(xy 248.933462 -367.297462) (xy 248.923302 -367.328704)
			(arc
				(start 248.957846 -367.4364)
				(mid 248.976322 -367.462032)
				(end 249.00636 -367.471706)
			)
			(arc
				(start 253.042928 -367.471706)
				(mid 253.078849 -367.456827)
				(end 253.093728 -367.420906)
			)
			(xy 253.093728 -367.034318)
			(arc
				(start 253.091442 -367.026952)
				(mid 253.074143 -366.952136)
				(end 253.068328 -366.875568)
			)
			(arc
				(start 253.068328 -366.875568)
				(mid 253.074164 -366.799003)
				(end 253.091442 -366.724184)
			)
			(xy 253.093728 -366.716818)
			(arc
				(start 253.093728 -366.291368)
				(mid 253.131074 -366.201206)
				(end 253.221236 -366.16386)
			)
			(arc
				(start 253.932436 -366.16386)
				(mid 254.022598 -366.201206)
				(end 254.059944 -366.291368)
			)
			(arc
				(start 254.059944 -366.31626)
				(mid 254.074823 -366.352181)
				(end 254.110744 -366.36706)
			)
			(arc
				(start 254.557276 -366.36706)
				(mid 254.916845 -366.515999)
				(end 255.065784 -366.875568)
			)
			(arc
				(start 255.065784 -366.875568)
				(mid 255.010025 -367.107083)
				(end 254.854964 -367.28781)
			)
			(xy 254.841502 -367.297462) (xy 254.831342 -367.328704)
			(arc
				(start 254.865886 -367.4364)
				(mid 254.884362 -367.462032)
				(end 254.9144 -367.471706)
			)
			(arc
				(start 258.893056 -367.471706)
				(mid 258.928977 -367.456827)
				(end 258.943856 -367.420906)
			)
			(xy 258.943856 -367.059718)
			(arc
				(start 258.94157 -367.052352)
				(mid 258.924271 -366.977536)
				(end 258.918456 -366.900968)
			)
			(arc
				(start 258.918456 -366.900968)
				(mid 258.924292 -366.824403)
				(end 258.94157 -366.749584)
			)
			(xy 258.943856 -366.742218)
			(arc
				(start 258.943856 -366.316768)
				(mid 258.981202 -366.226606)
				(end 259.071364 -366.18926)
			)
			(arc
				(start 259.782564 -366.18926)
				(mid 259.872726 -366.226606)
				(end 259.910072 -366.316768)
			)
			(arc
				(start 259.910072 -366.34166)
				(mid 259.924951 -366.377581)
				(end 259.960872 -366.39246)
			)
			(arc
				(start 260.50621 -366.39246)
				(mid 260.86551 -366.541234)
				(end 261.014464 -366.90046)
			)
			(arc
				(start 261.014464 -366.900968)
				(mid 260.966335 -367.116856)
				(end 260.831076 -367.291874)
			)
			(arc
				(start 260.831076 -367.291874)
				(mid 260.814502 -367.317662)
				(end 260.815836 -367.348262)
			)
			(arc
				(start 260.848094 -367.438178)
				(mid 260.866678 -367.462473)
				(end 260.895846 -367.471706)
			)
			(arc
				(start 264.246106 -367.471706)
				(mid 264.265629 -367.467805)
				(end 264.282174 -367.45672)
			)
			(arc
				(start 264.31113 -367.427764)
				(mid 264.322241 -367.41123)
				(end 264.326116 -367.391696)
			)
			(arc
				(start 264.326116 -366.365282)
				(mid 264.330017 -366.345759)
				(end 264.341102 -366.329214)
			)
			(arc
				(start 264.712196 -365.95812)
				(mid 264.72873 -365.947009)
				(end 264.748264 -365.943134)
			)
			(arc
				(start 264.913872 -365.943134)
				(mid 264.933919 -365.938902)
				(end 264.950702 -365.927132)
			)
			(xy 265.008868 -365.865664) (xy 265.015726 -365.84636) (xy 265.015218 -365.835692)
			(arc
				(start 265.01471 -365.814102)
				(mid 265.126451 -365.544335)
				(end 265.396218 -365.432594)
			)
			(arc
				(start 265.396726 -365.432594)
				(mid 265.504651 -365.448253)
				(end 265.603736 -365.493808)
			)
			(arc
				(start 265.603736 -365.493808)
				(mid 265.63666 -365.501732)
				(end 265.667236 -365.487204)
			)
			(arc
				(start 266.336272 -364.818168)
				(mid 266.347383 -364.801634)
				(end 266.351258 -364.7821)
			)
			(arc
				(start 266.351258 -362.182156)
				(mid 266.347377 -362.162935)
				(end 266.336526 -362.146596)
			)
			(arc
				(start 266.329668 -362.139484)
				(mid 266.318791 -362.123156)
				(end 266.314936 -362.103924)
			)
			(arc
				(start 266.314936 -357.728012)
				(mid 266.311035 -357.708489)
				(end 266.29995 -357.691944)
			)
			(arc
				(start 264.697718 -356.089712)
				(mid 264.681184 -356.078601)
				(end 264.66165 -356.074726)
			)
			(arc
				(start 254.156718 -356.074726)
				(mid 254.137195 -356.078627)
				(end 254.12065 -356.089712)
			)
			(xy 253.011178 -357.199184) (xy 252.99797 -357.199184)
			(arc
				(start 249.888756 -360.308398)
				(mid 249.872222 -360.319509)
				(end 249.852688 -360.323384)
			)
			(arc
				(start 241.683794 -360.323384)
				(mid 241.664271 -360.319483)
				(end 241.647726 -360.308398)
			)
			(arc
				(start 239.182656 -357.843328)
				(mid 239.166122 -357.832217)
				(end 239.146588 -357.828342)
			)
			(arc
				(start 208.527142 -357.828342)
				(mid 208.507619 -357.832243)
				(end 208.491074 -357.843328)
			)
			(arc
				(start 206.747618 -359.586784)
				(mid 206.736507 -359.603318)
				(end 206.732632 -359.622852)
			)
			(arc
				(start 206.732632 -362.383832)
				(mid 206.728731 -362.403355)
				(end 206.717646 -362.4199)
			)
			(xy 206.57312 -362.564426)
			(arc
				(start 206.569818 -362.567982)
				(mid 206.544127 -362.596393)
				(end 206.515716 -362.622084)
			)
			(xy 206.513684 -362.623862)
			(arc
				(start 205.236572 -363.900974)
				(mid 205.225461 -363.917508)
				(end 205.221586 -363.937042)
			)
			(arc
				(start 205.221586 -366.079278)
				(mid 205.217685 -366.098801)
				(end 205.2066 -366.115346)
			)
			(xy 205.006956 -366.31499) (xy 204.802994 -366.518952) (xy 204.802994 -366.909604) (xy 204.833728 -366.940338)
			(xy 205.223618 -366.940338)
			(arc
				(start 208.17586 -366.940338)
				(mid 208.195383 -366.944239)
				(end 208.211928 -366.955324)
			)
			(arc
				(start 208.345278 -367.088674)
				(mid 208.356389 -367.105208)
				(end 208.360264 -367.124742)
			)
			(arc
				(start 208.360264 -367.903252)
				(mid 208.364165 -367.922775)
				(end 208.37525 -367.93932)
			)
			(xy 208.37779 -367.94186) (xy 208.396332 -367.94948)
		)
		(stroke
			(width 0)
			(type solid)
		)
		(fill yes)
		(layer "F.Cu")
		(net "P12V_AUX")
	)
	(gr_poly
		(pts
			(arc
				(start 331.993494 -215.396318)
				(mid 332.008149 -215.391566)
				(end 332.020672 -215.382602)
			)
			(arc
				(start 332.151482 -215.251792)
				(mid 332.162593 -215.235258)
				(end 332.166468 -215.215724)
			)
			(arc
				(start 332.166468 -214.946992)
				(mid 332.162567 -214.927469)
				(end 332.151482 -214.910924)
			)
			(xy 332.017624 -214.777066) (xy 331.900784 -214.660226)
			(arc
				(start 331.097382 -213.85657)
				(mid 331.067561 -213.823071)
				(end 331.04201 -213.786212)
			)
			(arc
				(start 331.04201 -213.786212)
				(mid 331.025594 -213.755916)
				(end 331.012038 -213.724236)
			)
			(arc
				(start 331.009244 -213.716362)
				(mid 330.993687 -213.656151)
				(end 330.988416 -213.594188)
			)
			(arc
				(start 330.988416 -210.185)
				(mid 330.984515 -210.165477)
				(end 330.97343 -210.148932)
			)
			(xy 330.640944 -209.816446) (xy 330.636626 -209.812636) (xy 330.630022 -209.807302)
			(arc
				(start 330.62799 -209.806032)
				(mid 330.564519 -209.75453)
				(end 330.513436 -209.690716)
			)
			(xy 330.510388 -209.68589) (xy 330.402438 -209.57794)
			(arc
				(start 329.660504 -208.835752)
				(mid 329.580067 -208.71537)
				(end 329.551792 -208.57337)
			)
			(xy 329.551792 -208.12379) (xy 329.550522 -208.11871) (xy 329.549506 -208.113122)
			(arc
				(start 329.549506 -208.112868)
				(mid 329.54664 -208.092255)
				(end 329.545696 -208.071466)
			)
			(xy 329.545696 -207.833468) (xy 329.57516 -207.804004) (xy 329.576684 -207.804004) (xy 329.590654 -207.77581)
			(arc
				(start 329.599036 -207.760062)
				(mid 329.603965 -207.748044)
				(end 329.60564 -207.73517)
			)
			(arc
				(start 329.60564 -207.347566)
				(mid 329.603918 -207.334704)
				(end 329.599036 -207.322674)
			)
			(xy 329.593956 -207.313276) (xy 329.593702 -207.313022) (xy 329.590654 -207.30718) (xy 329.587606 -207.301084)
			(xy 329.575668 -207.287622) (xy 329.55611 -207.278732) (xy 329.545696 -207.278732)
			(arc
				(start 329.545696 -207.01127)
				(mid 329.612447 -206.850884)
				(end 329.77328 -206.78521)
			)
			(xy 329.77328 -206.785464) (xy 329.816968 -206.785464) (xy 329.823572 -206.783432) (xy 329.833732 -206.780892)
			(xy 329.833986 -206.780892) (xy 329.840844 -206.779114)
			(arc
				(start 329.846432 -206.776066)
				(mid 329.85245 -206.77215)
				(end 329.857862 -206.76743)
			)
			(arc
				(start 330.35748 -206.267812)
				(mid 330.368406 -206.251366)
				(end 330.372212 -206.231998)
			)
			(arc
				(start 330.372212 -205.986888)
				(mid 330.37285 -205.965134)
				(end 330.374752 -205.943454)
			)
			(xy 330.376276 -205.932278) (xy 330.369672 -205.911704)
			(arc
				(start 330.317348 -205.853792)
				(mid 330.300318 -205.841473)
				(end 330.279756 -205.837028)
			)
			(xy 329.619356 -205.837028)
			(arc
				(start 329.26528 -205.837028)
				(mid 329.182012 -205.806003)
				(end 329.139296 -205.728062)
			)
			(xy 329.136502 -205.709266) (xy 329.108054 -205.684628) (xy 329.04938 -205.684628)
			(arc
				(start 328.962004 -205.684628)
				(mid 328.802101 -205.657382)
				(end 328.660252 -205.57871)
			)
			(xy 328.653648 -205.573376)
			(arc
				(start 328.629772 -205.56474)
				(mid 328.621268 -205.562475)
				(end 328.6125 -205.561692)
			)
			(arc
				(start 327.731374 -205.561692)
				(mid 327.546497 -205.524918)
				(end 327.389744 -205.420214)
			)
			(arc
				(start 327.24979 -205.28026)
				(mid 327.138686 -205.107312)
				(end 327.109582 -204.903832)
			)
			(arc
				(start 327.110598 -204.893672)
				(mid 327.26615 -204.581462)
				(end 327.59142 -204.455522)
			)
			(xy 327.600056 -204.455522)
			(arc
				(start 327.610978 -204.45603)
				(mid 327.771167 -204.490326)
				(end 327.910698 -204.576172)
			)
			(xy 327.917556 -204.582268) (xy 327.951846 -204.595476) (xy 328.839068 -204.595476) (xy 328.879962 -204.597254)
			(arc
				(start 328.880216 -204.597254)
				(mid 328.964216 -204.612082)
				(end 329.0443 -204.64145)
			)
			(xy 329.05192 -204.645006) (xy 329.068684 -204.646784)
			(arc
				(start 329.137772 -204.631036)
				(mid 329.153355 -204.624658)
				(end 329.165966 -204.61351)
			)
			(xy 329.16622 -204.613256) (xy 329.17257 -204.606144) (xy 329.173078 -204.605636) (xy 329.174856 -204.603858)
			(xy 329.17511 -204.603604) (xy 329.181206 -204.597762) (xy 329.188572 -204.591158) (xy 329.196954 -204.574648)
			(xy 329.198478 -204.571092)
			(arc
				(start 329.198732 -204.571092)
				(mid 329.202618 -204.553021)
				(end 329.199748 -204.53477)
			)
			(xy 329.198478 -204.531468) (xy 329.188826 -204.51191)
			(arc
				(start 329.181206 -204.505306)
				(mid 329.149133 -204.462123)
				(end 329.137772 -204.409548)
			)
			(arc
				(start 329.137772 -203.484734)
				(mid 329.134007 -203.465543)
				(end 329.123294 -203.449174)
			)
			(xy 329.066906 -203.391262) (xy 329.048364 -203.383388)
			(arc
				(start 329.038458 -203.383388)
				(mid 328.707391 -203.23636)
				(end 328.571606 -202.900534)
			)
			(xy 328.571606 -202.5904) (xy 328.57186 -202.590146)
			(arc
				(start 328.57186 -202.265534)
				(mid 328.713285 -201.924105)
				(end 329.054714 -201.78268)
			)
			(arc
				(start 329.054714 -201.78268)
				(mid 329.175654 -201.798006)
				(end 329.288902 -201.843132)
			)
			(arc
				(start 329.288902 -201.843132)
				(mid 329.332503 -201.870364)
				(end 329.372976 -201.90206)
			)
			(xy 329.379834 -201.907902)
			(arc
				(start 329.40498 -201.917554)
				(mid 329.414087 -201.920178)
				(end 329.423522 -201.92111)
			)
			(arc
				(start 329.711558 -201.92111)
				(mid 329.715278 -201.912613)
				(end 329.7174 -201.903584)
			)
			(xy 329.73264 -201.888344)
			(arc
				(start 329.984862 -201.888344)
				(mid 330.039857 -201.895072)
				(end 330.091542 -201.915014)
			)
			(xy 330.09713 -201.918062) (xy 330.109068 -201.92111)
			(arc
				(start 330.157328 -201.92111)
				(mid 330.176851 -201.925011)
				(end 330.193396 -201.936096)
			)
			(arc
				(start 330.381102 -202.123802)
				(mid 330.392213 -202.140336)
				(end 330.396088 -202.15987)
			)
			(arc
				(start 330.396088 -202.917044)
				(mid 330.399989 -202.936567)
				(end 330.411074 -202.953112)
			)
			(arc
				(start 330.942696 -203.484734)
				(mid 330.953807 -203.501268)
				(end 330.957682 -203.520802)
			)
			(arc
				(start 330.957682 -204.513942)
				(mid 330.961583 -204.533465)
				(end 330.972668 -204.55001)
			)
			(arc
				(start 330.973684 -204.551026)
				(mid 330.990218 -204.562137)
				(end 331.009752 -204.566012)
			)
			(arc
				(start 332.184248 -204.566012)
				(mid 332.27441 -204.603358)
				(end 332.311756 -204.69352)
			)
			(arc
				(start 332.311756 -205.70952)
				(mid 332.27441 -205.799682)
				(end 332.184248 -205.837028)
			)
			(xy 331.430376 -205.837028) (xy 331.416406 -205.83906)
			(arc
				(start 331.12964 -206.125826)
				(mid 331.118714 -206.142272)
				(end 331.114908 -206.16164)
			)
			(xy 331.114908 -206.31912)
			(arc
				(start 331.116178 -206.324454)
				(mid 331.122852 -206.365361)
				(end 331.125068 -206.40675)
			)
			(arc
				(start 331.125068 -206.40675)
				(mid 331.07803 -206.590267)
				(end 330.948538 -206.728568)
			)
			(xy 330.943712 -206.731616) (xy 330.858368 -206.81696) (xy 330.271374 -207.4037) (xy 330.258166 -207.4164)
			(xy 330.257912 -207.416654)
			(arc
				(start 330.256896 -207.41767)
				(mid 330.244491 -207.434683)
				(end 330.240132 -207.455262)
			)
			(arc
				(start 330.240132 -207.73517)
				(mid 330.241854 -207.748032)
				(end 330.246736 -207.760062)
			)
			(xy 330.251816 -207.76946) (xy 330.25207 -207.769714) (xy 330.255118 -207.775556) (xy 330.258166 -207.781652)
			(xy 330.270104 -207.795114) (xy 330.289662 -207.804004) (xy 330.300076 -207.804004)
			(arc
				(start 330.300076 -208.071466)
				(mid 330.299118 -208.092254)
				(end 330.296266 -208.112868)
			)
			(xy 330.296266 -208.113122) (xy 330.29525 -208.11871) (xy 330.29398 -208.12379)
			(arc
				(start 330.29398 -208.398618)
				(mid 330.29793 -208.418005)
				(end 330.308966 -208.434432)
			)
			(xy 331.031596 -209.157062)
			(arc
				(start 331.040232 -209.16392)
				(mid 331.105053 -209.215939)
				(end 331.157072 -209.28076)
			)
			(xy 331.16393 -209.289396) (xy 331.218794 -209.34426) (xy 331.269848 -209.395568) (xy 331.270102 -209.395568)
			(arc
				(start 331.622146 -209.747866)
				(mid 331.651967 -209.781365)
				(end 331.677518 -209.818224)
			)
			(arc
				(start 331.677518 -209.818224)
				(mid 331.693934 -209.84852)
				(end 331.70749 -209.8802)
			)
			(arc
				(start 331.710284 -209.888074)
				(mid 331.725841 -209.948285)
				(end 331.731112 -210.010248)
			)
			(arc
				(start 331.731112 -213.419436)
				(mid 331.734877 -213.438627)
				(end 331.74559 -213.454996)
			)
			(xy 331.745844 -213.45525) (xy 332.127352 -213.836758)
			(arc
				(start 332.12786 -213.837266)
				(mid 332.144217 -213.848008)
				(end 332.16342 -213.851744)
			)
			(xy 332.610206 -213.851744) (xy 332.63586 -213.833964)
			(arc
				(start 332.641448 -213.818978)
				(mid 332.672345 -213.756047)
				(end 332.7146 -213.700106)
			)
			(arc
				(start 332.7146 -213.700106)
				(mid 332.724451 -213.684204)
				(end 332.727808 -213.665816)
			)
			(xy 332.727808 -213.041484) (xy 332.720442 -213.034118)
			(arc
				(start 332.720442 -211.848192)
				(mid 332.714931 -211.824924)
				(end 332.69936 -211.80679)
			)
			(arc
				(start 332.69936 -211.80679)
				(mid 332.586328 -211.675627)
				(end 332.54569 -211.507324)
			)
			(arc
				(start 332.54569 -211.507324)
				(mid 332.574645 -211.36413)
				(end 332.656942 -211.243418)
			)
			(xy 332.664308 -211.236052) (xy 332.672182 -211.21751) (xy 332.672182 -211.162138) (xy 332.664308 -211.143596)
			(arc
				(start 332.656942 -211.13623)
				(mid 332.545665 -210.872324)
				(end 332.656942 -210.608418)
			)
			(xy 332.664308 -210.601052) (xy 332.672182 -210.58251) (xy 332.672182 -210.527138) (xy 332.664308 -210.508596)
			(arc
				(start 332.656942 -210.50123)
				(mid 332.574621 -210.380528)
				(end 332.54569 -210.237324)
			)
			(arc
				(start 332.54569 -210.237324)
				(mid 332.586356 -210.069035)
				(end 332.69936 -209.937858)
			)
			(arc
				(start 332.69936 -209.937858)
				(mid 332.714892 -209.919704)
				(end 332.720442 -209.896456)
			)
			(xy 332.720442 -209.397092) (xy 332.717648 -209.385662) (xy 332.714854 -209.380074) (xy 332.702408 -209.35569)
			(xy 332.695296 -209.347054) (xy 332.690724 -209.343498) (xy 332.69047 -209.343244)
			(arc
				(start 332.68793 -209.341212)
				(mid 332.579016 -209.207618)
				(end 332.540102 -209.039714)
			)
			(arc
				(start 332.540102 -209.039714)
				(mid 332.564375 -208.905852)
				(end 332.634082 -208.789016)
			)
			(xy 332.640178 -208.781904) (xy 332.646528 -208.76514) (xy 332.646528 -208.679288) (xy 332.640178 -208.662524)
			(arc
				(start 332.634082 -208.655412)
				(mid 332.540074 -208.404714)
				(end 332.634082 -208.154016)
			)
			(xy 332.640178 -208.146904) (xy 332.646528 -208.13014) (xy 332.646528 -208.044288) (xy 332.640178 -208.027524)
			(arc
				(start 332.634082 -208.020412)
				(mid 332.564349 -207.903586)
				(end 332.540102 -207.769714)
			)
			(arc
				(start 332.540102 -207.76184)
				(mid 332.581397 -207.596656)
				(end 332.69047 -207.46593)
			)
			(xy 332.695296 -207.462374) (xy 332.702408 -207.453738)
			(arc
				(start 332.714854 -207.4291)
				(mid 332.718979 -207.417997)
				(end 332.720442 -207.40624)
			)
			(xy 332.720442 -201.696574) (xy 332.712822 -201.677778) (xy 332.705456 -201.670666)
			(arc
				(start 332.407768 -201.372978)
				(mid 332.391234 -201.361867)
				(end 332.3717 -201.357992)
			)
			(xy 326.59193 -201.357992) (xy 326.573134 -201.365612) (xy 326.566022 -201.372978)
			(arc
				(start 326.386952 -201.552048)
				(mid 326.375841 -201.568582)
				(end 326.371966 -201.588116)
			)
			(arc
				(start 326.371966 -206.971392)
				(mid 326.375867 -206.990915)
				(end 326.386952 -207.00746)
			)
			(arc
				(start 326.865996 -207.486504)
				(mid 326.88253 -207.497615)
				(end 326.902064 -207.50149)
			)
			(arc
				(start 328.051668 -207.50149)
				(mid 328.071191 -207.505391)
				(end 328.087736 -207.516476)
			)
			(arc
				(start 328.45883 -207.88757)
				(mid 328.469941 -207.904104)
				(end 328.473816 -207.923638)
			)
			(xy 328.473816 -208.8261) (xy 328.495152 -208.853532)
			(arc
				(start 328.512424 -208.85785)
				(mid 328.59327 -208.889865)
				(end 328.662538 -208.942432)
			)
			(xy 328.92873 -209.208624)
			(arc
				(start 329.325732 -209.605626)
				(mid 329.365489 -209.654171)
				(end 329.395074 -209.709512)
			)
			(arc
				(start 329.51547 -209.99958)
				(mid 329.527518 -210.017151)
				(end 329.545696 -210.028282)
			)
			(arc
				(start 329.545696 -210.028282)
				(mid 329.766139 -210.178528)
				(end 329.880214 -210.419696)
			)
			(xy 329.880468 -210.42122)
			(arc
				(start 329.880976 -210.423252)
				(mid 329.886093 -210.436095)
				(end 329.894438 -210.447128)
			)
			(arc
				(start 329.904598 -210.457288)
				(mid 329.915709 -210.473822)
				(end 329.919584 -210.493356)
			)
			(arc
				(start 329.919584 -211.13115)
				(mid 329.921673 -211.145568)
				(end 329.927712 -211.158836)
			)
			(arc
				(start 329.927712 -211.158836)
				(mid 329.988924 -211.3661)
				(end 329.927712 -211.573364)
			)
			(arc
				(start 329.927712 -211.573364)
				(mid 329.921609 -211.586613)
				(end 329.919584 -211.60105)
			)
			(arc
				(start 329.919584 -213.720934)
				(mid 329.923485 -213.740457)
				(end 329.93457 -213.757002)
			)
			(arc
				(start 331.559662 -215.382094)
				(mid 331.576196 -215.393205)
				(end 331.59573 -215.39708)
			)
			(xy 331.985112 -215.39708)
		)
		(stroke
			(width 0)
			(type solid)
		)
		(fill yes)
		(layer "F.Cu")
		(net "GND")
	)
	(gr_poly
		(pts
			(xy 240.087912 -254.10795) (xy 240.097494 -254.107563) (xy 240.115334 -254.100568) (xy 240.129367 -254.08752)
			(xy 240.13764 -254.070235) (xy 240.138712 -254.060706) (xy 240.138712 -253.653036) (xy 241.590068 -253.653036)
			(xy 241.590068 -254.060706) (xy 241.591189 -254.070218) (xy 241.599494 -254.087461) (xy 241.613505 -254.100499)
			(xy 241.6313 -254.107545) (xy 241.640868 -254.10795) (xy 241.835432 -254.10795) (xy 241.845011 -254.107559)
			(xy 241.862845 -254.100561) (xy 241.876872 -254.087513) (xy 241.885141 -254.070231) (xy 241.886232 -254.060706)
			(xy 241.886232 -253.665228) (xy 243.337588 -253.665228) (xy 243.337588 -254.060706) (xy 243.33871 -254.070216)
			(xy 243.347016 -254.087456) (xy 243.361027 -254.100489) (xy 243.378822 -254.107528) (xy 243.388388 -254.10795)
			(xy 244.848888 -254.10795) (xy 244.858112 -254.107535) (xy 244.875353 -254.100964) (xy 244.889144 -254.088708)
			(xy 244.897694 -254.072359) (xy 244.89918 -254.063246) (xy 244.89918 -253.677928) (xy 246.351044 -253.677928)
			(xy 246.351044 -254.063246) (xy 246.352501 -254.072378) (xy 246.361015 -254.088775) (xy 246.374819 -254.101055)
			(xy 246.392097 -254.107601) (xy 246.401336 -254.10795) (xy 247.577102 -254.10795) (xy 247.577864 -254.107188)
			(xy 247.922288 -254.107188) (xy 247.931875 -254.106805) (xy 247.949729 -254.099817) (xy 247.963778 -254.08677)
			(xy 247.972067 -254.069482) (xy 247.973088 -254.059944) (xy 247.973088 -253.861824) (xy 248.99874 -253.861824)
			(xy 249.007777 -253.860807) (xy 249.024299 -253.853244) (xy 249.030998 -253.847092) (xy 249.034554 -253.843536)
			(xy 249.042174 -253.824994) (xy 249.042174 -252.96495) (xy 249.041741 -252.954884) (xy 249.034011 -252.936296)
			(xy 249.027188 -252.928882) (xy 248.130822 -252.032516) (xy 248.12342 -252.02568) (xy 248.104822 -252.017972)
			(xy 248.094754 -252.01753) (xy 246.036338 -252.01753) (xy 246.026273 -252.017965) (xy 246.007688 -252.025699)
			(xy 246.00027 -252.032516) (xy 245.641114 -252.391672) (xy 245.633712 -252.398508) (xy 245.615114 -252.406216)
			(xy 245.605046 -252.406658) (xy 239.420908 -252.406658) (xy 239.410838 -252.406235) (xy 239.392236 -252.398518)
			(xy 239.38484 -252.391672) (xy 238.838486 -251.845318) (xy 238.831087 -251.838472) (xy 238.812489 -251.83074)
			(xy 238.802418 -251.830332) (xy 238.164878 -251.830332) (xy 238.154809 -251.829906) (xy 238.136207 -251.822189)
			(xy 238.12881 -251.815346) (xy 235.41355 -249.100086) (xy 235.406153 -249.093238) (xy 235.387554 -249.085508)
			(xy 235.377482 -249.0851) (xy 215.904572 -249.0851) (xy 215.894504 -249.085528) (xy 215.875907 -249.09325)
			(xy 215.868504 -249.100086) (xy 215.865964 -249.102372) (xy 215.865964 -250.777756) (xy 215.866493 -250.787748)
			(xy 215.874191 -250.806195) (xy 215.88095 -250.81357) (xy 215.885014 -250.817634) (xy 215.89241 -250.824485)
			(xy 215.911009 -250.832225) (xy 215.921082 -250.83262) (xy 220.287088 -250.83262) (xy 220.723968 -250.83262)
			(xy 220.723968 -251.445522) (xy 220.729048 -251.460508) (xy 220.734382 -251.467366) (xy 220.742506 -251.478585)
			(xy 220.754179 -251.503699) (xy 220.76018 -251.530735) (xy 220.760544 -251.544582) (xy 220.760544 -252.498149)
			(xy 221.153498 -252.498149) (xy 221.153498 -252.443651) (xy 221.161254 -252.389708) (xy 221.176607 -252.337417)
			(xy 221.199246 -252.287844) (xy 221.228709 -252.241997) (xy 221.264397 -252.200809) (xy 221.305582 -252.16512)
			(xy 221.351428 -252.135654) (xy 221.401 -252.113013) (xy 221.45329 -252.097658) (xy 221.507233 -252.089899)
			(xy 221.534482 -252.089412) (xy 221.560355 -252.089843) (xy 221.611628 -252.096824) (xy 221.661487 -252.110673)
			(xy 221.709014 -252.131137) (xy 221.753339 -252.157838) (xy 221.793646 -252.190288) (xy 221.829195 -252.22789)
			(xy 221.844616 -252.24867) (xy 221.853584 -252.260214) (xy 221.876666 -252.278124) (xy 221.903874 -252.288768)
			(xy 221.932982 -252.291274) (xy 221.961609 -252.285438) (xy 221.987412 -252.271736) (xy 222.008282 -252.251291)
			(xy 222.015812 -252.238764) (xy 222.03042 -252.213713) (xy 222.065944 -252.167882) (xy 222.107994 -252.127955)
			(xy 222.155602 -252.094851) (xy 222.207671 -252.069333) (xy 222.263002 -252.051988) (xy 222.320321 -252.043215)
			(xy 222.349314 -252.042676) (xy 222.376563 -252.043195) (xy 222.430507 -252.050953) (xy 222.482798 -252.066309)
			(xy 222.532371 -252.08895) (xy 222.578218 -252.118415) (xy 222.619405 -252.154105) (xy 222.655093 -252.195293)
			(xy 222.684557 -252.241141) (xy 222.707196 -252.290715) (xy 222.72255 -252.343006) (xy 222.730306 -252.396951)
			(xy 222.730306 -252.451449) (xy 222.726046 -252.48108) (xy 222.877886 -252.48108) (xy 222.881957 -252.425458)
			(xy 222.894083 -252.371021) (xy 222.914006 -252.31893) (xy 222.941302 -252.270295) (xy 222.975388 -252.226152)
			(xy 223.015537 -252.187443) (xy 223.060895 -252.154992) (xy 223.110495 -252.129491) (xy 223.163279 -252.111484)
			(xy 223.218122 -252.101354) (xy 223.273856 -252.099317) (xy 223.329293 -252.105417) (xy 223.38325 -252.119523)
			(xy 223.434579 -252.141335) (xy 223.482185 -252.170389) (xy 223.525053 -252.206064) (xy 223.56227 -252.247601)
			(xy 223.593043 -252.294114) (xy 223.616715 -252.344611) (xy 223.632783 -252.398018) (xy 223.640903 -252.453194)
			(xy 223.641412 -252.48108) (xy 223.640903 -252.508966) (xy 223.632783 -252.564142) (xy 223.616715 -252.617549)
			(xy 223.601337 -252.650354) (xy 225.272544 -252.650354) (xy 225.272544 -252.595846) (xy 225.280301 -252.541894)
			(xy 225.295658 -252.489594) (xy 225.318301 -252.440013) (xy 225.34777 -252.394158) (xy 225.383464 -252.352964)
			(xy 225.424658 -252.31727) (xy 225.470513 -252.287801) (xy 225.520094 -252.265158) (xy 225.572394 -252.249801)
			(xy 225.626346 -252.242044) (xy 225.6536 -252.241558) (xy 225.679652 -252.242015) (xy 225.731268 -252.249135)
			(xy 225.781435 -252.263215) (xy 225.829218 -252.283992) (xy 225.873728 -252.31108) (xy 225.914136 -252.343975)
			(xy 225.932238 -252.362716) (xy 225.940366 -252.371098) (xy 225.961194 -252.37948) (xy 226.063302 -252.372368)
			(xy 226.08286 -252.361446) (xy 226.089464 -252.351794) (xy 226.104875 -252.330781) (xy 226.140473 -252.292725)
			(xy 226.180917 -252.259867) (xy 226.225456 -252.232816) (xy 226.27326 -252.212076) (xy 226.323442 -252.198032)
			(xy 226.375067 -252.190946) (xy 226.401122 -252.190504) (xy 226.429609 -252.191017) (xy 226.48595 -252.199493)
			(xy 226.540404 -252.216253) (xy 226.591759 -252.240926) (xy 226.638875 -252.272961) (xy 226.680702 -252.311647)
			(xy 226.716311 -252.356123) (xy 226.731068 -252.380496) (xy 226.73818 -252.392688) (xy 226.761802 -252.405896)
			(xy 226.878388 -252.404372) (xy 226.901502 -252.390148) (xy 226.90836 -252.377956) (xy 226.922769 -252.352467)
			(xy 226.958216 -252.305866) (xy 227.000368 -252.265228) (xy 227.048233 -252.231507) (xy 227.100689 -252.205496)
			(xy 227.156503 -252.187805) (xy 227.214365 -252.17885) (xy 227.24364 -252.178312) (xy 227.271178 -252.178754)
			(xy 227.325682 -252.186667) (xy 227.378481 -252.202336) (xy 227.428477 -252.225436) (xy 227.474632 -252.255487)
			(xy 227.515984 -252.291864) (xy 227.551675 -252.33381) (xy 227.566728 -252.356874) (xy 227.573586 -252.367796)
			(xy 227.59543 -252.380242) (xy 227.705666 -252.383036) (xy 227.728272 -252.37186) (xy 227.735638 -252.361192)
			(xy 227.751029 -252.340117) (xy 227.78662 -252.30195) (xy 227.827081 -252.26899) (xy 227.871655 -252.241851)
			(xy 227.919512 -252.221038) (xy 227.969758 -252.206942) (xy 228.021457 -252.199823) (xy 228.04755 -252.199394)
			(xy 228.074805 -252.19985) (xy 228.128762 -252.207601) (xy 228.181066 -252.222953) (xy 228.230653 -252.245593)
			(xy 228.276512 -252.27506) (xy 228.317711 -252.310753) (xy 228.35341 -252.351948) (xy 228.382883 -252.397803)
			(xy 228.40553 -252.447387) (xy 228.420888 -252.499689) (xy 228.424348 -252.523752) (xy 230.546146 -252.523752)
			(xy 230.550217 -252.46813) (xy 230.562343 -252.413693) (xy 230.582266 -252.361602) (xy 230.609562 -252.312967)
			(xy 230.643648 -252.268824) (xy 230.683797 -252.230115) (xy 230.729155 -252.197664) (xy 230.778755 -252.172163)
			(xy 230.831539 -252.154156) (xy 230.886382 -252.144026) (xy 230.942116 -252.141989) (xy 230.997553 -252.148089)
			(xy 231.05151 -252.162195) (xy 231.102839 -252.184007) (xy 231.150445 -252.213061) (xy 231.193313 -252.248736)
			(xy 231.23053 -252.290273) (xy 231.261303 -252.336786) (xy 231.284975 -252.387283) (xy 231.301043 -252.44069)
			(xy 231.309163 -252.495866) (xy 231.309672 -252.523752) (xy 231.309163 -252.551638) (xy 231.307211 -252.5649)
			(xy 231.441242 -252.5649) (xy 231.445313 -252.509278) (xy 231.457439 -252.454841) (xy 231.477362 -252.40275)
			(xy 231.504658 -252.354115) (xy 231.538744 -252.309972) (xy 231.578893 -252.271263) (xy 231.624251 -252.238812)
			(xy 231.673851 -252.213311) (xy 231.726635 -252.195304) (xy 231.781478 -252.185174) (xy 231.837212 -252.183137)
			(xy 231.892649 -252.189237) (xy 231.946606 -252.203343) (xy 231.997935 -252.225155) (xy 232.045541 -252.254209)
			(xy 232.088409 -252.289884) (xy 232.125626 -252.331421) (xy 232.156399 -252.377934) (xy 232.180071 -252.428431)
			(xy 232.196139 -252.481838) (xy 232.204259 -252.537014) (xy 232.204768 -252.5649) (xy 232.204513 -252.57887)
			(xy 232.51871 -252.57887) (xy 232.522781 -252.523248) (xy 232.534907 -252.468811) (xy 232.55483 -252.41672)
			(xy 232.582126 -252.368085) (xy 232.616212 -252.323942) (xy 232.656361 -252.285233) (xy 232.701719 -252.252782)
			(xy 232.751319 -252.227281) (xy 232.804103 -252.209274) (xy 232.858946 -252.199144) (xy 232.91468 -252.197107)
			(xy 232.970117 -252.203207) (xy 233.024074 -252.217313) (xy 233.075403 -252.239125) (xy 233.123009 -252.268179)
			(xy 233.165877 -252.303854) (xy 233.203094 -252.345391) (xy 233.233867 -252.391904) (xy 233.257539 -252.442401)
			(xy 233.273607 -252.495808) (xy 233.281727 -252.550984) (xy 233.281847 -252.557534) (xy 234.556806 -252.557534)
			(xy 234.560877 -252.501912) (xy 234.573003 -252.447475) (xy 234.592926 -252.395384) (xy 234.620222 -252.346749)
			(xy 234.654308 -252.302606) (xy 234.694457 -252.263897) (xy 234.739815 -252.231446) (xy 234.789415 -252.205945)
			(xy 234.842199 -252.187938) (xy 234.897042 -252.177808) (xy 234.952776 -252.175771) (xy 235.008213 -252.181871)
			(xy 235.06217 -252.195977) (xy 235.113499 -252.217789) (xy 235.161105 -252.246843) (xy 235.203973 -252.282518)
			(xy 235.24119 -252.324055) (xy 235.271963 -252.370568) (xy 235.295635 -252.421065) (xy 235.311703 -252.474472)
			(xy 235.319823 -252.529648) (xy 235.320332 -252.557534) (xy 235.319823 -252.58542) (xy 235.311703 -252.640596)
			(xy 235.295635 -252.694003) (xy 235.271963 -252.7445) (xy 235.24119 -252.791013) (xy 235.203973 -252.83255)
			(xy 235.161105 -252.868225) (xy 235.113499 -252.897279) (xy 235.06217 -252.919091) (xy 235.008213 -252.933197)
			(xy 234.952776 -252.939297) (xy 234.897042 -252.93726) (xy 234.842199 -252.92713) (xy 234.789415 -252.909123)
			(xy 234.739815 -252.883622) (xy 234.694457 -252.851171) (xy 234.654308 -252.812462) (xy 234.620222 -252.768319)
			(xy 234.592926 -252.719684) (xy 234.573003 -252.667593) (xy 234.560877 -252.613156) (xy 234.556806 -252.557534)
			(xy 233.281847 -252.557534) (xy 233.282236 -252.57887) (xy 233.281727 -252.606756) (xy 233.273607 -252.661932)
			(xy 233.257539 -252.715339) (xy 233.233867 -252.765836) (xy 233.203094 -252.812349) (xy 233.165877 -252.853886)
			(xy 233.123009 -252.889561) (xy 233.075403 -252.918615) (xy 233.024074 -252.940427) (xy 232.970117 -252.954533)
			(xy 232.91468 -252.960633) (xy 232.858946 -252.958596) (xy 232.804103 -252.948466) (xy 232.751319 -252.930459)
			(xy 232.701719 -252.904958) (xy 232.656361 -252.872507) (xy 232.616212 -252.833798) (xy 232.582126 -252.789655)
			(xy 232.55483 -252.74102) (xy 232.534907 -252.688929) (xy 232.522781 -252.634492) (xy 232.51871 -252.57887)
			(xy 232.204513 -252.57887) (xy 232.204259 -252.592786) (xy 232.196139 -252.647962) (xy 232.180071 -252.701369)
			(xy 232.156399 -252.751866) (xy 232.125626 -252.798379) (xy 232.088409 -252.839916) (xy 232.045541 -252.875591)
			(xy 231.997935 -252.904645) (xy 231.946606 -252.926457) (xy 231.892649 -252.940563) (xy 231.837212 -252.946663)
			(xy 231.781478 -252.944626) (xy 231.726635 -252.934496) (xy 231.673851 -252.916489) (xy 231.624251 -252.890988)
			(xy 231.578893 -252.858537) (xy 231.538744 -252.819828) (xy 231.504658 -252.775685) (xy 231.477362 -252.72705)
			(xy 231.457439 -252.674959) (xy 231.445313 -252.620522) (xy 231.441242 -252.5649) (xy 231.307211 -252.5649)
			(xy 231.301043 -252.606814) (xy 231.284975 -252.660221) (xy 231.261303 -252.710718) (xy 231.23053 -252.757231)
			(xy 231.193313 -252.798768) (xy 231.150445 -252.834443) (xy 231.102839 -252.863497) (xy 231.05151 -252.885309)
			(xy 230.997553 -252.899415) (xy 230.942116 -252.905515) (xy 230.886382 -252.903478) (xy 230.831539 -252.893348)
			(xy 230.778755 -252.875341) (xy 230.729155 -252.84984) (xy 230.683797 -252.817389) (xy 230.643648 -252.77868)
			(xy 230.609562 -252.734537) (xy 230.582266 -252.685902) (xy 230.562343 -252.633811) (xy 230.550217 -252.579374)
			(xy 230.546146 -252.523752) (xy 228.424348 -252.523752) (xy 228.428646 -252.553645) (xy 228.428646 -252.608155)
			(xy 228.420888 -252.662111) (xy 228.40553 -252.714413) (xy 228.382883 -252.763997) (xy 228.35341 -252.809852)
			(xy 228.317711 -252.851047) (xy 228.276512 -252.88674) (xy 228.230653 -252.916207) (xy 228.181066 -252.938847)
			(xy 228.128762 -252.954199) (xy 228.074805 -252.96195) (xy 228.04755 -252.96241) (xy 228.020013 -252.961965)
			(xy 227.965509 -252.954052) (xy 227.912711 -252.938382) (xy 227.862714 -252.915282) (xy 227.81656 -252.885232)
			(xy 227.775207 -252.848856) (xy 227.739516 -252.806911) (xy 227.724462 -252.783848) (xy 227.717604 -252.772926)
			(xy 227.69576 -252.76048) (xy 227.585524 -252.757686) (xy 227.562918 -252.768862) (xy 227.555552 -252.77953)
			(xy 227.540174 -252.800615) (xy 227.504579 -252.83878) (xy 227.464117 -252.871739) (xy 227.41954 -252.898877)
			(xy 227.371682 -252.919687) (xy 227.321434 -252.933783) (xy 227.269734 -252.940899) (xy 227.24364 -252.941328)
			(xy 227.215152 -252.94083) (xy 227.158812 -252.932349) (xy 227.104358 -252.915584) (xy 227.053003 -252.890909)
			(xy 227.005888 -252.858872) (xy 226.964061 -252.820185) (xy 226.928451 -252.775709) (xy 226.913694 -252.751336)
			(xy 226.906582 -252.739144) (xy 226.88296 -252.725936) (xy 226.766374 -252.72746) (xy 226.74326 -252.741684)
			(xy 226.736402 -252.753876) (xy 226.721993 -252.779366) (xy 226.686549 -252.82597) (xy 226.644399 -252.866611)
			(xy 226.596533 -252.900333) (xy 226.544077 -252.926344) (xy 226.488261 -252.944033) (xy 226.430398 -252.952984)
			(xy 226.401122 -252.95352) (xy 226.37507 -252.953055) (xy 226.323454 -252.945938) (xy 226.273287 -252.93186)
			(xy 226.225504 -252.911085) (xy 226.180994 -252.883998) (xy 226.140586 -252.851103) (xy 226.122484 -252.832362)
			(xy 226.114356 -252.82398) (xy 226.093528 -252.815598) (xy 225.99142 -252.82271) (xy 225.971862 -252.833632)
			(xy 225.965258 -252.843284) (xy 225.949857 -252.864304) (xy 225.914254 -252.902356) (xy 225.873807 -252.935211)
			(xy 225.829267 -252.96226) (xy 225.781462 -252.982999) (xy 225.731281 -252.997043) (xy 225.679655 -253.004131)
			(xy 225.6536 -253.004574) (xy 225.626346 -253.004156) (xy 225.572394 -252.996399) (xy 225.520094 -252.981042)
			(xy 225.470513 -252.958399) (xy 225.424658 -252.92893) (xy 225.383464 -252.893236) (xy 225.34777 -252.852042)
			(xy 225.318301 -252.806187) (xy 225.295658 -252.756606) (xy 225.280301 -252.704306) (xy 225.272544 -252.650354)
			(xy 223.601337 -252.650354) (xy 223.593043 -252.668046) (xy 223.56227 -252.714559) (xy 223.525053 -252.756096)
			(xy 223.482185 -252.791771) (xy 223.434579 -252.820825) (xy 223.38325 -252.842637) (xy 223.329293 -252.856743)
			(xy 223.273856 -252.862843) (xy 223.218122 -252.860806) (xy 223.163279 -252.850676) (xy 223.110495 -252.832669)
			(xy 223.060895 -252.807168) (xy 223.015537 -252.774717) (xy 222.975388 -252.736008) (xy 222.941302 -252.691865)
			(xy 222.914006 -252.64323) (xy 222.894083 -252.591139) (xy 222.881957 -252.536702) (xy 222.877886 -252.48108)
			(xy 222.726046 -252.48108) (xy 222.72255 -252.505394) (xy 222.707196 -252.557685) (xy 222.684557 -252.607259)
			(xy 222.655093 -252.653107) (xy 222.619405 -252.694295) (xy 222.578218 -252.729985) (xy 222.532371 -252.75945)
			(xy 222.482798 -252.782091) (xy 222.430507 -252.797447) (xy 222.376563 -252.805205) (xy 222.349314 -252.805692)
			(xy 222.323441 -252.805262) (xy 222.272168 -252.798281) (xy 222.22231 -252.784432) (xy 222.174782 -252.763968)
			(xy 222.130457 -252.737266) (xy 222.09015 -252.704816) (xy 222.054601 -252.667214) (xy 222.03918 -252.646434)
			(xy 222.030217 -252.634886) (xy 222.007135 -252.616974) (xy 221.979925 -252.60633) (xy 221.950816 -252.603824)
			(xy 221.922188 -252.609662) (xy 221.896383 -252.623365) (xy 221.875514 -252.643812) (xy 221.867984 -252.65634)
			(xy 221.85338 -252.681394) (xy 221.817856 -252.727224) (xy 221.775805 -252.767151) (xy 221.728196 -252.800254)
			(xy 221.676126 -252.825772) (xy 221.620794 -252.843117) (xy 221.563475 -252.851889) (xy 221.534482 -252.852428)
			(xy 221.507233 -252.851901) (xy 221.45329 -252.844142) (xy 221.401 -252.828787) (xy 221.351428 -252.806146)
			(xy 221.305582 -252.77668) (xy 221.264397 -252.740991) (xy 221.228709 -252.699803) (xy 221.199246 -252.653956)
			(xy 221.176607 -252.604383) (xy 221.161254 -252.552092) (xy 221.153498 -252.498149) (xy 220.760544 -252.498149)
			(xy 220.760544 -252.560836) (xy 220.759997 -252.577528) (xy 220.751361 -252.609777) (xy 220.734685 -252.638699)
			(xy 220.711102 -252.66233) (xy 220.682213 -252.679064) (xy 220.649981 -252.687764) (xy 220.63329 -252.688344)
			(xy 220.484446 -252.688344) (xy 220.484446 -252.699266) (xy 220.253052 -252.93066) (xy 220.245653 -252.937503)
			(xy 220.227054 -252.945226) (xy 220.216984 -252.945646) (xy 219.8878 -252.945646) (xy 219.877731 -252.94607)
			(xy 219.859131 -252.95379) (xy 219.851732 -252.960632) (xy 219.58935 -253.223014) (xy 219.5825 -253.230411)
			(xy 219.574763 -253.249009) (xy 219.574364 -253.259082) (xy 219.574364 -253.938532) (xy 219.574795 -253.948598)
			(xy 219.582524 -253.967188) (xy 219.58935 -253.9746) (xy 219.679012 -254.064262) (xy 219.686409 -254.071111)
			(xy 219.705008 -254.078847) (xy 219.71508 -254.079248) (xy 220.547438 -254.079248) (xy 220.557504 -254.079679)
			(xy 220.576094 -254.087409) (xy 220.583506 -254.094234) (xy 220.585284 -254.096012) (xy 231.968294 -254.096012)
			(xy 231.986836 -254.103886) (xy 231.9909 -254.10795)
		)
		(stroke
			(width 0)
			(type solid)
		)
		(fill yes)
		(layer "F.Cu")
		(net "GND")
	)
	(gr_poly
		(pts
			(xy 442.340492 -254.636778) (xy 442.340492 -249.722132) (xy 443.234064 -248.82856) (xy 450.650864 -248.82856)
			(xy 451.187058 -248.292366) (xy 451.187058 -244.18163) (xy 451.432676 -243.936012) (xy 451.767448 -243.936012)
			(xy 451.777515 -243.935581) (xy 451.796108 -243.927855) (xy 451.803516 -243.921026) (xy 451.807834 -243.916708)
			(xy 456.889866 -243.916708) (xy 456.897737 -243.917008) (xy 456.912733 -243.9218) (xy 456.91933 -243.926106)
			(xy 456.924156 -243.929408) (xy 456.949302 -243.939822) (xy 456.953868 -243.941825) (xy 456.96219 -243.947317)
			(xy 456.965812 -243.950744) (xy 457.263754 -244.248686) (xy 457.270592 -244.256087) (xy 457.278302 -244.274686)
			(xy 457.27874 -244.284754) (xy 457.27874 -247.833896) (xy 457.279164 -247.843966) (xy 457.286881 -247.862567)
			(xy 457.293726 -247.869964) (xy 457.328016 -247.904254) (xy 457.335413 -247.911103) (xy 457.354012 -247.918839)
			(xy 457.364084 -247.91924) (xy 458.56652 -247.91924) (xy 458.576587 -247.918812) (xy 458.595181 -247.911085)
			(xy 458.602588 -247.904254) (xy 458.763116 -247.743726) (xy 458.76996 -247.736328) (xy 458.777681 -247.717728)
			(xy 458.778102 -247.707658) (xy 458.778102 -246.835422) (xy 458.77854 -246.825358) (xy 458.786274 -246.806775)
			(xy 458.793088 -246.799354) (xy 458.979016 -246.613426) (xy 458.986414 -246.606579) (xy 459.005012 -246.598847)
			(xy 459.015084 -246.59844) (xy 459.603602 -246.59844) (xy 459.613612 -246.597952) (xy 459.63211 -246.590294)
			(xy 459.646272 -246.576142) (xy 459.653945 -246.55765) (xy 459.654402 -246.54764) (xy 459.654402 -243.86794)
			(xy 459.653968 -243.857875) (xy 459.646238 -243.839286) (xy 459.639416 -243.831872) (xy 456.23988 -240.432336)
			(xy 456.232482 -240.425489) (xy 456.213884 -240.417756) (xy 456.203812 -240.41735) (xy 441.044584 -240.41735)
			(xy 438.613804 -242.84813) (xy 451.77837 -242.84813) (xy 451.7788 -242.821815) (xy 451.786044 -242.769685)
			(xy 451.800371 -242.719042) (xy 451.821511 -242.670844) (xy 451.849063 -242.626001) (xy 451.882506 -242.585362)
			(xy 451.90156 -242.567206) (xy 451.911528 -242.557354) (xy 451.92619 -242.533484) (xy 451.93381 -242.506527)
			(xy 451.933816 -242.478514) (xy 451.926206 -242.451553) (xy 451.911554 -242.427677) (xy 451.90156 -242.417854)
			(xy 451.882482 -242.399722) (xy 451.849028 -242.359086) (xy 451.821473 -242.314241) (xy 451.800339 -242.266035)
			(xy 451.786026 -242.215384) (xy 451.778806 -242.163247) (xy 451.77837 -242.13693) (xy 451.778829 -242.109658)
			(xy 451.786588 -242.05567) (xy 451.801952 -242.003335) (xy 451.824609 -241.95372) (xy 451.854096 -241.907834)
			(xy 451.889814 -241.866613) (xy 451.931036 -241.830895) (xy 451.976921 -241.801408) (xy 452.026537 -241.778752)
			(xy 452.078872 -241.763388) (xy 452.13286 -241.755629) (xy 452.160132 -241.755168) (xy 452.186446 -241.755624)
			(xy 452.238575 -241.762863) (xy 452.289217 -241.777185) (xy 452.337416 -241.798319) (xy 452.382259 -241.825867)
			(xy 452.422899 -241.859306) (xy 452.441056 -241.878358) (xy 452.450878 -241.888359) (xy 452.474756 -241.903022)
			(xy 452.501722 -241.910641) (xy 452.529742 -241.910641) (xy 452.556708 -241.903022) (xy 452.580586 -241.888359)
			(xy 452.590408 -241.878358) (xy 452.610241 -241.857594) (xy 452.65503 -241.821665) (xy 452.704692 -241.792844)
			(xy 452.758108 -241.771781) (xy 452.814075 -241.75895) (xy 452.871332 -241.754641) (xy 452.928589 -241.75895)
			(xy 452.984556 -241.771781) (xy 453.037972 -241.792844) (xy 453.087634 -241.821665) (xy 453.132423 -241.857594)
			(xy 453.152256 -241.878358) (xy 453.162078 -241.888359) (xy 453.185956 -241.903022) (xy 453.212922 -241.910641)
			(xy 453.240942 -241.910641) (xy 453.267908 -241.903022) (xy 453.291786 -241.888359) (xy 453.301608 -241.878358)
			(xy 453.319758 -241.859298) (xy 453.36039 -241.825842) (xy 453.405232 -241.798285) (xy 453.453433 -241.777148)
			(xy 453.504081 -241.762831) (xy 453.556216 -241.755607) (xy 453.582532 -241.755168) (xy 453.609804 -241.755595)
			(xy 453.663791 -241.763362) (xy 453.716123 -241.778732) (xy 453.765736 -241.801395) (xy 453.811618 -241.830887)
			(xy 453.852836 -241.866608) (xy 453.888551 -241.907832) (xy 453.918035 -241.953719) (xy 453.940689 -242.003335)
			(xy 453.956052 -242.05567) (xy 453.96381 -242.109658) (xy 453.964294 -242.13693) (xy 453.963848 -242.163245)
			(xy 453.956609 -242.215374) (xy 453.942286 -242.266017) (xy 453.92115 -242.314216) (xy 453.8936 -242.359059)
			(xy 453.860157 -242.399698) (xy 453.841104 -242.417854) (xy 453.83107 -242.427646) (xy 453.816403 -242.451532)
			(xy 453.808785 -242.478506) (xy 453.80879 -242.506535) (xy 453.816419 -242.533506) (xy 453.831096 -242.557385)
			(xy 453.841104 -242.567206) (xy 453.860156 -242.585365) (xy 453.893614 -242.625994) (xy 453.921173 -242.670834)
			(xy 453.942312 -242.719034) (xy 453.95663 -242.769681) (xy 453.963855 -242.821814) (xy 453.964294 -242.84813)
			(xy 453.963804 -242.875399) (xy 453.956039 -242.92938) (xy 453.940671 -242.981708) (xy 453.918014 -243.031316)
			(xy 453.888528 -243.077195) (xy 453.852813 -243.118412) (xy 453.811597 -243.154127) (xy 453.765718 -243.183613)
			(xy 453.71611 -243.20627) (xy 453.663782 -243.221638) (xy 453.609801 -243.229403) (xy 453.582532 -243.229892)
			(xy 453.556216 -243.229472) (xy 453.504086 -243.222228) (xy 453.453442 -243.2079) (xy 453.405243 -243.186758)
			(xy 453.360401 -243.159204) (xy 453.319763 -243.125757) (xy 453.301608 -243.106702) (xy 453.291786 -243.096701)
			(xy 453.267908 -243.082038) (xy 453.240942 -243.074419) (xy 453.212922 -243.074419) (xy 453.185956 -243.082038)
			(xy 453.162078 -243.096701) (xy 453.152256 -243.106702) (xy 453.132423 -243.127466) (xy 453.087634 -243.163395)
			(xy 453.037972 -243.192216) (xy 452.984556 -243.213279) (xy 452.928589 -243.22611) (xy 452.871332 -243.230419)
			(xy 452.814075 -243.22611) (xy 452.758108 -243.213279) (xy 452.704692 -243.192216) (xy 452.65503 -243.163395)
			(xy 452.610241 -243.127466) (xy 452.590408 -243.106702) (xy 452.580586 -243.096701) (xy 452.556708 -243.082038)
			(xy 452.529742 -243.074419) (xy 452.501722 -243.074419) (xy 452.474756 -243.082038) (xy 452.450878 -243.096701)
			(xy 452.441056 -243.106702) (xy 452.422915 -243.125772) (xy 452.382282 -243.159228) (xy 452.337439 -243.186785)
			(xy 452.289235 -243.207921) (xy 452.238585 -243.222235) (xy 452.186449 -243.229456) (xy 452.160132 -243.229892)
			(xy 452.132863 -243.229369) (xy 452.07888 -243.221612) (xy 452.02655 -243.206251) (xy 451.976939 -243.1836)
			(xy 451.931057 -243.154118) (xy 451.889837 -243.118407) (xy 451.854119 -243.077193) (xy 451.82463 -243.031315)
			(xy 451.801971 -242.981708) (xy 451.786601 -242.929381) (xy 451.778836 -242.875399) (xy 451.77837 -242.84813)
			(xy 438.613804 -242.84813) (xy 435.861714 -245.60022) (xy 435.861714 -249.945398) (xy 431.966878 -253.840234)
			(xy 423.991532 -253.840234) (xy 423.984133 -253.847077) (xy 423.965534 -253.854797) (xy 423.955464 -253.85522)
			(xy 389.499856 -253.85522) (xy 389.358886 -253.99619) (xy 377.390152 -253.99619) (xy 377.334018 -254.052324)
			(xy 377.326652 -254.059436) (xy 377.319032 -254.078232) (xy 377.319032 -255.431544) (xy 377.319464 -255.44161)
			(xy 377.327193 -255.4602) (xy 377.334018 -255.467612) (xy 377.50496 -255.638554) (xy 377.51236 -255.645396)
			(xy 377.530958 -255.653116) (xy 377.541028 -255.65354) (xy 385.485894 -255.65354) (xy 385.495964 -255.653963)
			(xy 385.514566 -255.661681) (xy 385.521962 -255.668526) (xy 386.45211 -256.598674) (xy 386.458955 -256.606072)
			(xy 386.466676 -256.624672) (xy 386.467096 -256.634742) (xy 386.467096 -262.368284) (xy 386.466657 -262.378347)
			(xy 386.458921 -262.396929) (xy 386.45211 -262.404352) (xy 385.990592 -262.86587) (xy 385.983194 -262.872718)
			(xy 385.964596 -262.880455) (xy 385.954524 -262.880856) (xy 382.30937 -262.880856) (xy 382.30429 -262.88111)
			(xy 382.295781 -262.882346) (xy 382.280244 -262.88969) (xy 382.267991 -262.901739) (xy 382.263904 -262.909304)
			(xy 382.253109 -262.935976) (xy 382.224671 -262.985994) (xy 382.196029 -263.022334) (xy 386.230874 -263.022334)
			(xy 386.234947 -262.966675) (xy 386.247082 -262.912202) (xy 386.267018 -262.860076) (xy 386.294332 -262.811408)
			(xy 386.32844 -262.767236) (xy 386.368617 -262.728501) (xy 386.414005 -262.696029) (xy 386.463637 -262.670511)
			(xy 386.516457 -262.652492) (xy 386.571336 -262.642355) (xy 386.627107 -262.640317) (xy 386.682581 -262.64642)
			(xy 386.736574 -262.660536) (xy 386.787937 -262.682363) (xy 386.835575 -262.711436) (xy 386.878471 -262.747135)
			(xy 386.915713 -262.788699) (xy 386.946507 -262.835243) (xy 386.970195 -262.885774) (xy 386.986273 -262.939216)
			(xy 386.994399 -262.99443) (xy 386.994908 -263.022334) (xy 386.994399 -263.050238) (xy 386.986273 -263.105452)
			(xy 386.970195 -263.158894) (xy 386.946507 -263.209425) (xy 386.915713 -263.255969) (xy 386.878471 -263.297533)
			(xy 386.835575 -263.333232) (xy 386.787937 -263.362305) (xy 386.736574 -263.384132) (xy 386.682581 -263.398248)
			(xy 386.627107 -263.404351) (xy 386.571336 -263.402313) (xy 386.516457 -263.392176) (xy 386.463637 -263.374157)
			(xy 386.414005 -263.348639) (xy 386.368617 -263.316167) (xy 386.32844 -263.277432) (xy 386.294332 -263.23326)
			(xy 386.267018 -263.184592) (xy 386.247082 -263.132466) (xy 386.234947 -263.077993) (xy 386.230874 -263.022334)
			(xy 382.196029 -263.022334) (xy 382.189055 -263.031182) (xy 382.147065 -263.070519) (xy 382.099652 -263.103115)
			(xy 382.047887 -263.128233) (xy 381.992941 -263.145306) (xy 381.936056 -263.153946) (xy 381.907288 -263.154414)
			(xy 381.879301 -263.153929) (xy 381.823927 -263.145763) (xy 381.77034 -263.129594) (xy 381.719691 -263.105769)
			(xy 381.673067 -263.074799) (xy 381.631468 -263.037349) (xy 381.595787 -262.994222) (xy 381.566791 -262.946345)
			(xy 381.555498 -262.920734) (xy 381.553212 -262.9154) (xy 381.546608 -262.906002) (xy 381.517144 -262.880094)
			(xy 381.509524 -262.876792) (xy 381.504961 -262.874784) (xy 381.496646 -262.869285) (xy 381.493014 -262.86587)
			(xy 381.175768 -262.548624) (xy 381.168926 -262.541225) (xy 381.161209 -262.522626) (xy 381.160782 -262.512556)
			(xy 381.160782 -260.847078) (xy 381.153162 -260.828282) (xy 381.145796 -260.82117) (xy 381.108458 -260.783832)
			(xy 381.101059 -260.776989) (xy 381.08246 -260.769265) (xy 381.07239 -260.768846) (xy 377.499626 -260.768846)
			(xy 377.489563 -260.769284) (xy 377.470982 -260.777022) (xy 377.463558 -260.783832) (xy 377.17476 -261.07263)
			(xy 377.167394 -261.079742) (xy 377.159774 -261.098538) (xy 377.159774 -262.70204) (xy 377.160204 -262.712108)
			(xy 377.167925 -262.730704) (xy 377.17476 -262.738108) (xy 377.349512 -262.91286) (xy 377.369832 -262.92048)
			(xy 377.381262 -262.919718) (xy 377.522615 -262.910315) (xy 377.805764 -262.900279) (xy 377.947428 -262.899652)
			(xy 377.948952 -262.899652) (xy 377.949714 -262.899652) (xy 378.075803 -262.900147) (xy 378.327857 -262.908095)
			(xy 378.579535 -262.923983) (xy 378.830587 -262.947795) (xy 379.080764 -262.979507) (xy 379.329817 -263.019088)
			(xy 379.577499 -263.066498) (xy 379.823564 -263.121691) (xy 380.067767 -263.184611) (xy 380.309866 -263.255197)
			(xy 380.54962 -263.333377) (xy 380.786791 -263.419074) (xy 381.021144 -263.512204) (xy 381.252445 -263.612673)
			(xy 381.480464 -263.720382) (xy 381.704976 -263.835223) (xy 381.925757 -263.957083) (xy 382.142588 -264.085841)
			(xy 382.355253 -264.221369) (xy 382.563542 -264.363531) (xy 382.569353 -264.367772) (xy 386.190234 -264.367772)
			(xy 386.194307 -264.312113) (xy 386.206442 -264.25764) (xy 386.226378 -264.205514) (xy 386.253692 -264.156846)
			(xy 386.2878 -264.112674) (xy 386.327977 -264.073939) (xy 386.373365 -264.041467) (xy 386.422997 -264.015949)
			(xy 386.475817 -263.99793) (xy 386.530696 -263.987793) (xy 386.586467 -263.985755) (xy 386.641941 -263.991858)
			(xy 386.695934 -264.005974) (xy 386.747297 -264.027801) (xy 386.794935 -264.056874) (xy 386.837831 -264.092573)
			(xy 386.875073 -264.134137) (xy 386.905867 -264.180681) (xy 386.929555 -264.231212) (xy 386.945633 -264.284654)
			(xy 386.953759 -264.339868) (xy 386.954268 -264.367772) (xy 386.953759 -264.395676) (xy 386.945633 -264.45089)
			(xy 386.929555 -264.504332) (xy 386.905867 -264.554863) (xy 386.875073 -264.601407) (xy 386.853639 -264.625328)
			(xy 388.762746 -264.625328) (xy 388.766819 -264.569669) (xy 388.778954 -264.515196) (xy 388.79889 -264.46307)
			(xy 388.826204 -264.414402) (xy 388.860312 -264.37023) (xy 388.900489 -264.331495) (xy 388.945877 -264.299023)
			(xy 388.995509 -264.273505) (xy 389.048329 -264.255486) (xy 389.103208 -264.245349) (xy 389.158979 -264.243311)
			(xy 389.214453 -264.249414) (xy 389.268446 -264.26353) (xy 389.319809 -264.285357) (xy 389.367447 -264.31443)
			(xy 389.410343 -264.350129) (xy 389.447585 -264.391693) (xy 389.478379 -264.438237) (xy 389.502067 -264.488768)
			(xy 389.518145 -264.54221) (xy 389.526271 -264.597424) (xy 389.52678 -264.625328) (xy 389.526271 -264.653232)
			(xy 389.518145 -264.708446) (xy 389.502067 -264.761888) (xy 389.478379 -264.812419) (xy 389.447585 -264.858963)
			(xy 389.410343 -264.900527) (xy 389.367447 -264.936226) (xy 389.319809 -264.965299) (xy 389.268446 -264.987126)
			(xy 389.214453 -265.001242) (xy 389.158979 -265.007345) (xy 389.103208 -265.005307) (xy 389.048329 -264.99517)
			(xy 388.995509 -264.977151) (xy 388.945877 -264.951633) (xy 388.900489 -264.919161) (xy 388.860312 -264.880426)
			(xy 388.826204 -264.836254) (xy 388.79889 -264.787586) (xy 388.778954 -264.73546) (xy 388.766819 -264.680987)
			(xy 388.762746 -264.625328) (xy 386.853639 -264.625328) (xy 386.837831 -264.642971) (xy 386.794935 -264.67867)
			(xy 386.747297 -264.707743) (xy 386.695934 -264.72957) (xy 386.641941 -264.743686) (xy 386.586467 -264.749789)
			(xy 386.530696 -264.747751) (xy 386.475817 -264.737614) (xy 386.422997 -264.719595) (xy 386.373365 -264.694077)
			(xy 386.327977 -264.661605) (xy 386.2878 -264.62287) (xy 386.253692 -264.578698) (xy 386.226378 -264.53003)
			(xy 386.206442 -264.477904) (xy 386.194307 -264.423431) (xy 386.190234 -264.367772) (xy 382.569353 -264.367772)
			(xy 382.767246 -264.512187) (xy 382.966164 -264.66719) (xy 383.160099 -264.828384) (xy 383.348856 -264.99561)
			(xy 383.53225 -265.168703) (xy 383.710098 -265.347489) (xy 383.882222 -265.531791) (xy 384.048453 -265.721426)
			(xy 384.061957 -265.737848) (xy 388.732266 -265.737848) (xy 388.736339 -265.682189) (xy 388.748474 -265.627716)
			(xy 388.76841 -265.57559) (xy 388.795724 -265.526922) (xy 388.829832 -265.48275) (xy 388.870009 -265.444015)
			(xy 388.915397 -265.411543) (xy 388.965029 -265.386025) (xy 389.017849 -265.368006) (xy 389.072728 -265.357869)
			(xy 389.128499 -265.355831) (xy 389.183973 -265.361934) (xy 389.237966 -265.37605) (xy 389.289329 -265.397877)
			(xy 389.336967 -265.42695) (xy 389.379863 -265.462649) (xy 389.417105 -265.504213) (xy 389.447899 -265.550757)
			(xy 389.471587 -265.601288) (xy 389.487665 -265.65473) (xy 389.495791 -265.709944) (xy 389.4963 -265.737848)
			(xy 389.495791 -265.765752) (xy 389.487665 -265.820966) (xy 389.471587 -265.874408) (xy 389.447899 -265.924939)
			(xy 389.417105 -265.971483) (xy 389.379863 -266.013047) (xy 389.336967 -266.048746) (xy 389.289329 -266.077819)
			(xy 389.237966 -266.099646) (xy 389.183973 -266.113762) (xy 389.128499 -266.119865) (xy 389.072728 -266.117827)
			(xy 389.017849 -266.10769) (xy 388.965029 -266.089671) (xy 388.915397 -266.064153) (xy 388.870009 -266.031681)
			(xy 388.829832 -265.992946) (xy 388.795724 -265.948774) (xy 388.76841 -265.900106) (xy 388.748474 -265.84798)
			(xy 388.736339 -265.793507) (xy 388.732266 -265.737848) (xy 384.061957 -265.737848) (xy 384.208624 -265.916206)
			(xy 384.362578 -266.115937) (xy 384.51016 -266.320421) (xy 384.651224 -266.529455) (xy 384.785631 -266.74283)
			(xy 384.913245 -266.960336) (xy 384.914914 -266.963398) (xy 386.95579 -266.963398) (xy 386.959863 -266.907739)
			(xy 386.971998 -266.853266) (xy 386.991934 -266.80114) (xy 387.019248 -266.752472) (xy 387.053356 -266.7083)
			(xy 387.093533 -266.669565) (xy 387.138921 -266.637093) (xy 387.188553 -266.611575) (xy 387.241373 -266.593556)
			(xy 387.296252 -266.583419) (xy 387.352023 -266.581381) (xy 387.407497 -266.587484) (xy 387.46149 -266.6016)
			(xy 387.512853 -266.623427) (xy 387.560491 -266.6525) (xy 387.603387 -266.688199) (xy 387.640629 -266.729763)
			(xy 387.671423 -266.776307) (xy 387.695111 -266.826838) (xy 387.711189 -266.88028) (xy 387.716394 -266.915646)
			(xy 388.735822 -266.915646) (xy 388.739895 -266.859987) (xy 388.75203 -266.805514) (xy 388.771966 -266.753388)
			(xy 388.79928 -266.70472) (xy 388.833388 -266.660548) (xy 388.873565 -266.621813) (xy 388.918953 -266.589341)
			(xy 388.968585 -266.563823) (xy 389.021405 -266.545804) (xy 389.076284 -266.535667) (xy 389.132055 -266.533629)
			(xy 389.187529 -266.539732) (xy 389.241522 -266.553848) (xy 389.292885 -266.575675) (xy 389.340523 -266.604748)
			(xy 389.383419 -266.640447) (xy 389.420661 -266.682011) (xy 389.451455 -266.728555) (xy 389.475143 -266.779086)
			(xy 389.491221 -266.832528) (xy 389.499347 -266.887742) (xy 389.499856 -266.915646) (xy 389.499347 -266.94355)
			(xy 389.491221 -266.998764) (xy 389.475143 -267.052206) (xy 389.451455 -267.102737) (xy 389.420661 -267.149281)
			(xy 389.383419 -267.190845) (xy 389.340523 -267.226544) (xy 389.292885 -267.255617) (xy 389.241522 -267.277444)
			(xy 389.187529 -267.29156) (xy 389.132055 -267.297663) (xy 389.076284 -267.295625) (xy 389.021405 -267.285488)
			(xy 388.968585 -267.267469) (xy 388.918953 -267.241951) (xy 388.873565 -267.209479) (xy 388.833388 -267.170744)
			(xy 388.79928 -267.126572) (xy 388.771966 -267.077904) (xy 388.75203 -267.025778) (xy 388.739895 -266.971305)
			(xy 388.735822 -266.915646) (xy 387.716394 -266.915646) (xy 387.719315 -266.935494) (xy 387.719824 -266.963398)
			(xy 387.719315 -266.991302) (xy 387.711189 -267.046516) (xy 387.695111 -267.099958) (xy 387.671423 -267.150489)
			(xy 387.640629 -267.197033) (xy 387.603387 -267.238597) (xy 387.560491 -267.274296) (xy 387.512853 -267.303369)
			(xy 387.46149 -267.325196) (xy 387.407497 -267.339312) (xy 387.352023 -267.345415) (xy 387.296252 -267.343377)
			(xy 387.241373 -267.33324) (xy 387.188553 -267.315221) (xy 387.138921 -267.289703) (xy 387.093533 -267.257231)
			(xy 387.053356 -267.218496) (xy 387.019248 -267.174324) (xy 386.991934 -267.125656) (xy 386.971998 -267.07353)
			(xy 386.959863 -267.019057) (xy 386.95579 -266.963398) (xy 384.914914 -266.963398) (xy 385.033942 -267.181755)
			(xy 385.091178 -267.294106) (xy 385.097897 -267.306385) (xy 385.116843 -267.326975) (xy 385.140661 -267.341658)
			(xy 385.167568 -267.349334) (xy 385.195548 -267.349428) (xy 385.222506 -267.341934) (xy 385.246423 -267.327413)
			(xy 385.256278 -267.317474) (xy 385.274381 -267.298702) (xy 385.314826 -267.26578) (xy 385.35938 -267.238676)
			(xy 385.407212 -267.217896) (xy 385.457429 -267.203826) (xy 385.509095 -267.19673) (xy 385.53517 -267.196316)
			(xy 385.562443 -267.196777) (xy 385.616434 -267.204536) (xy 385.668772 -267.219899) (xy 385.71839 -267.242555)
			(xy 385.764279 -267.272041) (xy 385.805505 -267.307759) (xy 385.841227 -267.348979) (xy 385.87072 -267.394864)
			(xy 385.893382 -267.444479) (xy 385.908753 -267.496815) (xy 385.916519 -267.550805) (xy 385.916932 -267.578078)
			(xy 385.916547 -267.602793) (xy 385.910169 -267.65181) (xy 385.897504 -267.69959) (xy 385.888484 -267.722604)
			(xy 385.883561 -267.735955) (xy 385.880523 -267.764237) (xy 385.885402 -267.79226) (xy 385.897821 -267.81785)
			(xy 385.916815 -267.839023) (xy 385.940912 -267.854136) (xy 385.968243 -267.862017) (xy 385.982464 -267.862558)
			(xy 425.195492 -267.862558) (xy 429.114712 -267.862558)
		)
		(stroke
			(width 0)
			(type solid)
		)
		(fill yes)
		(layer "F.Cu")
		(net "P1V8_PLL0_PEX3")
	)
	(gr_poly
		(pts
			(xy 134.581392 -293.661846) (xy 134.588504 -293.654734) (xy 139.076684 -293.654734) (xy 139.086746 -293.654294)
			(xy 139.105322 -293.646551) (xy 139.112752 -293.639748) (xy 139.495022 -293.257478) (xy 139.501873 -293.250082)
			(xy 139.509612 -293.231483) (xy 139.510008 -293.22141) (xy 139.510008 -286.201358) (xy 139.509578 -286.191291)
			(xy 139.501853 -286.172697) (xy 139.495022 -286.16529) (xy 139.270486 -285.940754) (xy 139.263089 -285.933904)
			(xy 139.244491 -285.926166) (xy 139.234418 -285.925768) (xy 133.905752 -285.925768) (xy 133.895686 -285.925335)
			(xy 133.877098 -285.917605) (xy 133.869684 -285.910782) (xy 133.685534 -285.726632) (xy 133.678133 -285.719793)
			(xy 133.659535 -285.712077) (xy 133.649466 -285.711646) (xy 131.705858 -285.711646) (xy 131.687316 -285.704026)
			(xy 131.685284 -285.701994) (xy 131.685284 -284.651958) (xy 131.685714 -284.641891) (xy 131.693438 -284.623296)
			(xy 131.70027 -284.61589) (xy 131.701032 -284.615128) (xy 131.708431 -284.608283) (xy 131.727029 -284.600556)
			(xy 131.7371 -284.600142) (xy 132.809996 -284.600142) (xy 132.820065 -284.599718) (xy 132.838665 -284.591998)
			(xy 132.846064 -284.585156) (xy 132.870448 -284.560772) (xy 132.877846 -284.553925) (xy 132.896445 -284.546197)
			(xy 132.906516 -284.545786) (xy 133.460998 -284.545786) (xy 133.471068 -284.545363) (xy 133.489672 -284.537647)
			(xy 133.497066 -284.5308) (xy 133.515354 -284.512512) (xy 133.522207 -284.505116) (xy 133.529953 -284.486518)
			(xy 133.53034 -284.476444) (xy 133.53034 -284.37713) (xy 133.529897 -284.3671) (xy 133.522312 -284.348535)
			(xy 133.515608 -284.341062) (xy 133.488684 -284.314138) (xy 133.481286 -284.30729) (xy 133.462688 -284.299555)
			(xy 133.452616 -284.299152) (xy 132.844794 -284.299152) (xy 132.834725 -284.298726) (xy 132.816127 -284.291005)
			(xy 132.808726 -284.284166) (xy 132.605526 -284.080966) (xy 132.598682 -284.073567) (xy 132.590956 -284.054969)
			(xy 132.59054 -284.044898) (xy 132.59054 -283.33192) (xy 132.590979 -283.321857) (xy 132.598718 -283.303278)
			(xy 132.605526 -283.295852) (xy 132.697982 -283.203396) (xy 132.705385 -283.196563) (xy 132.723983 -283.188859)
			(xy 132.73405 -283.18841) (xy 133.493002 -283.18841) (xy 133.494272 -283.18714) (xy 133.494272 -282.9814)
			(xy 133.486652 -282.962858) (xy 133.482334 -282.95854) (xy 132.74421 -282.95854) (xy 132.73414 -282.958117)
			(xy 132.715539 -282.950399) (xy 132.708142 -282.943554) (xy 132.605526 -282.840938) (xy 132.598687 -282.833537)
			(xy 132.590971 -282.814939) (xy 132.59054 -282.80487) (xy 132.59054 -282.71343) (xy 132.590102 -282.703367)
			(xy 132.582363 -282.684786) (xy 132.575554 -282.677362) (xy 132.560314 -282.662122) (xy 132.552912 -282.655287)
			(xy 132.534313 -282.64758) (xy 132.524246 -282.647136) (xy 130.79857 -282.647136) (xy 130.792728 -282.652978)
			(xy 130.792728 -284.865064) (xy 130.792225 -284.875116) (xy 130.784508 -284.893681) (xy 130.777742 -284.901132)
			(xy 130.692144 -284.98673) (xy 130.684746 -284.993575) (xy 130.666147 -285.0013) (xy 130.656076 -285.001716)
			(xy 127.633476 -285.001716) (xy 127.623407 -285.001289) (xy 127.604808 -284.99357) (xy 127.597408 -284.98673)
			(xy 127.586486 -284.975808) (xy 127.579087 -284.968963) (xy 127.560489 -284.961232) (xy 127.550418 -284.960822)
			(xy 127.02921 -284.960822) (xy 127.019139 -284.961244) (xy 127.000534 -284.968958) (xy 126.993142 -284.975808)
			(xy 126.849124 -285.119826) (xy 126.842279 -285.127225) (xy 126.83455 -285.145823) (xy 126.834138 -285.155894)
			(xy 126.834138 -285.720536) (xy 126.80442 -285.750254) (xy 126.797562 -285.750254) (xy 126.637034 -285.910782)
			(xy 126.629633 -285.91762) (xy 126.611034 -285.925333) (xy 126.600966 -285.925768) (xy 125.74524 -285.925768)
			(xy 125.735175 -285.925333) (xy 125.71659 -285.9176) (xy 125.709172 -285.910782) (xy 125.525022 -285.726632)
			(xy 125.517621 -285.719794) (xy 125.499022 -285.712083) (xy 125.488954 -285.711646) (xy 123.545346 -285.711646)
			(xy 123.526804 -285.704026) (xy 123.524772 -285.701994) (xy 123.524772 -284.651958) (xy 123.525202 -284.641891)
			(xy 123.532924 -284.623295) (xy 123.539758 -284.61589) (xy 123.54052 -284.615128) (xy 123.547918 -284.608282)
			(xy 123.566517 -284.60055) (xy 123.576588 -284.600142) (xy 124.649484 -284.600142) (xy 124.659546 -284.599702)
			(xy 124.678123 -284.59196) (xy 124.685552 -284.585156) (xy 124.709936 -284.560772) (xy 124.717333 -284.553923)
			(xy 124.735932 -284.546191) (xy 124.746004 -284.545786) (xy 125.300486 -284.545786) (xy 125.310549 -284.545347)
			(xy 125.329129 -284.537609) (xy 125.336554 -284.5308) (xy 125.354842 -284.512512) (xy 125.361697 -284.505117)
			(xy 125.369445 -284.486518) (xy 125.369828 -284.476444) (xy 125.369828 -284.37713) (xy 125.369388 -284.367098)
			(xy 125.361812 -284.348525) (xy 125.355096 -284.341062) (xy 125.328172 -284.314138) (xy 125.320774 -284.307292)
			(xy 125.302175 -284.299561) (xy 125.292104 -284.299152) (xy 124.684282 -284.299152) (xy 124.674214 -284.298724)
			(xy 124.655619 -284.291) (xy 124.648214 -284.284166) (xy 124.445014 -284.080966) (xy 124.438171 -284.073566)
			(xy 124.430447 -284.054968) (xy 124.430028 -284.044898) (xy 124.430028 -283.33192) (xy 124.430466 -283.321857)
			(xy 124.438204 -283.303276) (xy 124.445014 -283.295852) (xy 124.53747 -283.203396) (xy 124.544872 -283.196561)
			(xy 124.563471 -283.188853) (xy 124.573538 -283.18841) (xy 125.33249 -283.18841) (xy 125.33376 -283.18714)
			(xy 125.33376 -282.9814) (xy 125.32614 -282.962858) (xy 125.321822 -282.95854) (xy 124.583698 -282.95854)
			(xy 124.573629 -282.958115) (xy 124.555031 -282.950393) (xy 124.54763 -282.943554) (xy 124.445014 -282.840938)
			(xy 124.438176 -282.833537) (xy 124.430462 -282.814938) (xy 124.430028 -282.80487) (xy 124.430028 -282.71343)
			(xy 124.429524 -282.703379) (xy 124.421806 -282.684815) (xy 124.415042 -282.677362) (xy 124.399802 -282.662122)
			(xy 124.392405 -282.655273) (xy 124.373806 -282.647534) (xy 124.363734 -282.647136) (xy 122.638058 -282.647136)
			(xy 122.632216 -282.652978) (xy 122.632216 -284.865064) (xy 122.631782 -284.875129) (xy 122.624053 -284.893719)
			(xy 122.61723 -284.901132) (xy 122.531632 -284.98673) (xy 122.524233 -284.993573) (xy 122.505634 -285.001294)
			(xy 122.495564 -285.001716) (xy 119.472964 -285.001716) (xy 119.462896 -285.001287) (xy 119.4443 -284.993565)
			(xy 119.436896 -284.98673) (xy 119.425974 -284.975808) (xy 119.418574 -284.968965) (xy 119.399976 -284.961239)
			(xy 119.389906 -284.960822) (xy 118.847616 -284.960822) (xy 117.88267 -285.925768) (xy 117.246654 -285.925768)
			(xy 117.236588 -285.925336) (xy 117.217999 -285.917606) (xy 117.210586 -285.910782) (xy 117.026436 -285.726632)
			(xy 117.019036 -285.719792) (xy 117.000437 -285.712076) (xy 116.990368 -285.711646) (xy 115.04676 -285.711646)
			(xy 115.028218 -285.704026) (xy 115.026186 -285.701994) (xy 115.026186 -284.651958) (xy 115.026616 -284.641891)
			(xy 115.03434 -284.623296) (xy 115.041172 -284.61589) (xy 115.041934 -284.615128) (xy 115.049333 -284.608284)
			(xy 115.067931 -284.600557) (xy 115.078002 -284.600142) (xy 116.150898 -284.600142) (xy 116.160967 -284.599718)
			(xy 116.179567 -284.591997) (xy 116.186966 -284.585156) (xy 116.21135 -284.560772) (xy 116.218748 -284.553925)
			(xy 116.237347 -284.546198) (xy 116.247418 -284.545786) (xy 116.8019 -284.545786) (xy 116.81197 -284.545363)
			(xy 116.830573 -284.537647) (xy 116.837968 -284.5308) (xy 116.856256 -284.512512) (xy 116.863109 -284.505116)
			(xy 116.870855 -284.486518) (xy 116.871242 -284.476444) (xy 116.871242 -284.37713) (xy 116.870799 -284.3671)
			(xy 116.863214 -284.348535) (xy 116.85651 -284.341062) (xy 116.829586 -284.314138) (xy 116.822189 -284.30729)
			(xy 116.80359 -284.299554) (xy 116.793518 -284.299152) (xy 116.185696 -284.299152) (xy 116.175627 -284.298727)
			(xy 116.157028 -284.291006) (xy 116.149628 -284.284166) (xy 115.946428 -284.080966) (xy 115.939584 -284.073567)
			(xy 115.931857 -284.054969) (xy 115.931442 -284.044898) (xy 115.931442 -283.33192) (xy 115.931881 -283.321857)
			(xy 115.939621 -283.303278) (xy 115.946428 -283.295852) (xy 116.038884 -283.203396) (xy 116.046287 -283.196563)
			(xy 116.064885 -283.18886) (xy 116.074952 -283.18841) (xy 116.833904 -283.18841) (xy 116.835174 -283.18714)
			(xy 116.835174 -282.9814) (xy 116.827554 -282.962858) (xy 116.823236 -282.95854) (xy 116.085112 -282.95854)
			(xy 116.075042 -282.958117) (xy 116.05644 -282.950399) (xy 116.049044 -282.943554) (xy 115.946428 -282.840938)
			(xy 115.939588 -282.833537) (xy 115.931872 -282.814939) (xy 115.931442 -282.80487) (xy 115.931442 -282.71343)
			(xy 115.931005 -282.703367) (xy 115.923266 -282.684786) (xy 115.916456 -282.677362) (xy 115.901216 -282.662122)
			(xy 115.893814 -282.655286) (xy 115.875215 -282.647579) (xy 115.865148 -282.647136) (xy 114.139472 -282.647136)
			(xy 114.13363 -282.652978) (xy 114.13363 -284.865064) (xy 114.133127 -284.875116) (xy 114.12541 -284.893681)
			(xy 114.118644 -284.901132) (xy 114.033046 -284.98673) (xy 114.025648 -284.993576) (xy 114.007049 -285.001302)
			(xy 113.996978 -285.001716) (xy 110.974378 -285.001716) (xy 110.964309 -285.001289) (xy 110.945709 -284.993571)
			(xy 110.93831 -284.98673) (xy 110.927388 -284.975808) (xy 110.919989 -284.968963) (xy 110.901391 -284.961231)
			(xy 110.89132 -284.960822) (xy 110.370112 -284.960822) (xy 110.360041 -284.961243) (xy 110.341436 -284.968957)
			(xy 110.334044 -284.975808) (xy 110.190026 -285.119826) (xy 110.183181 -285.127225) (xy 110.175452 -285.145823)
			(xy 110.17504 -285.155894) (xy 110.17504 -285.720536) (xy 110.145322 -285.750254) (xy 110.138464 -285.750254)
			(xy 109.977936 -285.910782) (xy 109.970535 -285.91762) (xy 109.951936 -285.925334) (xy 109.941868 -285.925768)
			(xy 109.086142 -285.925768) (xy 109.076077 -285.925334) (xy 109.057491 -285.917601) (xy 109.050074 -285.910782)
			(xy 108.865924 -285.726632) (xy 108.858523 -285.719794) (xy 108.839924 -285.712082) (xy 108.829856 -285.711646)
			(xy 106.886248 -285.711646) (xy 106.867706 -285.704026) (xy 106.865674 -285.701994) (xy 106.865674 -284.651958)
			(xy 106.866104 -284.641891) (xy 106.873826 -284.623295) (xy 106.88066 -284.61589) (xy 106.881422 -284.615128)
			(xy 106.88882 -284.608282) (xy 106.907419 -284.600551) (xy 106.91749 -284.600142) (xy 107.990386 -284.600142)
			(xy 108.000448 -284.599702) (xy 108.019024 -284.591959) (xy 108.026454 -284.585156) (xy 108.050838 -284.560772)
			(xy 108.058235 -284.553924) (xy 108.076834 -284.546192) (xy 108.086906 -284.545786) (xy 108.641388 -284.545786)
			(xy 108.651459 -284.545365) (xy 108.670065 -284.537652) (xy 108.677456 -284.5308) (xy 108.695744 -284.512512)
			(xy 108.702598 -284.505117) (xy 108.710346 -284.486518) (xy 108.71073 -284.476444) (xy 108.71073 -284.37713)
			(xy 108.71029 -284.367098) (xy 108.702714 -284.348525) (xy 108.695998 -284.341062) (xy 108.669074 -284.314138)
			(xy 108.661676 -284.307291) (xy 108.643077 -284.29956) (xy 108.633006 -284.299152) (xy 108.025184 -284.299152)
			(xy 108.015116 -284.298725) (xy 107.996521 -284.291001) (xy 107.989116 -284.284166) (xy 107.785916 -284.080966)
			(xy 107.779073 -284.073566) (xy 107.771349 -284.054968) (xy 107.77093 -284.044898) (xy 107.77093 -283.33192)
			(xy 107.771368 -283.321857) (xy 107.779107 -283.303276) (xy 107.785916 -283.295852) (xy 107.878372 -283.203396)
			(xy 107.885775 -283.196561) (xy 107.904373 -283.188854) (xy 107.91444 -283.18841) (xy 108.673392 -283.18841)
			(xy 108.674662 -283.18714) (xy 108.674662 -282.9814) (xy 108.667042 -282.962858) (xy 108.662724 -282.95854)
			(xy 107.9246 -282.95854) (xy 107.914531 -282.958115) (xy 107.895932 -282.950394) (xy 107.888532 -282.943554)
			(xy 107.785916 -282.840938) (xy 107.779078 -282.833537) (xy 107.771363 -282.814938) (xy 107.77093 -282.80487)
			(xy 107.77093 -282.71343) (xy 107.770426 -282.703379) (xy 107.762708 -282.684815) (xy 107.755944 -282.677362)
			(xy 107.740704 -282.662122) (xy 107.733307 -282.655273) (xy 107.714709 -282.647533) (xy 107.704636 -282.647136)
			(xy 105.97896 -282.647136) (xy 105.973118 -282.652978) (xy 105.973118 -284.865064) (xy 105.972684 -284.875129)
			(xy 105.964955 -284.893719) (xy 105.958132 -284.901132) (xy 105.872534 -284.98673) (xy 105.865135 -284.993574)
			(xy 105.846536 -285.001295) (xy 105.836466 -285.001716) (xy 102.813866 -285.001716) (xy 102.803798 -285.001287)
			(xy 102.785201 -284.993566) (xy 102.777798 -284.98673) (xy 102.766876 -284.975808) (xy 102.759476 -284.968965)
			(xy 102.740878 -284.961238) (xy 102.730808 -284.960822) (xy 102.2096 -284.960822) (xy 102.19953 -284.961246)
			(xy 102.180928 -284.968962) (xy 102.173532 -284.975808) (xy 102.029514 -285.119826) (xy 102.02267 -285.127225)
			(xy 102.014943 -285.145823) (xy 102.014528 -285.155894) (xy 102.014528 -286.789368) (xy 108.67212 -286.789368)
			(xy 108.676193 -286.733709) (xy 108.688328 -286.679236) (xy 108.708264 -286.62711) (xy 108.735578 -286.578442)
			(xy 108.769686 -286.53427) (xy 108.809863 -286.495535) (xy 108.855251 -286.463063) (xy 108.904883 -286.437545)
			(xy 108.957703 -286.419526) (xy 109.012582 -286.409389) (xy 109.068353 -286.407351) (xy 109.123827 -286.413454)
			(xy 109.17782 -286.42757) (xy 109.229183 -286.449397) (xy 109.276821 -286.47847) (xy 109.319717 -286.514169)
			(xy 109.356959 -286.555733) (xy 109.387753 -286.602277) (xy 109.411441 -286.652808) (xy 109.427519 -286.70625)
			(xy 109.429621 -286.720534) (xy 109.55858 -286.720534) (xy 109.562653 -286.664875) (xy 109.574788 -286.610402)
			(xy 109.594724 -286.558276) (xy 109.622038 -286.509608) (xy 109.656146 -286.465436) (xy 109.696323 -286.426701)
			(xy 109.741711 -286.394229) (xy 109.791343 -286.368711) (xy 109.844163 -286.350692) (xy 109.899042 -286.340555)
			(xy 109.954813 -286.338517) (xy 110.010287 -286.34462) (xy 110.06428 -286.358736) (xy 110.115643 -286.380563)
			(xy 110.163281 -286.409636) (xy 110.206177 -286.445335) (xy 110.243419 -286.486899) (xy 110.274213 -286.533443)
			(xy 110.297901 -286.583974) (xy 110.313979 -286.637416) (xy 110.322105 -286.69263) (xy 110.322614 -286.720534)
			(xy 110.322105 -286.748438) (xy 110.316006 -286.789876) (xy 125.407672 -286.789876) (xy 125.411745 -286.734217)
			(xy 125.42388 -286.679744) (xy 125.443816 -286.627618) (xy 125.47113 -286.57895) (xy 125.505238 -286.534778)
			(xy 125.545415 -286.496043) (xy 125.590803 -286.463571) (xy 125.640435 -286.438053) (xy 125.693255 -286.420034)
			(xy 125.748134 -286.409897) (xy 125.803905 -286.407859) (xy 125.859379 -286.413962) (xy 125.913372 -286.428078)
			(xy 125.964735 -286.449905) (xy 126.012373 -286.478978) (xy 126.055269 -286.514677) (xy 126.092511 -286.556241)
			(xy 126.123305 -286.602785) (xy 126.146993 -286.653316) (xy 126.162478 -286.704786) (xy 126.294386 -286.704786)
			(xy 126.298459 -286.649127) (xy 126.310594 -286.594654) (xy 126.33053 -286.542528) (xy 126.357844 -286.49386)
			(xy 126.391952 -286.449688) (xy 126.432129 -286.410953) (xy 126.477517 -286.378481) (xy 126.527149 -286.352963)
			(xy 126.579969 -286.334944) (xy 126.634848 -286.324807) (xy 126.690619 -286.322769) (xy 126.746093 -286.328872)
			(xy 126.800086 -286.342988) (xy 126.851449 -286.364815) (xy 126.899087 -286.393888) (xy 126.941983 -286.429587)
			(xy 126.979225 -286.471151) (xy 127.010019 -286.517695) (xy 127.033707 -286.568226) (xy 127.049785 -286.621668)
			(xy 127.057911 -286.676882) (xy 127.05842 -286.704786) (xy 127.057911 -286.73269) (xy 127.049785 -286.787904)
			(xy 127.033707 -286.841346) (xy 127.010019 -286.891877) (xy 126.979225 -286.938421) (xy 126.941983 -286.979985)
			(xy 126.899087 -287.015684) (xy 126.851449 -287.044757) (xy 126.800086 -287.066584) (xy 126.746093 -287.0807)
			(xy 126.690619 -287.086803) (xy 126.634848 -287.084765) (xy 126.579969 -287.074628) (xy 126.527149 -287.056609)
			(xy 126.477517 -287.031091) (xy 126.432129 -286.998619) (xy 126.391952 -286.959884) (xy 126.357844 -286.915712)
			(xy 126.33053 -286.867044) (xy 126.310594 -286.814918) (xy 126.298459 -286.760445) (xy 126.294386 -286.704786)
			(xy 126.162478 -286.704786) (xy 126.163071 -286.706758) (xy 126.171197 -286.761972) (xy 126.171706 -286.789876)
			(xy 126.171197 -286.81778) (xy 126.163071 -286.872994) (xy 126.146993 -286.926436) (xy 126.123305 -286.976967)
			(xy 126.092511 -287.023511) (xy 126.055269 -287.065075) (xy 126.012373 -287.100774) (xy 125.964735 -287.129847)
			(xy 125.913372 -287.151674) (xy 125.859379 -287.16579) (xy 125.803905 -287.171893) (xy 125.748134 -287.169855)
			(xy 125.693255 -287.159718) (xy 125.640435 -287.141699) (xy 125.590803 -287.116181) (xy 125.545415 -287.083709)
			(xy 125.505238 -287.044974) (xy 125.47113 -287.000802) (xy 125.443816 -286.952134) (xy 125.42388 -286.900008)
			(xy 125.411745 -286.845535) (xy 125.407672 -286.789876) (xy 110.316006 -286.789876) (xy 110.313979 -286.803652)
			(xy 110.297901 -286.857094) (xy 110.274213 -286.907625) (xy 110.243419 -286.954169) (xy 110.206177 -286.995733)
			(xy 110.163281 -287.031432) (xy 110.115643 -287.060505) (xy 110.06428 -287.082332) (xy 110.010287 -287.096448)
			(xy 109.954813 -287.102551) (xy 109.899042 -287.100513) (xy 109.844163 -287.090376) (xy 109.791343 -287.072357)
			(xy 109.741711 -287.046839) (xy 109.696323 -287.014367) (xy 109.656146 -286.975632) (xy 109.622038 -286.93146)
			(xy 109.594724 -286.882792) (xy 109.574788 -286.830666) (xy 109.562653 -286.776193) (xy 109.55858 -286.720534)
			(xy 109.429621 -286.720534) (xy 109.435645 -286.761464) (xy 109.436154 -286.789368) (xy 109.435645 -286.817272)
			(xy 109.427519 -286.872486) (xy 109.411441 -286.925928) (xy 109.387753 -286.976459) (xy 109.356959 -287.023003)
			(xy 109.319717 -287.064567) (xy 109.276821 -287.100266) (xy 109.229183 -287.129339) (xy 109.17782 -287.151166)
			(xy 109.123827 -287.165282) (xy 109.068353 -287.171385) (xy 109.012582 -287.169347) (xy 108.957703 -287.15921)
			(xy 108.904883 -287.141191) (xy 108.855251 -287.115673) (xy 108.809863 -287.083201) (xy 108.769686 -287.044466)
			(xy 108.735578 -287.000294) (xy 108.708264 -286.951626) (xy 108.688328 -286.8995) (xy 108.676193 -286.845027)
			(xy 108.67212 -286.789368) (xy 102.014528 -286.789368) (xy 102.014528 -287.845754) (xy 102.01478 -287.853373)
			(xy 102.019174 -287.867961) (xy 102.023164 -287.874456) (xy 102.030806 -287.885886) (xy 103.455724 -287.885886)
			(xy 103.455724 -287.13684) (xy 103.462074 -287.13049) (xy 103.480616 -287.12287) (xy 103.619046 -287.12287)
			(xy 103.62311 -287.118806) (xy 108.443776 -287.118806) (xy 108.453844 -287.119242) (xy 108.472442 -287.126955)
			(xy 108.479844 -287.133792) (xy 108.536994 -287.190942) (xy 108.543844 -287.198334) (xy 108.551558 -287.216939)
			(xy 108.55198 -287.22701) (xy 108.55198 -287.299654) (xy 108.55325 -287.300924) (xy 108.55325 -287.443926)
			(xy 111.562388 -287.443926) (xy 111.562388 -287.34004) (xy 111.56315 -287.339278) (xy 111.56315 -287.225994)
			(xy 111.563559 -287.215923) (xy 111.57129 -287.197324) (xy 111.578136 -287.189926) (xy 111.63427 -287.133792)
			(xy 111.641685 -287.126972) (xy 111.660273 -287.119241) (xy 111.670338 -287.118806) (xy 116.604288 -287.118806)
			(xy 116.614357 -287.119236) (xy 116.632955 -287.126953) (xy 116.640356 -287.133792) (xy 116.647722 -287.141158)
			(xy 116.654539 -287.148576) (xy 116.662272 -287.167162) (xy 116.662708 -287.177226) (xy 116.662708 -287.872678)
			(xy 120.11025 -287.872678) (xy 120.11025 -287.152842) (xy 120.11787 -287.1343) (xy 120.122442 -287.129728)
			(xy 120.129837 -287.122881) (xy 120.14844 -287.115165) (xy 120.15851 -287.114742) (xy 120.2563 -287.114742)
			(xy 120.26011 -287.118806) (xy 125.102874 -287.118806) (xy 125.112942 -287.119243) (xy 125.13154 -287.126956)
			(xy 125.138942 -287.133792) (xy 125.196092 -287.190942) (xy 125.202942 -287.198334) (xy 125.210656 -287.216939)
			(xy 125.211078 -287.22701) (xy 125.211078 -287.299654) (xy 125.212348 -287.300924) (xy 125.212348 -287.443926)
			(xy 128.221486 -287.443926) (xy 128.221486 -287.34004) (xy 128.222248 -287.339278) (xy 128.222248 -287.225994)
			(xy 128.222657 -287.215923) (xy 128.230388 -287.197324) (xy 128.237234 -287.189926) (xy 128.293368 -287.133792)
			(xy 128.300784 -287.126972) (xy 128.319371 -287.119241) (xy 128.329436 -287.118806) (xy 133.263386 -287.118806)
			(xy 133.273455 -287.119237) (xy 133.292053 -287.126954) (xy 133.299454 -287.133792) (xy 133.30682 -287.141158)
			(xy 133.313637 -287.148576) (xy 133.32137 -287.167162) (xy 133.321806 -287.177226) (xy 133.321806 -292.461696)
			(xy 133.321404 -292.471768) (xy 133.31367 -292.490367) (xy 133.30682 -292.497764) (xy 133.265418 -292.539166)
			(xy 133.258002 -292.545986) (xy 133.239415 -292.553718) (xy 133.22935 -292.554152) (xy 128.40716 -292.554152)
			(xy 128.397114 -292.553791) (xy 128.378517 -292.546197) (xy 128.371092 -292.53942) (xy 128.238758 -292.407086)
			(xy 128.231913 -292.39969) (xy 128.224198 -292.381087) (xy 128.223772 -292.371018) (xy 128.223772 -287.443926)
			(xy 128.221486 -287.443926) (xy 125.212348 -287.443926) (xy 125.211078 -287.443926) (xy 125.211078 -292.468808)
			(xy 125.210662 -292.478878) (xy 125.202935 -292.497476) (xy 125.196092 -292.504876) (xy 125.140212 -292.560756)
			(xy 125.132797 -292.567577) (xy 125.114209 -292.575309) (xy 125.104144 -292.575742) (xy 120.504458 -292.575742)
			(xy 120.494384 -292.575354) (xy 120.475786 -292.567609) (xy 120.46839 -292.560756) (xy 120.162066 -292.254432)
			(xy 120.155243 -292.247019) (xy 120.147514 -292.228429) (xy 120.14708 -292.218364) (xy 120.14708 -287.951672)
			(xy 120.146674 -287.9416) (xy 120.13894 -287.923003) (xy 120.132094 -287.915604) (xy 120.125236 -287.908746)
			(xy 120.118429 -287.90132) (xy 120.110689 -287.882741) (xy 120.11025 -287.872678) (xy 116.662708 -287.872678)
			(xy 116.662708 -292.461696) (xy 116.662305 -292.471768) (xy 116.654571 -292.490367) (xy 116.647722 -292.497764)
			(xy 116.60632 -292.539166) (xy 116.598903 -292.545985) (xy 116.580317 -292.553718) (xy 116.570252 -292.554152)
			(xy 111.748062 -292.554152) (xy 111.738016 -292.553789) (xy 111.719419 -292.546196) (xy 111.711994 -292.53942)
			(xy 111.57966 -292.407086) (xy 111.572816 -292.39969) (xy 111.5651 -292.381087) (xy 111.564674 -292.371018)
			(xy 111.564674 -287.443926) (xy 111.562388 -287.443926) (xy 108.55325 -287.443926) (xy 108.55198 -287.443926)
			(xy 108.55198 -292.468808) (xy 108.551564 -292.478878) (xy 108.543837 -292.497476) (xy 108.536994 -292.504876)
			(xy 108.481114 -292.560756) (xy 108.473698 -292.567576) (xy 108.455111 -292.575309) (xy 108.445046 -292.575742)
			(xy 103.84536 -292.575742) (xy 103.835286 -292.575353) (xy 103.816688 -292.567608) (xy 103.809292 -292.560756)
			(xy 103.502968 -292.254432) (xy 103.496145 -292.247019) (xy 103.488416 -292.228429) (xy 103.487982 -292.218364)
			(xy 103.487982 -287.960308) (xy 103.487557 -287.950239) (xy 103.479837 -287.931641) (xy 103.472996 -287.92424)
			(xy 103.47071 -287.921954) (xy 103.463902 -287.914528) (xy 103.456163 -287.895949) (xy 103.455724 -287.885886)
			(xy 102.030806 -287.885886) (xy 102.069087 -287.943142) (xy 102.155116 -288.084225) (xy 102.234334 -288.229243)
			(xy 102.306558 -288.377868) (xy 102.371627 -288.529761) (xy 102.429393 -288.68458) (xy 102.479723 -288.841972)
			(xy 102.522506 -289.001582) (xy 102.557642 -289.163047) (xy 102.585054 -289.326002) (xy 102.604678 -289.490077)
			(xy 102.616471 -289.654899) (xy 102.620404 -289.820097) (xy 102.616471 -289.985294) (xy 102.604679 -290.150117)
			(xy 102.585055 -290.314191) (xy 102.557644 -290.477146) (xy 102.522507 -290.638611) (xy 102.479725 -290.798221)
			(xy 102.429395 -290.955614) (xy 102.37163 -291.110433) (xy 102.306561 -291.262326) (xy 102.234337 -291.410951)
			(xy 102.15512 -291.555969) (xy 102.06909 -291.697052) (xy 102.023164 -291.765736) (xy 102.019104 -291.772199)
			(xy 102.014703 -291.786807) (xy 102.014528 -291.794438) (xy 102.014528 -293.472362) (xy 102.014963 -293.482427)
			(xy 102.022696 -293.501012) (xy 102.029514 -293.50843) (xy 102.175564 -293.65448) (xy 102.182965 -293.661318)
			(xy 102.201563 -293.669033) (xy 102.211632 -293.669466) (xy 134.56285 -293.669466)
		)
		(stroke
			(width 0)
			(type solid)
		)
		(fill yes)
		(layer "F.Cu")
		(net "GND")
	)
	(gr_poly
		(pts
			(xy 371.5766 -293.669466) (xy 371.58667 -293.669042) (xy 371.605271 -293.661324) (xy 371.612668 -293.65448)
			(xy 371.9703 -293.296848) (xy 371.977138 -293.289447) (xy 371.984854 -293.270849) (xy 371.985286 -293.26078)
			(xy 371.985286 -286.191198) (xy 371.984862 -286.181128) (xy 371.977146 -286.162526) (xy 371.9703 -286.15513)
			(xy 371.755924 -285.940754) (xy 371.748524 -285.933913) (xy 371.729925 -285.926198) (xy 371.719856 -285.925768)
			(xy 366.105948 -285.925768) (xy 366.095883 -285.925335) (xy 366.077295 -285.917603) (xy 366.06988 -285.910782)
			(xy 365.88573 -285.726632) (xy 365.878329 -285.719793) (xy 365.859731 -285.712079) (xy 365.849662 -285.711646)
			(xy 363.906054 -285.711646) (xy 363.887512 -285.704026) (xy 363.88548 -285.701994) (xy 363.88548 -284.651958)
			(xy 363.88591 -284.641891) (xy 363.893633 -284.623295) (xy 363.900466 -284.61589) (xy 363.901228 -284.615128)
			(xy 363.908627 -284.608283) (xy 363.927225 -284.600554) (xy 363.937296 -284.600142) (xy 365.010192 -284.600142)
			(xy 365.020262 -284.599719) (xy 365.038863 -284.592) (xy 365.04626 -284.585156) (xy 365.070644 -284.560772)
			(xy 365.078041 -284.553925) (xy 365.09664 -284.546195) (xy 365.106712 -284.545786) (xy 365.661194 -284.545786)
			(xy 365.671264 -284.545364) (xy 365.689869 -284.537649) (xy 365.697262 -284.5308) (xy 365.71555 -284.512512)
			(xy 365.722404 -284.505117) (xy 365.73015 -284.486518) (xy 365.730536 -284.476444) (xy 365.730536 -284.37713)
			(xy 365.730096 -284.367098) (xy 365.722521 -284.348524) (xy 365.715804 -284.341062) (xy 365.68888 -284.314138)
			(xy 365.681482 -284.30729) (xy 365.662884 -284.299557) (xy 365.652812 -284.299152) (xy 365.04499 -284.299152)
			(xy 365.034922 -284.298726) (xy 365.016324 -284.291003) (xy 365.008922 -284.284166) (xy 364.805722 -284.080966)
			(xy 364.798878 -284.073567) (xy 364.791153 -284.054968) (xy 364.790736 -284.044898) (xy 364.790736 -283.33192)
			(xy 364.791174 -283.321857) (xy 364.798913 -283.303277) (xy 364.805722 -283.295852) (xy 364.898178 -283.203396)
			(xy 364.905581 -283.196562) (xy 364.924179 -283.188857) (xy 364.934246 -283.18841) (xy 365.693198 -283.18841)
			(xy 365.694468 -283.18714) (xy 365.694468 -282.9814) (xy 365.686848 -282.962858) (xy 365.68253 -282.95854)
			(xy 364.944406 -282.95854) (xy 364.934337 -282.958116) (xy 364.915736 -282.950397) (xy 364.908338 -282.943554)
			(xy 364.805722 -282.840938) (xy 364.798883 -282.833537) (xy 364.791168 -282.814939) (xy 364.790736 -282.80487)
			(xy 364.790736 -282.71343) (xy 364.790298 -282.703367) (xy 364.782559 -282.684787) (xy 364.77575 -282.677362)
			(xy 364.76051 -282.662122) (xy 364.753113 -282.655272) (xy 364.734515 -282.64753) (xy 364.724442 -282.647136)
			(xy 362.998766 -282.647136) (xy 362.992924 -282.652978) (xy 362.992924 -284.865064) (xy 362.99249 -284.87513)
			(xy 362.984762 -284.893719) (xy 362.977938 -284.901132) (xy 362.89234 -284.98673) (xy 362.884942 -284.993575)
			(xy 362.866343 -285.001298) (xy 362.856272 -285.001716) (xy 359.833672 -285.001716) (xy 359.823604 -285.001288)
			(xy 359.805005 -284.993569) (xy 359.797604 -284.98673) (xy 359.786682 -284.975808) (xy 359.779283 -284.968964)
			(xy 359.760685 -284.961235) (xy 359.750614 -284.960822) (xy 359.229406 -284.960822) (xy 359.219336 -284.961245)
			(xy 359.200732 -284.96896) (xy 359.193338 -284.975808) (xy 359.04932 -285.119826) (xy 359.042475 -285.127225)
			(xy 359.034747 -285.145823) (xy 359.034334 -285.155894) (xy 359.034334 -285.720536) (xy 359.004616 -285.750254)
			(xy 358.997758 -285.750254) (xy 358.83723 -285.910782) (xy 358.829828 -285.917619) (xy 358.81123 -285.925331)
			(xy 358.801162 -285.925768) (xy 357.945436 -285.925768) (xy 357.935372 -285.925333) (xy 357.916787 -285.917598)
			(xy 357.909368 -285.910782) (xy 357.725218 -285.726632) (xy 357.717817 -285.719795) (xy 357.699218 -285.712085)
			(xy 357.68915 -285.711646) (xy 355.745542 -285.711646) (xy 355.727 -285.704026) (xy 355.724968 -285.701994)
			(xy 355.724968 -284.651958) (xy 355.725398 -284.64189) (xy 355.733119 -284.623294) (xy 355.739954 -284.61589)
			(xy 355.740716 -284.615128) (xy 355.748114 -284.608281) (xy 355.766712 -284.600548) (xy 355.776784 -284.600142)
			(xy 356.84968 -284.600142) (xy 356.859742 -284.599703) (xy 356.87832 -284.591961) (xy 356.885748 -284.585156)
			(xy 356.910132 -284.560772) (xy 356.917529 -284.553923) (xy 356.936128 -284.546189) (xy 356.9462 -284.545786)
			(xy 357.500682 -284.545786) (xy 357.510745 -284.545348) (xy 357.529327 -284.537611) (xy 357.53675 -284.5308)
			(xy 357.555038 -284.512512) (xy 357.561893 -284.505117) (xy 357.569642 -284.486519) (xy 357.570024 -284.476444)
			(xy 357.570024 -284.37713) (xy 357.569584 -284.367099) (xy 357.562008 -284.348526) (xy 357.555292 -284.341062)
			(xy 357.528368 -284.314138) (xy 357.52097 -284.307292) (xy 357.502371 -284.299563) (xy 357.4923 -284.299152)
			(xy 356.884478 -284.299152) (xy 356.874411 -284.298723) (xy 356.855817 -284.290998) (xy 356.84841 -284.284166)
			(xy 356.64521 -284.080966) (xy 356.638368 -284.073566) (xy 356.630644 -284.054968) (xy 356.630224 -284.044898)
			(xy 356.630224 -283.33192) (xy 356.630662 -283.321857) (xy 356.6384 -283.303276) (xy 356.64521 -283.295852)
			(xy 356.737666 -283.203396) (xy 356.745068 -283.19656) (xy 356.763666 -283.18885) (xy 356.773734 -283.18841)
			(xy 357.532686 -283.18841) (xy 357.533956 -283.18714) (xy 357.533956 -282.9814) (xy 357.526336 -282.962858)
			(xy 357.522018 -282.95854) (xy 356.783894 -282.95854) (xy 356.773826 -282.958114) (xy 356.755228 -282.950392)
			(xy 356.747826 -282.943554) (xy 356.64521 -282.840938) (xy 356.638372 -282.833537) (xy 356.630659 -282.814938)
			(xy 356.630224 -282.80487) (xy 356.630224 -282.71343) (xy 356.629789 -282.703365) (xy 356.622059 -282.684777)
			(xy 356.615238 -282.677362) (xy 356.599998 -282.662122) (xy 356.5926 -282.655274) (xy 356.574002 -282.647536)
			(xy 356.56393 -282.647136) (xy 354.838254 -282.647136) (xy 354.832412 -282.652978) (xy 354.832412 -284.865064)
			(xy 354.831978 -284.875129) (xy 354.824248 -284.893718) (xy 354.817426 -284.901132) (xy 354.731828 -284.98673)
			(xy 354.724429 -284.993573) (xy 354.70583 -285.001292) (xy 354.69576 -285.001716) (xy 351.67316 -285.001716)
			(xy 351.663093 -285.001286) (xy 351.644497 -284.993563) (xy 351.637092 -284.98673) (xy 351.62617 -284.975808)
			(xy 351.61877 -284.968965) (xy 351.600172 -284.961241) (xy 351.590102 -284.960822) (xy 351.047812 -284.960822)
			(xy 350.082866 -285.925768) (xy 349.44685 -285.925768) (xy 349.436785 -285.925335) (xy 349.418196 -285.917604)
			(xy 349.410782 -285.910782) (xy 349.226632 -285.726632) (xy 349.219231 -285.719793) (xy 349.200633 -285.712078)
			(xy 349.190564 -285.711646) (xy 347.246956 -285.711646) (xy 347.228414 -285.704026) (xy 347.226382 -285.701994)
			(xy 347.226382 -284.651958) (xy 347.226812 -284.641891) (xy 347.234535 -284.623296) (xy 347.241368 -284.61589)
			(xy 347.24213 -284.615128) (xy 347.249529 -284.608283) (xy 347.268127 -284.600555) (xy 347.278198 -284.600142)
			(xy 348.351094 -284.600142) (xy 348.361163 -284.599718) (xy 348.379764 -284.591999) (xy 348.387162 -284.585156)
			(xy 348.411546 -284.560772) (xy 348.418943 -284.553925) (xy 348.437543 -284.546196) (xy 348.447614 -284.545786)
			(xy 349.002096 -284.545786) (xy 349.012166 -284.545363) (xy 349.03077 -284.537648) (xy 349.038164 -284.5308)
			(xy 349.056452 -284.512512) (xy 349.063305 -284.505116) (xy 349.071052 -284.486518) (xy 349.071438 -284.476444)
			(xy 349.071438 -284.37713) (xy 349.070995 -284.3671) (xy 349.06341 -284.348535) (xy 349.056706 -284.341062)
			(xy 349.029782 -284.314138) (xy 349.022384 -284.30729) (xy 349.003786 -284.299556) (xy 348.993714 -284.299152)
			(xy 348.385892 -284.299152) (xy 348.375824 -284.298726) (xy 348.357226 -284.291004) (xy 348.349824 -284.284166)
			(xy 348.146624 -284.080966) (xy 348.13978 -284.073567) (xy 348.132054 -284.054968) (xy 348.131638 -284.044898)
			(xy 348.131638 -283.33192) (xy 348.132077 -283.321857) (xy 348.139816 -283.303277) (xy 348.146624 -283.295852)
			(xy 348.23908 -283.203396) (xy 348.246483 -283.196563) (xy 348.265081 -283.188858) (xy 348.275148 -283.18841)
			(xy 349.0341 -283.18841) (xy 349.03537 -283.18714) (xy 349.03537 -282.9814) (xy 349.02775 -282.962858)
			(xy 349.023432 -282.95854) (xy 348.285308 -282.95854) (xy 348.275238 -282.958117) (xy 348.256638 -282.950398)
			(xy 348.24924 -282.943554) (xy 348.146624 -282.840938) (xy 348.139785 -282.833537) (xy 348.132069 -282.814939)
			(xy 348.131638 -282.80487) (xy 348.131638 -282.71343) (xy 348.1312 -282.703367) (xy 348.123461 -282.684787)
			(xy 348.116652 -282.677362) (xy 348.101412 -282.662122) (xy 348.094015 -282.655271) (xy 348.075417 -282.647529)
			(xy 348.065344 -282.647136) (xy 346.339668 -282.647136) (xy 346.333826 -282.652978) (xy 346.333826 -284.865064)
			(xy 346.333392 -284.87513) (xy 346.325664 -284.89372) (xy 346.31884 -284.901132) (xy 346.233242 -284.98673)
			(xy 346.225844 -284.993575) (xy 346.207245 -285.001299) (xy 346.197174 -285.001716) (xy 343.174574 -285.001716)
			(xy 343.164506 -285.001289) (xy 343.145906 -284.993569) (xy 343.138506 -284.98673) (xy 343.127584 -284.975808)
			(xy 343.120185 -284.968963) (xy 343.101587 -284.961233) (xy 343.091516 -284.960822) (xy 342.570308 -284.960822)
			(xy 342.560238 -284.961244) (xy 342.541633 -284.968959) (xy 342.53424 -284.975808) (xy 342.390222 -285.119826)
			(xy 342.383377 -285.127225) (xy 342.375649 -285.145823) (xy 342.375236 -285.155894) (xy 342.375236 -285.720536)
			(xy 342.345518 -285.750254) (xy 342.33866 -285.750254) (xy 342.178132 -285.910782) (xy 342.170731 -285.91762)
			(xy 342.152132 -285.925332) (xy 342.142064 -285.925768) (xy 341.286338 -285.925768) (xy 341.276273 -285.925333)
			(xy 341.257688 -285.917599) (xy 341.25027 -285.910782) (xy 341.06612 -285.726632) (xy 341.058719 -285.719795)
			(xy 341.04012 -285.712084) (xy 341.030052 -285.711646) (xy 339.086444 -285.711646) (xy 339.067902 -285.704026)
			(xy 339.06587 -285.701994) (xy 339.06587 -284.651958) (xy 339.0663 -284.641891) (xy 339.074022 -284.623294)
			(xy 339.080856 -284.61589) (xy 339.081618 -284.615128) (xy 339.089016 -284.608281) (xy 339.107614 -284.600549)
			(xy 339.117686 -284.600142) (xy 340.190582 -284.600142) (xy 340.200644 -284.599702) (xy 340.219222 -284.59196)
			(xy 340.22665 -284.585156) (xy 340.251034 -284.560772) (xy 340.258431 -284.553923) (xy 340.27703 -284.54619)
			(xy 340.287102 -284.545786) (xy 340.841584 -284.545786) (xy 340.851647 -284.545347) (xy 340.870228 -284.53761)
			(xy 340.877652 -284.5308) (xy 340.89594 -284.512512) (xy 340.902795 -284.505117) (xy 340.910543 -284.486518)
			(xy 340.910926 -284.476444) (xy 340.910926 -284.37713) (xy 340.910486 -284.367099) (xy 340.90291 -284.348525)
			(xy 340.896194 -284.341062) (xy 340.86927 -284.314138) (xy 340.861872 -284.307292) (xy 340.843273 -284.299562)
			(xy 340.833202 -284.299152) (xy 340.22538 -284.299152) (xy 340.215312 -284.298724) (xy 340.196718 -284.290999)
			(xy 340.189312 -284.284166) (xy 339.986112 -284.080966) (xy 339.97927 -284.073566) (xy 339.971546 -284.054968)
			(xy 339.971126 -284.044898) (xy 339.971126 -283.33192) (xy 339.971564 -283.321857) (xy 339.979302 -283.303276)
			(xy 339.986112 -283.295852) (xy 340.078568 -283.203396) (xy 340.08597 -283.196561) (xy 340.104568 -283.188852)
			(xy 340.114636 -283.18841) (xy 340.873588 -283.18841) (xy 340.874858 -283.18714) (xy 340.874858 -282.9814)
			(xy 340.867238 -282.962858) (xy 340.86292 -282.95854) (xy 340.124796 -282.95854) (xy 340.114727 -282.958115)
			(xy 340.09613 -282.950392) (xy 340.088728 -282.943554) (xy 339.986112 -282.840938) (xy 339.979274 -282.833537)
			(xy 339.971561 -282.814938) (xy 339.971126 -282.80487) (xy 339.971126 -282.71343) (xy 339.970622 -282.703379)
			(xy 339.962903 -282.684815) (xy 339.95614 -282.677362) (xy 339.9409 -282.662122) (xy 339.933502 -282.655273)
			(xy 339.914904 -282.647535) (xy 339.904832 -282.647136) (xy 338.179156 -282.647136) (xy 338.173314 -282.652978)
			(xy 338.173314 -284.865064) (xy 338.17288 -284.875129) (xy 338.165151 -284.893718) (xy 338.158328 -284.901132)
			(xy 338.07273 -284.98673) (xy 338.065331 -284.993573) (xy 338.046732 -285.001293) (xy 338.036662 -285.001716)
			(xy 335.014062 -285.001716) (xy 335.003994 -285.001287) (xy 334.985398 -284.993564) (xy 334.977994 -284.98673)
			(xy 334.967072 -284.975808) (xy 334.959672 -284.968965) (xy 334.941074 -284.96124) (xy 334.931004 -284.960822)
			(xy 334.409796 -284.960822) (xy 334.399727 -284.961246) (xy 334.381125 -284.968964) (xy 334.373728 -284.975808)
			(xy 334.22971 -285.119826) (xy 334.222867 -285.127226) (xy 334.21514 -285.145824) (xy 334.214724 -285.155894)
			(xy 334.214724 -286.699452) (xy 340.923878 -286.699452) (xy 340.927951 -286.643793) (xy 340.940086 -286.58932)
			(xy 340.960022 -286.537194) (xy 340.987336 -286.488526) (xy 341.021444 -286.444354) (xy 341.061621 -286.405619)
			(xy 341.107009 -286.373147) (xy 341.156641 -286.347629) (xy 341.209461 -286.32961) (xy 341.26434 -286.319473)
			(xy 341.320111 -286.317435) (xy 341.375585 -286.323538) (xy 341.429578 -286.337654) (xy 341.480941 -286.359481)
			(xy 341.528579 -286.388554) (xy 341.571475 -286.424253) (xy 341.608717 -286.465817) (xy 341.639511 -286.512361)
			(xy 341.663199 -286.562892) (xy 341.673258 -286.596328) (xy 341.831928 -286.596328) (xy 341.836001 -286.540669)
			(xy 341.848136 -286.486196) (xy 341.868072 -286.43407) (xy 341.895386 -286.385402) (xy 341.929494 -286.34123)
			(xy 341.969671 -286.302495) (xy 342.015059 -286.270023) (xy 342.064691 -286.244505) (xy 342.117511 -286.226486)
			(xy 342.17239 -286.216349) (xy 342.228161 -286.214311) (xy 342.283635 -286.220414) (xy 342.337628 -286.23453)
			(xy 342.388991 -286.256357) (xy 342.436629 -286.28543) (xy 342.479525 -286.321129) (xy 342.516767 -286.362693)
			(xy 342.547561 -286.409237) (xy 342.571249 -286.459768) (xy 342.587327 -286.51321) (xy 342.595453 -286.568424)
			(xy 342.595962 -286.596328) (xy 342.595453 -286.624232) (xy 342.587327 -286.679446) (xy 342.571249 -286.732888)
			(xy 342.547561 -286.783419) (xy 342.51909 -286.826452) (xy 357.611678 -286.826452) (xy 357.615751 -286.770793)
			(xy 357.627886 -286.71632) (xy 357.647822 -286.664194) (xy 357.675136 -286.615526) (xy 357.709244 -286.571354)
			(xy 357.749421 -286.532619) (xy 357.794809 -286.500147) (xy 357.844441 -286.474629) (xy 357.897261 -286.45661)
			(xy 357.95214 -286.446473) (xy 358.007911 -286.444435) (xy 358.063385 -286.450538) (xy 358.117378 -286.464654)
			(xy 358.168741 -286.486481) (xy 358.216379 -286.515554) (xy 358.259275 -286.551253) (xy 358.296517 -286.592817)
			(xy 358.327311 -286.639361) (xy 358.350999 -286.689892) (xy 358.365796 -286.739076) (xy 358.564686 -286.739076)
			(xy 358.568759 -286.683417) (xy 358.580894 -286.628944) (xy 358.60083 -286.576818) (xy 358.628144 -286.52815)
			(xy 358.662252 -286.483978) (xy 358.702429 -286.445243) (xy 358.747817 -286.412771) (xy 358.797449 -286.387253)
			(xy 358.850269 -286.369234) (xy 358.905148 -286.359097) (xy 358.960919 -286.357059) (xy 359.016393 -286.363162)
			(xy 359.070386 -286.377278) (xy 359.121749 -286.399105) (xy 359.169387 -286.428178) (xy 359.212283 -286.463877)
			(xy 359.249525 -286.505441) (xy 359.280319 -286.551985) (xy 359.304007 -286.602516) (xy 359.320085 -286.655958)
			(xy 359.328211 -286.711172) (xy 359.32872 -286.739076) (xy 359.328211 -286.76698) (xy 359.320085 -286.822194)
			(xy 359.304007 -286.875636) (xy 359.280319 -286.926167) (xy 359.249525 -286.972711) (xy 359.212283 -287.014275)
			(xy 359.169387 -287.049974) (xy 359.121749 -287.079047) (xy 359.070386 -287.100874) (xy 359.016393 -287.11499)
			(xy 358.960919 -287.121093) (xy 358.905148 -287.119055) (xy 358.850269 -287.108918) (xy 358.797449 -287.090899)
			(xy 358.747817 -287.065381) (xy 358.702429 -287.032909) (xy 358.662252 -286.994174) (xy 358.628144 -286.950002)
			(xy 358.60083 -286.901334) (xy 358.580894 -286.849208) (xy 358.568759 -286.794735) (xy 358.564686 -286.739076)
			(xy 358.365796 -286.739076) (xy 358.367077 -286.743334) (xy 358.375203 -286.798548) (xy 358.375712 -286.826452)
			(xy 358.375203 -286.854356) (xy 358.367077 -286.90957) (xy 358.350999 -286.963012) (xy 358.327311 -287.013543)
			(xy 358.296517 -287.060087) (xy 358.259275 -287.101651) (xy 358.216379 -287.13735) (xy 358.168741 -287.166423)
			(xy 358.117378 -287.18825) (xy 358.063385 -287.202366) (xy 358.007911 -287.208469) (xy 357.95214 -287.206431)
			(xy 357.897261 -287.196294) (xy 357.844441 -287.178275) (xy 357.794809 -287.152757) (xy 357.749421 -287.120285)
			(xy 357.709244 -287.08155) (xy 357.675136 -287.037378) (xy 357.647822 -286.98871) (xy 357.627886 -286.936584)
			(xy 357.615751 -286.882111) (xy 357.611678 -286.826452) (xy 342.51909 -286.826452) (xy 342.516767 -286.829963)
			(xy 342.479525 -286.871527) (xy 342.436629 -286.907226) (xy 342.388991 -286.936299) (xy 342.337628 -286.958126)
			(xy 342.283635 -286.972242) (xy 342.228161 -286.978345) (xy 342.17239 -286.976307) (xy 342.117511 -286.96617)
			(xy 342.064691 -286.948151) (xy 342.015059 -286.922633) (xy 341.969671 -286.890161) (xy 341.929494 -286.851426)
			(xy 341.895386 -286.807254) (xy 341.868072 -286.758586) (xy 341.848136 -286.70646) (xy 341.836001 -286.651987)
			(xy 341.831928 -286.596328) (xy 341.673258 -286.596328) (xy 341.679277 -286.616334) (xy 341.687403 -286.671548)
			(xy 341.687912 -286.699452) (xy 341.687403 -286.727356) (xy 341.679277 -286.78257) (xy 341.663199 -286.836012)
			(xy 341.639511 -286.886543) (xy 341.608717 -286.933087) (xy 341.571475 -286.974651) (xy 341.528579 -287.01035)
			(xy 341.480941 -287.039423) (xy 341.429578 -287.06125) (xy 341.375585 -287.075366) (xy 341.320111 -287.081469)
			(xy 341.26434 -287.079431) (xy 341.209461 -287.069294) (xy 341.156641 -287.051275) (xy 341.107009 -287.025757)
			(xy 341.061621 -286.993285) (xy 341.021444 -286.95455) (xy 340.987336 -286.910378) (xy 340.960022 -286.86171)
			(xy 340.940086 -286.809584) (xy 340.927951 -286.755111) (xy 340.923878 -286.699452) (xy 334.214724 -286.699452)
			(xy 334.214724 -287.845754) (xy 334.214975 -287.853373) (xy 334.21903 -287.866836) (xy 335.63433 -287.866836)
			(xy 335.63433 -287.151572) (xy 335.64195 -287.13303) (xy 335.64449 -287.13049) (xy 335.651898 -287.123661)
			(xy 335.670491 -287.115935) (xy 335.680558 -287.115504) (xy 335.824322 -287.115504) (xy 335.824322 -287.118806)
			(xy 340.643972 -287.118806) (xy 340.65404 -287.119244) (xy 340.672638 -287.126956) (xy 340.68004 -287.133792)
			(xy 340.73719 -287.190942) (xy 340.74404 -287.198335) (xy 340.751754 -287.216939) (xy 340.752176 -287.22701)
			(xy 340.752176 -287.299654) (xy 340.753446 -287.300924) (xy 340.753446 -287.443926) (xy 343.762584 -287.443926)
			(xy 343.762584 -287.34004) (xy 343.763346 -287.339278) (xy 343.763346 -287.225994) (xy 343.763756 -287.215923)
			(xy 343.771486 -287.197324) (xy 343.778332 -287.189926) (xy 343.834466 -287.133792) (xy 343.841883 -287.126973)
			(xy 343.860469 -287.119241) (xy 343.870534 -287.118806) (xy 348.804484 -287.118806) (xy 348.814552 -287.119238)
			(xy 348.83315 -287.126954) (xy 348.840552 -287.133792) (xy 348.847918 -287.141158) (xy 348.854734 -287.148576)
			(xy 348.862467 -287.167162) (xy 348.862904 -287.177226) (xy 348.862904 -287.866328) (xy 352.300794 -287.866328)
			(xy 352.300794 -287.167828) (xy 352.301209 -287.157757) (xy 352.308934 -287.139158) (xy 352.31578 -287.13176)
			(xy 352.325178 -287.122362) (xy 352.332587 -287.115534) (xy 352.35118 -287.107808) (xy 352.361246 -287.107376)
			(xy 352.484436 -287.107376) (xy 352.484436 -287.118806) (xy 357.30307 -287.118806) (xy 357.313138 -287.119246)
			(xy 357.331736 -287.126956) (xy 357.339138 -287.133792) (xy 357.396288 -287.190942) (xy 357.403137 -287.198335)
			(xy 357.410852 -287.21694) (xy 357.411274 -287.22701) (xy 357.411274 -287.299654) (xy 357.412544 -287.300924)
			(xy 357.412544 -287.443926) (xy 360.421682 -287.443926) (xy 360.421682 -287.34004) (xy 360.422444 -287.339278)
			(xy 360.422444 -287.225994) (xy 360.422855 -287.215923) (xy 360.430584 -287.197324) (xy 360.43743 -287.189926)
			(xy 360.493564 -287.133792) (xy 360.500982 -287.126974) (xy 360.519567 -287.119242) (xy 360.529632 -287.118806)
			(xy 365.463582 -287.118806) (xy 365.47365 -287.119239) (xy 365.492248 -287.126954) (xy 365.49965 -287.133792)
			(xy 365.507016 -287.141158) (xy 365.513832 -287.148577) (xy 365.521565 -287.167162) (xy 365.522002 -287.177226)
			(xy 365.522002 -292.461696) (xy 365.521601 -292.471769) (xy 365.513866 -292.490368) (xy 365.507016 -292.497764)
			(xy 365.465614 -292.539166) (xy 365.458199 -292.545988) (xy 365.439611 -292.553719) (xy 365.429546 -292.554152)
			(xy 360.607356 -292.554152) (xy 360.597309 -292.553793) (xy 360.578713 -292.546198) (xy 360.571288 -292.53942)
			(xy 360.438954 -292.407086) (xy 360.432109 -292.39969) (xy 360.424394 -292.381087) (xy 360.423968 -292.371018)
			(xy 360.423968 -287.443926) (xy 360.421682 -287.443926) (xy 357.412544 -287.443926) (xy 357.411274 -287.443926)
			(xy 357.411274 -292.468808) (xy 357.41086 -292.478879) (xy 357.403132 -292.497477) (xy 357.396288 -292.504876)
			(xy 357.340408 -292.560756) (xy 357.332994 -292.567579) (xy 357.314406 -292.57531) (xy 357.30434 -292.575742)
			(xy 352.704654 -292.575742) (xy 352.694586 -292.575304) (xy 352.675987 -292.567594) (xy 352.668586 -292.560756)
			(xy 352.362262 -292.254432) (xy 352.355438 -292.247019) (xy 352.34771 -292.22843) (xy 352.347276 -292.218364)
			(xy 352.347276 -287.954974) (xy 352.34687 -287.944902) (xy 352.339136 -287.926305) (xy 352.33229 -287.918906)
			(xy 352.31578 -287.902396) (xy 352.308943 -287.894994) (xy 352.301222 -287.876396) (xy 352.300794 -287.866328)
			(xy 348.862904 -287.866328) (xy 348.862904 -292.461696) (xy 348.862502 -292.471768) (xy 348.854768 -292.490368)
			(xy 348.847918 -292.497764) (xy 348.806516 -292.539166) (xy 348.7991 -292.545987) (xy 348.780513 -292.553719)
			(xy 348.770448 -292.554152) (xy 343.948258 -292.554152) (xy 343.938211 -292.553792) (xy 343.919615 -292.546197)
			(xy 343.91219 -292.53942) (xy 343.779856 -292.407086) (xy 343.773011 -292.39969) (xy 343.765296 -292.381087)
			(xy 343.76487 -292.371018) (xy 343.76487 -287.443926) (xy 343.762584 -287.443926) (xy 340.753446 -287.443926)
			(xy 340.752176 -287.443926) (xy 340.752176 -292.468808) (xy 340.751761 -292.478879) (xy 340.744034 -292.497477)
			(xy 340.73719 -292.504876) (xy 340.68131 -292.560756) (xy 340.673895 -292.567578) (xy 340.655308 -292.57531)
			(xy 340.645242 -292.575742) (xy 336.045556 -292.575742) (xy 336.035482 -292.575355) (xy 336.016884 -292.567609)
			(xy 336.009488 -292.560756) (xy 335.703164 -292.254432) (xy 335.69634 -292.247019) (xy 335.688612 -292.22843)
			(xy 335.688178 -292.218364) (xy 335.688178 -287.962848) (xy 335.687733 -287.952781) (xy 335.680027 -287.934183)
			(xy 335.673192 -287.92678) (xy 335.649316 -287.902904) (xy 335.642487 -287.895495) (xy 335.63476 -287.876903)
			(xy 335.63433 -287.866836) (xy 334.21903 -287.866836) (xy 334.219369 -287.867961) (xy 334.22336 -287.874456)
			(xy 334.269283 -287.943142) (xy 334.355313 -288.084225) (xy 334.43453 -288.229243) (xy 334.506755 -288.377867)
			(xy 334.571824 -288.529761) (xy 334.629589 -288.68458) (xy 334.67992 -288.841972) (xy 334.722702 -289.001582)
			(xy 334.757839 -289.163047) (xy 334.785251 -289.326002) (xy 334.804875 -289.490077) (xy 334.816667 -289.654899)
			(xy 334.820601 -289.820097) (xy 334.816668 -289.985294) (xy 334.804875 -290.150117) (xy 334.785252 -290.314192)
			(xy 334.75784 -290.477146) (xy 334.722704 -290.638612) (xy 334.679922 -290.798221) (xy 334.629591 -290.955614)
			(xy 334.571826 -291.110433) (xy 334.506757 -291.262326) (xy 334.434533 -291.410951) (xy 334.355316 -291.555969)
			(xy 334.269286 -291.697053) (xy 334.22336 -291.765736) (xy 334.2193 -291.772199) (xy 334.2149 -291.786808)
			(xy 334.214724 -291.794438) (xy 334.214724 -293.472362) (xy 334.215159 -293.482427) (xy 334.222892 -293.501013)
			(xy 334.22971 -293.50843) (xy 334.37576 -293.65448) (xy 334.383161 -293.661319) (xy 334.401759 -293.669035)
			(xy 334.411828 -293.669466)
		)
		(stroke
			(width 0)
			(type solid)
		)
		(fill yes)
		(layer "F.Cu")
		(net "GND")
	)
	(gr_poly
		(pts
			(xy 462.374742 -340.523322) (xy 462.384809 -340.522892) (xy 462.403405 -340.515169) (xy 462.41081 -340.508336)
			(xy 463.09915 -339.819996) (xy 463.104136 -339.814496) (xy 463.110979 -339.80133) (xy 463.112612 -339.794088)
			(xy 463.113628 -339.784436) (xy 463.113628 -336.427064) (xy 463.113793 -336.422239) (xy 463.115716 -336.412779)
			(xy 463.117438 -336.408268) (xy 463.117438 -336.40776) (xy 463.125058 -336.388964) (xy 463.126468 -336.384785)
			(xy 463.128002 -336.376101) (xy 463.128106 -336.371692) (xy 463.128106 -334.743552) (xy 463.128229 -334.738599)
			(xy 463.130157 -334.728881) (xy 463.131916 -334.724248) (xy 463.134964 -334.716882) (xy 463.136602 -334.712612)
			(xy 463.138514 -334.703669) (xy 463.138774 -334.699102) (xy 463.138774 -327.410572) (xy 463.138281 -327.40057)
			(xy 463.130615 -327.382092) (xy 463.116462 -327.367954) (xy 463.097977 -327.360309) (xy 463.087974 -327.359772)
			(xy 443.490096 -327.359772) (xy 443.484088 -327.359945) (xy 443.472411 -327.362779) (xy 443.466982 -327.36536)
			(xy 443.463507 -327.367198) (xy 443.457125 -327.371789) (xy 443.454282 -327.374504) (xy 440.9059 -329.922886)
			(xy 440.898502 -329.929734) (xy 440.879904 -329.93747) (xy 440.869832 -329.937872) (xy 373.176546 -329.937872)
			(xy 373.170536 -329.93804) (xy 373.158854 -329.940863) (xy 373.153432 -329.94346) (xy 373.149955 -329.945296)
			(xy 373.143569 -329.949882) (xy 373.140732 -329.952604) (xy 368.134138 -334.959198) (xy 368.126736 -334.966035)
			(xy 368.108138 -334.973747) (xy 368.09807 -334.974184) (xy 361.3404 -334.974184) (xy 361.33033 -334.97376)
			(xy 361.311727 -334.966044) (xy 361.304332 -334.959198) (xy 358.311196 -331.966062) (xy 358.308346 -331.963355)
			(xy 358.301968 -331.95876) (xy 358.298496 -331.956918) (xy 358.292146 -331.953616) (xy 358.284018 -331.952092)
			(xy 358.25824 -331.947301) (xy 358.208222 -331.931579) (xy 358.160827 -331.909156) (xy 358.11695 -331.880453)
			(xy 358.077416 -331.846013) (xy 358.042972 -331.806483) (xy 358.014265 -331.762609) (xy 357.991836 -331.715217)
			(xy 357.976109 -331.6652) (xy 357.971344 -331.639418) (xy 357.96982 -331.63129) (xy 357.966518 -331.62494)
			(xy 357.964682 -331.621463) (xy 357.960095 -331.615078) (xy 357.957374 -331.61224) (xy 356.297738 -329.952604)
			(xy 356.294887 -329.949898) (xy 356.28851 -329.945303) (xy 356.285038 -329.94346) (xy 356.279611 -329.940876)
			(xy 356.267932 -329.938053) (xy 356.261924 -329.937872) (xy 344.77452 -329.937872) (xy 344.769694 -329.938888)
			(xy 344.751527 -329.942232) (xy 344.714759 -329.945798) (xy 344.696288 -329.946) (xy 344.69578 -329.946)
			(xy 344.695272 -329.946) (xy 344.676803 -329.945773) (xy 344.640036 -329.942206) (xy 344.621866 -329.938888)
			(xy 344.61704 -329.937872) (xy 343.40292 -329.937872) (xy 343.398094 -329.938888) (xy 343.379927 -329.942232)
			(xy 343.343159 -329.945798) (xy 343.324688 -329.946) (xy 343.32418 -329.946) (xy 343.323672 -329.946)
			(xy 343.305203 -329.945773) (xy 343.268436 -329.942206) (xy 343.250266 -329.938888) (xy 343.24544 -329.937872)
			(xy 342.03132 -329.937872) (xy 342.026494 -329.938888) (xy 342.008327 -329.942232) (xy 341.971559 -329.945798)
			(xy 341.953088 -329.946) (xy 341.95258 -329.946) (xy 341.952072 -329.946) (xy 341.933603 -329.945773)
			(xy 341.896836 -329.942206) (xy 341.878666 -329.938888) (xy 341.87384 -329.937872) (xy 340.65972 -329.937872)
			(xy 340.654894 -329.938888) (xy 340.636727 -329.942232) (xy 340.599959 -329.945798) (xy 340.581488 -329.946)
			(xy 340.58098 -329.946) (xy 340.580472 -329.946) (xy 340.562003 -329.945773) (xy 340.525236 -329.942206)
			(xy 340.507066 -329.938888) (xy 340.50224 -329.937872) (xy 339.28812 -329.937872) (xy 339.283294 -329.938888)
			(xy 339.265127 -329.942232) (xy 339.228359 -329.945798) (xy 339.209888 -329.946) (xy 339.20938 -329.946)
			(xy 339.208872 -329.946) (xy 339.190403 -329.945773) (xy 339.153636 -329.942206) (xy 339.135466 -329.938888)
			(xy 339.13064 -329.937872) (xy 337.91652 -329.937872) (xy 337.911694 -329.938888) (xy 337.893527 -329.942232)
			(xy 337.856759 -329.945798) (xy 337.838288 -329.946) (xy 337.83778 -329.946) (xy 337.837272 -329.946)
			(xy 337.818803 -329.945773) (xy 337.782036 -329.942206) (xy 337.763866 -329.938888) (xy 337.75904 -329.937872)
			(xy 331.241908 -329.937872) (xy 331.238302 -329.937934) (xy 331.231163 -329.938953) (xy 331.227684 -329.939904)
			(xy 331.207618 -329.945746) (xy 331.201776 -329.949302) (xy 331.180264 -329.962207) (xy 331.135367 -329.984595)
			(xy 331.112114 -329.994006) (xy 331.075323 -330.007727) (xy 330.998975 -330.026075) (xy 330.959968 -330.030582)
			(xy 330.956412 -330.03109) (xy 330.932282 -330.035003) (xy 330.883574 -330.039201) (xy 330.85913 -330.039472)
			(xy 267.463524 -330.039472) (xy 267.443264 -330.039322) (xy 267.40284 -330.036528) (xy 267.382752 -330.033884)
			(xy 267.379196 -330.033376) (xy 267.075412 -330.033376) (xy 267.044101 -330.032946) (xy 266.981858 -330.02606)
			(xy 266.920751 -330.012369) (xy 266.86152 -329.992042) (xy 266.804884 -329.965322) (xy 266.777978 -329.949302)
			(xy 266.772136 -329.945746) (xy 266.75207 -329.939904) (xy 266.748591 -329.938952) (xy 266.741452 -329.937926)
			(xy 266.737846 -329.937872) (xy 256.619502 -329.937872) (xy 256.613494 -329.938045) (xy 256.601816 -329.940877)
			(xy 256.596388 -329.94346) (xy 256.592913 -329.945298) (xy 256.586531 -329.949888) (xy 256.583688 -329.952604)
			(xy 256.473706 -330.062586) (xy 256.466309 -330.069435) (xy 256.44771 -330.077174) (xy 256.437638 -330.077572)
			(xy 250.934728 -330.077572) (xy 250.928719 -330.077742) (xy 250.917038 -330.080569) (xy 250.911614 -330.08316)
			(xy 250.908138 -330.084997) (xy 250.901753 -330.089585) (xy 250.898914 -330.092304) (xy 250.38939 -330.601828)
			(xy 250.382396 -330.609576) (xy 250.374776 -330.628984) (xy 250.374658 -330.63942) (xy 250.377198 -330.713334)
			(xy 250.377465 -330.718737) (xy 250.380023 -330.729245) (xy 250.382278 -330.734162) (xy 250.38685 -330.743306)
			(xy 250.39447 -330.750164) (xy 250.414591 -330.768357) (xy 250.449991 -330.809458) (xy 250.475734 -330.849732)
			(xy 250.668534 -330.849732) (xy 250.672607 -330.794073) (xy 250.684742 -330.7396) (xy 250.704678 -330.687474)
			(xy 250.731992 -330.638806) (xy 250.7661 -330.594634) (xy 250.806277 -330.555899) (xy 250.851665 -330.523427)
			(xy 250.901297 -330.497909) (xy 250.954117 -330.47989) (xy 251.008996 -330.469753) (xy 251.064767 -330.467715)
			(xy 251.120241 -330.473818) (xy 251.174234 -330.487934) (xy 251.225597 -330.509761) (xy 251.273235 -330.538834)
			(xy 251.316131 -330.574533) (xy 251.353373 -330.616097) (xy 251.384167 -330.662641) (xy 251.407855 -330.713172)
			(xy 251.423933 -330.766614) (xy 251.432059 -330.821828) (xy 251.432568 -330.849732) (xy 251.432059 -330.877636)
			(xy 251.423933 -330.93285) (xy 251.407855 -330.986292) (xy 251.402692 -330.997306) (xy 351.42119 -330.997306)
			(xy 351.425261 -330.941684) (xy 351.437387 -330.887247) (xy 351.45731 -330.835156) (xy 351.484606 -330.786521)
			(xy 351.518692 -330.742378) (xy 351.558841 -330.703669) (xy 351.604199 -330.671218) (xy 351.653799 -330.645717)
			(xy 351.706583 -330.62771) (xy 351.761426 -330.61758) (xy 351.81716 -330.615543) (xy 351.872597 -330.621643)
			(xy 351.926554 -330.635749) (xy 351.977883 -330.657561) (xy 352.025489 -330.686615) (xy 352.068357 -330.72229)
			(xy 352.105574 -330.763827) (xy 352.136347 -330.81034) (xy 352.160019 -330.860837) (xy 352.176087 -330.914244)
			(xy 352.184207 -330.96942) (xy 352.184716 -330.997306) (xy 352.43719 -330.997306) (xy 352.441261 -330.941684)
			(xy 352.453387 -330.887247) (xy 352.47331 -330.835156) (xy 352.500606 -330.786521) (xy 352.534692 -330.742378)
			(xy 352.574841 -330.703669) (xy 352.620199 -330.671218) (xy 352.669799 -330.645717) (xy 352.722583 -330.62771)
			(xy 352.777426 -330.61758) (xy 352.83316 -330.615543) (xy 352.888597 -330.621643) (xy 352.942554 -330.635749)
			(xy 352.993883 -330.657561) (xy 353.041489 -330.686615) (xy 353.084357 -330.72229) (xy 353.121574 -330.763827)
			(xy 353.152347 -330.81034) (xy 353.176019 -330.860837) (xy 353.192087 -330.914244) (xy 353.200207 -330.96942)
			(xy 353.200716 -330.997306) (xy 353.200207 -331.025192) (xy 353.192087 -331.080368) (xy 353.176019 -331.133775)
			(xy 353.152347 -331.184272) (xy 353.121574 -331.230785) (xy 353.084357 -331.272322) (xy 353.041489 -331.307997)
			(xy 352.993883 -331.337051) (xy 352.942554 -331.358863) (xy 352.888597 -331.372969) (xy 352.83316 -331.379069)
			(xy 352.777426 -331.377032) (xy 352.722583 -331.366902) (xy 352.669799 -331.348895) (xy 352.620199 -331.323394)
			(xy 352.574841 -331.290943) (xy 352.534692 -331.252234) (xy 352.500606 -331.208091) (xy 352.47331 -331.159456)
			(xy 352.453387 -331.107365) (xy 352.441261 -331.052928) (xy 352.43719 -330.997306) (xy 352.184716 -330.997306)
			(xy 352.184207 -331.025192) (xy 352.176087 -331.080368) (xy 352.160019 -331.133775) (xy 352.136347 -331.184272)
			(xy 352.105574 -331.230785) (xy 352.068357 -331.272322) (xy 352.025489 -331.307997) (xy 351.977883 -331.337051)
			(xy 351.926554 -331.358863) (xy 351.872597 -331.372969) (xy 351.81716 -331.379069) (xy 351.761426 -331.377032)
			(xy 351.706583 -331.366902) (xy 351.653799 -331.348895) (xy 351.604199 -331.323394) (xy 351.558841 -331.290943)
			(xy 351.518692 -331.252234) (xy 351.484606 -331.208091) (xy 351.45731 -331.159456) (xy 351.437387 -331.107365)
			(xy 351.425261 -331.052928) (xy 351.42119 -330.997306) (xy 251.402692 -330.997306) (xy 251.384167 -331.036823)
			(xy 251.353373 -331.083367) (xy 251.316131 -331.124931) (xy 251.273235 -331.16063) (xy 251.225597 -331.189703)
			(xy 251.174234 -331.21153) (xy 251.120241 -331.225646) (xy 251.064767 -331.231749) (xy 251.008996 -331.229711)
			(xy 250.954117 -331.219574) (xy 250.901297 -331.201555) (xy 250.851665 -331.176037) (xy 250.806277 -331.143565)
			(xy 250.7661 -331.10483) (xy 250.731992 -331.060658) (xy 250.704678 -331.01199) (xy 250.684742 -330.959864)
			(xy 250.672607 -330.905391) (xy 250.668534 -330.849732) (xy 250.475734 -330.849732) (xy 250.479205 -330.855163)
			(xy 250.501644 -330.904549) (xy 250.516853 -330.956617) (xy 250.524525 -331.010316) (xy 250.525026 -331.037438)
			(xy 250.52453 -331.065211) (xy 250.516484 -331.120171) (xy 250.500554 -331.173383) (xy 250.477076 -331.223723)
			(xy 250.446546 -331.270126) (xy 250.40961 -331.311612) (xy 250.367049 -331.347303) (xy 250.34367 -331.362304)
			(xy 250.336387 -331.368224) (xy 250.326475 -331.384146) (xy 250.324366 -331.393292) (xy 250.32335 -331.402944)
			(xy 250.32335 -336.009996) (xy 250.324366 -336.019648) (xy 250.325995 -336.026891) (xy 250.332839 -336.040058)
			(xy 250.337828 -336.045556) (xy 251.090684 -336.798412) (xy 251.09753 -336.805811) (xy 251.105263 -336.824409)
			(xy 251.10567 -336.83448) (xy 251.10567 -336.899758) (xy 251.105767 -336.903903) (xy 251.107174 -336.912074)
			(xy 251.108464 -336.916014) (xy 251.11075 -336.923126) (xy 251.11583 -336.929984) (xy 251.131763 -336.952055)
			(xy 251.159758 -336.998745) (xy 251.17171 -337.023202) (xy 254.6604 -340.511892) (xy 262.89254 -340.511892)
			(xy 262.896145 -340.511826) (xy 262.903283 -340.510803) (xy 262.906764 -340.50986) (xy 263.038082 -340.378542)
			(xy 263.056224 -340.361121) (xy 263.096927 -340.331578) (xy 263.141745 -340.308753) (xy 263.189576 -340.293207)
			(xy 263.239249 -340.285322) (xy 263.264396 -340.284816) (xy 267.470128 -340.284816) (xy 267.480196 -340.284388)
			(xy 267.498795 -340.276669) (xy 267.506196 -340.26983) (xy 268.296898 -339.478874) (xy 268.30374 -339.471474)
			(xy 268.311466 -339.452876) (xy 268.311884 -339.442806) (xy 268.311884 -334.507078) (xy 268.308446 -334.501229)
			(xy 268.299042 -334.491455) (xy 268.293342 -334.487774) (xy 268.287926 -334.484845) (xy 268.276114 -334.481385)
			(xy 268.269974 -334.480916) (xy 268.0208 -334.480916) (xy 268.01078 -334.481336) (xy 267.992266 -334.489006)
			(xy 267.978097 -334.503179) (xy 267.970432 -334.521696) (xy 267.97 -334.531716) (xy 267.97 -334.54086)
			(xy 267.705078 -334.54086) (xy 267.70457 -334.54086) (xy 267.684839 -334.540623) (xy 267.645916 -334.534163)
			(xy 267.608699 -334.521062) (xy 267.574313 -334.501714) (xy 267.558774 -334.489552) (xy 267.553186 -334.485996)
			(xy 266.888976 -334.485996) (xy 266.878816 -334.493616) (xy 266.858066 -334.517425) (xy 266.811636 -334.56024)
			(xy 266.760264 -334.596979) (xy 266.704739 -334.627076) (xy 266.645915 -334.650069) (xy 266.584698 -334.665603)
			(xy 266.522029 -334.673439) (xy 266.49045 -334.673956) (xy 266.489942 -334.673956) (xy 266.458361 -334.67348)
			(xy 266.395686 -334.665657) (xy 266.334463 -334.650127) (xy 266.275637 -334.627129) (xy 266.220114 -334.597018)
			(xy 266.168752 -334.560258) (xy 266.122341 -334.517416) (xy 266.101576 -334.493616) (xy 266.091416 -334.485996)
			(xy 265.594846 -334.485996) (xy 265.586974 -334.486294) (xy 265.571975 -334.491083) (xy 265.565382 -334.495394)
			(xy 265.562842 -334.497172) (xy 265.55573 -334.514698) (xy 265.555222 -334.515714) (xy 265.549321 -334.52992)
			(xy 265.531831 -334.555215) (xy 265.508807 -334.575601) (xy 265.481579 -334.589897) (xy 265.451726 -334.597277)
			(xy 265.43635 -334.597756) (xy 264.36955 -334.597756) (xy 264.352894 -334.597208) (xy 264.320716 -334.588587)
			(xy 264.291859 -334.571942) (xy 264.268284 -334.548405) (xy 264.251593 -334.519575) (xy 264.242919 -334.487411)
			(xy 264.242296 -334.470756) (xy 264.242296 -334.240886) (xy 264.240518 -334.227932) (xy 264.240264 -334.226662)
			(xy 264.049256 -334.035654) (xy 264.031766 -334.017525) (xy 264.002134 -333.976791) (xy 263.979242 -333.931921)
			(xy 263.963655 -333.884021) (xy 263.955758 -333.834272) (xy 263.955276 -333.809086) (xy 263.955276 -333.316326)
			(xy 263.95579 -333.291143) (xy 263.963703 -333.241403) (xy 263.979291 -333.19351) (xy 264.002172 -333.148641)
			(xy 264.031783 -333.107899) (xy 264.049256 -333.089758) (xy 264.08761 -333.051404) (xy 264.089414 -333.044128)
			(xy 264.089156 -333.029149) (xy 264.087102 -333.02194) (xy 264.053574 -332.988412) (xy 264.052304 -332.987904)
			(xy 264.03427 -332.98638) (xy 264.013366 -332.98426) (xy 263.972819 -332.973263) (xy 263.935001 -332.954963)
			(xy 263.901217 -332.929991) (xy 263.872627 -332.899206) (xy 263.850218 -332.86367) (xy 263.834761 -332.824604)
			(xy 263.826788 -332.783356) (xy 263.826244 -332.762352) (xy 263.826244 -332.759304) (xy 263.826244 -332.718664)
			(xy 263.824466 -332.705456) (xy 263.823196 -332.704186) (xy 263.815801 -332.697331) (xy 263.797202 -332.689584)
			(xy 263.787128 -332.6892) (xy 263.230106 -332.6892) (xy 263.221089 -332.689559) (xy 263.204172 -332.695804)
			(xy 263.197086 -332.701392) (xy 263.191244 -332.706472) (xy 263.186926 -332.73111) (xy 263.181372 -332.76058)
			(xy 263.164246 -332.818054) (xy 263.14048 -332.873116) (xy 263.110403 -332.925) (xy 263.074433 -332.972987)
			(xy 263.054084 -332.995016) (xy 263.034272 -333.014828) (xy 263.027922 -333.020924) (xy 263.02208 -333.034132)
			(xy 263.019966 -333.039079) (xy 263.01765 -333.049583) (xy 263.017508 -333.05496) (xy 263.017508 -333.908908)
			(xy 263.017047 -333.934061) (xy 263.009188 -333.983748) (xy 262.99365 -334.031593) (xy 262.970814 -334.076417)
			(xy 262.941245 -334.117114) (xy 262.923782 -334.135222) (xy 262.865616 -334.193388) (xy 262.865362 -334.19415)
			(xy 262.863584 -334.207358) (xy 262.863584 -334.46593) (xy 262.863838 -334.469994) (xy 262.863323 -334.486692)
			(xy 262.85475 -334.518966) (xy 262.838132 -334.547932) (xy 262.826754 -334.560164) (xy 262.821674 -334.56499)
			(xy 262.81634 -334.569816) (xy 262.813546 -334.572102) (xy 262.809228 -334.581754) (xy 262.807196 -334.586652)
			(xy 262.805019 -334.597027) (xy 262.80491 -334.602328) (xy 262.80491 -334.678274) (xy 262.805048 -334.683572)
			(xy 262.807222 -334.693943) (xy 262.809228 -334.698848) (xy 262.813546 -334.7085) (xy 262.821674 -334.715866)
			(xy 262.834533 -334.728238) (xy 262.853438 -334.758486) (xy 262.86327 -334.792773) (xy 262.863838 -334.810608)
			(xy 262.863838 -335.700624) (xy 262.864187 -335.709578) (xy 262.870338 -335.726396) (xy 262.881886 -335.740084)
			(xy 262.889492 -335.74482) (xy 262.969248 -335.74482) (xy 262.994429 -335.745339) (xy 263.044164 -335.753261)
			(xy 263.092052 -335.768856) (xy 263.136915 -335.791741) (xy 263.177651 -335.821353) (xy 263.195816 -335.8388)
			(xy 263.575292 -336.218276) (xy 263.592783 -336.236404) (xy 263.622416 -336.277138) (xy 263.645307 -336.322008)
			(xy 263.660892 -336.369908) (xy 263.661014 -336.370676) (xy 264.242296 -336.370676) (xy 264.242296 -335.760568)
			(xy 264.242806 -335.743872) (xy 264.251445 -335.711618) (xy 264.268127 -335.682691) (xy 264.291718 -335.65906)
			(xy 264.320615 -335.642329) (xy 264.352855 -335.633635) (xy 264.36955 -335.63306) (xy 264.67562 -335.63306)
			(xy 264.681201 -335.632898) (xy 264.692095 -335.63047) (xy 264.69721 -335.628234) (xy 264.729535 -335.613696)
			(xy 264.797392 -335.593222) (xy 264.867511 -335.582878) (xy 264.90295 -335.58226) (xy 266.151868 -335.58226)
			(xy 266.183501 -335.582761) (xy 266.246229 -335.591005) (xy 266.307342 -335.60737) (xy 266.365796 -335.631575)
			(xy 266.420588 -335.663205) (xy 266.470781 -335.701719) (xy 266.493498 -335.723738) (xy 266.625324 -335.855564)
			(xy 266.633452 -335.863946) (xy 266.640564 -335.871566) (xy 266.659868 -335.879948) (xy 266.70762 -335.879948)
			(xy 266.726924 -335.871566) (xy 266.734036 -335.863946) (xy 266.756883 -335.84075) (xy 266.807754 -335.800114)
			(xy 266.86362 -335.766677) (xy 266.923469 -335.741043) (xy 266.986219 -335.723677) (xy 267.050732 -335.714893)
			(xy 267.083286 -335.71434) (xy 267.083794 -335.71434) (xy 267.115408 -335.714869) (xy 267.178094 -335.723121)
			(xy 267.239167 -335.739484) (xy 267.297582 -335.76368) (xy 267.352339 -335.795293) (xy 267.402501 -335.833782)
			(xy 267.44721 -335.87849) (xy 267.485701 -335.928651) (xy 267.517315 -335.983407) (xy 267.541512 -336.041821)
			(xy 267.557877 -336.102894) (xy 267.566131 -336.16558) (xy 267.566648 -336.197194) (xy 267.566648 -339.192362)
			(xy 267.567081 -339.202431) (xy 267.574795 -339.221029) (xy 267.581634 -339.22843) (xy 267.605764 -339.252306)
			(xy 267.627703 -339.274998) (xy 267.666095 -339.325098) (xy 267.697638 -339.379769) (xy 267.721796 -339.438082)
			(xy 267.738157 -339.499043) (xy 267.746442 -339.561615) (xy 267.746988 -339.593174) (xy 267.746988 -339.593936)
			(xy 267.746525 -339.625558) (xy 267.738269 -339.68826) (xy 267.721901 -339.749349) (xy 267.697703 -339.80778)
			(xy 267.666087 -339.862554) (xy 267.627595 -339.912735) (xy 267.582884 -339.957464) (xy 267.532719 -339.995977)
			(xy 267.477958 -340.027615) (xy 267.419537 -340.051837) (xy 267.358454 -340.06823) (xy 267.295756 -340.076512)
			(xy 267.264134 -340.077044) (xy 267.235501 -340.076574) (xy 267.178641 -340.069756) (xy 267.122985 -340.05627)
			(xy 267.06931 -340.036306) (xy 267.018369 -340.010142) (xy 266.994386 -339.994494) (xy 266.994132 -339.994494)
			(xy 266.98635 -339.989779) (xy 266.968654 -339.985606) (xy 266.959588 -339.986366) (xy 266.883642 -339.996272)
			(xy 266.867386 -340.005162) (xy 266.86129 -340.01202) (xy 266.84159 -340.033834) (xy 266.797762 -340.073003)
			(xy 266.749506 -340.106564) (xy 266.697533 -340.134021) (xy 266.642612 -340.154968) (xy 266.585556 -340.169095)
			(xy 266.527206 -340.176194) (xy 266.497816 -340.176612) (xy 266.466189 -340.176181) (xy 266.403472 -340.167965)
			(xy 266.342365 -340.151632) (xy 266.283912 -340.127461) (xy 266.229115 -340.095866) (xy 266.178911 -340.057389)
			(xy 266.156186 -340.035388) (xy 265.942064 -339.821266) (xy 265.920165 -339.798537) (xy 265.881768 -339.748446)
			(xy 265.850218 -339.693783) (xy 265.826053 -339.635477) (xy 265.809685 -339.574522) (xy 265.801391 -339.511955)
			(xy 265.80084 -339.480398) (xy 265.80084 -336.599276) (xy 265.800333 -336.589272) (xy 265.792673 -336.570787)
			(xy 265.778526 -336.556636) (xy 265.760044 -336.54897) (xy 265.75004 -336.548476) (xy 264.90295 -336.548476)
			(xy 264.867511 -336.547869) (xy 264.797394 -336.537512) (xy 264.729542 -336.517027) (xy 264.69721 -336.502502)
			(xy 264.692093 -336.500269) (xy 264.681201 -336.497826) (xy 264.67562 -336.497676) (xy 264.36955 -336.497676)
			(xy 264.352889 -336.497157) (xy 264.320702 -336.488534) (xy 264.291836 -336.471886) (xy 264.268253 -336.448344)
			(xy 264.251553 -336.419508) (xy 264.242873 -336.387336) (xy 264.242296 -336.370676) (xy 263.661014 -336.370676)
			(xy 263.668786 -336.419658) (xy 263.669272 -336.444844) (xy 263.669272 -339.15731) (xy 263.906 -339.15731)
			(xy 263.906 -338.54771) (xy 263.906595 -338.531054) (xy 263.915203 -338.498872) (xy 263.931835 -338.470009)
			(xy 263.955362 -338.446424) (xy 263.984185 -338.429722) (xy 264.016345 -338.421036) (xy 264.033 -338.420456)
			(xy 265.100308 -338.420456) (xy 265.116999 -338.421027) (xy 265.149247 -338.429657) (xy 265.178169 -338.446327)
			(xy 265.2018 -338.469906) (xy 265.218535 -338.498791) (xy 265.227236 -338.53102) (xy 265.227816 -338.54771)
			(xy 265.227816 -339.15731) (xy 265.227321 -339.173974) (xy 265.218702 -339.206169) (xy 265.202052 -339.235041)
			(xy 265.178505 -339.258626) (xy 265.14966 -339.275323) (xy 265.117479 -339.283994) (xy 265.100816 -339.284564)
			(xy 264.033508 -339.284564) (xy 264.016811 -339.284058) (xy 263.984552 -339.275425) (xy 263.955621 -339.258745)
			(xy 263.931988 -339.235152) (xy 263.915258 -339.206251) (xy 263.906571 -339.174006) (xy 263.906 -339.15731)
			(xy 263.669272 -339.15731) (xy 263.669272 -339.233764) (xy 263.668751 -339.258944) (xy 263.660827 -339.308678)
			(xy 263.64523 -339.356564) (xy 263.622344 -339.401425) (xy 263.59273 -339.442159) (xy 263.575292 -339.460332)
			(xy 263.000744 -340.03488) (xy 262.981642 -340.053202) (xy 262.938579 -340.083969) (xy 262.891059 -340.107269)
			(xy 262.86587 -340.115398) (xy 262.861806 -340.120478) (xy 262.859495 -340.124016) (xy 262.855923 -340.131674)
			(xy 262.854694 -340.135718) (xy 262.85029 -340.152314) (xy 262.833965 -340.182507) (xy 262.810212 -340.207285)
			(xy 262.780736 -340.22487) (xy 262.747649 -340.234002) (xy 262.730488 -340.234524) (xy 261.6581 -340.234524)
			(xy 261.641921 -340.233321) (xy 261.610919 -340.223788) (xy 261.583303 -340.206779) (xy 261.560838 -340.183385)
			(xy 261.544964 -340.155101) (xy 261.536696 -340.123739) (xy 261.53618 -340.107524) (xy 261.53618 -339.49767)
			(xy 261.536725 -339.481014) (xy 261.545344 -339.448835) (xy 261.561989 -339.419978) (xy 261.585527 -339.396405)
			(xy 261.614359 -339.379717) (xy 261.646525 -339.37105) (xy 261.66318 -339.370416) (xy 262.730488 -339.370416)
			(xy 262.741664 -339.37067) (xy 262.741918 -339.37067) (xy 262.754364 -339.371178) (xy 262.760206 -339.369146)
			(xy 262.830818 -339.298534) (xy 262.832539 -339.291654) (xy 262.832529 -339.277477) (xy 262.830818 -339.270594)
			(xy 262.795258 -339.235034) (xy 262.791702 -339.23351) (xy 262.783066 -339.23351) (xy 262.780526 -339.233764)
			(xy 262.766302 -339.233764) (xy 262.734688 -339.233247) (xy 262.672 -339.224995) (xy 262.610925 -339.20863)
			(xy 262.552509 -339.184434) (xy 262.497752 -339.15282) (xy 262.447588 -339.11433) (xy 262.402878 -339.069621)
			(xy 262.364386 -339.019458) (xy 262.332771 -338.964701) (xy 262.308574 -338.906286) (xy 262.292208 -338.845212)
			(xy 262.283954 -338.782524) (xy 262.283448 -338.75091) (xy 262.283448 -338.474304) (xy 262.28294 -338.466938)
			(xy 262.28183 -338.460697) (xy 262.276942 -338.449005) (xy 262.273288 -338.443824) (xy 262.268462 -338.438236)
			(xy 262.230616 -338.40039) (xy 262.225028 -338.395564) (xy 262.219844 -338.391917) (xy 262.208153 -338.38703)
			(xy 262.201914 -338.385912) (xy 262.194548 -338.385404) (xy 261.675626 -338.385404) (xy 261.66826 -338.385912)
			(xy 261.662101 -338.386996) (xy 261.650535 -338.391742) (xy 261.6454 -338.39531) (xy 261.639558 -338.40039)
			(xy 260.871716 -339.168486) (xy 260.848998 -339.190505) (xy 260.798805 -339.229019) (xy 260.744013 -339.26065)
			(xy 260.68556 -339.284855) (xy 260.624447 -339.301221) (xy 260.56172 -339.309467) (xy 260.530086 -339.309964)
			(xy 260.12521 -339.309964) (xy 260.093583 -339.309469) (xy 260.030871 -339.301212) (xy 259.969774 -339.284836)
			(xy 259.911338 -339.260624) (xy 259.856564 -339.228989) (xy 259.806389 -339.190472) (xy 259.761673 -339.145735)
			(xy 259.723181 -339.095541) (xy 259.691572 -339.040752) (xy 259.667388 -338.982304) (xy 259.651043 -338.921199)
			(xy 259.642815 -338.858483) (xy 259.642356 -338.826856) (xy 259.64288 -338.79426) (xy 259.651624 -338.729659)
			(xy 259.668972 -338.666819) (xy 259.694612 -338.606882) (xy 259.728077 -338.550936) (xy 259.768759 -338.499997)
			(xy 259.791962 -338.477098) (xy 259.792216 -338.476844) (xy 259.795938 -338.47323) (xy 259.801949 -338.464777)
			(xy 259.804154 -338.46008) (xy 259.807964 -338.450936) (xy 259.807964 -338.378292) (xy 259.807964 -338.378038)
			(xy 259.807542 -338.368945) (xy 259.801096 -338.351937) (xy 259.78911 -338.338255) (xy 259.781294 -338.333588)
			(xy 259.436362 -338.333588) (xy 259.428535 -338.338238) (xy 259.416553 -338.351929) (xy 259.41011 -338.368943)
			(xy 259.409692 -338.378038) (xy 259.409692 -338.386166) (xy 259.379974 -338.415884) (xy 258.826 -338.415884)
			(xy 258.81598 -338.415464) (xy 258.797466 -338.407794) (xy 258.783297 -338.393621) (xy 258.775632 -338.375104)
			(xy 258.7752 -338.365084) (xy 258.7752 -338.201508) (xy 258.7752 -338.198968) (xy 258.774232 -338.189325)
			(xy 258.766085 -338.171757) (xy 258.752044 -338.15842) (xy 258.73408 -338.151187) (xy 258.7244 -338.150708)
			(xy 258.715256 -338.150708) (xy 258.715256 -337.883246) (xy 258.715667 -337.86376) (xy 258.722349 -337.825364)
			(xy 258.735507 -337.788679) (xy 258.754751 -337.754789) (xy 258.766818 -337.739482) (xy 258.772152 -337.731608)
			(xy 258.772152 -336.521044) (xy 258.772617 -336.495892) (xy 258.780481 -336.446208) (xy 258.796024 -336.398367)
			(xy 258.818861 -336.353547) (xy 258.848431 -336.312852) (xy 258.865878 -336.29473) (xy 258.928362 -336.232246)
			(xy 258.930648 -336.22615) (xy 258.929886 -336.210148) (xy 258.929886 -336.209132) (xy 258.928616 -336.176874)
			(xy 258.928616 -336.176366) (xy 258.929094 -336.145645) (xy 258.936526 -336.084653) (xy 258.951254 -336.025001)
			(xy 258.973063 -335.967559) (xy 259.001635 -335.913164) (xy 259.036554 -335.862607) (xy 259.07731 -335.816628)
			(xy 259.123311 -335.775894) (xy 259.173884 -335.741001) (xy 259.228295 -335.712457) (xy 259.285748 -335.690677)
			(xy 259.345407 -335.675979) (xy 259.406402 -335.668578) (xy 259.437124 -335.668112) (xy 259.469854 -335.668621)
			(xy 259.534774 -335.677023) (xy 259.598078 -335.693686) (xy 259.658722 -335.718333) (xy 259.715702 -335.750557)
			(xy 259.768076 -335.789826) (xy 259.814979 -335.83549) (xy 259.855636 -335.886795) (xy 259.889373 -335.942892)
			(xy 259.915634 -336.002855) (xy 259.925312 -336.034126) (xy 259.92709 -336.040476) (xy 259.929728 -336.048333)
			(xy 259.939193 -336.061927) (xy 259.945632 -336.067146) (xy 259.94995 -336.070448) (xy 260.857746 -336.070448)
			(xy 260.867811 -336.070015) (xy 260.886399 -336.062283) (xy 260.893814 -336.055462) (xy 261.12978 -335.81975)
			(xy 261.147922 -335.802328) (xy 261.188625 -335.772784) (xy 261.233442 -335.749959) (xy 261.281274 -335.734412)
			(xy 261.330947 -335.726526) (xy 261.356094 -335.726024) (xy 261.515352 -335.726024) (xy 261.523212 -335.721346)
			(xy 261.535226 -335.707572) (xy 261.541644 -335.690459) (xy 261.542022 -335.68132) (xy 261.542022 -335.649316)
			(xy 261.541537 -335.639305) (xy 261.533881 -335.620803) (xy 261.519728 -335.60664) (xy 261.501233 -335.59897)
			(xy 261.491222 -335.598516) (xy 260.999732 -335.598516) (xy 260.98977 -335.599003) (xy 260.971348 -335.606593)
			(xy 260.963918 -335.613248) (xy 260.801866 -335.775554) (xy 260.779147 -335.797573) (xy 260.728953 -335.836088)
			(xy 260.674161 -335.867722) (xy 260.615709 -335.891934) (xy 260.554597 -335.908309) (xy 260.49187 -335.916567)
			(xy 260.428602 -335.916567) (xy 260.365875 -335.908309) (xy 260.304763 -335.891934) (xy 260.246311 -335.867722)
			(xy 260.191519 -335.836088) (xy 260.141325 -335.797573) (xy 260.118606 -335.775554) (xy 260.109716 -335.766664)
			(xy 260.085496 -335.741584) (xy 260.043793 -335.685711) (xy 260.010559 -335.62442) (xy 259.997956 -335.591912)
			(xy 259.988574 -335.565104) (xy 259.975427 -335.509849) (xy 259.968848 -335.453433) (xy 259.968492 -335.425034)
			(xy 259.968492 -334.949292) (xy 259.968492 -334.946752) (xy 259.967531 -334.937435) (xy 259.959857 -334.920365)
			(xy 259.946621 -334.907133) (xy 259.929549 -334.899465) (xy 259.920232 -334.898492) (xy 259.399786 -334.898492)
			(xy 259.368172 -334.897974) (xy 259.305484 -334.88972) (xy 259.24441 -334.873354) (xy 259.185994 -334.849158)
			(xy 259.131236 -334.817544) (xy 259.081073 -334.779053) (xy 259.036362 -334.734345) (xy 258.99787 -334.684184)
			(xy 258.966253 -334.629427) (xy 258.942053 -334.571013) (xy 258.925685 -334.50994) (xy 258.917427 -334.447252)
			(xy 258.916932 -334.415638) (xy 258.916932 -334.41513) (xy 258.917489 -334.382578) (xy 258.926279 -334.318068)
			(xy 258.943651 -334.255323) (xy 258.969289 -334.195478) (xy 259.00273 -334.139617) (xy 259.043367 -334.088752)
			(xy 259.066538 -334.06588) (xy 259.066792 -334.065626) (xy 259.070521 -334.062016) (xy 259.076547 -334.05357)
			(xy 259.07873 -334.048862) (xy 259.08254 -334.039718) (xy 259.08254 -333.977996) (xy 259.08254 -333.977742)
			(xy 259.082121 -333.968646) (xy 259.075681 -333.951629) (xy 259.063704 -333.937931) (xy 259.05587 -333.933292)
			(xy 258.745482 -333.933292) (xy 258.737653 -333.937941) (xy 258.725668 -333.951631) (xy 258.719223 -333.968646)
			(xy 258.718812 -333.977742) (xy 258.718812 -334.224884) (xy 258.718812 -334.227424) (xy 258.719779 -334.237067)
			(xy 258.727925 -334.254636) (xy 258.741967 -334.267972) (xy 258.759932 -334.275202) (xy 258.769612 -334.275684)
			(xy 258.778756 -334.275684) (xy 258.778756 -334.543146) (xy 258.778234 -334.565453) (xy 258.769486 -334.6092)
			(xy 258.752337 -334.650387) (xy 258.727452 -334.687416) (xy 258.695796 -334.718852) (xy 258.658594 -334.743479)
			(xy 258.61729 -334.76034) (xy 258.573482 -334.768784) (xy 258.551172 -334.769206) (xy 258.551172 -334.768952)
			(xy 258.510786 -334.768952) (xy 258.497578 -334.77073) (xy 258.496816 -334.770984) (xy 257.569208 -335.698592)
			(xy 257.551079 -335.716082) (xy 257.510346 -335.745713) (xy 257.465475 -335.768602) (xy 257.417575 -335.784185)
			(xy 257.367826 -335.792076) (xy 257.34264 -335.792572) (xy 251.808996 -335.792572) (xy 251.802187 -335.792791)
			(xy 251.789056 -335.796398) (xy 251.783088 -335.799684) (xy 251.760818 -335.812468) (xy 251.71358 -335.832607)
			(xy 251.664072 -335.846238) (xy 251.613183 -335.853116) (xy 251.587508 -335.853532) (xy 251.58065 -335.853532)
			(xy 251.552423 -335.85253) (xy 251.496714 -335.843233) (xy 251.442983 -335.825825) (xy 251.392406 -335.800688)
			(xy 251.346086 -335.76837) (xy 251.305035 -335.729578) (xy 251.270152 -335.685158) (xy 251.242196 -335.636082)
			(xy 251.22178 -335.583421) (xy 251.209349 -335.528326) (xy 251.205175 -335.472) (xy 251.209349 -335.415675)
			(xy 251.22178 -335.36058) (xy 251.242196 -335.307919) (xy 251.270151 -335.258843) (xy 251.305035 -335.214423)
			(xy 251.346085 -335.175631) (xy 251.392405 -335.143313) (xy 251.442983 -335.118175) (xy 251.496713 -335.100768)
			(xy 251.552422 -335.09147) (xy 251.58065 -335.090516) (xy 251.587508 -335.090516) (xy 251.613185 -335.090917)
			(xy 251.664078 -335.097778) (xy 251.713587 -335.111415) (xy 251.760816 -335.13158) (xy 251.783088 -335.144364)
			(xy 251.789056 -335.147646) (xy 251.802188 -335.151243) (xy 251.808996 -335.151476) (xy 257.188716 -335.151476)
			(xy 257.198784 -335.151049) (xy 257.217382 -335.143328) (xy 257.224784 -335.13649) (xy 258.022344 -334.339184)
			(xy 258.022598 -334.338422) (xy 258.024376 -334.325214) (xy 258.024376 -334.305402) (xy 258.054094 -334.275684)
			(xy 258.054348 -334.275684) (xy 258.069334 -334.260698) (xy 258.076187 -334.253303) (xy 258.083932 -334.234704)
			(xy 258.08432 -334.22463) (xy 258.08432 -333.801212) (xy 258.08432 -333.798672) (xy 258.083353 -333.789027)
			(xy 258.075208 -333.771454) (xy 258.061167 -333.758111) (xy 258.043202 -333.750871) (xy 258.03352 -333.750412)
			(xy 258.024376 -333.750412) (xy 258.024376 -333.48295) (xy 258.024898 -333.460645) (xy 258.033648 -333.4169)
			(xy 258.050798 -333.375717) (xy 258.075683 -333.338692) (xy 258.10734 -333.30726) (xy 258.144541 -333.282639)
			(xy 258.185845 -333.265783) (xy 258.229651 -333.257345) (xy 258.25196 -333.25689) (xy 258.25196 -333.257144)
			(xy 258.54787 -333.257144) (xy 258.548378 -333.25689) (xy 258.562015 -333.25684) (xy 258.589141 -333.259641)
			(xy 258.60248 -333.262478) (xy 258.619545 -333.26671) (xy 258.65221 -333.279715) (xy 258.667504 -333.288386)
			(xy 258.675378 -333.292704) (xy 259.130038 -333.292704) (xy 259.136134 -333.289402) (xy 259.156275 -333.278468)
			(xy 259.199798 -333.264137) (xy 259.222494 -333.260954) (xy 259.230149 -333.260122) (xy 259.245529 -333.259361)
			(xy 259.253228 -333.25943) (xy 259.253736 -333.259684) (xy 259.54609 -333.259684) (xy 259.546598 -333.25943)
			(xy 259.560235 -333.259381) (xy 259.587361 -333.262186) (xy 259.6007 -333.265018) (xy 259.617764 -333.269252)
			(xy 259.650426 -333.282261) (xy 259.665724 -333.290926) (xy 259.673598 -333.295244) (xy 260.092698 -333.295244)
			(xy 260.109208 -333.289148) (xy 260.111748 -333.287116) (xy 260.123629 -333.276963) (xy 260.151175 -333.262221)
			(xy 260.181471 -333.254585) (xy 260.197092 -333.254096) (xy 260.705346 -333.254096) (xy 260.722057 -333.254647)
			(xy 260.754337 -333.263307) (xy 260.783277 -333.280025) (xy 260.806905 -333.303663) (xy 260.823612 -333.332609)
			(xy 260.832259 -333.364893) (xy 260.832854 -333.381604) (xy 260.832854 -333.526384) (xy 260.832916 -333.52999)
			(xy 260.833933 -333.53713) (xy 260.834886 -333.540608) (xy 261.124446 -333.829914) (xy 261.131843 -333.836763)
			(xy 261.150442 -333.844494) (xy 261.160514 -333.8449) (xy 261.511034 -333.8449) (xy 261.518907 -333.844605)
			(xy 261.533909 -333.839821) (xy 261.540498 -333.835502) (xy 261.543038 -333.833724) (xy 261.55015 -333.816198)
			(xy 261.550658 -333.815182) (xy 261.556559 -333.800975) (xy 261.574048 -333.775678) (xy 261.597072 -333.755289)
			(xy 261.624299 -333.740989) (xy 261.654154 -333.733604) (xy 261.66953 -333.73314) (xy 262.33247 -333.73314)
			(xy 262.341562 -333.732706) (xy 262.35857 -333.726257) (xy 262.372274 -333.714296) (xy 262.37692 -333.70647)
			(xy 262.37692 -333.076296) (xy 262.376766 -333.070573) (xy 262.374192 -333.059419) (xy 262.37184 -333.054198)
			(xy 262.364474 -333.038958) (xy 262.35914 -333.034386) (xy 262.33513 -333.013622) (xy 262.291935 -332.967104)
			(xy 262.254865 -332.915573) (xy 262.224496 -332.85983) (xy 262.2013 -332.80074) (xy 262.185637 -332.739223)
			(xy 262.17775 -332.676236) (xy 262.177276 -332.644496) (xy 262.177784 -332.621382) (xy 262.179834 -332.587982)
			(xy 262.191611 -332.522108) (xy 262.21192 -332.458347) (xy 262.240412 -332.397798) (xy 262.276595 -332.341506)
			(xy 262.319845 -332.290443) (xy 262.369414 -332.245489) (xy 262.424449 -332.207421) (xy 262.483998 -332.176895)
			(xy 262.51535 -332.165198) (xy 262.554974 -332.153006) (xy 262.579358 -332.147164) (xy 262.582406 -332.146402)
			(xy 262.600641 -332.12818) (xy 262.641858 -332.097224) (xy 262.6875 -332.073267) (xy 262.73639 -332.056929)
			(xy 262.787265 -332.048632) (xy 262.813038 -332.048104) (xy 263.931654 -332.048104) (xy 263.941052 -332.04785)
			(xy 263.94156 -332.04785) (xy 263.966742 -332.048363) (xy 264.01648 -332.056278) (xy 264.064369 -332.071871)
			(xy 264.109232 -332.09476) (xy 264.149964 -332.124381) (xy 264.168128 -332.14183) (xy 264.257028 -332.23073)
			(xy 264.270236 -332.232508) (xy 264.290556 -332.232508) (xy 264.319766 -332.261718) (xy 264.320274 -332.262226)
			(xy 264.336276 -332.277974) (xy 264.343659 -332.284551) (xy 264.361958 -332.291989) (xy 264.371836 -332.292452)
			(xy 264.793984 -332.292452) (xy 264.804004 -332.292035) (xy 264.822518 -332.284366) (xy 264.836684 -332.270191)
			(xy 264.844341 -332.251672) (xy 264.844784 -332.241652) (xy 264.844784 -332.232508) (xy 265.1125 -332.232508)
			(xy 265.135991 -332.233134) (xy 265.181956 -332.242867) (xy 265.203686 -332.251812) (xy 265.223499 -332.261118)
			(xy 265.259397 -332.286156) (xy 265.289818 -332.317623) (xy 265.313629 -332.354348) (xy 265.329942 -332.394961)
			(xy 265.338151 -332.437952) (xy 265.33856 -332.459838) (xy 265.33856 -332.75905) (xy 265.33856 -332.759558)
			(xy 265.338166 -332.781853) (xy 265.329679 -332.825623) (xy 265.312786 -332.866885) (xy 265.288144 -332.904041)
			(xy 265.256704 -332.935654) (xy 265.219683 -332.960501) (xy 265.178515 -332.977619) (xy 265.134793 -332.986347)
			(xy 265.1125 -332.986888) (xy 265.070336 -332.986888) (xy 265.057128 -332.988666) (xy 265.056366 -332.98892)
			(xy 264.611358 -333.434182) (xy 264.604518 -333.441582) (xy 264.596805 -333.460181) (xy 264.596372 -333.47025)
			(xy 264.596372 -333.655162) (xy 264.596811 -333.665194) (xy 264.604384 -333.68377) (xy 264.611104 -333.69123)
			(xy 264.650982 -333.731108) (xy 264.664952 -333.73314) (xy 265.43635 -333.73314) (xy 265.451736 -333.73356)
			(xy 265.481614 -333.740917) (xy 265.508862 -333.755214) (xy 265.531894 -333.77562) (xy 265.549369 -333.800947)
			(xy 265.555222 -333.815182) (xy 265.55573 -333.816198) (xy 265.557254 -333.820008) (xy 265.56018 -333.826601)
			(xy 265.569072 -333.837951) (xy 265.57478 -333.84236) (xy 265.57859 -333.8449) (xy 266.091416 -333.8449)
			(xy 266.101576 -333.83728) (xy 266.122326 -333.813471) (xy 266.168756 -333.770655) (xy 266.220128 -333.733916)
			(xy 266.275653 -333.703818) (xy 266.334476 -333.680825) (xy 266.395694 -333.66529) (xy 266.458363 -333.657453)
			(xy 266.489942 -333.65694) (xy 266.49045 -333.65694) (xy 266.522031 -333.657416) (xy 266.584707 -333.665237)
			(xy 266.645931 -333.680767) (xy 266.704758 -333.703764) (xy 266.760281 -333.733874) (xy 266.811645 -333.770634)
			(xy 266.858056 -333.813475) (xy 266.878816 -333.83728) (xy 266.888976 -333.8449) (xy 267.549376 -333.8449)
			(xy 267.552932 -333.842614) (xy 267.568502 -333.829525) (xy 267.603377 -333.8086) (xy 267.641432 -333.79425)
			(xy 267.681441 -333.786937) (xy 267.701776 -333.78648) (xy 267.9192 -333.78648) (xy 267.929209 -333.786968)
			(xy 267.947704 -333.794626) (xy 267.961862 -333.808779) (xy 267.969528 -333.827271) (xy 267.97 -333.83728)
			(xy 267.97 -333.846424) (xy 268.256004 -333.846424) (xy 268.25829 -333.846424) (xy 268.264431 -333.845965)
			(xy 268.276242 -333.842497) (xy 268.281658 -333.839566) (xy 268.287367 -333.835898) (xy 268.296762 -333.826113)
			(xy 268.3002 -333.820262) (xy 268.3002 -333.448152) (xy 268.295484 -333.440503) (xy 268.28182 -333.42885)
			(xy 268.264982 -333.422607) (xy 268.256004 -333.422244) (xy 268.24813 -333.422244) (xy 268.218412 -333.392526)
			(xy 268.218412 -332.838044) (xy 268.218824 -332.828018) (xy 268.226487 -332.809488) (xy 268.240661 -332.795305)
			(xy 268.259186 -332.78763) (xy 268.269212 -332.787244) (xy 268.432534 -332.787244) (xy 268.442532 -332.786814)
			(xy 268.460993 -332.779129) (xy 268.475092 -332.764949) (xy 268.482671 -332.746444) (xy 268.48308 -332.736444)
			(xy 268.48308 -332.7273) (xy 268.750796 -332.7273) (xy 268.773108 -332.727817) (xy 268.816866 -332.736558)
			(xy 268.858065 -332.753702) (xy 268.895107 -332.778584) (xy 268.926557 -332.81024) (xy 268.951196 -332.847445)
			(xy 268.96807 -332.888755) (xy 268.976524 -332.93257) (xy 268.976856 -332.954884) (xy 268.976856 -333.254096)
			(xy 268.976856 -333.254604) (xy 268.976533 -333.274418) (xy 268.969806 -333.313468) (xy 268.956383 -333.35075)
			(xy 268.946884 -333.368142) (xy 268.946376 -333.369158) (xy 268.941296 -333.378556) (xy 268.941296 -333.8576)
			(xy 268.941533 -333.865101) (xy 268.945935 -333.879441) (xy 268.949932 -333.885794) (xy 268.949932 -333.886048)
			(xy 268.961992 -333.904824) (xy 268.979224 -333.945981) (xy 268.988028 -333.989723) (xy 268.98854 -334.012032)
			(xy 268.98854 -334.313022) (xy 268.98854 -334.31353) (xy 268.988215 -334.333344) (xy 268.981486 -334.372393)
			(xy 268.968064 -334.409675) (xy 268.958568 -334.427068) (xy 268.95806 -334.428084) (xy 268.95298 -334.437482)
			(xy 268.95298 -339.59673) (xy 268.952462 -339.621911) (xy 268.944543 -339.671648) (xy 268.92895 -339.719537)
			(xy 268.906067 -339.764402) (xy 268.876456 -339.805141) (xy 268.859 -339.823298) (xy 268.23543 -340.446868)
			(xy 268.23416 -340.451694) (xy 268.249654 -340.489032) (xy 268.252732 -340.49591) (xy 268.262292 -340.50755)
			(xy 268.26845 -340.511892) (xy 364.298484 -340.511892) (xy 364.306929 -340.511498) (xy 364.322878 -340.505926)
			(xy 364.329726 -340.50097) (xy 364.336838 -340.495636) (xy 364.345728 -340.481412) (xy 364.346744 -340.477602)
			(xy 364.353276 -340.451402) (xy 364.372722 -340.40103) (xy 364.399074 -340.353902) (xy 364.431806 -340.310959)
			(xy 364.470264 -340.273058) (xy 364.513679 -340.240955) (xy 364.561186 -340.215292) (xy 364.611836 -340.196582)
			(xy 364.664617 -340.185197) (xy 364.718476 -340.181364) (xy 364.772338 -340.185162) (xy 364.825126 -340.196512)
			(xy 364.875788 -340.21519) (xy 364.923312 -340.240822) (xy 364.966748 -340.272897) (xy 365.00523 -340.310773)
			(xy 365.03799 -340.353695) (xy 365.064372 -340.400806) (xy 365.083851 -340.451165) (xy 365.090456 -340.477348)
			(xy 365.090456 -340.477856) (xy 365.093504 -340.490048) (xy 365.107474 -340.50097) (xy 365.114301 -340.505966)
			(xy 365.130263 -340.511543) (xy 365.138716 -340.511892) (xy 365.767112 -340.511892) (xy 365.777192 -340.511469)
			(xy 365.795794 -340.503698) (xy 365.809938 -340.489333) (xy 365.814102 -340.480142) (xy 365.830358 -340.433406)
			(xy 365.84636 -340.38667) (xy 365.848631 -340.379177) (xy 365.849018 -340.363533) (xy 365.847122 -340.355936)
			(xy 365.84255 -340.340442) (xy 365.839248 -340.337648) (xy 365.829596 -340.330282) (xy 365.807217 -340.312078)
			(xy 365.767676 -340.270076) (xy 365.734904 -340.222603) (xy 365.709645 -340.170741) (xy 365.692474 -340.11567)
			(xy 365.683782 -340.058643) (xy 365.683292 -340.0298) (xy 365.68337 -340.017062) (xy 365.685024 -339.991641)
			(xy 365.686594 -339.979) (xy 365.691082 -339.949783) (xy 365.707896 -339.893116) (xy 365.733242 -339.839716)
			(xy 365.766514 -339.790861) (xy 365.806918 -339.747717) (xy 365.82985 -339.729064) (xy 365.83424 -339.725429)
			(xy 365.84143 -339.716587) (xy 365.844074 -339.711538) (xy 365.8489 -339.70214) (xy 365.85017 -339.654134)
			(xy 365.85144 -339.612478) (xy 365.851434 -339.606857) (xy 365.849262 -339.595831) (xy 365.847122 -339.590634)
			(xy 365.842804 -339.580728) (xy 365.834168 -339.573108) (xy 365.814268 -339.554917) (xy 365.779279 -339.513898)
			(xy 365.750413 -339.468362) (xy 365.728244 -339.419216) (xy 365.713215 -339.367439) (xy 365.705625 -339.314061)
			(xy 365.705136 -339.287104) (xy 365.705622 -339.259853) (xy 365.713378 -339.205905) (xy 365.728733 -339.15361)
			(xy 365.751375 -339.104033) (xy 365.780841 -339.058183) (xy 365.816532 -339.016992) (xy 365.857723 -338.981301)
			(xy 365.903573 -338.951835) (xy 365.95315 -338.929193) (xy 366.005445 -338.913838) (xy 366.059393 -338.906082)
			(xy 366.113895 -338.906082) (xy 366.167843 -338.913838) (xy 366.220138 -338.929193) (xy 366.269715 -338.951835)
			(xy 366.315565 -338.981301) (xy 366.356756 -339.016992) (xy 366.392447 -339.058183) (xy 366.421913 -339.104033)
			(xy 366.444555 -339.15361) (xy 366.45991 -339.205905) (xy 366.467666 -339.259853) (xy 366.468152 -339.287104)
			(xy 366.468406 -339.287104) (xy 366.467873 -339.315988) (xy 366.459158 -339.373095) (xy 366.441929 -339.428233)
			(xy 366.41658 -339.480142) (xy 366.383691 -339.527633) (xy 366.344014 -339.56962) (xy 366.321594 -339.58784)
			(xy 366.317208 -339.591479) (xy 366.310025 -339.600324) (xy 366.30737 -339.605366) (xy 366.302544 -339.614764)
			(xy 366.301274 -339.66277) (xy 366.300004 -339.704426) (xy 366.300011 -339.710047) (xy 366.302185 -339.721072)
			(xy 366.304322 -339.72627) (xy 366.30864 -339.736176) (xy 366.317276 -339.743796) (xy 366.337178 -339.761985)
			(xy 366.372172 -339.803002) (xy 366.401042 -339.848538) (xy 366.423213 -339.897684) (xy 366.438244 -339.949463)
			(xy 366.445835 -340.002842) (xy 366.446308 -340.0298) (xy 366.44578 -340.058642) (xy 366.4371 -340.115669)
			(xy 366.419939 -340.17074) (xy 366.394687 -340.222602) (xy 366.361918 -340.270075) (xy 366.32238 -340.312076)
			(xy 366.300004 -340.330282) (xy 366.290352 -340.337648) (xy 366.28705 -340.340442) (xy 366.282478 -340.355936)
			(xy 366.280561 -340.36353) (xy 366.280953 -340.379179) (xy 366.28324 -340.38667) (xy 366.299242 -340.433406)
			(xy 366.315498 -340.480142) (xy 366.319691 -340.489305) (xy 366.333855 -340.503616) (xy 366.352422 -340.511408)
			(xy 366.362488 -340.511892) (xy 462.321402 -340.511892) (xy 462.326292 -340.512033) (xy 462.335881 -340.51396)
			(xy 462.340452 -340.515702) (xy 462.350104 -340.519512) (xy 462.354671 -340.521265) (xy 462.364264 -340.523181)
			(xy 462.369154 -340.523322)
		)
		(stroke
			(width 0)
			(type solid)
		)
		(fill yes)
		(layer "F.Cu")
		(net "P3V3_AUX")
	)
	(gr_poly
		(pts
			(xy 200.481692 -418.081968) (xy 200.538276 -418.081432) (xy 200.651116 -418.072836) (xy 200.76298 -418.055715)
			(xy 200.873227 -418.030169) (xy 200.98122 -417.996343) (xy 201.086341 -417.954433) (xy 201.187984 -417.904678)
			(xy 201.285565 -417.847366) (xy 201.378524 -417.782825) (xy 201.466326 -417.711427) (xy 201.548466 -417.633582)
			(xy 201.586846 -417.592002) (xy 201.634058 -417.54062) (xy 201.733379 -417.442584) (xy 201.837997 -417.350223)
			(xy 201.947589 -417.26382) (xy 202.061814 -417.183644) (xy 202.18032 -417.109943) (xy 202.302741 -417.042944)
			(xy 202.428697 -416.982855) (xy 202.557798 -416.929861) (xy 202.689647 -416.884127) (xy 202.823834 -416.845794)
			(xy 202.959945 -416.81498) (xy 203.097558 -416.791782) (xy 203.236248 -416.77627) (xy 203.375587 -416.768492)
			(xy 203.445364 -416.768026) (xy 271.794732 -416.768026) (xy 271.864502 -416.768512) (xy 272.003824 -416.776289)
			(xy 272.142499 -416.791801) (xy 272.280097 -416.814999) (xy 272.416192 -416.845812) (xy 272.550363 -416.884144)
			(xy 272.682195 -416.929877) (xy 272.811281 -416.982869) (xy 272.937221 -417.042957) (xy 273.059624 -417.109954)
			(xy 273.178113 -417.183654) (xy 273.292321 -417.263827) (xy 273.401895 -417.350227) (xy 273.506495 -417.442585)
			(xy 273.605798 -417.540617) (xy 273.652996 -417.592002) (xy 273.691387 -417.633573) (xy 273.773525 -417.71142)
			(xy 273.861325 -417.782821) (xy 273.954282 -417.847364) (xy 274.051862 -417.90468) (xy 274.153504 -417.954438)
			(xy 274.258623 -417.996352) (xy 274.366616 -418.030181) (xy 274.476862 -418.055732) (xy 274.588726 -418.072856)
			(xy 274.701566 -418.081457) (xy 274.75815 -418.081968) (xy 465.600034 -418.081968) (xy 465.65584 -418.081445)
			(xy 465.767139 -418.073102) (xy 465.877504 -418.056464) (xy 465.986317 -418.031626) (xy 466.092969 -417.998726)
			(xy 466.196865 -417.957947) (xy 466.297422 -417.909518) (xy 466.39408 -417.85371) (xy 466.486296 -417.790835)
			(xy 466.573556 -417.721245) (xy 466.655372 -417.645328) (xy 466.731285 -417.563509) (xy 466.800872 -417.476246)
			(xy 466.863743 -417.384027) (xy 466.919547 -417.287367) (xy 466.967972 -417.186808) (xy 467.008746 -417.082911)
			(xy 467.041642 -416.976257) (xy 467.066476 -416.867443) (xy 467.083109 -416.757078) (xy 467.091447 -416.645778)
			(xy 467.09203 -416.589972) (xy 467.09203 -246.488204) (xy 467.091555 -246.434943) (xy 467.083957 -246.328691)
			(xy 467.068799 -246.223252) (xy 467.046159 -246.119163) (xy 467.016151 -246.016954) (xy 466.97893 -245.917146)
			(xy 466.934683 -245.820247) (xy 466.883638 -245.726751) (xy 466.826053 -245.637134) (xy 466.762223 -245.551854)
			(xy 466.692472 -245.471343) (xy 466.65515 -245.433342) (xy 464.026504 -242.80495) (xy 463.977112 -242.75486)
			(xy 463.883366 -242.649956) (xy 463.795648 -242.539961) (xy 463.714235 -242.425221) (xy 463.639382 -242.306097)
			(xy 463.571326 -242.182964) (xy 463.510281 -242.056209) (xy 463.456438 -241.926231) (xy 463.409967 -241.793439)
			(xy 463.371014 -241.65825) (xy 463.339701 -241.52109) (xy 463.316128 -241.382391) (xy 463.300367 -241.242587)
			(xy 463.29247 -241.10212) (xy 463.291936 -241.031776) (xy 463.291936 -87.588344) (xy 463.292417 -87.517998)
			(xy 463.3003 -87.377526) (xy 463.316048 -87.237717) (xy 463.339614 -87.099011) (xy 463.370921 -86.961846)
			(xy 463.409872 -86.826652) (xy 463.456344 -86.693856) (xy 463.510191 -86.563875) (xy 463.571243 -86.437119)
			(xy 463.639308 -86.313987) (xy 463.714172 -86.194865) (xy 463.7956 -86.08013) (xy 463.883333 -85.970143)
			(xy 463.977098 -85.865249) (xy 464.026504 -85.81517) (xy 466.65515 -83.186524) (xy 466.692477 -83.148543)
			(xy 466.762224 -83.068056) (xy 466.826051 -82.982799) (xy 466.883632 -82.893206) (xy 466.934676 -82.799733)
			(xy 466.978921 -82.702856) (xy 467.016141 -82.60307) (xy 467.046149 -82.500883) (xy 467.068789 -82.396815)
			(xy 467.083947 -82.291397) (xy 467.091547 -82.185167) (xy 467.09203 -82.131916) (xy 467.09203 -1.999996)
			(xy 467.091508 -1.944189) (xy 467.083167 -1.832886) (xy 467.066532 -1.722518) (xy 467.041695 -1.613701)
			(xy 467.008796 -1.507045) (xy 466.968019 -1.403146) (xy 466.919592 -1.302584) (xy 466.863785 -1.205923)
			(xy 466.800911 -1.113702) (xy 466.731321 -1.026437) (xy 466.655404 -0.944617) (xy 466.573586 -0.868699)
			(xy 466.486322 -0.799107) (xy 466.394103 -0.736231) (xy 466.297442 -0.680422) (xy 466.196882 -0.631993)
			(xy 466.092983 -0.591214) (xy 465.986328 -0.558313) (xy 465.877512 -0.533474) (xy 465.767144 -0.516836)
			(xy 465.655841 -0.508493) (xy 465.600034 -0.508) (xy 446.265046 -0.508) (xy 446.209237 -0.508508)
			(xy 446.097932 -0.516845) (xy 445.987561 -0.533478) (xy 445.878741 -0.558312) (xy 445.772082 -0.591209)
			(xy 445.668179 -0.631985) (xy 445.567615 -0.680412) (xy 445.47095 -0.736218) (xy 445.378726 -0.799093)
			(xy 445.291459 -0.868683) (xy 445.209636 -0.944601) (xy 445.133716 -1.026421) (xy 445.064123 -1.113686)
			(xy 445.001245 -1.205908) (xy 444.945435 -1.30257) (xy 444.897005 -1.403134) (xy 444.856226 -1.507035)
			(xy 444.823325 -1.613693) (xy 444.798487 -1.722512) (xy 444.781851 -1.832882) (xy 444.773509 -1.944187)
			(xy 444.77305 -1.999996) (xy 444.77305 -11.850116) (xy 444.772563 -11.904445) (xy 444.764743 -12.01282)
			(xy 444.749144 -12.120352) (xy 444.725847 -12.226483) (xy 444.694973 -12.330662) (xy 444.656682 -12.432349)
			(xy 444.611173 -12.531017) (xy 444.558681 -12.626154) (xy 444.49948 -12.717267) (xy 444.433875 -12.803883)
			(xy 444.3984 -12.845034) (xy 444.3984 -12.869164) (xy 444.399924 -12.870688) (xy 445.002666 -12.870688)
			(xy 445.036079 -12.812735) (xy 445.096046 -12.69314) (xy 445.147945 -12.569831) (xy 445.191548 -12.443349)
			(xy 445.226662 -12.314252) (xy 445.253132 -12.183111) (xy 445.270842 -12.050501) (xy 445.279714 -11.917009)
			(xy 445.280288 -11.850116) (xy 445.280288 -1.999996) (xy 445.280813 -1.954511) (xy 445.289205 -1.86393)
			(xy 445.305918 -1.774509) (xy 445.33081 -1.687012) (xy 445.363666 -1.602183) (xy 445.404209 -1.520748)
			(xy 445.452091 -1.4434) (xy 445.506904 -1.370799) (xy 445.568182 -1.303564) (xy 445.6354 -1.242269)
			(xy 445.707987 -1.187437) (xy 445.785322 -1.139534) (xy 445.866747 -1.098971) (xy 445.951567 -1.066092)
			(xy 446.039058 -1.041178) (xy 446.128474 -1.024441) (xy 446.219053 -1.016025) (xy 446.264538 -1.015492)
			(xy 465.600034 -1.015492) (xy 465.64553 -1.016018) (xy 465.736134 -1.024416) (xy 465.825577 -1.041135)
			(xy 465.913097 -1.066034) (xy 465.997946 -1.0989) (xy 466.079402 -1.139453) (xy 466.15677 -1.187348)
			(xy 466.229389 -1.242176) (xy 466.296641 -1.303468) (xy 466.357952 -1.370703) (xy 466.412799 -1.443308)
			(xy 466.460715 -1.520662) (xy 466.501291 -1.602107) (xy 466.53418 -1.686947) (xy 466.559103 -1.77446)
			(xy 466.575847 -1.863898) (xy 466.584269 -1.9545) (xy 466.584792 -1.999996) (xy 466.584792 -82.131916)
			(xy 466.58434 -82.174869) (xy 466.576857 -82.260449) (xy 466.561942 -82.345051) (xy 466.539707 -82.42803)
			(xy 466.510322 -82.508754) (xy 466.474011 -82.586609) (xy 466.43105 -82.661002) (xy 466.381767 -82.731366)
			(xy 466.326536 -82.797165) (xy 466.296502 -82.827876) (xy 463.667856 -85.456522) (xy 463.612395 -85.512692)
			(xy 463.50675 -85.630005) (xy 463.407391 -85.752687) (xy 463.314588 -85.880401) (xy 463.228597 -86.012797)
			(xy 463.149654 -86.149512) (xy 463.077975 -86.290172) (xy 463.013756 -86.43439) (xy 462.957173 -86.581772)
			(xy 462.908382 -86.731914) (xy 462.867516 -86.884404) (xy 462.834688 -87.038823) (xy 462.809987 -87.194749)
			(xy 462.793481 -87.351755) (xy 462.785215 -87.509409) (xy 462.784698 -87.588344) (xy 462.784444 -87.588344)
			(xy 462.784444 -241.031776) (xy 462.784698 -241.031776) (xy 462.785221 -241.11071) (xy 462.793497 -241.268361)
			(xy 462.810012 -241.425363) (xy 462.834721 -241.581286) (xy 462.867556 -241.735702) (xy 462.908426 -241.888188)
			(xy 462.95722 -242.038326) (xy 463.013805 -242.185705) (xy 463.078025 -242.329921) (xy 463.149704 -242.470579)
			(xy 463.228645 -242.607292) (xy 463.314633 -242.739687) (xy 463.407432 -242.867401) (xy 463.506787 -242.990083)
			(xy 463.612426 -243.107398) (xy 463.667856 -243.163598) (xy 466.296502 -245.79199) (xy 466.326545 -245.822708)
			(xy 466.381767 -245.888545) (xy 466.431041 -245.958944) (xy 466.473992 -246.033368) (xy 466.510295 -246.111253)
			(xy 466.539672 -246.192005) (xy 466.561901 -246.27501) (xy 466.576812 -246.359636) (xy 466.584291 -246.445239)
			(xy 466.584792 -246.488204) (xy 466.584792 -311.003696) (xy 466.06206 -311.526428) (xy 463.476594 -311.526428)
			(xy 462.478628 -312.524394) (xy 462.478628 -314.710064) (xy 463.635598 -315.867034) (xy 465.334604 -315.867034)
			(xy 466.584792 -317.117222) (xy 466.584792 -416.589972) (xy 466.584269 -416.635457) (xy 466.575879 -416.72604)
			(xy 466.559168 -416.815462) (xy 466.534278 -416.902962) (xy 466.501423 -416.987792) (xy 466.460881 -417.069229)
			(xy 466.412999 -417.146579) (xy 466.358186 -417.219181) (xy 466.296908 -417.286417) (xy 466.229689 -417.347713)
			(xy 466.157102 -417.402547) (xy 466.079765 -417.45045) (xy 465.998339 -417.491014) (xy 465.913518 -417.523892)
			(xy 465.826025 -417.548806) (xy 465.736608 -417.565541) (xy 465.646027 -417.573956) (xy 465.600542 -417.574476)
			(xy 414.915604 -417.574476) (xy 414.915604 -417.797742) (xy 400.95424 -417.797742) (xy 400.95424 -417.574476)
			(xy 326.621648 -417.574476) (xy 326.621648 -417.747958) (xy 313.065922 -417.747958) (xy 313.065922 -417.574476)
			(xy 274.757896 -417.574476) (xy 274.712278 -417.573956) (xy 274.621433 -417.565503) (xy 274.531761 -417.548679)
			(xy 274.44403 -417.523628) (xy 274.358994 -417.490566) (xy 274.277383 -417.449777) (xy 274.199897 -417.40161)
			(xy 274.1272 -417.346479) (xy 274.059918 -417.284856) (xy 274.028916 -417.251388) (xy 273.975737 -417.193452)
			(xy 273.864198 -417.082562) (xy 273.74703 -416.977639) (xy 273.624551 -416.878967) (xy 273.497093 -416.786815)
			(xy 273.365004 -416.701434) (xy 273.228643 -416.623056) (xy 273.088382 -416.551895) (xy 272.9446 -416.488143)
			(xy 272.79769 -416.431975) (xy 272.648052 -416.383543) (xy 272.496091 -416.342979) (xy 272.342223 -416.310393)
			(xy 272.186865 -416.285874) (xy 272.030439 -416.269488) (xy 271.873373 -416.261281) (xy 271.794732 -416.260788)
			(xy 203.445364 -416.260788) (xy 203.366716 -416.261295) (xy 203.209634 -416.269493) (xy 203.053193 -416.285871)
			(xy 202.897818 -416.310383) (xy 202.743933 -416.342963) (xy 202.591957 -416.383522) (xy 202.442301 -416.431951)
			(xy 202.295375 -416.488117) (xy 202.151576 -416.551867) (xy 202.011298 -416.623028) (xy 201.87492 -416.701407)
			(xy 201.742815 -416.78679) (xy 201.615341 -416.878945) (xy 201.492846 -416.977621) (xy 201.375663 -417.08255)
			(xy 201.26411 -417.193446) (xy 201.210926 -417.251388) (xy 201.179905 -417.284839) (xy 201.112632 -417.346472)
			(xy 201.039943 -417.401611) (xy 200.96246 -417.449784) (xy 200.880851 -417.490577) (xy 200.795815 -417.523638)
			(xy 200.708083 -417.548685) (xy 200.61841 -417.565501) (xy 200.527564 -417.573943) (xy 200.481946 -417.574476)
			(xy 154.673554 -417.574476) (xy 154.673554 -417.693856) (xy 141.027912 -417.693856) (xy 141.027912 -417.574476)
			(xy 66.745104 -417.574476) (xy 66.745104 -417.671758) (xy 53.039772 -417.671758) (xy 53.039772 -417.574476)
			(xy 1.999996 -417.574476) (xy 1.954504 -417.573951) (xy 1.863908 -417.565555) (xy 1.774473 -417.548837)
			(xy 1.686963 -417.523938) (xy 1.602123 -417.49107) (xy 1.520677 -417.450515) (xy 1.443321 -417.402618)
			(xy 1.370714 -417.347788) (xy 1.303476 -417.286492) (xy 1.242181 -417.219254) (xy 1.187351 -417.146647)
			(xy 1.139454 -417.069291) (xy 1.098899 -416.987845) (xy 1.066032 -416.903005) (xy 1.041133 -416.815495)
			(xy 1.024414 -416.72606) (xy 1.016019 -416.635464) (xy 1.015492 -416.589972) (xy 1.015492 -246.48795)
			(xy 1.015971 -246.444999) (xy 1.023477 -246.359425) (xy 1.038407 -246.27483) (xy 1.060648 -246.191857)
			(xy 1.090032 -246.111137) (xy 1.126334 -246.033282) (xy 1.16928 -245.958885) (xy 1.218542 -245.888512)
			(xy 1.273746 -245.822696) (xy 1.303782 -245.79199) (xy 3.93192 -243.163852) (xy 3.987399 -243.107671)
			(xy 4.093079 -242.990336) (xy 4.192472 -242.86763) (xy 4.285305 -242.739888) (xy 4.371323 -242.607463)
			(xy 4.450292 -242.470716) (xy 4.521994 -242.330023) (xy 4.586233 -242.185769) (xy 4.642833 -242.03835)
			(xy 4.691638 -241.888171) (xy 4.732514 -241.735642) (xy 4.765351 -241.581183) (xy 4.790056 -241.425217)
			(xy 4.806563 -241.268172) (xy 4.814827 -241.110477) (xy 4.815332 -241.031522) (xy 4.815332 -112.329468)
			(xy 5.138166 -112.006634) (xy 32.463232 -112.006634) (xy 32.482028 -111.999014) (xy 32.48914 -111.991648)
			(xy 34.012124 -110.468664) (xy 34.018973 -110.461267) (xy 34.026706 -110.442668) (xy 34.02711 -110.432596)
			(xy 34.02711 -96.227646) (xy 34.027543 -96.21758) (xy 34.035273 -96.198991) (xy 34.042096 -96.191578)
			(xy 35.760406 -94.473268) (xy 35.767802 -94.466415) (xy 35.7864 -94.458672) (xy 35.796474 -94.458282)
			(xy 47.559214 -94.458282) (xy 47.564168 -94.458162) (xy 47.573888 -94.45624) (xy 47.578518 -94.454472)
			(xy 47.603918 -94.444058) (xy 47.610776 -94.437454) (xy 47.645653 -94.405338) (xy 47.720195 -94.346739)
			(xy 47.799641 -94.294983) (xy 47.883365 -94.250479) (xy 47.970708 -94.213578) (xy 48.060979 -94.184572)
			(xy 48.153468 -94.163688) (xy 48.247445 -94.151091) (xy 48.342169 -94.146881) (xy 48.436893 -94.151091)
			(xy 48.53087 -94.163688) (xy 48.623359 -94.184572) (xy 48.71363 -94.213578) (xy 48.800973 -94.250479)
			(xy 48.884697 -94.294983) (xy 48.964143 -94.346739) (xy 49.038685 -94.405338) (xy 49.073562 -94.437454)
			(xy 49.08042 -94.443804) (xy 49.107344 -94.454726) (xy 49.111796 -94.456395) (xy 49.121132 -94.458189)
			(xy 49.125886 -94.458282) (xy 56.744616 -94.458282) (xy 56.763412 -94.450662) (xy 56.770524 -94.443296)
			(xy 58.716926 -92.496894) (xy 58.724326 -92.490052) (xy 58.742924 -92.482328) (xy 58.752994 -92.481908)
			(xy 65.296034 -92.481908) (xy 65.31483 -92.474288) (xy 65.321942 -92.466922) (xy 71.601076 -86.187788)
			(xy 71.607923 -86.18039) (xy 71.615657 -86.161792) (xy 71.616062 -86.15172) (xy 71.616062 -79.58074)
			(xy 71.616498 -79.570676) (xy 71.624234 -79.552093) (xy 71.631048 -79.544672) (xy 73.12152 -78.0542)
			(xy 73.12892 -78.047357) (xy 73.147518 -78.03963) (xy 73.157588 -78.039214) (xy 77.040232 -78.039214)
			(xy 77.059028 -78.031594) (xy 77.06614 -78.024228) (xy 79.21244 -75.877928) (xy 79.219839 -75.871085)
			(xy 79.238438 -75.86336) (xy 79.248508 -75.862942) (xy 86.893146 -75.862942) (xy 86.903212 -75.863375)
			(xy 86.9218 -75.871106) (xy 86.929214 -75.877928) (xy 87.78494 -76.733654) (xy 87.792339 -76.740499)
			(xy 87.810937 -76.748226) (xy 87.821008 -76.74864) (xy 90.064336 -76.74864) (xy 90.076274 -76.745846)
			(xy 90.084524 -76.743564) (xy 90.09893 -76.734339) (xy 90.104468 -76.727812) (xy 90.104722 -76.727558)
			(xy 90.15222 -76.666598) (xy 90.155362 -76.662365) (xy 90.159973 -76.652887) (xy 90.161364 -76.647802)
			(xy 90.163904 -76.63815) (xy 90.162634 -76.628752) (xy 90.161872 -76.622402) (xy 90.156272 -76.599118)
			(xy 90.150285 -76.551605) (xy 90.149934 -76.52766) (xy 90.149934 -76.527152) (xy 90.15042 -76.499901)
			(xy 90.158176 -76.445953) (xy 90.173531 -76.393658) (xy 90.196173 -76.344081) (xy 90.225639 -76.298231)
			(xy 90.26133 -76.25704) (xy 90.302521 -76.221349) (xy 90.348371 -76.191883) (xy 90.397948 -76.169241)
			(xy 90.450243 -76.153886) (xy 90.504191 -76.14613) (xy 90.558693 -76.14613) (xy 90.612641 -76.153886)
			(xy 90.664936 -76.169241) (xy 90.714513 -76.191883) (xy 90.760363 -76.221349) (xy 90.801554 -76.25704)
			(xy 90.837245 -76.298231) (xy 90.866711 -76.344081) (xy 90.889353 -76.393658) (xy 90.904708 -76.445953)
			(xy 90.912464 -76.499901) (xy 90.91295 -76.527152) (xy 90.91295 -76.52766) (xy 90.912607 -76.550817)
			(xy 90.907 -76.596791) (xy 90.901774 -76.619354) (xy 90.901012 -76.622402) (xy 90.89898 -76.638658)
			(xy 90.90406 -76.657708) (xy 90.959432 -76.729082) (xy 90.966968 -76.737881) (xy 90.98774 -76.748084)
			(xy 90.99931 -76.74864) (xy 106.34853 -76.74864) (xy 106.367326 -76.74102) (xy 106.374438 -76.733654)
			(xy 107.715558 -75.392534) (xy 107.722399 -75.385134) (xy 107.730116 -75.366535) (xy 107.730544 -75.356466)
			(xy 107.730544 -71.984616) (xy 107.730104 -71.974554) (xy 107.722362 -71.955977) (xy 107.715558 -71.948548)
			(xy 106.285284 -70.518274) (xy 106.277888 -70.511422) (xy 106.259289 -70.503682) (xy 106.249216 -70.503288)
			(xy 102.403402 -70.503288) (xy 102.395274 -70.49516) (xy 100.57384 -70.49516) (xy 100.565204 -70.503796)
			(xy 100.069396 -70.503796) (xy 99.700588 -70.134988) (xy 99.222052 -70.134988) (xy 99.215448 -70.12813)
			(xy 99.027742 -70.12813) (xy 98.949002 -70.20687) (xy 98.949002 -70.80504) (xy 99.958144 -71.814182)
			(xy 99.958144 -72.778366) (xy 99.839018 -72.897492) (xy 99.831615 -72.904326) (xy 99.813017 -72.912032)
			(xy 99.80295 -72.912478) (xy 96.776286 -72.912478) (xy 96.766217 -72.912052) (xy 96.747619 -72.904331)
			(xy 96.740218 -72.897492) (xy 96.641158 -72.798432) (xy 96.641158 -70.840346) (xy 96.579944 -70.779132)
			(xy 91.890596 -70.779132) (xy 91.880525 -70.778709) (xy 91.861919 -70.770997) (xy 91.854528 -70.764146)
			(xy 91.608656 -70.518274) (xy 91.601259 -70.511426) (xy 91.58266 -70.503696) (xy 91.572588 -70.503288)
			(xy 76.403454 -70.503288) (xy 76.395326 -70.49516) (xy 74.573892 -70.49516) (xy 74.565256 -70.503796)
			(xy 74.149966 -70.503796) (xy 73.781158 -70.134988) (xy 73.222104 -70.134988) (xy 73.2155 -70.12813)
			(xy 73.027794 -70.12813) (xy 72.949054 -70.20687) (xy 72.949054 -70.80504) (xy 73.958196 -71.814182)
			(xy 73.958196 -72.922638) (xy 73.94956 -72.931274) (xy 73.942161 -72.938117) (xy 73.923562 -72.945841)
			(xy 73.913492 -72.94626) (xy 70.8406 -72.94626) (xy 70.64121 -72.74687) (xy 70.64121 -70.840346)
			(xy 70.579996 -70.779132) (xy 66.325496 -70.779132) (xy 66.290952 -70.813676) (xy 66.27241 -70.795134)
			(xy 66.265298 -70.787768) (xy 66.246502 -70.780148) (xy 52.665122 -70.780148) (xy 52.655162 -70.779658)
			(xy 52.636745 -70.772062) (xy 52.629308 -70.765416) (xy 52.382166 -70.518274) (xy 52.375054 -70.510908)
			(xy 52.374546 -70.510654) (xy 52.36718 -70.503288) (xy 50.403506 -70.503288) (xy 50.395378 -70.49516)
			(xy 48.573944 -70.49516) (xy 48.565308 -70.503796) (xy 48.150018 -70.503796) (xy 47.78121 -70.134988)
			(xy 47.222156 -70.134988) (xy 47.215552 -70.12813) (xy 47.027846 -70.12813) (xy 46.949106 -70.20687)
			(xy 46.949106 -70.80504) (xy 47.958248 -71.814182) (xy 47.958248 -72.546718) (xy 47.54499 -72.959976)
			(xy 47.537592 -72.966823) (xy 47.518994 -72.974558) (xy 47.508922 -72.974962) (xy 45.0088 -72.974962)
			(xy 44.641262 -72.607424) (xy 44.641262 -70.840346) (xy 44.580048 -70.779132) (xy 26.643076 -70.779132)
			(xy 26.367232 -70.503288) (xy 24.403558 -70.503288) (xy 24.39543 -70.49516) (xy 22.573996 -70.49516)
			(xy 22.56536 -70.503796) (xy 22.15007 -70.503796) (xy 21.781262 -70.134988) (xy 21.222208 -70.134988)
			(xy 21.215604 -70.12813) (xy 21.027898 -70.12813) (xy 20.949158 -70.20687) (xy 20.949158 -70.80504)
			(xy 21.9583 -71.814182) (xy 21.9583 -72.66432) (xy 21.681694 -72.940926) (xy 21.674299 -72.947779)
			(xy 21.6557 -72.955523) (xy 21.645626 -72.955912) (xy 18.8976 -72.955912) (xy 18.641314 -72.699626)
			(xy 18.641314 -70.840346) (xy 18.5801 -70.779132) (xy 14.056868 -70.779132) (xy 11.872468 -72.963532)
			(xy 11.865356 -72.970898) (xy 11.025886 -73.810368) (xy 90.899232 -73.810368) (xy 90.903305 -73.754709)
			(xy 90.91544 -73.700236) (xy 90.935376 -73.64811) (xy 90.96269 -73.599442) (xy 90.996798 -73.55527)
			(xy 91.036975 -73.516535) (xy 91.082363 -73.484063) (xy 91.131995 -73.458545) (xy 91.184815 -73.440526)
			(xy 91.239694 -73.430389) (xy 91.295465 -73.428351) (xy 91.350939 -73.434454) (xy 91.404932 -73.44857)
			(xy 91.456295 -73.470397) (xy 91.503933 -73.49947) (xy 91.546829 -73.535169) (xy 91.584071 -73.576733)
			(xy 91.614865 -73.623277) (xy 91.638553 -73.673808) (xy 91.654631 -73.72725) (xy 91.662757 -73.782464)
			(xy 91.663266 -73.810368) (xy 91.662757 -73.838272) (xy 91.654631 -73.893486) (xy 91.638553 -73.946928)
			(xy 91.614865 -73.997459) (xy 91.584071 -74.044003) (xy 91.546829 -74.085567) (xy 91.503933 -74.121266)
			(xy 91.456295 -74.150339) (xy 91.404932 -74.172166) (xy 91.350939 -74.186282) (xy 91.295465 -74.192385)
			(xy 91.239694 -74.190347) (xy 91.184815 -74.18021) (xy 91.131995 -74.162191) (xy 91.082363 -74.136673)
			(xy 91.036975 -74.104201) (xy 90.996798 -74.065466) (xy 90.96269 -74.021294) (xy 90.935376 -73.972626)
			(xy 90.91544 -73.9205) (xy 90.903305 -73.866027) (xy 90.899232 -73.810368) (xy 11.025886 -73.810368)
			(xy 8.578088 -76.258166) (xy 8.57069 -76.265014) (xy 8.552092 -76.27275) (xy 8.54202 -76.273152)
			(xy 1.3462 -76.273152) (xy 1.015492 -75.942444) (xy 1.015492 -1.999996) (xy 1.016017 -1.954504) (xy 1.024413 -1.863908)
			(xy 1.041131 -1.774473) (xy 1.06603 -1.686962) (xy 1.098898 -1.602122) (xy 1.139453 -1.520677) (xy 1.18735 -1.443321)
			(xy 1.24218 -1.370714) (xy 1.303476 -1.303476) (xy 1.370714 -1.24218) (xy 1.443321 -1.18735) (xy 1.520677 -1.139453)
			(xy 1.602122 -1.098898) (xy 1.686962 -1.06603) (xy 1.774473 -1.041131) (xy 1.863908 -1.024413) (xy 1.954504 -1.016017)
			(xy 1.999996 -1.015492) (xy 5.964936 -1.015492) (xy 6.010428 -1.016017) (xy 6.101024 -1.024413) (xy 6.190458 -1.041131)
			(xy 6.277969 -1.066031) (xy 6.362809 -1.098898) (xy 6.444254 -1.139454) (xy 6.52161 -1.187351) (xy 6.594217 -1.242181)
			(xy 6.661455 -1.303476) (xy 6.72275 -1.370714) (xy 6.77758 -1.443321) (xy 6.825477 -1.520677) (xy 6.866033 -1.602123)
			(xy 6.8989 -1.686963) (xy 6.923799 -1.774473) (xy 6.940518 -1.863908) (xy 6.948913 -1.954504) (xy 6.94944 -1.999996)
			(xy 6.94944 -11.850116) (xy 6.949945 -11.913435) (xy 6.957912 -12.039821) (xy 6.973799 -12.165458)
			(xy 6.997542 -12.289849) (xy 7.029049 -12.412504) (xy 7.068194 -12.532939) (xy 7.114823 -12.650679)
			(xy 7.168753 -12.765259) (xy 7.229771 -12.876227) (xy 7.297635 -12.983144) (xy 7.372078 -13.08559)
			(xy 7.452807 -13.18316) (xy 7.539502 -13.275469) (xy 7.631822 -13.362152) (xy 7.729402 -13.442869)
			(xy 7.831857 -13.517299) (xy 7.938784 -13.585149) (xy 8.049759 -13.646153) (xy 8.164346 -13.700068)
			(xy 8.282092 -13.746683) (xy 8.402532 -13.785813) (xy 8.525191 -13.817304) (xy 8.649585 -13.841031)
			(xy 8.775224 -13.856902) (xy 8.901611 -13.864853) (xy 8.96493 -13.865352) (xy 15.851124 -13.865352)
			(xy 15.851124 -13.358114) (xy 8.96493 -13.358114) (xy 8.911089 -13.357645) (xy 8.80368 -13.349963)
			(xy 8.697093 -13.334638) (xy 8.591871 -13.311748) (xy 8.48855 -13.28141) (xy 8.387656 -13.243779)
			(xy 8.289705 -13.199046) (xy 8.195194 -13.147439) (xy 8.104605 -13.089221) (xy 8.0184 -13.024689)
			(xy 7.937019 -12.954171) (xy 7.860876 -12.878028) (xy 7.790359 -12.796646) (xy 7.725827 -12.710442)
			(xy 7.667609 -12.619853) (xy 7.616002 -12.525342) (xy 7.57127 -12.42739) (xy 7.533638 -12.326496)
			(xy 7.503301 -12.223175) (xy 7.480411 -12.117953) (xy 7.465087 -12.011366) (xy 7.457405 -11.903957)
			(xy 7.456932 -11.850116) (xy 7.456932 -1.999996) (xy 7.45641 -1.944189) (xy 7.448069 -1.832887) (xy 7.431434 -1.72252)
			(xy 7.406597 -1.613704) (xy 7.373698 -1.507049) (xy 7.332921 -1.40315) (xy 7.284493 -1.30259) (xy 7.228686 -1.205929)
			(xy 7.165812 -1.113709) (xy 7.096221 -1.026446) (xy 7.020305 -0.944627) (xy 6.938486 -0.86871) (xy 6.851222 -0.79912)
			(xy 6.759003 -0.736245) (xy 6.662342 -0.680438) (xy 6.561782 -0.63201) (xy 6.457883 -0.591233) (xy 6.351228 -0.558334)
			(xy 6.242412 -0.533497) (xy 6.132045 -0.516861) (xy 6.020743 -0.50852) (xy 5.964936 -0.508) (xy 1.999996 -0.508)
			(xy 1.944189 -0.508522) (xy 1.832887 -0.516863) (xy 1.72252 -0.533498) (xy 1.613704 -0.558335) (xy 1.507049 -0.591234)
			(xy 1.403151 -0.632011) (xy 1.30259 -0.680439) (xy 1.205929 -0.736246) (xy 1.11371 -0.799121) (xy 1.026446 -0.868711)
			(xy 0.944628 -0.944628) (xy 0.868711 -1.026446) (xy 0.799121 -1.11371) (xy 0.736246 -1.205929) (xy 0.680439 -1.30259)
			(xy 0.632011 -1.403151) (xy 0.591234 -1.507049) (xy 0.558335 -1.613704) (xy 0.533498 -1.72252) (xy 0.516863 -1.832887)
			(xy 0.508522 -1.944189) (xy 0.508 -1.999996) (xy 0.508 -78.58887) (xy 41.399712 -78.58887) (xy 41.403785 -78.533211)
			(xy 41.41592 -78.478738) (xy 41.435856 -78.426612) (xy 41.46317 -78.377944) (xy 41.497278 -78.333772)
			(xy 41.537455 -78.295037) (xy 41.582843 -78.262565) (xy 41.632475 -78.237047) (xy 41.685295 -78.219028)
			(xy 41.740174 -78.208891) (xy 41.795945 -78.206853) (xy 41.851419 -78.212956) (xy 41.905412 -78.227072)
			(xy 41.913422 -78.230476) (xy 65.14795 -78.230476) (xy 65.152023 -78.174817) (xy 65.164158 -78.120344)
			(xy 65.184094 -78.068218) (xy 65.211408 -78.01955) (xy 65.245516 -77.975378) (xy 65.285693 -77.936643)
			(xy 65.331081 -77.904171) (xy 65.380713 -77.878653) (xy 65.433533 -77.860634) (xy 65.488412 -77.850497)
			(xy 65.544183 -77.848459) (xy 65.599657 -77.854562) (xy 65.65365 -77.868678) (xy 65.705013 -77.890505)
			(xy 65.752651 -77.919578) (xy 65.795547 -77.955277) (xy 65.832789 -77.996841) (xy 65.863583 -78.043385)
			(xy 65.887271 -78.093916) (xy 65.903349 -78.147358) (xy 65.911475 -78.202572) (xy 65.911984 -78.230476)
			(xy 65.911475 -78.25838) (xy 65.903349 -78.313594) (xy 65.887271 -78.367036) (xy 65.863583 -78.417567)
			(xy 65.832789 -78.464111) (xy 65.795547 -78.505675) (xy 65.752651 -78.541374) (xy 65.705013 -78.570447)
			(xy 65.65365 -78.592274) (xy 65.599657 -78.60639) (xy 65.544183 -78.612493) (xy 65.488412 -78.610455)
			(xy 65.433533 -78.600318) (xy 65.380713 -78.582299) (xy 65.331081 -78.556781) (xy 65.285693 -78.524309)
			(xy 65.245516 -78.485574) (xy 65.211408 -78.441402) (xy 65.184094 -78.392734) (xy 65.164158 -78.340608)
			(xy 65.152023 -78.286135) (xy 65.14795 -78.230476) (xy 41.913422 -78.230476) (xy 41.956775 -78.248899)
			(xy 42.004413 -78.277972) (xy 42.047309 -78.313671) (xy 42.084551 -78.355235) (xy 42.115345 -78.401779)
			(xy 42.139033 -78.45231) (xy 42.155111 -78.505752) (xy 42.163237 -78.560966) (xy 42.163746 -78.58887)
			(xy 42.163237 -78.616774) (xy 42.155111 -78.671988) (xy 42.139033 -78.72543) (xy 42.115345 -78.775961)
			(xy 42.084551 -78.822505) (xy 42.047309 -78.864069) (xy 42.004413 -78.899768) (xy 41.956775 -78.928841)
			(xy 41.905412 -78.950668) (xy 41.851419 -78.964784) (xy 41.795945 -78.970887) (xy 41.740174 -78.968849)
			(xy 41.685295 -78.958712) (xy 41.632475 -78.940693) (xy 41.582843 -78.915175) (xy 41.537455 -78.882703)
			(xy 41.497278 -78.843968) (xy 41.46317 -78.799796) (xy 41.435856 -78.751128) (xy 41.41592 -78.699002)
			(xy 41.403785 -78.644529) (xy 41.399712 -78.58887) (xy 0.508 -78.58887) (xy 0.508 -79.164434) (xy 42.852338 -79.164434)
			(xy 42.856411 -79.108775) (xy 42.868546 -79.054302) (xy 42.888482 -79.002176) (xy 42.915796 -78.953508)
			(xy 42.949904 -78.909336) (xy 42.990081 -78.870601) (xy 43.035469 -78.838129) (xy 43.085101 -78.812611)
			(xy 43.137921 -78.794592) (xy 43.1928 -78.784455) (xy 43.248571 -78.782417) (xy 43.304045 -78.78852)
			(xy 43.358038 -78.802636) (xy 43.409401 -78.824463) (xy 43.457039 -78.853536) (xy 43.499935 -78.889235)
			(xy 43.537177 -78.930799) (xy 43.567971 -78.977343) (xy 43.591659 -79.027874) (xy 43.607737 -79.081316)
			(xy 43.615863 -79.13653) (xy 43.616372 -79.164434) (xy 43.615863 -79.192338) (xy 43.607737 -79.247552)
			(xy 43.591659 -79.300994) (xy 43.567971 -79.351525) (xy 43.537177 -79.398069) (xy 43.499935 -79.439633)
			(xy 43.457039 -79.475332) (xy 43.409401 -79.504405) (xy 43.358038 -79.526232) (xy 43.304045 -79.540348)
			(xy 43.248571 -79.546451) (xy 43.1928 -79.544413) (xy 43.137921 -79.534276) (xy 43.085101 -79.516257)
			(xy 43.035469 -79.490739) (xy 42.990081 -79.458267) (xy 42.949904 -79.419532) (xy 42.915796 -79.37536)
			(xy 42.888482 -79.326692) (xy 42.868546 -79.274566) (xy 42.856411 -79.220093) (xy 42.852338 -79.164434)
			(xy 0.508 -79.164434) (xy 0.508 -79.727552) (xy 58.251596 -79.727552) (xy 58.255669 -79.671893) (xy 58.267804 -79.61742)
			(xy 58.28774 -79.565294) (xy 58.315054 -79.516626) (xy 58.349162 -79.472454) (xy 58.389339 -79.433719)
			(xy 58.434727 -79.401247) (xy 58.484359 -79.375729) (xy 58.537179 -79.35771) (xy 58.592058 -79.347573)
			(xy 58.647829 -79.345535) (xy 58.703303 -79.351638) (xy 58.757296 -79.365754) (xy 58.808659 -79.387581)
			(xy 58.856297 -79.416654) (xy 58.899193 -79.452353) (xy 58.936435 -79.493917) (xy 58.967229 -79.540461)
			(xy 58.990917 -79.590992) (xy 59.006995 -79.644434) (xy 59.015121 -79.699648) (xy 59.01563 -79.727552)
			(xy 59.015121 -79.755456) (xy 59.006995 -79.81067) (xy 58.990917 -79.864112) (xy 58.967229 -79.914643)
			(xy 58.936435 -79.961187) (xy 58.899193 -80.002751) (xy 58.856297 -80.03845) (xy 58.808659 -80.067523)
			(xy 58.757296 -80.08935) (xy 58.703303 -80.103466) (xy 58.647829 -80.109569) (xy 58.592058 -80.107531)
			(xy 58.537179 -80.097394) (xy 58.484359 -80.079375) (xy 58.434727 -80.053857) (xy 58.389339 -80.021385)
			(xy 58.349162 -79.98265) (xy 58.315054 -79.938478) (xy 58.28774 -79.88981) (xy 58.267804 -79.837684)
			(xy 58.255669 -79.783211) (xy 58.251596 -79.727552) (xy 0.508 -79.727552) (xy 0.508 -82.131916) (xy 0.508487 -82.185165)
			(xy 0.516104 -82.291392) (xy 0.531277 -82.396804) (xy 0.553928 -82.500867) (xy 0.583941 -82.603049)
			(xy 0.621164 -82.702831) (xy 0.665407 -82.799705) (xy 0.716446 -82.893178) (xy 0.774019 -82.982773)
			(xy 0.837835 -83.068035) (xy 0.907568 -83.14853) (xy 0.94488 -83.186524) (xy 2.7837 -85.025522) (xy 44.856897 -85.025522)
			(xy 44.856897 -84.896414) (xy 44.864845 -84.76755) (xy 44.880711 -84.639421) (xy 44.904435 -84.512511)
			(xy 44.935926 -84.387302) (xy 44.975066 -84.264269) (xy 45.021705 -84.143879) (xy 45.075667 -84.026589)
			(xy 45.136747 -83.912843) (xy 45.204714 -83.803072) (xy 45.27931 -83.697695) (xy 45.360251 -83.597109)
			(xy 45.44723 -83.501697) (xy 45.539919 -83.41182) (xy 45.637964 -83.32782) (xy 45.740995 -83.250014)
			(xy 45.84862 -83.178699) (xy 45.960431 -83.114145) (xy 46.076004 -83.056597) (xy 46.194901 -83.006272)
			(xy 46.31667 -82.963362) (xy 46.44085 -82.92803) (xy 46.566969 -82.90041) (xy 46.694549 -82.880606)
			(xy 46.823107 -82.868693) (xy 46.952154 -82.864717) (xy 47.081201 -82.868693) (xy 47.209759 -82.880606)
			(xy 47.337339 -82.90041) (xy 47.463458 -82.92803) (xy 47.587638 -82.963362) (xy 47.709407 -83.006272)
			(xy 47.828304 -83.056597) (xy 47.943877 -83.114145) (xy 48.055688 -83.178699) (xy 48.163313 -83.250014)
			(xy 48.266344 -83.32782) (xy 48.364389 -83.41182) (xy 48.457078 -83.501697) (xy 48.544057 -83.597109)
			(xy 48.624998 -83.697695) (xy 48.699594 -83.803072) (xy 48.767561 -83.912843) (xy 48.828641 -84.026589)
			(xy 48.882603 -84.143879) (xy 48.929242 -84.264269) (xy 48.968382 -84.387302) (xy 48.999873 -84.512511)
			(xy 49.023597 -84.639421) (xy 49.039463 -84.76755) (xy 49.047411 -84.896414) (xy 49.047908 -84.960968)
			(xy 49.047411 -85.025522) (xy 49.039463 -85.154386) (xy 49.023597 -85.282515) (xy 49.004459 -85.384894)
			(xy 59.304172 -85.384894) (xy 59.308245 -85.329235) (xy 59.32038 -85.274762) (xy 59.340316 -85.222636)
			(xy 59.36763 -85.173968) (xy 59.401738 -85.129796) (xy 59.441915 -85.091061) (xy 59.487303 -85.058589)
			(xy 59.536935 -85.033071) (xy 59.589755 -85.015052) (xy 59.644634 -85.004915) (xy 59.700405 -85.002877)
			(xy 59.755879 -85.00898) (xy 59.809872 -85.023096) (xy 59.861235 -85.044923) (xy 59.908873 -85.073996)
			(xy 59.951769 -85.109695) (xy 59.989011 -85.151259) (xy 60.019805 -85.197803) (xy 60.043493 -85.248334)
			(xy 60.059571 -85.301776) (xy 60.067697 -85.35699) (xy 60.068206 -85.384894) (xy 60.067697 -85.412798)
			(xy 60.059571 -85.468012) (xy 60.043493 -85.521454) (xy 60.019805 -85.571985) (xy 59.989011 -85.618529)
			(xy 59.951769 -85.660093) (xy 59.908873 -85.695792) (xy 59.861235 -85.724865) (xy 59.809872 -85.746692)
			(xy 59.755879 -85.760808) (xy 59.700405 -85.766911) (xy 59.644634 -85.764873) (xy 59.589755 -85.754736)
			(xy 59.536935 -85.736717) (xy 59.487303 -85.711199) (xy 59.441915 -85.678727) (xy 59.401738 -85.639992)
			(xy 59.36763 -85.59582) (xy 59.340316 -85.547152) (xy 59.32038 -85.495026) (xy 59.308245 -85.440553)
			(xy 59.304172 -85.384894) (xy 49.004459 -85.384894) (xy 48.999873 -85.409425) (xy 48.968382 -85.534634)
			(xy 48.929242 -85.657667) (xy 48.882603 -85.778057) (xy 48.828641 -85.895347) (xy 48.767561 -86.009094)
			(xy 48.699594 -86.118864) (xy 48.624998 -86.224241) (xy 48.544057 -86.324827) (xy 48.457078 -86.420239)
			(xy 48.364389 -86.510116) (xy 48.266344 -86.594116) (xy 48.163313 -86.671922) (xy 48.055688 -86.743237)
			(xy 47.943877 -86.807791) (xy 47.828304 -86.865339) (xy 47.709407 -86.915664) (xy 47.587638 -86.958574)
			(xy 47.464969 -86.993476) (xy 59.628784 -86.993476) (xy 59.632857 -86.937817) (xy 59.644992 -86.883344)
			(xy 59.664928 -86.831218) (xy 59.692242 -86.78255) (xy 59.72635 -86.738378) (xy 59.766527 -86.699643)
			(xy 59.811915 -86.667171) (xy 59.861547 -86.641653) (xy 59.914367 -86.623634) (xy 59.969246 -86.613497)
			(xy 60.025017 -86.611459) (xy 60.080491 -86.617562) (xy 60.134484 -86.631678) (xy 60.185847 -86.653505)
			(xy 60.233485 -86.682578) (xy 60.276381 -86.718277) (xy 60.313623 -86.759841) (xy 60.344417 -86.806385)
			(xy 60.368105 -86.856916) (xy 60.384183 -86.910358) (xy 60.392309 -86.965572) (xy 60.392818 -86.993476)
			(xy 60.392309 -87.02138) (xy 60.384183 -87.076594) (xy 60.368105 -87.130036) (xy 60.344417 -87.180567)
			(xy 60.313623 -87.227111) (xy 60.276381 -87.268675) (xy 60.233485 -87.304374) (xy 60.185847 -87.333447)
			(xy 60.134484 -87.355274) (xy 60.080491 -87.36939) (xy 60.025017 -87.375493) (xy 59.969246 -87.373455)
			(xy 59.914367 -87.363318) (xy 59.861547 -87.345299) (xy 59.811915 -87.319781) (xy 59.766527 -87.287309)
			(xy 59.72635 -87.248574) (xy 59.692242 -87.204402) (xy 59.664928 -87.155734) (xy 59.644992 -87.103608)
			(xy 59.632857 -87.049135) (xy 59.628784 -86.993476) (xy 47.464969 -86.993476) (xy 47.463458 -86.993906)
			(xy 47.337339 -87.021526) (xy 47.209759 -87.04133) (xy 47.081201 -87.053243) (xy 46.952154 -87.057219)
			(xy 46.823107 -87.053243) (xy 46.694549 -87.04133) (xy 46.566969 -87.021526) (xy 46.44085 -86.993906)
			(xy 46.31667 -86.958574) (xy 46.194901 -86.915664) (xy 46.076004 -86.865339) (xy 45.960431 -86.807791)
			(xy 45.84862 -86.743237) (xy 45.740995 -86.671922) (xy 45.637964 -86.594116) (xy 45.539919 -86.510116)
			(xy 45.44723 -86.420239) (xy 45.360251 -86.324827) (xy 45.27931 -86.224241) (xy 45.204714 -86.118864)
			(xy 45.136747 -86.009094) (xy 45.075667 -85.895347) (xy 45.021705 -85.778057) (xy 44.975066 -85.657667)
			(xy 44.935926 -85.534634) (xy 44.904435 -85.409425) (xy 44.880711 -85.282515) (xy 44.864845 -85.154386)
			(xy 44.856897 -85.025522) (xy 2.7837 -85.025522) (xy 3.573272 -85.81517) (xy 3.622687 -85.865245)
			(xy 3.716468 -85.970133) (xy 3.804219 -86.080117) (xy 3.885663 -86.194848) (xy 3.960544 -86.313966)
			(xy 4.028628 -86.437097) (xy 4.089698 -86.563852) (xy 4.143563 -86.693833) (xy 4.190054 -86.82663)
			(xy 4.229024 -86.961825) (xy 4.260351 -87.098994) (xy 4.283935 -87.237703) (xy 4.299703 -87.377516)
			(xy 4.307605 -87.517994) (xy 4.308094 -87.588344) (xy 4.308094 -91.315794) (xy 31.655002 -91.315794)
			(xy 31.659075 -91.260135) (xy 31.67121 -91.205662) (xy 31.691146 -91.153536) (xy 31.71846 -91.104868)
			(xy 31.752568 -91.060696) (xy 31.792745 -91.021961) (xy 31.838133 -90.989489) (xy 31.887765 -90.963971)
			(xy 31.940585 -90.945952) (xy 31.995464 -90.935815) (xy 32.051235 -90.933777) (xy 32.106709 -90.93988)
			(xy 32.160702 -90.953996) (xy 32.212065 -90.975823) (xy 32.259703 -91.004896) (xy 32.302599 -91.040595)
			(xy 32.339841 -91.082159) (xy 32.370635 -91.128703) (xy 32.394323 -91.179234) (xy 32.410401 -91.232676)
			(xy 32.410485 -91.233244) (xy 58.86526 -91.233244) (xy 58.869333 -91.177585) (xy 58.881468 -91.123112)
			(xy 58.901404 -91.070986) (xy 58.928718 -91.022318) (xy 58.962826 -90.978146) (xy 59.003003 -90.939411)
			(xy 59.048391 -90.906939) (xy 59.098023 -90.881421) (xy 59.150843 -90.863402) (xy 59.205722 -90.853265)
			(xy 59.261493 -90.851227) (xy 59.316967 -90.85733) (xy 59.37096 -90.871446) (xy 59.422323 -90.893273)
			(xy 59.469961 -90.922346) (xy 59.512857 -90.958045) (xy 59.550099 -90.999609) (xy 59.580893 -91.046153)
			(xy 59.604581 -91.096684) (xy 59.620659 -91.150126) (xy 59.628785 -91.20534) (xy 59.629294 -91.233244)
			(xy 59.628785 -91.261148) (xy 59.620659 -91.316362) (xy 59.604581 -91.369804) (xy 59.580893 -91.420335)
			(xy 59.550099 -91.466879) (xy 59.512857 -91.508443) (xy 59.469961 -91.544142) (xy 59.422323 -91.573215)
			(xy 59.37096 -91.595042) (xy 59.316967 -91.609158) (xy 59.261493 -91.615261) (xy 59.205722 -91.613223)
			(xy 59.150843 -91.603086) (xy 59.098023 -91.585067) (xy 59.048391 -91.559549) (xy 59.003003 -91.527077)
			(xy 58.962826 -91.488342) (xy 58.928718 -91.44417) (xy 58.901404 -91.395502) (xy 58.881468 -91.343376)
			(xy 58.869333 -91.288903) (xy 58.86526 -91.233244) (xy 32.410485 -91.233244) (xy 32.418527 -91.28789)
			(xy 32.419036 -91.315794) (xy 32.418527 -91.343698) (xy 32.410401 -91.398912) (xy 32.394323 -91.452354)
			(xy 32.370635 -91.502885) (xy 32.339841 -91.549429) (xy 32.302599 -91.590993) (xy 32.259703 -91.626692)
			(xy 32.212065 -91.655765) (xy 32.160702 -91.677592) (xy 32.106709 -91.691708) (xy 32.051235 -91.697811)
			(xy 31.995464 -91.695773) (xy 31.940585 -91.685636) (xy 31.887765 -91.667617) (xy 31.838133 -91.642099)
			(xy 31.792745 -91.609627) (xy 31.752568 -91.570892) (xy 31.71846 -91.52672) (xy 31.691146 -91.478052)
			(xy 31.67121 -91.425926) (xy 31.659075 -91.371453) (xy 31.655002 -91.315794) (xy 4.308094 -91.315794)
			(xy 4.308094 -92.927424) (xy 31.55899 -92.927424) (xy 31.563063 -92.871765) (xy 31.575198 -92.817292)
			(xy 31.595134 -92.765166) (xy 31.622448 -92.716498) (xy 31.656556 -92.672326) (xy 31.696733 -92.633591)
			(xy 31.742121 -92.601119) (xy 31.791753 -92.575601) (xy 31.844573 -92.557582) (xy 31.899452 -92.547445)
			(xy 31.955223 -92.545407) (xy 32.010697 -92.55151) (xy 32.06469 -92.565626) (xy 32.116053 -92.587453)
			(xy 32.163691 -92.616526) (xy 32.206587 -92.652225) (xy 32.243829 -92.693789) (xy 32.274623 -92.740333)
			(xy 32.298311 -92.790864) (xy 32.314389 -92.844306) (xy 32.322515 -92.89952) (xy 32.323024 -92.927424)
			(xy 32.322515 -92.955328) (xy 32.314389 -93.010542) (xy 32.298311 -93.063984) (xy 32.274623 -93.114515)
			(xy 32.243829 -93.161059) (xy 32.206587 -93.202623) (xy 32.163691 -93.238322) (xy 32.116053 -93.267395)
			(xy 32.06469 -93.289222) (xy 32.010697 -93.303338) (xy 31.955223 -93.309441) (xy 31.899452 -93.307403)
			(xy 31.844573 -93.297266) (xy 31.791753 -93.279247) (xy 31.742121 -93.253729) (xy 31.696733 -93.221257)
			(xy 31.656556 -93.182522) (xy 31.622448 -93.13835) (xy 31.595134 -93.089682) (xy 31.575198 -93.037556)
			(xy 31.563063 -92.983083) (xy 31.55899 -92.927424) (xy 4.308094 -92.927424) (xy 4.308094 -95.12554)
			(xy 24.574498 -95.12554) (xy 24.578571 -95.069881) (xy 24.590706 -95.015408) (xy 24.610642 -94.963282)
			(xy 24.637956 -94.914614) (xy 24.672064 -94.870442) (xy 24.712241 -94.831707) (xy 24.757629 -94.799235)
			(xy 24.807261 -94.773717) (xy 24.860081 -94.755698) (xy 24.91496 -94.745561) (xy 24.970731 -94.743523)
			(xy 25.026205 -94.749626) (xy 25.080198 -94.763742) (xy 25.131561 -94.785569) (xy 25.179199 -94.814642)
			(xy 25.222095 -94.850341) (xy 25.259337 -94.891905) (xy 25.290131 -94.938449) (xy 25.313819 -94.98898)
			(xy 25.329897 -95.042422) (xy 25.338023 -95.097636) (xy 25.338532 -95.12554) (xy 25.338023 -95.153444)
			(xy 25.329897 -95.208658) (xy 25.313819 -95.2621) (xy 25.290131 -95.312631) (xy 25.259337 -95.359175)
			(xy 25.222095 -95.400739) (xy 25.179199 -95.436438) (xy 25.131561 -95.465511) (xy 25.080198 -95.487338)
			(xy 25.026205 -95.501454) (xy 24.970731 -95.507557) (xy 24.91496 -95.505519) (xy 24.860081 -95.495382)
			(xy 24.807261 -95.477363) (xy 24.757629 -95.451845) (xy 24.712241 -95.419373) (xy 24.672064 -95.380638)
			(xy 24.637956 -95.336466) (xy 24.610642 -95.287798) (xy 24.590706 -95.235672) (xy 24.578571 -95.181199)
			(xy 24.574498 -95.12554) (xy 4.308094 -95.12554) (xy 4.308094 -95.986092) (xy 25.048208 -95.986092)
			(xy 25.052281 -95.930433) (xy 25.064416 -95.87596) (xy 25.084352 -95.823834) (xy 25.111666 -95.775166)
			(xy 25.145774 -95.730994) (xy 25.185951 -95.692259) (xy 25.231339 -95.659787) (xy 25.280971 -95.634269)
			(xy 25.333791 -95.61625) (xy 25.38867 -95.606113) (xy 25.444441 -95.604075) (xy 25.499915 -95.610178)
			(xy 25.553908 -95.624294) (xy 25.605271 -95.646121) (xy 25.652909 -95.675194) (xy 25.695805 -95.710893)
			(xy 25.733047 -95.752457) (xy 25.763841 -95.799001) (xy 25.787529 -95.849532) (xy 25.803607 -95.902974)
			(xy 25.811733 -95.958188) (xy 25.812242 -95.986092) (xy 25.811733 -96.013996) (xy 25.803607 -96.06921)
			(xy 25.787529 -96.122652) (xy 25.763841 -96.173183) (xy 25.733047 -96.219727) (xy 25.695805 -96.261291)
			(xy 25.652909 -96.29699) (xy 25.605271 -96.326063) (xy 25.553908 -96.34789) (xy 25.499915 -96.362006)
			(xy 25.444441 -96.368109) (xy 25.38867 -96.366071) (xy 25.333791 -96.355934) (xy 25.280971 -96.337915)
			(xy 25.231339 -96.312397) (xy 25.185951 -96.279925) (xy 25.145774 -96.24119) (xy 25.111666 -96.197018)
			(xy 25.084352 -96.14835) (xy 25.064416 -96.096224) (xy 25.052281 -96.041751) (xy 25.048208 -95.986092)
			(xy 4.308094 -95.986092) (xy 4.308094 -97.021904) (xy 25.034492 -97.021904) (xy 25.038565 -96.966245)
			(xy 25.0507 -96.911772) (xy 25.070636 -96.859646) (xy 25.09795 -96.810978) (xy 25.132058 -96.766806)
			(xy 25.172235 -96.728071) (xy 25.217623 -96.695599) (xy 25.267255 -96.670081) (xy 25.320075 -96.652062)
			(xy 25.374954 -96.641925) (xy 25.430725 -96.639887) (xy 25.486199 -96.64599) (xy 25.540192 -96.660106)
			(xy 25.591555 -96.681933) (xy 25.639193 -96.711006) (xy 25.682089 -96.746705) (xy 25.719331 -96.788269)
			(xy 25.750125 -96.834813) (xy 25.773813 -96.885344) (xy 25.789891 -96.938786) (xy 25.798017 -96.994)
			(xy 25.798526 -97.021904) (xy 25.798017 -97.049808) (xy 25.789891 -97.105022) (xy 25.773813 -97.158464)
			(xy 25.750125 -97.208995) (xy 25.719331 -97.255539) (xy 25.682089 -97.297103) (xy 25.639193 -97.332802)
			(xy 25.591555 -97.361875) (xy 25.540192 -97.383702) (xy 25.486199 -97.397818) (xy 25.430725 -97.403921)
			(xy 25.374954 -97.401883) (xy 25.320075 -97.391746) (xy 25.267255 -97.373727) (xy 25.217623 -97.348209)
			(xy 25.172235 -97.315737) (xy 25.132058 -97.277002) (xy 25.09795 -97.23283) (xy 25.070636 -97.184162)
			(xy 25.0507 -97.132036) (xy 25.038565 -97.077563) (xy 25.034492 -97.021904) (xy 4.308094 -97.021904)
			(xy 4.308094 -241.031522) (xy 4.307605 -241.10188) (xy 4.299704 -241.242374) (xy 4.283937 -241.382205)
			(xy 4.260354 -241.52093) (xy 4.229028 -241.658116) (xy 4.190059 -241.793328) (xy 4.143568 -241.926143)
			(xy 4.089703 -242.056141) (xy 4.028633 -242.182915) (xy 3.960549 -242.306064) (xy 3.885667 -242.425201)
			(xy 3.804222 -242.539952) (xy 3.71647 -242.649955) (xy 3.622687 -242.754863) (xy 3.573272 -242.80495)
			(xy 0.94488 -245.433342) (xy 0.90756 -245.471344) (xy 0.837813 -245.551857) (xy 0.773985 -245.637139)
			(xy 0.716403 -245.726756) (xy 0.66536 -245.820253) (xy 0.621114 -245.917151) (xy 0.583893 -246.016959)
			(xy 0.553885 -246.119167) (xy 0.531243 -246.223255) (xy 0.516083 -246.328692) (xy 0.508481 -246.434943)
			(xy 0.508 -246.488204) (xy 0.508 -416.589972) (xy 0.508522 -416.645779) (xy 0.516863 -416.757081)
			(xy 0.533498 -416.867448) (xy 0.558335 -416.976264) (xy 0.591234 -417.082919) (xy 0.632011 -417.186818)
			(xy 0.680438 -417.287379) (xy 0.736245 -417.384039) (xy 0.79912 -417.476259) (xy 0.86871 -417.563523)
			(xy 0.944627 -417.645342) (xy 1.026446 -417.721259) (xy 1.113709 -417.790849) (xy 1.205929 -417.853724)
			(xy 1.302589 -417.909531) (xy 1.40315 -417.957958) (xy 1.507049 -417.998736) (xy 1.613704 -418.031635)
			(xy 1.72252 -418.056471) (xy 1.832887 -418.073107) (xy 1.944189 -418.081448) (xy 1.999996 -418.081968)
		)
		(stroke
			(width 0)
			(type solid)
		)
		(fill yes)
		(layer "F.Cu")
		(net "GND")
	)
	(gr_poly
		(pts
			(xy 113.45418 -338.062062) (xy 113.464243 -338.061623) (xy 113.482823 -338.053884) (xy 113.490248 -338.047076)
			(xy 114.046762 -337.490562) (xy 114.04727 -337.490054) (xy 114.053851 -337.482672) (xy 114.061302 -337.464374)
			(xy 114.061748 -337.454494) (xy 114.061748 -330.114656) (xy 114.062176 -330.104644) (xy 114.069855 -330.08615)
			(xy 114.084028 -330.072004) (xy 114.102535 -330.064358) (xy 114.112548 -330.063856) (xy 114.716052 -330.063856)
			(xy 114.719862 -330.063348) (xy 114.733324 -330.06157) (xy 114.746786 -330.060046) (xy 114.779044 -330.058776)
			(xy 114.780822 -330.058776) (xy 114.812826 -330.060046) (xy 114.826288 -330.06157) (xy 114.83975 -330.063348)
			(xy 114.84356 -330.063856) (xy 114.917728 -330.063856) (xy 114.927605 -330.063395) (xy 114.945906 -330.055956)
			(xy 114.953288 -330.049378) (xy 114.953542 -330.049124) (xy 115.353592 -329.649074) (xy 115.3541 -329.648566)
			(xy 115.360691 -329.641188) (xy 115.368156 -329.622889) (xy 115.368578 -329.613006) (xy 115.368578 -327.514458)
			(xy 115.360958 -327.495662) (xy 115.353592 -327.48855) (xy 113.105438 -325.240396) (xy 113.089436 -325.23303)
			(xy 113.080546 -325.232268) (xy 113.054425 -325.229277) (xy 113.003295 -325.217032) (xy 112.954331 -325.197882)
			(xy 112.908461 -325.17219) (xy 112.866554 -325.140441) (xy 112.829404 -325.103238) (xy 112.797714 -325.061286)
			(xy 112.772087 -325.015379) (xy 112.753006 -324.966388) (xy 112.740834 -324.915241) (xy 112.7379 -324.889114)
			(xy 112.737138 -324.880224) (xy 112.729772 -324.86473) (xy 112.644428 -324.779386) (xy 112.63703 -324.772542)
			(xy 112.61843 -324.76482) (xy 112.60836 -324.7644) (xy 112.203738 -324.7644) (xy 112.193953 -324.764851)
			(xy 112.175805 -324.772174) (xy 112.168432 -324.778624) (xy 112.118648 -324.826884) (xy 112.113499 -324.832203)
			(xy 112.106276 -324.845116) (xy 112.104424 -324.852284) (xy 112.101884 -324.863206) (xy 112.10163 -324.868032)
			(xy 112.10163 -324.868286) (xy 112.099981 -324.896027) (xy 112.089651 -324.95063) (xy 112.071505 -325.003154)
			(xy 112.045927 -325.052489) (xy 112.013458 -325.097588) (xy 111.974788 -325.137498) (xy 111.930734 -325.171371)
			(xy 111.88223 -325.198491) (xy 111.830303 -325.218284) (xy 111.776054 -325.23033) (xy 111.72063 -325.234373)
			(xy 111.665206 -325.23033) (xy 111.610957 -325.218284) (xy 111.55903 -325.198491) (xy 111.510526 -325.171371)
			(xy 111.466472 -325.137498) (xy 111.427802 -325.097588) (xy 111.395333 -325.052489) (xy 111.369755 -325.003154)
			(xy 111.351609 -324.95063) (xy 111.341279 -324.896027) (xy 111.33963 -324.868286) (xy 111.33963 -324.868032)
			(xy 111.339376 -324.863206) (xy 111.336836 -324.852284) (xy 111.334963 -324.845125) (xy 111.327743 -324.832215)
			(xy 111.322612 -324.826884) (xy 111.272828 -324.778624) (xy 111.265474 -324.77215) (xy 111.247311 -324.764849)
			(xy 111.237522 -324.7644) (xy 110.806738 -324.7644) (xy 110.796953 -324.764851) (xy 110.778805 -324.772174)
			(xy 110.771432 -324.778624) (xy 110.721648 -324.826884) (xy 110.716499 -324.832203) (xy 110.709276 -324.845116)
			(xy 110.707424 -324.852284) (xy 110.704884 -324.863206) (xy 110.70463 -324.868032) (xy 110.70463 -324.868286)
			(xy 110.702981 -324.896027) (xy 110.692651 -324.95063) (xy 110.674505 -325.003154) (xy 110.648927 -325.052489)
			(xy 110.616458 -325.097588) (xy 110.577788 -325.137498) (xy 110.533734 -325.171371) (xy 110.48523 -325.198491)
			(xy 110.433303 -325.218284) (xy 110.379054 -325.23033) (xy 110.32363 -325.234373) (xy 110.268206 -325.23033)
			(xy 110.213957 -325.218284) (xy 110.16203 -325.198491) (xy 110.113526 -325.171371) (xy 110.069472 -325.137498)
			(xy 110.030802 -325.097588) (xy 109.998333 -325.052489) (xy 109.972755 -325.003154) (xy 109.954609 -324.95063)
			(xy 109.944279 -324.896027) (xy 109.94263 -324.868286) (xy 109.94263 -324.868032) (xy 109.942376 -324.863206)
			(xy 109.939836 -324.852284) (xy 109.937963 -324.845125) (xy 109.930743 -324.832215) (xy 109.925612 -324.826884)
			(xy 109.875828 -324.778624) (xy 109.868474 -324.77215) (xy 109.850311 -324.764849) (xy 109.840522 -324.7644)
			(xy 109.409738 -324.7644) (xy 109.399953 -324.764851) (xy 109.381805 -324.772174) (xy 109.374432 -324.778624)
			(xy 109.324648 -324.826884) (xy 109.319499 -324.832203) (xy 109.312276 -324.845116) (xy 109.310424 -324.852284)
			(xy 109.307884 -324.863206) (xy 109.30763 -324.868032) (xy 109.30763 -324.868286) (xy 109.305981 -324.896027)
			(xy 109.295651 -324.95063) (xy 109.277505 -325.003154) (xy 109.251927 -325.052489) (xy 109.219458 -325.097588)
			(xy 109.180788 -325.137498) (xy 109.136734 -325.171371) (xy 109.08823 -325.198491) (xy 109.036303 -325.218284)
			(xy 108.982054 -325.23033) (xy 108.92663 -325.234373) (xy 108.871206 -325.23033) (xy 108.816957 -325.218284)
			(xy 108.76503 -325.198491) (xy 108.716526 -325.171371) (xy 108.672472 -325.137498) (xy 108.633802 -325.097588)
			(xy 108.601333 -325.052489) (xy 108.575755 -325.003154) (xy 108.557609 -324.95063) (xy 108.547279 -324.896027)
			(xy 108.54563 -324.868286) (xy 108.54563 -324.868032) (xy 108.545376 -324.863206) (xy 108.542836 -324.852284)
			(xy 108.540963 -324.845125) (xy 108.533743 -324.832215) (xy 108.528612 -324.826884) (xy 108.478828 -324.778624)
			(xy 108.471474 -324.77215) (xy 108.453311 -324.764849) (xy 108.443522 -324.7644) (xy 98.92665 -324.7644)
			(xy 98.907854 -324.77202) (xy 98.900742 -324.779386) (xy 97.855024 -325.825104) (xy 104.056178 -325.825104)
			(xy 104.060249 -325.769482) (xy 104.072375 -325.715045) (xy 104.092298 -325.662954) (xy 104.119594 -325.614319)
			(xy 104.15368 -325.570176) (xy 104.193829 -325.531467) (xy 104.239187 -325.499016) (xy 104.288787 -325.473515)
			(xy 104.341571 -325.455508) (xy 104.396414 -325.445378) (xy 104.452148 -325.443341) (xy 104.507585 -325.449441)
			(xy 104.561542 -325.463547) (xy 104.612871 -325.485359) (xy 104.660477 -325.514413) (xy 104.703345 -325.550088)
			(xy 104.740562 -325.591625) (xy 104.771335 -325.638138) (xy 104.795007 -325.688635) (xy 104.811075 -325.742042)
			(xy 104.819195 -325.797218) (xy 104.819704 -325.825104) (xy 104.819195 -325.85299) (xy 104.811075 -325.908166)
			(xy 104.795007 -325.961573) (xy 104.771335 -326.01207) (xy 104.740562 -326.058583) (xy 104.703345 -326.10012)
			(xy 104.660477 -326.135795) (xy 104.612871 -326.164849) (xy 104.561542 -326.186661) (xy 104.507585 -326.200767)
			(xy 104.452148 -326.206867) (xy 104.396414 -326.20483) (xy 104.341571 -326.1947) (xy 104.288787 -326.176693)
			(xy 104.239187 -326.151192) (xy 104.193829 -326.118741) (xy 104.15368 -326.080032) (xy 104.119594 -326.035889)
			(xy 104.092298 -325.987254) (xy 104.072375 -325.935163) (xy 104.060249 -325.880726) (xy 104.056178 -325.825104)
			(xy 97.855024 -325.825104) (xy 97.534222 -326.145906) (xy 97.527374 -326.153304) (xy 97.519639 -326.171902)
			(xy 97.519236 -326.181974) (xy 97.519236 -326.916034) (xy 100.632512 -326.916034) (xy 100.636583 -326.860412)
			(xy 100.648709 -326.805975) (xy 100.668632 -326.753884) (xy 100.695928 -326.705249) (xy 100.730014 -326.661106)
			(xy 100.770163 -326.622397) (xy 100.815521 -326.589946) (xy 100.865121 -326.564445) (xy 100.917905 -326.546438)
			(xy 100.972748 -326.536308) (xy 101.028482 -326.534271) (xy 101.083919 -326.540371) (xy 101.137876 -326.554477)
			(xy 101.189205 -326.576289) (xy 101.236811 -326.605343) (xy 101.279679 -326.641018) (xy 101.316896 -326.682555)
			(xy 101.337433 -326.713596) (xy 109.961678 -326.713596) (xy 109.965749 -326.657974) (xy 109.977875 -326.603537)
			(xy 109.997798 -326.551446) (xy 110.025094 -326.502811) (xy 110.05918 -326.458668) (xy 110.099329 -326.419959)
			(xy 110.144687 -326.387508) (xy 110.194287 -326.362007) (xy 110.247071 -326.344) (xy 110.301914 -326.33387)
			(xy 110.357648 -326.331833) (xy 110.413085 -326.337933) (xy 110.467042 -326.352039) (xy 110.518371 -326.373851)
			(xy 110.565977 -326.402905) (xy 110.608845 -326.43858) (xy 110.646062 -326.480117) (xy 110.676835 -326.52663)
			(xy 110.700507 -326.577127) (xy 110.716575 -326.630534) (xy 110.724695 -326.68571) (xy 110.725204 -326.713596)
			(xy 110.724695 -326.741482) (xy 110.718706 -326.782176) (xy 110.867696 -326.782176) (xy 110.871767 -326.726554)
			(xy 110.883893 -326.672117) (xy 110.903816 -326.620026) (xy 110.931112 -326.571391) (xy 110.965198 -326.527248)
			(xy 111.005347 -326.488539) (xy 111.050705 -326.456088) (xy 111.100305 -326.430587) (xy 111.153089 -326.41258)
			(xy 111.207932 -326.40245) (xy 111.263666 -326.400413) (xy 111.319103 -326.406513) (xy 111.37306 -326.420619)
			(xy 111.424389 -326.442431) (xy 111.471995 -326.471485) (xy 111.514863 -326.50716) (xy 111.55208 -326.548697)
			(xy 111.582853 -326.59521) (xy 111.606525 -326.645707) (xy 111.622593 -326.699114) (xy 111.630713 -326.75429)
			(xy 111.631222 -326.782176) (xy 111.630713 -326.810062) (xy 111.622593 -326.865238) (xy 111.606525 -326.918645)
			(xy 111.582853 -326.969142) (xy 111.55208 -327.015655) (xy 111.514863 -327.057192) (xy 111.471995 -327.092867)
			(xy 111.424389 -327.121921) (xy 111.37306 -327.143733) (xy 111.319103 -327.157839) (xy 111.263666 -327.163939)
			(xy 111.207932 -327.161902) (xy 111.153089 -327.151772) (xy 111.100305 -327.133765) (xy 111.050705 -327.108264)
			(xy 111.005347 -327.075813) (xy 110.965198 -327.037104) (xy 110.931112 -326.992961) (xy 110.903816 -326.944326)
			(xy 110.883893 -326.892235) (xy 110.871767 -326.837798) (xy 110.867696 -326.782176) (xy 110.718706 -326.782176)
			(xy 110.716575 -326.796658) (xy 110.700507 -326.850065) (xy 110.676835 -326.900562) (xy 110.646062 -326.947075)
			(xy 110.608845 -326.988612) (xy 110.565977 -327.024287) (xy 110.518371 -327.053341) (xy 110.467042 -327.075153)
			(xy 110.413085 -327.089259) (xy 110.357648 -327.095359) (xy 110.301914 -327.093322) (xy 110.247071 -327.083192)
			(xy 110.194287 -327.065185) (xy 110.144687 -327.039684) (xy 110.099329 -327.007233) (xy 110.05918 -326.968524)
			(xy 110.025094 -326.924381) (xy 109.997798 -326.875746) (xy 109.977875 -326.823655) (xy 109.965749 -326.769218)
			(xy 109.961678 -326.713596) (xy 101.337433 -326.713596) (xy 101.347669 -326.729068) (xy 101.371341 -326.779565)
			(xy 101.387409 -326.832972) (xy 101.395529 -326.888148) (xy 101.396038 -326.916034) (xy 101.395529 -326.94392)
			(xy 101.387409 -326.999096) (xy 101.371341 -327.052503) (xy 101.347669 -327.103) (xy 101.316896 -327.149513)
			(xy 101.279679 -327.19105) (xy 101.236811 -327.226725) (xy 101.189205 -327.255779) (xy 101.137876 -327.277591)
			(xy 101.083919 -327.291697) (xy 101.028482 -327.297797) (xy 100.972748 -327.29576) (xy 100.917905 -327.28563)
			(xy 100.865121 -327.267623) (xy 100.815521 -327.242122) (xy 100.770163 -327.209671) (xy 100.730014 -327.170962)
			(xy 100.695928 -327.126819) (xy 100.668632 -327.078184) (xy 100.648709 -327.026093) (xy 100.636583 -326.971656)
			(xy 100.632512 -326.916034) (xy 97.519236 -326.916034) (xy 97.519236 -328.995786) (xy 97.518982 -329.00112)
			(xy 97.517712 -329.01255) (xy 97.531174 -329.050904) (xy 97.533617 -329.057313) (xy 97.541338 -329.068643)
			(xy 97.546414 -329.073256) (xy 97.548192 -329.074526) (xy 97.60839 -329.116436) (xy 97.617168 -329.121995)
			(xy 97.637496 -329.126181) (xy 97.64776 -329.124564) (xy 97.655634 -329.12304) (xy 97.659952 -329.12177)
			(xy 97.660968 -329.121262) (xy 97.685468 -329.112974) (xy 97.735865 -329.101338) (xy 97.787253 -329.095466)
			(xy 97.813114 -329.0951) (xy 97.823782 -329.0951) (xy 97.856145 -329.09641) (xy 97.92004 -329.107023)
			(xy 97.9818 -329.12654) (xy 98.011234 -329.140058) (xy 98.01606 -329.142344) (xy 98.038412 -329.148186)
			(xy 98.051874 -329.146662) (xy 98.089974 -329.136248) (xy 98.104452 -329.126088) (xy 98.109786 -329.118722)
			(xy 98.130614 -329.091544) (xy 98.15027 -329.068748) (xy 98.195103 -329.028588) (xy 98.245306 -328.995384)
			(xy 98.29981 -328.969845) (xy 98.357452 -328.952516) (xy 98.417003 -328.943765) (xy 98.447098 -328.943208)
			(xy 98.475261 -328.943666) (xy 98.531064 -328.951336) (xy 98.585302 -328.966533) (xy 98.636966 -328.988973)
			(xy 98.685092 -329.018239) (xy 98.728786 -329.053787) (xy 98.767232 -329.094952) (xy 98.799715 -329.140969)
			(xy 98.825629 -329.190981) (xy 98.844492 -329.244056) (xy 98.855952 -329.299204) (xy 98.859796 -329.3554)
			(xy 98.855952 -329.411596) (xy 98.844492 -329.466744) (xy 98.825629 -329.519819) (xy 98.799715 -329.569831)
			(xy 98.767232 -329.615848) (xy 98.728786 -329.657013) (xy 98.685092 -329.692561) (xy 98.636966 -329.721827)
			(xy 98.585302 -329.744267) (xy 98.531064 -329.759464) (xy 98.475261 -329.767134) (xy 98.447098 -329.767692)
			(xy 98.446844 -329.767692) (xy 98.414586 -329.766422) (xy 98.40087 -329.764898) (xy 98.38817 -329.76312)
			(xy 98.376994 -329.761342) (xy 98.355658 -329.767692) (xy 98.288602 -329.825604) (xy 98.2807 -329.833161)
			(xy 98.271636 -329.853036) (xy 98.271076 -329.863958) (xy 98.271076 -330.10602) (xy 98.271587 -330.116952)
			(xy 98.280663 -330.136842) (xy 98.288602 -330.144374) (xy 98.355404 -330.202032) (xy 98.37674 -330.208382)
			(xy 98.387916 -330.206604) (xy 98.402625 -330.20453) (xy 98.432245 -330.202244) (xy 98.447098 -330.202032)
			(xy 98.476545 -330.202557) (xy 98.534841 -330.210938) (xy 98.59135 -330.22753) (xy 98.644923 -330.251994)
			(xy 98.694469 -330.283834) (xy 98.73898 -330.3224) (xy 98.777549 -330.366909) (xy 98.809392 -330.416453)
			(xy 98.833861 -330.470024) (xy 98.850456 -330.526532) (xy 98.858841 -330.584827) (xy 98.85934 -330.614274)
			(xy 98.85934 -330.622402) (xy 98.861118 -330.630022) (xy 98.861118 -330.63053) (xy 98.866885 -330.654955)
			(xy 98.873127 -330.704752) (xy 98.873564 -330.729844) (xy 98.873564 -330.730606) (xy 98.873039 -330.760041)
			(xy 98.864664 -330.818313) (xy 98.848084 -330.874801) (xy 98.823638 -330.928356) (xy 98.791821 -330.977888)
			(xy 98.753283 -331.022391) (xy 98.708805 -331.060959) (xy 98.659293 -331.092808) (xy 98.605754 -331.11729)
			(xy 98.549277 -331.133906) (xy 98.491011 -331.14232) (xy 98.461576 -331.142848) (xy 98.432762 -331.142366)
			(xy 98.375696 -331.134335) (xy 98.320306 -331.118432) (xy 98.267671 -331.094969) (xy 98.218818 -331.064402)
			(xy 98.174699 -331.027328) (xy 98.136175 -330.984469) (xy 98.103997 -330.936661) (xy 98.09099 -330.910946)
			(xy 98.08718 -330.903072) (xy 98.067622 -330.884022) (xy 98.060764 -330.877418) (xy 97.998788 -330.851002)
			(xy 97.98812 -330.8477) (xy 97.98161 -330.84672) (xy 97.96849 -330.847751) (xy 97.962212 -330.849732)
			(xy 97.926279 -330.861268) (xy 97.85186 -330.873781) (xy 97.81413 -330.874624) (xy 97.805494 -330.87437)
			(xy 97.804986 -330.87437) (xy 97.767711 -330.873032) (xy 97.694321 -330.85975) (xy 97.658936 -330.847954)
			(xy 97.655634 -330.846684) (xy 97.6376 -330.842874) (xy 97.617026 -330.847192) (xy 97.60839 -330.853288)
			(xy 97.54108 -330.900024) (xy 97.531413 -330.907639) (xy 97.520004 -330.929398) (xy 97.519236 -330.94168)
			(xy 97.519236 -332.038452) (xy 99.004118 -332.038452) (xy 99.008189 -331.98283) (xy 99.020315 -331.928393)
			(xy 99.040238 -331.876302) (xy 99.067534 -331.827667) (xy 99.10162 -331.783524) (xy 99.141769 -331.744815)
			(xy 99.187127 -331.712364) (xy 99.236727 -331.686863) (xy 99.289511 -331.668856) (xy 99.344354 -331.658726)
			(xy 99.400088 -331.656689) (xy 99.455525 -331.662789) (xy 99.509482 -331.676895) (xy 99.560811 -331.698707)
			(xy 99.608417 -331.727761) (xy 99.651285 -331.763436) (xy 99.688502 -331.804973) (xy 99.719275 -331.851486)
			(xy 99.742947 -331.901983) (xy 99.759015 -331.95539) (xy 99.767135 -332.010566) (xy 99.767644 -332.038452)
			(xy 99.767135 -332.066338) (xy 99.759015 -332.121514) (xy 99.742947 -332.174921) (xy 99.719275 -332.225418)
			(xy 99.688502 -332.271931) (xy 99.651285 -332.313468) (xy 99.608417 -332.349143) (xy 99.560811 -332.378197)
			(xy 99.509482 -332.400009) (xy 99.455525 -332.414115) (xy 99.400088 -332.420215) (xy 99.344354 -332.418178)
			(xy 99.289511 -332.408048) (xy 99.236727 -332.390041) (xy 99.187127 -332.36454) (xy 99.141769 -332.332089)
			(xy 99.10162 -332.29338) (xy 99.067534 -332.249237) (xy 99.040238 -332.200602) (xy 99.020315 -332.148511)
			(xy 99.008189 -332.094074) (xy 99.004118 -332.038452) (xy 97.519236 -332.038452) (xy 97.519236 -333.614522)
			(xy 100.858828 -333.614522) (xy 100.859276 -333.587268) (xy 100.867031 -333.533315) (xy 100.882386 -333.481014)
			(xy 100.905028 -333.431432) (xy 100.934497 -333.385577) (xy 100.970193 -333.344383) (xy 101.011388 -333.308689)
			(xy 101.057244 -333.279222) (xy 101.106827 -333.256581) (xy 101.159128 -333.241228) (xy 101.213082 -333.233475)
			(xy 101.240336 -333.233014) (xy 101.260757 -333.233335) (xy 101.301357 -333.237788) (xy 101.321362 -333.241904)
			(xy 101.32187 -333.241904) (xy 101.3333 -333.24419) (xy 101.344222 -333.24165) (xy 101.349806 -333.240212)
			(xy 101.360198 -333.235223) (xy 101.364796 -333.231744) (xy 101.42601 -333.182214) (xy 101.434486 -333.174632)
			(xy 101.444385 -333.154195) (xy 101.44506 -333.142844) (xy 101.44506 -332.523084) (xy 101.44564 -332.497362)
			(xy 101.454347 -332.446659) (xy 101.471429 -332.398132) (xy 101.496402 -332.353154) (xy 101.528559 -332.312997)
			(xy 101.547422 -332.2955) (xy 101.645212 -332.208378) (xy 101.649311 -332.204917) (xy 101.658667 -332.19967)
			(xy 101.663754 -332.197964) (xy 101.767386 -332.165452) (xy 101.772471 -332.164071) (xy 101.782968 -332.163176)
			(xy 101.788214 -332.163674) (xy 101.788468 -332.163674) (xy 101.834188 -332.168754) (xy 101.842316 -332.16977)
			(xy 101.856794 -332.170532) (xy 101.873439 -332.169952) (xy 101.905597 -332.161338) (xy 101.934429 -332.144696)
			(xy 101.957973 -332.12116) (xy 101.974624 -332.092332) (xy 101.983247 -332.060177) (xy 101.983794 -332.043532)
			(xy 101.983277 -332.026878) (xy 101.974663 -331.994704) (xy 101.958014 -331.965856) (xy 101.934464 -331.942302)
			(xy 101.90562 -331.925647) (xy 101.873448 -331.917026) (xy 101.856794 -331.916532) (xy 101.842316 -331.917294)
			(xy 101.842062 -331.917294) (xy 101.788468 -331.92339) (xy 101.788214 -331.92339) (xy 101.782968 -331.923911)
			(xy 101.772465 -331.923022) (xy 101.767386 -331.921612) (xy 101.663754 -331.8891) (xy 101.658671 -331.887388)
			(xy 101.649328 -331.882125) (xy 101.645212 -331.878686) (xy 101.547422 -331.791564) (xy 101.528538 -331.774088)
			(xy 101.496382 -331.733926) (xy 101.471412 -331.688943) (xy 101.454334 -331.640411) (xy 101.445632 -331.589704)
			(xy 101.44506 -331.56398) (xy 101.44506 -329.375008) (xy 101.425756 -329.348338) (xy 101.410008 -329.343258)
			(xy 101.383325 -329.334058) (xy 101.33281 -329.308882) (xy 101.286553 -329.276543) (xy 101.245563 -329.237744)
			(xy 101.210733 -329.193332) (xy 101.182822 -329.144275) (xy 101.16244 -329.091644) (xy 101.15003 -329.036584)
			(xy 101.145864 -328.980298) (xy 101.150031 -328.924011) (xy 101.162442 -328.868952) (xy 101.182825 -328.81632)
			(xy 101.210736 -328.767264) (xy 101.245566 -328.722852) (xy 101.286557 -328.684054) (xy 101.332814 -328.651715)
			(xy 101.383329 -328.62654) (xy 101.410008 -328.617326) (xy 101.425756 -328.612246) (xy 101.44506 -328.585576)
			(xy 101.44506 -328.03465) (xy 101.445566 -328.010673) (xy 101.453135 -327.963319) (xy 101.468016 -327.917732)
			(xy 101.489843 -327.875032) (xy 101.518079 -327.836271) (xy 101.534722 -327.819004) (xy 101.853746 -327.499726)
			(xy 101.871075 -327.483067) (xy 101.91001 -327.454877) (xy 101.952879 -327.433133) (xy 101.998625 -327.418373)
			(xy 102.046119 -327.410961) (xy 102.070154 -327.410572) (xy 104.75087 -327.410572) (xy 104.773261 -327.410938)
			(xy 104.817575 -327.417394) (xy 104.860472 -327.430246) (xy 104.901036 -327.449218) (xy 104.911742 -327.456292)
			(xy 108.97184 -327.456292) (xy 108.975911 -327.40067) (xy 108.988037 -327.346233) (xy 109.00796 -327.294142)
			(xy 109.035256 -327.245507) (xy 109.069342 -327.201364) (xy 109.109491 -327.162655) (xy 109.154849 -327.130204)
			(xy 109.204449 -327.104703) (xy 109.257233 -327.086696) (xy 109.312076 -327.076566) (xy 109.36781 -327.074529)
			(xy 109.423247 -327.080629) (xy 109.477204 -327.094735) (xy 109.528533 -327.116547) (xy 109.576139 -327.145601)
			(xy 109.619007 -327.181276) (xy 109.656224 -327.222813) (xy 109.686997 -327.269326) (xy 109.710669 -327.319823)
			(xy 109.726737 -327.37323) (xy 109.734857 -327.428406) (xy 109.735366 -327.456292) (xy 111.608106 -327.456292)
			(xy 111.612177 -327.40067) (xy 111.624303 -327.346233) (xy 111.644226 -327.294142) (xy 111.671522 -327.245507)
			(xy 111.705608 -327.201364) (xy 111.745757 -327.162655) (xy 111.791115 -327.130204) (xy 111.840715 -327.104703)
			(xy 111.893499 -327.086696) (xy 111.948342 -327.076566) (xy 112.004076 -327.074529) (xy 112.059513 -327.080629)
			(xy 112.11347 -327.094735) (xy 112.164799 -327.116547) (xy 112.212405 -327.145601) (xy 112.255273 -327.181276)
			(xy 112.29249 -327.222813) (xy 112.323263 -327.269326) (xy 112.346935 -327.319823) (xy 112.363003 -327.37323)
			(xy 112.371123 -327.428406) (xy 112.371632 -327.456292) (xy 112.371123 -327.484178) (xy 112.363003 -327.539354)
			(xy 112.346935 -327.592761) (xy 112.323263 -327.643258) (xy 112.29249 -327.689771) (xy 112.255273 -327.731308)
			(xy 112.212405 -327.766983) (xy 112.164799 -327.796037) (xy 112.11347 -327.817849) (xy 112.059513 -327.831955)
			(xy 112.004076 -327.838055) (xy 111.948342 -327.836018) (xy 111.893499 -327.825888) (xy 111.840715 -327.807881)
			(xy 111.791115 -327.78238) (xy 111.745757 -327.749929) (xy 111.705608 -327.71122) (xy 111.671522 -327.667077)
			(xy 111.644226 -327.618442) (xy 111.624303 -327.566351) (xy 111.612177 -327.511914) (xy 111.608106 -327.456292)
			(xy 109.735366 -327.456292) (xy 109.734857 -327.484178) (xy 109.726737 -327.539354) (xy 109.710669 -327.592761)
			(xy 109.686997 -327.643258) (xy 109.656224 -327.689771) (xy 109.619007 -327.731308) (xy 109.576139 -327.766983)
			(xy 109.528533 -327.796037) (xy 109.477204 -327.817849) (xy 109.423247 -327.831955) (xy 109.36781 -327.838055)
			(xy 109.312076 -327.836018) (xy 109.257233 -327.825888) (xy 109.204449 -327.807881) (xy 109.154849 -327.78238)
			(xy 109.109491 -327.749929) (xy 109.069342 -327.71122) (xy 109.035256 -327.667077) (xy 109.00796 -327.618442)
			(xy 108.988037 -327.566351) (xy 108.975911 -327.511914) (xy 108.97184 -327.456292) (xy 104.911742 -327.456292)
			(xy 104.938398 -327.473905) (xy 104.95534 -327.48855) (xy 104.958388 -327.49109) (xy 104.969577 -327.499181)
			(xy 104.994603 -327.510836) (xy 105.021548 -327.516842) (xy 105.03535 -327.517252) (xy 105.035604 -327.517252)
			(xy 105.050336 -327.51649) (xy 105.051352 -327.51649) (xy 105.109264 -327.51014) (xy 105.114798 -327.509709)
			(xy 105.125822 -327.510985) (xy 105.131108 -327.51268) (xy 105.240074 -327.549764) (xy 105.245527 -327.551801)
			(xy 105.255405 -327.557954) (xy 105.259632 -327.561956) (xy 105.776014 -328.078592) (xy 105.792646 -328.095868)
			(xy 105.797637 -328.102722) (xy 107.71581 -328.102722) (xy 107.719881 -328.0471) (xy 107.732007 -327.992663)
			(xy 107.75193 -327.940572) (xy 107.779226 -327.891937) (xy 107.813312 -327.847794) (xy 107.853461 -327.809085)
			(xy 107.898819 -327.776634) (xy 107.948419 -327.751133) (xy 108.001203 -327.733126) (xy 108.056046 -327.722996)
			(xy 108.11178 -327.720959) (xy 108.167217 -327.727059) (xy 108.221174 -327.741165) (xy 108.272503 -327.762977)
			(xy 108.320109 -327.792031) (xy 108.362977 -327.827706) (xy 108.400194 -327.869243) (xy 108.430967 -327.915756)
			(xy 108.454639 -327.966253) (xy 108.470707 -328.01966) (xy 108.478827 -328.074836) (xy 108.479336 -328.102722)
			(xy 108.478827 -328.130608) (xy 108.470707 -328.185784) (xy 108.454639 -328.239191) (xy 108.430967 -328.289688)
			(xy 108.400194 -328.336201) (xy 108.362977 -328.377738) (xy 108.320109 -328.413413) (xy 108.28731 -328.43343)
			(xy 114.249198 -328.43343) (xy 114.253269 -328.377808) (xy 114.265395 -328.323371) (xy 114.285318 -328.27128)
			(xy 114.312614 -328.222645) (xy 114.3467 -328.178502) (xy 114.386849 -328.139793) (xy 114.432207 -328.107342)
			(xy 114.481807 -328.081841) (xy 114.534591 -328.063834) (xy 114.589434 -328.053704) (xy 114.645168 -328.051667)
			(xy 114.700605 -328.057767) (xy 114.754562 -328.071873) (xy 114.805891 -328.093685) (xy 114.853497 -328.122739)
			(xy 114.896365 -328.158414) (xy 114.933582 -328.199951) (xy 114.964355 -328.246464) (xy 114.988027 -328.296961)
			(xy 115.004095 -328.350368) (xy 115.012215 -328.405544) (xy 115.012724 -328.43343) (xy 115.012215 -328.461316)
			(xy 115.004095 -328.516492) (xy 114.988027 -328.569899) (xy 114.964355 -328.620396) (xy 114.933582 -328.666909)
			(xy 114.896365 -328.708446) (xy 114.853497 -328.744121) (xy 114.805891 -328.773175) (xy 114.754562 -328.794987)
			(xy 114.700605 -328.809093) (xy 114.645168 -328.815193) (xy 114.589434 -328.813156) (xy 114.534591 -328.803026)
			(xy 114.481807 -328.785019) (xy 114.432207 -328.759518) (xy 114.386849 -328.727067) (xy 114.3467 -328.688358)
			(xy 114.312614 -328.644215) (xy 114.285318 -328.59558) (xy 114.265395 -328.543489) (xy 114.253269 -328.489052)
			(xy 114.249198 -328.43343) (xy 108.28731 -328.43343) (xy 108.272503 -328.442467) (xy 108.221174 -328.464279)
			(xy 108.167217 -328.478385) (xy 108.11178 -328.484485) (xy 108.056046 -328.482448) (xy 108.001203 -328.472318)
			(xy 107.948419 -328.454311) (xy 107.898819 -328.42881) (xy 107.853461 -328.396359) (xy 107.813312 -328.35765)
			(xy 107.779226 -328.313507) (xy 107.75193 -328.264872) (xy 107.732007 -328.212781) (xy 107.719881 -328.158344)
			(xy 107.71581 -328.102722) (xy 105.797637 -328.102722) (xy 105.820874 -328.134632) (xy 105.842699 -328.17733)
			(xy 105.857584 -328.222913) (xy 105.865163 -328.270263) (xy 105.865676 -328.294238) (xy 105.865676 -329.44943)
			(xy 114.249198 -329.44943) (xy 114.253269 -329.393808) (xy 114.265395 -329.339371) (xy 114.285318 -329.28728)
			(xy 114.312614 -329.238645) (xy 114.3467 -329.194502) (xy 114.386849 -329.155793) (xy 114.432207 -329.123342)
			(xy 114.481807 -329.097841) (xy 114.534591 -329.079834) (xy 114.589434 -329.069704) (xy 114.645168 -329.067667)
			(xy 114.700605 -329.073767) (xy 114.754562 -329.087873) (xy 114.805891 -329.109685) (xy 114.853497 -329.138739)
			(xy 114.896365 -329.174414) (xy 114.933582 -329.215951) (xy 114.964355 -329.262464) (xy 114.988027 -329.312961)
			(xy 115.004095 -329.366368) (xy 115.012215 -329.421544) (xy 115.012724 -329.44943) (xy 115.012215 -329.477316)
			(xy 115.004095 -329.532492) (xy 114.988027 -329.585899) (xy 114.964355 -329.636396) (xy 114.933582 -329.682909)
			(xy 114.896365 -329.724446) (xy 114.853497 -329.760121) (xy 114.805891 -329.789175) (xy 114.754562 -329.810987)
			(xy 114.700605 -329.825093) (xy 114.645168 -329.831193) (xy 114.589434 -329.829156) (xy 114.534591 -329.819026)
			(xy 114.481807 -329.801019) (xy 114.432207 -329.775518) (xy 114.386849 -329.743067) (xy 114.3467 -329.704358)
			(xy 114.312614 -329.660215) (xy 114.285318 -329.61158) (xy 114.265395 -329.559489) (xy 114.253269 -329.505052)
			(xy 114.249198 -329.44943) (xy 105.865676 -329.44943) (xy 105.865676 -329.9079) (xy 105.86604 -329.917925)
			(xy 105.873663 -329.936467) (xy 105.88782 -329.950661) (xy 105.896918 -329.95489) (xy 105.983532 -329.990958)
			(xy 105.992842 -329.994308) (xy 106.012609 -329.994416) (xy 106.030961 -329.987072) (xy 106.038396 -329.980544)
			(xy 106.038904 -329.980036) (xy 106.039158 -329.979782) (xy 106.060762 -329.959094) (xy 106.109197 -329.924)
			(xy 106.162516 -329.896897) (xy 106.219413 -329.878451) (xy 106.278492 -329.869113) (xy 106.308398 -329.86853)
			(xy 106.335654 -329.868917) (xy 106.38961 -329.876674) (xy 106.441914 -329.892032) (xy 106.491499 -329.914676)
			(xy 106.537357 -329.944147) (xy 106.578554 -329.979845) (xy 106.614251 -330.021041) (xy 106.643723 -330.066899)
			(xy 106.666368 -330.116485) (xy 106.681725 -330.168788) (xy 106.689483 -330.222744) (xy 106.689483 -330.22921)
			(xy 107.248196 -330.22921) (xy 107.252267 -330.173588) (xy 107.264393 -330.119151) (xy 107.284316 -330.06706)
			(xy 107.311612 -330.018425) (xy 107.345698 -329.974282) (xy 107.385847 -329.935573) (xy 107.431205 -329.903122)
			(xy 107.480805 -329.877621) (xy 107.533589 -329.859614) (xy 107.588432 -329.849484) (xy 107.644166 -329.847447)
			(xy 107.699603 -329.853547) (xy 107.75356 -329.867653) (xy 107.804889 -329.889465) (xy 107.852495 -329.918519)
			(xy 107.895363 -329.954194) (xy 107.93258 -329.995731) (xy 107.963353 -330.042244) (xy 107.987025 -330.092741)
			(xy 108.003093 -330.146148) (xy 108.011213 -330.201324) (xy 108.011722 -330.22921) (xy 108.011213 -330.257096)
			(xy 108.003093 -330.312272) (xy 107.987025 -330.365679) (xy 107.963353 -330.416176) (xy 107.93258 -330.462689)
			(xy 107.895363 -330.504226) (xy 107.852495 -330.539901) (xy 107.804889 -330.568955) (xy 107.75356 -330.590767)
			(xy 107.699603 -330.604873) (xy 107.644166 -330.610973) (xy 107.588432 -330.608936) (xy 107.533589 -330.598806)
			(xy 107.480805 -330.580799) (xy 107.431205 -330.555298) (xy 107.385847 -330.522847) (xy 107.345698 -330.484138)
			(xy 107.311612 -330.439995) (xy 107.284316 -330.39136) (xy 107.264393 -330.339269) (xy 107.252267 -330.284832)
			(xy 107.248196 -330.22921) (xy 106.689483 -330.22921) (xy 106.689483 -330.277256) (xy 106.681725 -330.331212)
			(xy 106.666368 -330.383515) (xy 106.643723 -330.433101) (xy 106.614251 -330.478959) (xy 106.578554 -330.520155)
			(xy 106.537357 -330.555853) (xy 106.491499 -330.585324) (xy 106.441914 -330.607968) (xy 106.38961 -330.623326)
			(xy 106.335654 -330.631083) (xy 106.308398 -330.631546) (xy 106.278492 -330.630962) (xy 106.219415 -330.621616)
			(xy 106.162519 -330.603168) (xy 106.109198 -330.576071) (xy 106.060756 -330.540987) (xy 106.039158 -330.520294)
			(xy 106.038904 -330.52004) (xy 106.038396 -330.519532) (xy 106.030991 -330.512956) (xy 106.012627 -330.505588)
			(xy 105.99284 -330.505732) (xy 105.983532 -330.509118) (xy 105.896918 -330.545186) (xy 105.887899 -330.549523)
			(xy 105.873815 -330.563709) (xy 105.866176 -330.582182) (xy 105.865676 -330.592176) (xy 105.865676 -331.545692)
			(xy 107.25353 -331.545692) (xy 107.257601 -331.49007) (xy 107.269727 -331.435633) (xy 107.28965 -331.383542)
			(xy 107.316946 -331.334907) (xy 107.351032 -331.290764) (xy 107.391181 -331.252055) (xy 107.436539 -331.219604)
			(xy 107.486139 -331.194103) (xy 107.538923 -331.176096) (xy 107.593766 -331.165966) (xy 107.6495 -331.163929)
			(xy 107.704937 -331.170029) (xy 107.758894 -331.184135) (xy 107.810223 -331.205947) (xy 107.857829 -331.235001)
			(xy 107.900697 -331.270676) (xy 107.937914 -331.312213) (xy 107.968687 -331.358726) (xy 107.992359 -331.409223)
			(xy 108.008427 -331.46263) (xy 108.016547 -331.517806) (xy 108.017056 -331.545692) (xy 108.016547 -331.573578)
			(xy 108.008427 -331.628754) (xy 107.992359 -331.682161) (xy 107.968687 -331.732658) (xy 107.937914 -331.779171)
			(xy 107.900697 -331.820708) (xy 107.857829 -331.856383) (xy 107.810223 -331.885437) (xy 107.758894 -331.907249)
			(xy 107.704937 -331.921355) (xy 107.6495 -331.927455) (xy 107.593766 -331.925418) (xy 107.538923 -331.915288)
			(xy 107.486139 -331.897281) (xy 107.436539 -331.87178) (xy 107.391181 -331.839329) (xy 107.351032 -331.80062)
			(xy 107.316946 -331.756477) (xy 107.28965 -331.707842) (xy 107.269727 -331.655751) (xy 107.257601 -331.601314)
			(xy 107.25353 -331.545692) (xy 105.865676 -331.545692) (xy 105.865676 -332.536292) (xy 105.866194 -332.546354)
			(xy 105.873973 -332.564917) (xy 105.888269 -332.579085) (xy 105.897426 -332.583282) (xy 105.999026 -332.624684)
			(xy 106.028998 -332.618334) (xy 106.03992 -332.607158) (xy 106.057985 -332.589215) (xy 106.097983 -332.557715)
			(xy 106.141816 -332.531813) (xy 106.188705 -332.511971) (xy 106.237815 -332.498541) (xy 106.288275 -332.491761)
			(xy 106.313732 -332.491334) (xy 106.340985 -332.491738) (xy 106.394935 -332.499499) (xy 106.447232 -332.514859)
			(xy 106.49681 -332.537504) (xy 106.542662 -332.566975) (xy 106.583853 -332.60267) (xy 106.619545 -332.643864)
			(xy 106.649011 -332.689718) (xy 106.671652 -332.739298) (xy 106.687008 -332.791596) (xy 106.694764 -332.845547)
			(xy 106.694764 -332.872842) (xy 107.243116 -332.872842) (xy 107.247187 -332.81722) (xy 107.259313 -332.762783)
			(xy 107.279236 -332.710692) (xy 107.306532 -332.662057) (xy 107.340618 -332.617914) (xy 107.380767 -332.579205)
			(xy 107.426125 -332.546754) (xy 107.475725 -332.521253) (xy 107.528509 -332.503246) (xy 107.583352 -332.493116)
			(xy 107.639086 -332.491079) (xy 107.694523 -332.497179) (xy 107.74848 -332.511285) (xy 107.799809 -332.533097)
			(xy 107.847415 -332.562151) (xy 107.890283 -332.597826) (xy 107.9275 -332.639363) (xy 107.958273 -332.685876)
			(xy 107.981945 -332.736373) (xy 107.998013 -332.78978) (xy 108.006133 -332.844956) (xy 108.006642 -332.872842)
			(xy 108.006133 -332.900728) (xy 107.998013 -332.955904) (xy 107.981945 -333.009311) (xy 107.958273 -333.059808)
			(xy 107.940307 -333.086964) (xy 111.605566 -333.086964) (xy 111.609637 -333.031342) (xy 111.621763 -332.976905)
			(xy 111.641686 -332.924814) (xy 111.668982 -332.876179) (xy 111.703068 -332.832036) (xy 111.743217 -332.793327)
			(xy 111.788575 -332.760876) (xy 111.838175 -332.735375) (xy 111.890959 -332.717368) (xy 111.945802 -332.707238)
			(xy 112.001536 -332.705201) (xy 112.056973 -332.711301) (xy 112.11093 -332.725407) (xy 112.162259 -332.747219)
			(xy 112.209865 -332.776273) (xy 112.252733 -332.811948) (xy 112.28995 -332.853485) (xy 112.320723 -332.899998)
			(xy 112.344395 -332.950495) (xy 112.360463 -333.003902) (xy 112.368583 -333.059078) (xy 112.369092 -333.086964)
			(xy 112.368583 -333.11485) (xy 112.360463 -333.170026) (xy 112.344395 -333.223433) (xy 112.320723 -333.27393)
			(xy 112.28995 -333.320443) (xy 112.252733 -333.36198) (xy 112.209865 -333.397655) (xy 112.162259 -333.426709)
			(xy 112.11093 -333.448521) (xy 112.056973 -333.462627) (xy 112.001536 -333.468727) (xy 111.945802 -333.46669)
			(xy 111.890959 -333.45656) (xy 111.838175 -333.438553) (xy 111.788575 -333.413052) (xy 111.743217 -333.380601)
			(xy 111.703068 -333.341892) (xy 111.668982 -333.297749) (xy 111.641686 -333.249114) (xy 111.621763 -333.197023)
			(xy 111.609637 -333.142586) (xy 111.605566 -333.086964) (xy 107.940307 -333.086964) (xy 107.9275 -333.106321)
			(xy 107.890283 -333.147858) (xy 107.847415 -333.183533) (xy 107.799809 -333.212587) (xy 107.74848 -333.234399)
			(xy 107.694523 -333.248505) (xy 107.639086 -333.254605) (xy 107.583352 -333.252568) (xy 107.528509 -333.242438)
			(xy 107.475725 -333.224431) (xy 107.426125 -333.19893) (xy 107.380767 -333.166479) (xy 107.340618 -333.12777)
			(xy 107.306532 -333.083627) (xy 107.279236 -333.034992) (xy 107.259313 -332.982901) (xy 107.247187 -332.928464)
			(xy 107.243116 -332.872842) (xy 106.694764 -332.872842) (xy 106.694764 -332.900053) (xy 106.687008 -332.954004)
			(xy 106.671652 -333.006302) (xy 106.649011 -333.055882) (xy 106.619545 -333.101736) (xy 106.583853 -333.14293)
			(xy 106.542662 -333.178625) (xy 106.49681 -333.208096) (xy 106.447232 -333.230741) (xy 106.394935 -333.246101)
			(xy 106.340985 -333.253862) (xy 106.313732 -333.25435) (xy 106.288273 -333.253941) (xy 106.237806 -333.247171)
			(xy 106.188689 -333.233747) (xy 106.141794 -333.213909) (xy 106.097955 -333.188007) (xy 106.057952 -333.156504)
			(xy 106.03992 -333.138526) (xy 106.028998 -333.12735) (xy 105.999026 -333.121) (xy 105.897426 -333.162402)
			(xy 105.888227 -333.16655) (xy 105.873865 -333.180703) (xy 105.866098 -333.19931) (xy 105.865676 -333.209392)
			(xy 105.865676 -334.186784) (xy 109.31271 -334.186784) (xy 109.313221 -334.158045) (xy 109.321847 -334.101217)
			(xy 109.338899 -334.046326) (xy 109.363994 -333.994614) (xy 109.396562 -333.947252) (xy 109.415834 -333.925926)
			(xy 109.416088 -333.925672) (xy 109.422135 -333.918402) (xy 109.429053 -333.900824) (xy 109.42955 -333.891382)
			(xy 109.430058 -333.822548) (xy 109.429982 -333.817731) (xy 109.428189 -333.808265) (xy 109.426502 -333.803752)
			(xy 109.4232 -333.79537) (xy 109.41685 -333.788004) (xy 109.416342 -333.787496) (xy 109.397807 -333.766342)
			(xy 109.366537 -333.719595) (xy 109.34246 -333.668767) (xy 109.326098 -333.614958) (xy 109.317805 -333.559331)
			(xy 109.317282 -333.53121) (xy 109.317768 -333.503959) (xy 109.325524 -333.450011) (xy 109.340879 -333.397716)
			(xy 109.363521 -333.348139) (xy 109.392987 -333.302289) (xy 109.428678 -333.261098) (xy 109.469869 -333.225407)
			(xy 109.515719 -333.195941) (xy 109.565296 -333.173299) (xy 109.617591 -333.157944) (xy 109.671539 -333.150188)
			(xy 109.726041 -333.150188) (xy 109.779989 -333.157944) (xy 109.832284 -333.173299) (xy 109.881861 -333.195941)
			(xy 109.927711 -333.225407) (xy 109.968902 -333.261098) (xy 110.004593 -333.302289) (xy 110.034059 -333.348139)
			(xy 110.056701 -333.397716) (xy 110.072056 -333.450011) (xy 110.079812 -333.503959) (xy 110.080298 -333.53121)
			(xy 110.079781 -333.559949) (xy 110.071157 -333.616777) (xy 110.054105 -333.671668) (xy 110.029012 -333.723379)
			(xy 109.996445 -333.770741) (xy 109.977174 -333.792068) (xy 109.97692 -333.792322) (xy 109.970876 -333.799595)
			(xy 109.963956 -333.817171) (xy 109.963458 -333.826612) (xy 109.96295 -333.895446) (xy 109.963034 -333.900263)
			(xy 109.964822 -333.909728) (xy 109.966506 -333.914242) (xy 109.969808 -333.922624) (xy 109.976158 -333.92999)
			(xy 109.976666 -333.930498) (xy 109.995199 -333.951653) (xy 110.02647 -333.9984) (xy 110.050547 -334.049228)
			(xy 110.066909 -334.103037) (xy 110.075203 -334.158664) (xy 110.075726 -334.186784) (xy 110.07524 -334.214035)
			(xy 110.067484 -334.267983) (xy 110.052129 -334.320278) (xy 110.029487 -334.369855) (xy 110.000021 -334.415705)
			(xy 109.96433 -334.456896) (xy 109.923139 -334.492587) (xy 109.877289 -334.522053) (xy 109.827712 -334.544695)
			(xy 109.775417 -334.56005) (xy 109.721469 -334.567806) (xy 109.666967 -334.567806) (xy 109.613019 -334.56005)
			(xy 109.560724 -334.544695) (xy 109.511147 -334.522053) (xy 109.465297 -334.492587) (xy 109.424106 -334.456896)
			(xy 109.388415 -334.415705) (xy 109.358949 -334.369855) (xy 109.336307 -334.320278) (xy 109.320952 -334.267983)
			(xy 109.313196 -334.214035) (xy 109.31271 -334.186784) (xy 105.865676 -334.186784) (xy 105.865676 -334.868012)
			(xy 105.865168 -334.892932) (xy 105.857024 -334.942102) (xy 105.841004 -334.989298) (xy 105.817533 -335.033266)
			(xy 105.787234 -335.072839) (xy 105.76941 -335.090262) (xy 105.768648 -335.09077) (xy 105.508806 -335.350612)
			(xy 105.508298 -335.351374) (xy 105.490873 -335.369196) (xy 105.451303 -335.399499) (xy 105.407336 -335.422971)
			(xy 105.360139 -335.438989) (xy 105.310968 -335.447126) (xy 105.286048 -335.44764) (xy 104.603042 -335.44764)
			(xy 104.578123 -335.447107) (xy 104.528953 -335.438971) (xy 104.481757 -335.422958) (xy 104.437789 -335.399492)
			(xy 104.398216 -335.369196) (xy 104.380792 -335.351374) (xy 104.379776 -335.350104) (xy 104.263952 -335.23428)
			(xy 104.262682 -335.233264) (xy 104.244836 -335.215862) (xy 104.214537 -335.176285) (xy 104.191071 -335.132312)
			(xy 104.175059 -335.085111) (xy 104.166928 -335.035935) (xy 104.166416 -335.011014) (xy 104.166416 -333.931768)
			(xy 104.16603 -333.921694) (xy 104.158284 -333.903095) (xy 104.15143 -333.8957) (xy 104.10698 -333.85125)
			(xy 104.099575 -333.844416) (xy 104.08098 -333.836691) (xy 104.070912 -333.836264) (xy 103.410258 -333.836264)
			(xy 103.400321 -333.836834) (xy 103.381971 -333.844481) (xy 103.367908 -333.858531) (xy 103.360244 -333.876873)
			(xy 103.359712 -333.88681) (xy 103.359712 -334.59039) (xy 103.359209 -334.61531) (xy 103.351067 -334.664482)
			(xy 103.335047 -334.711678) (xy 103.311574 -334.755646) (xy 103.281271 -334.795218) (xy 103.263446 -334.81264)
			(xy 103.262684 -334.813148) (xy 103.199692 -334.87614) (xy 103.199184 -334.876902) (xy 103.18177 -334.894736)
			(xy 103.142197 -334.925036) (xy 103.098227 -334.948506) (xy 103.051028 -334.96452) (xy 103.001854 -334.972655)
			(xy 102.976934 -334.973168) (xy 102.13213 -334.973168) (xy 102.107211 -334.972634) (xy 102.058042 -334.964497)
			(xy 102.010846 -334.948483) (xy 101.966878 -334.925018) (xy 101.927304 -334.894723) (xy 101.90988 -334.876902)
			(xy 101.909372 -334.87614) (xy 101.542088 -334.508856) (xy 101.541326 -334.508348) (xy 101.52348 -334.490946)
			(xy 101.49318 -334.45137) (xy 101.469712 -334.407397) (xy 101.4537 -334.360195) (xy 101.44557 -334.311019)
			(xy 101.44506 -334.286098) (xy 101.44506 -334.0862) (xy 101.444368 -334.074851) (xy 101.434484 -334.05441)
			(xy 101.42601 -334.04683) (xy 101.364796 -333.9973) (xy 101.360208 -333.993804) (xy 101.349814 -333.988809)
			(xy 101.344222 -333.987394) (xy 101.3333 -333.984854) (xy 101.32187 -333.98714) (xy 101.321362 -333.98714)
			(xy 101.301361 -333.991275) (xy 101.260758 -333.995726) (xy 101.240336 -333.99603) (xy 101.213085 -333.995511)
			(xy 101.159137 -333.98776) (xy 101.106842 -333.972409) (xy 101.057263 -333.949773) (xy 101.011411 -333.920311)
			(xy 100.970218 -333.884623) (xy 100.934524 -333.843436) (xy 100.905055 -333.797588) (xy 100.882411 -333.748013)
			(xy 100.867053 -333.69572) (xy 100.859293 -333.641773) (xy 100.858828 -333.614522) (xy 97.519236 -333.614522)
			(xy 97.519236 -335.69783) (xy 97.767392 -335.69783) (xy 97.771463 -335.642208) (xy 97.783589 -335.587771)
			(xy 97.803512 -335.53568) (xy 97.830808 -335.487045) (xy 97.864894 -335.442902) (xy 97.905043 -335.404193)
			(xy 97.950401 -335.371742) (xy 98.000001 -335.346241) (xy 98.052785 -335.328234) (xy 98.107628 -335.318104)
			(xy 98.163362 -335.316067) (xy 98.218799 -335.322167) (xy 98.272756 -335.336273) (xy 98.324085 -335.358085)
			(xy 98.371691 -335.387139) (xy 98.414559 -335.422814) (xy 98.451776 -335.464351) (xy 98.482549 -335.510864)
			(xy 98.506221 -335.561361) (xy 98.522289 -335.614768) (xy 98.530409 -335.669944) (xy 98.530918 -335.69783)
			(xy 98.530409 -335.725716) (xy 98.522289 -335.780892) (xy 98.506221 -335.834299) (xy 98.483988 -335.881726)
			(xy 111.234218 -335.881726) (xy 111.238289 -335.826104) (xy 111.250415 -335.771667) (xy 111.270338 -335.719576)
			(xy 111.297634 -335.670941) (xy 111.33172 -335.626798) (xy 111.371869 -335.588089) (xy 111.417227 -335.555638)
			(xy 111.466827 -335.530137) (xy 111.519611 -335.51213) (xy 111.574454 -335.502) (xy 111.630188 -335.499963)
			(xy 111.685625 -335.506063) (xy 111.739582 -335.520169) (xy 111.790911 -335.541981) (xy 111.838517 -335.571035)
			(xy 111.881385 -335.60671) (xy 111.918602 -335.648247) (xy 111.949375 -335.69476) (xy 111.973047 -335.745257)
			(xy 111.989115 -335.798664) (xy 111.997235 -335.85384) (xy 111.997744 -335.881726) (xy 111.997235 -335.909612)
			(xy 111.989115 -335.964788) (xy 111.973047 -336.018195) (xy 111.949375 -336.068692) (xy 111.918602 -336.115205)
			(xy 111.881385 -336.156742) (xy 111.838517 -336.192417) (xy 111.790911 -336.221471) (xy 111.739582 -336.243283)
			(xy 111.685625 -336.257389) (xy 111.630188 -336.263489) (xy 111.574454 -336.261452) (xy 111.519611 -336.251322)
			(xy 111.466827 -336.233315) (xy 111.417227 -336.207814) (xy 111.371869 -336.175363) (xy 111.33172 -336.136654)
			(xy 111.297634 -336.092511) (xy 111.270338 -336.043876) (xy 111.250415 -335.991785) (xy 111.238289 -335.937348)
			(xy 111.234218 -335.881726) (xy 98.483988 -335.881726) (xy 98.482549 -335.884796) (xy 98.451776 -335.931309)
			(xy 98.414559 -335.972846) (xy 98.371691 -336.008521) (xy 98.324085 -336.037575) (xy 98.272756 -336.059387)
			(xy 98.218799 -336.073493) (xy 98.163362 -336.079593) (xy 98.107628 -336.077556) (xy 98.052785 -336.067426)
			(xy 98.000001 -336.049419) (xy 97.950401 -336.023918) (xy 97.905043 -335.991467) (xy 97.864894 -335.952758)
			(xy 97.830808 -335.908615) (xy 97.803512 -335.85998) (xy 97.783589 -335.807889) (xy 97.771463 -335.753452)
			(xy 97.767392 -335.69783) (xy 97.519236 -335.69783) (xy 97.519236 -336.590275) (xy 108.719256 -336.590275)
			(xy 108.719256 -336.535725) (xy 108.727019 -336.48173) (xy 108.742388 -336.429389) (xy 108.76505 -336.379769)
			(xy 108.794543 -336.333879) (xy 108.830267 -336.292653) (xy 108.871495 -336.256931) (xy 108.917386 -336.227441)
			(xy 108.967008 -336.204781) (xy 109.019349 -336.189415) (xy 109.073345 -336.181654) (xy 109.10062 -336.181192)
			(xy 109.128555 -336.181703) (xy 109.183829 -336.189849) (xy 109.237325 -336.205963) (xy 109.287902 -336.229703)
			(xy 109.334478 -336.26056) (xy 109.37606 -336.297876) (xy 109.41176 -336.340854) (xy 109.440814 -336.388576)
			(xy 109.452156 -336.41411) (xy 109.457826 -336.426346) (xy 109.474455 -336.447563) (xy 109.496062 -336.463682)
			(xy 109.521138 -336.473576) (xy 109.54793 -336.476553) (xy 109.574566 -336.472407) (xy 109.599185 -336.461426)
			(xy 109.60989 -336.453226) (xy 109.630421 -336.437059) (xy 109.675055 -336.409881) (xy 109.722977 -336.38904)
			(xy 109.773292 -336.374926) (xy 109.825061 -336.367802) (xy 109.85119 -336.367374) (xy 109.878464 -336.367765)
			(xy 109.932457 -336.375527) (xy 109.984796 -336.390893) (xy 110.034415 -336.413553) (xy 110.080304 -336.443043)
			(xy 110.121529 -336.478764) (xy 110.157251 -336.519988) (xy 110.186743 -336.565876) (xy 110.209403 -336.615495)
			(xy 110.224771 -336.667833) (xy 110.232534 -336.721826) (xy 110.232534 -336.776374) (xy 110.224771 -336.830367)
			(xy 110.209403 -336.882705) (xy 110.186743 -336.932324) (xy 110.157251 -336.978212) (xy 110.121529 -337.019436)
			(xy 110.080304 -337.055157) (xy 110.034415 -337.084647) (xy 109.984796 -337.107307) (xy 109.932457 -337.122673)
			(xy 109.878464 -337.130435) (xy 109.85119 -337.130898) (xy 109.823255 -337.130385) (xy 109.767981 -337.12224)
			(xy 109.714484 -337.106126) (xy 109.663907 -337.082387) (xy 109.617331 -337.05153) (xy 109.575749 -337.014214)
			(xy 109.54005 -336.971236) (xy 109.510996 -336.923514) (xy 109.499654 -336.89798) (xy 109.493973 -336.885749)
			(xy 109.477345 -336.864535) (xy 109.45574 -336.848418) (xy 109.430667 -336.838524) (xy 109.403877 -336.835545)
			(xy 109.377243 -336.839689) (xy 109.352625 -336.850666) (xy 109.34192 -336.858864) (xy 109.321385 -336.875025)
			(xy 109.276752 -336.902205) (xy 109.228831 -336.923046) (xy 109.178517 -336.937162) (xy 109.126748 -336.944288)
			(xy 109.10062 -336.944716) (xy 109.073345 -336.944346) (xy 109.019349 -336.936585) (xy 108.967008 -336.921219)
			(xy 108.917386 -336.898559) (xy 108.871495 -336.869069) (xy 108.830267 -336.833347) (xy 108.794543 -336.792122)
			(xy 108.76505 -336.746231) (xy 108.742388 -336.696611) (xy 108.727019 -336.64427) (xy 108.719256 -336.590275)
			(xy 97.519236 -336.590275) (xy 97.519236 -336.98561) (xy 99.107496 -336.98561) (xy 99.111567 -336.929988)
			(xy 99.123693 -336.875551) (xy 99.143616 -336.82346) (xy 99.170912 -336.774825) (xy 99.204998 -336.730682)
			(xy 99.245147 -336.691973) (xy 99.290505 -336.659522) (xy 99.340105 -336.634021) (xy 99.392889 -336.616014)
			(xy 99.447732 -336.605884) (xy 99.503466 -336.603847) (xy 99.558903 -336.609947) (xy 99.61286 -336.624053)
			(xy 99.664189 -336.645865) (xy 99.711795 -336.674919) (xy 99.754663 -336.710594) (xy 99.79188 -336.752131)
			(xy 99.822653 -336.798644) (xy 99.846325 -336.849141) (xy 99.862393 -336.902548) (xy 99.870513 -336.957724)
			(xy 99.871022 -336.98561) (xy 99.870513 -337.013496) (xy 99.862393 -337.068672) (xy 99.846325 -337.122079)
			(xy 99.822653 -337.172576) (xy 99.79188 -337.219089) (xy 99.754663 -337.260626) (xy 99.711795 -337.296301)
			(xy 99.664189 -337.325355) (xy 99.61286 -337.347167) (xy 99.558903 -337.361273) (xy 99.503466 -337.367373)
			(xy 99.447732 -337.365336) (xy 99.392889 -337.355206) (xy 99.340105 -337.337199) (xy 99.290505 -337.311698)
			(xy 99.245147 -337.279247) (xy 99.204998 -337.240538) (xy 99.170912 -337.196395) (xy 99.143616 -337.14776)
			(xy 99.123693 -337.095669) (xy 99.111567 -337.041232) (xy 99.107496 -336.98561) (xy 97.519236 -336.98561)
			(xy 97.519236 -337.451954) (xy 97.51967 -337.462019) (xy 97.527402 -337.480606) (xy 97.534222 -337.488022)
			(xy 98.093276 -338.047076) (xy 98.100677 -338.053913) (xy 98.119276 -338.061624) (xy 98.129344 -338.062062)
		)
		(stroke
			(width 0)
			(type solid)
		)
		(fill yes)
		(layer "F.Cu")
		(net "P3V3_CLK_BUFFER_9ZXL0451E_VZX3P3")
	)
	(gr_poly
		(pts
			(xy 466.850984 -304.987452) (xy 466.861046 -304.987012) (xy 466.879624 -304.979271) (xy 466.887052 -304.972466)
			(xy 467.033356 -304.826162) (xy 467.040201 -304.818763) (xy 467.047929 -304.800165) (xy 467.048342 -304.790094)
			(xy 467.048342 -246.89308) (xy 467.04123 -246.875046) (xy 467.034372 -246.867934) (xy 467.031324 -246.864632)
			(xy 467.0298 -246.8626) (xy 466.798914 -246.631714) (xy 466.79208 -246.624311) (xy 466.784374 -246.605713)
			(xy 466.783928 -246.595646) (xy 466.783928 -245.624858) (xy 466.776816 -245.606824) (xy 466.769958 -245.599712)
			(xy 466.76691 -245.59641) (xy 466.765386 -245.594378) (xy 463.240882 -242.069874) (xy 463.234031 -242.062478)
			(xy 463.226293 -242.043879) (xy 463.225896 -242.033806) (xy 463.225896 -238.253778) (xy 463.225469 -238.24371)
			(xy 463.217748 -238.225111) (xy 463.21091 -238.21771) (xy 462.994502 -238.001302) (xy 462.987104 -237.994455)
			(xy 462.968506 -237.986719) (xy 462.958434 -237.986316) (xy 459.952852 -237.986316) (xy 459.947961 -237.986452)
			(xy 459.938369 -237.98837) (xy 459.933802 -237.990126) (xy 459.913482 -237.998254) (xy 459.909164 -237.999524)
			(xy 459.895956 -238.001302) (xy 445.868298 -238.001302) (xy 445.861423 -238.001489) (xy 445.848155 -238.005087)
			(xy 445.842136 -238.008414) (xy 445.815386 -238.023938) (xy 445.759204 -238.049806) (xy 445.70057 -238.069491)
			(xy 445.64016 -238.082766) (xy 445.578675 -238.089477) (xy 445.54775 -238.089948) (xy 443.6364 -238.089948)
			(xy 443.605472 -238.089515) (xy 443.54398 -238.082819) (xy 443.483564 -238.069548) (xy 443.424927 -238.049856)
			(xy 443.368747 -238.023971) (xy 443.342014 -238.008414) (xy 443.335987 -238.005108) (xy 443.322724 -238.001512)
			(xy 443.315852 -238.001302) (xy 441.649612 -238.001302) (xy 441.639541 -238.000881) (xy 441.620933 -237.99317)
			(xy 441.613544 -237.986316) (xy 440.699398 -237.07217) (xy 440.692557 -237.06477) (xy 440.684833 -237.046172)
			(xy 440.684412 -237.036102) (xy 440.684412 -221.856046) (xy 440.684845 -221.84598) (xy 440.692575 -221.827391)
			(xy 440.699398 -221.819978) (xy 442.150754 -220.368622) (xy 442.158155 -220.361782) (xy 442.176753 -220.354064)
			(xy 442.186822 -220.353636) (xy 462.859882 -220.353636) (xy 462.869944 -220.353196) (xy 462.888521 -220.345454)
			(xy 462.89595 -220.33865) (xy 463.21091 -220.02369) (xy 463.217765 -220.016295) (xy 463.22551 -219.997696)
			(xy 463.225896 -219.987622) (xy 463.225896 -122.524774) (xy 463.218784 -122.50674) (xy 463.211926 -122.499628)
			(xy 463.208878 -122.496326) (xy 463.207354 -122.494294) (xy 463.029808 -122.316748) (xy 463.022412 -122.309895)
			(xy 463.003814 -122.30215) (xy 462.99374 -122.301762) (xy 456.685142 -122.301762) (xy 456.6666 -122.309636)
			(xy 456.659488 -122.317002) (xy 456.657964 -122.318272) (xy 456.656186 -122.319542) (xy 451.26402 -127.711708)
			(xy 451.256617 -127.718541) (xy 451.238019 -127.726245) (xy 451.227952 -127.726694) (xy 436.88762 -127.726694)
			(xy 436.869078 -127.734568) (xy 436.861966 -127.741934) (xy 436.860442 -127.743204) (xy 436.858664 -127.744474)
			(xy 435.482492 -129.120646) (xy 435.475654 -129.128047) (xy 435.467937 -129.146645) (xy 435.467506 -129.156714)
			(xy 435.467506 -137.65276) (xy 444.341248 -137.65276) (xy 444.345319 -137.597138) (xy 444.357445 -137.542701)
			(xy 444.377368 -137.49061) (xy 444.404664 -137.441975) (xy 444.43875 -137.397832) (xy 444.478899 -137.359123)
			(xy 444.524257 -137.326672) (xy 444.573857 -137.301171) (xy 444.626641 -137.283164) (xy 444.681484 -137.273034)
			(xy 444.737218 -137.270997) (xy 444.792655 -137.277097) (xy 444.846612 -137.291203) (xy 444.897941 -137.313015)
			(xy 444.945547 -137.342069) (xy 444.988415 -137.377744) (xy 445.025632 -137.419281) (xy 445.056405 -137.465794)
			(xy 445.080077 -137.516291) (xy 445.096145 -137.569698) (xy 445.104265 -137.624874) (xy 445.104774 -137.65276)
			(xy 445.104265 -137.680646) (xy 445.096145 -137.735822) (xy 445.080077 -137.789229) (xy 445.056405 -137.839726)
			(xy 445.025632 -137.886239) (xy 444.988415 -137.927776) (xy 444.977268 -137.937053) (xy 445.665563 -137.937053)
			(xy 445.665563 -137.882547) (xy 445.67332 -137.828597) (xy 445.688676 -137.7763) (xy 445.711319 -137.72672)
			(xy 445.740787 -137.680868) (xy 445.77648 -137.639676) (xy 445.817673 -137.603983) (xy 445.863526 -137.574516)
			(xy 445.913106 -137.551874) (xy 445.965403 -137.536519) (xy 446.019353 -137.528763) (xy 446.046606 -137.5283)
			(xy 446.074709 -137.528782) (xy 446.130306 -137.537029) (xy 446.184092 -137.553344) (xy 446.234901 -137.577374)
			(xy 446.281636 -137.608598) (xy 446.323284 -137.646341) (xy 446.3415 -137.667746) (xy 446.348803 -137.675928)
			(xy 446.368414 -137.685684) (xy 446.379346 -137.686542) (xy 446.466976 -137.689082) (xy 446.487296 -137.680446)
			(xy 446.494662 -137.672318) (xy 446.512803 -137.653333) (xy 446.553392 -137.620017) (xy 446.598162 -137.592577)
			(xy 446.64627 -137.571529) (xy 446.696808 -137.557272) (xy 446.748823 -137.550074) (xy 446.775078 -137.549636)
			(xy 446.802335 -137.550009) (xy 446.856295 -137.557765) (xy 446.908601 -137.573121) (xy 446.95819 -137.595765)
			(xy 447.004051 -137.625235) (xy 447.045251 -137.660933) (xy 447.080951 -137.702131) (xy 447.110425 -137.747991)
			(xy 447.133072 -137.797578) (xy 447.148431 -137.849884) (xy 447.156189 -137.903843) (xy 447.156189 -137.958357)
			(xy 447.148431 -138.012316) (xy 447.133072 -138.064622) (xy 447.110425 -138.114209) (xy 447.080951 -138.160069)
			(xy 447.045251 -138.201267) (xy 447.004051 -138.236965) (xy 446.95819 -138.266435) (xy 446.908601 -138.289079)
			(xy 446.856295 -138.304435) (xy 446.802335 -138.312191) (xy 446.775078 -138.312652) (xy 446.746976 -138.312128)
			(xy 446.69138 -138.303892) (xy 446.637595 -138.287587) (xy 446.586784 -138.263565) (xy 446.540049 -138.232347)
			(xy 446.4984 -138.194609) (xy 446.480184 -138.173206) (xy 446.472879 -138.165026) (xy 446.45327 -138.155267)
			(xy 446.442338 -138.15441) (xy 446.354708 -138.15187) (xy 446.334388 -138.160506) (xy 446.327022 -138.168634)
			(xy 446.308879 -138.187617) (xy 446.268292 -138.220935) (xy 446.223523 -138.248377) (xy 446.175415 -138.269425)
			(xy 446.124877 -138.283682) (xy 446.072861 -138.290879) (xy 446.046606 -138.291316) (xy 446.019353 -138.290837)
			(xy 445.965403 -138.283081) (xy 445.913106 -138.267726) (xy 445.863526 -138.245084) (xy 445.817673 -138.215617)
			(xy 445.77648 -138.179924) (xy 445.740787 -138.138732) (xy 445.711319 -138.09288) (xy 445.688676 -138.0433)
			(xy 445.67332 -137.991003) (xy 445.665563 -137.937053) (xy 444.977268 -137.937053) (xy 444.945547 -137.963451)
			(xy 444.897941 -137.992505) (xy 444.846612 -138.014317) (xy 444.792655 -138.028423) (xy 444.737218 -138.034523)
			(xy 444.681484 -138.032486) (xy 444.626641 -138.022356) (xy 444.573857 -138.004349) (xy 444.524257 -137.978848)
			(xy 444.478899 -137.946397) (xy 444.43875 -137.907688) (xy 444.404664 -137.863545) (xy 444.377368 -137.81491)
			(xy 444.357445 -137.762819) (xy 444.345319 -137.708382) (xy 444.341248 -137.65276) (xy 435.467506 -137.65276)
			(xy 435.467506 -139.682728) (xy 435.467934 -139.692796) (xy 435.475657 -139.711392) (xy 435.482492 -139.718796)
			(xy 436.50916 -140.745464) (xy 436.516001 -140.752864) (xy 436.523718 -140.771463) (xy 436.524146 -140.781532)
			(xy 436.524146 -145.389346) (xy 436.523713 -145.399411) (xy 436.515981 -145.417998) (xy 436.50916 -145.425414)
			(xy 433.861972 -148.072602) (xy 433.855118 -148.079997) (xy 433.847373 -148.098596) (xy 433.846986 -148.10867)
			(xy 433.846986 -158.775654) (xy 433.846553 -158.78572) (xy 433.838823 -158.804308) (xy 433.832 -158.811722)
			(xy 431.748438 -160.895284) (xy 431.741037 -160.902122) (xy 431.722438 -160.909837) (xy 431.71237 -160.91027)
			(xy 420.069518 -160.91027) (xy 420.063871 -160.910389) (xy 420.052841 -160.912816) (xy 420.047674 -160.915096)
			(xy 420.028116 -160.924494) (xy 420.021512 -160.931098) (xy 419.989027 -160.963665) (xy 419.919323 -161.023698)
			(xy 419.844714 -161.077512) (xy 419.765752 -161.124709) (xy 419.683022 -161.164938) (xy 419.597139 -161.197902)
			(xy 419.508738 -161.223355) (xy 419.418475 -161.241109) (xy 419.32702 -161.251033) (xy 419.23505 -161.253053)
			(xy 419.143247 -161.247154) (xy 419.052292 -161.233379) (xy 418.962859 -161.211831) (xy 418.875612 -161.18267)
			(xy 418.791196 -161.146111) (xy 418.710238 -161.102426) (xy 418.633338 -161.051939) (xy 418.561066 -160.995024)
			(xy 418.52723 -160.963864) (xy 418.494464 -160.931606) (xy 418.486844 -160.923986) (xy 418.468048 -160.915096)
			(xy 418.462933 -160.912858) (xy 418.452039 -160.910426) (xy 418.446458 -160.91027) (xy 417.372038 -160.91027)
			(xy 417.353496 -160.918144) (xy 417.346384 -160.92551) (xy 417.34486 -160.92678) (xy 417.343082 -160.92805)
			(xy 413.14878 -165.122352) (xy 413.141933 -165.129749) (xy 413.134205 -165.148349) (xy 413.133794 -165.15842)
			(xy 413.133794 -174.275242) (xy 413.133363 -174.285309) (xy 413.125637 -174.303901) (xy 413.118808 -174.31131)
			(xy 411.67558 -175.754538) (xy 411.665358 -175.765504) (xy 411.65122 -175.791922) (xy 411.645355 -175.821306)
			(xy 411.648265 -175.851128) (xy 411.659701 -175.878823) (xy 411.67868 -175.902009) (xy 411.703569 -175.918693)
			(xy 411.732227 -175.92744) (xy 411.747208 -175.92802) (xy 417.481004 -175.92802) (xy 417.514068 -175.928479)
			(xy 417.579749 -175.936158) (xy 417.64409 -175.951423) (xy 417.675314 -175.96231) (xy 417.704285 -175.973326)
			(xy 417.759849 -176.000797) (xy 417.81209 -176.034155) (xy 417.860387 -176.073005) (xy 417.882578 -176.094644)
			(xy 419.558216 -177.770282) (xy 419.579858 -177.792469) (xy 419.618699 -177.840773) (xy 419.652053 -177.893016)
			(xy 419.679524 -177.948579) (xy 419.69055 -177.977546) (xy 419.701403 -178.008779) (xy 419.716653 -178.07312)
			(xy 419.724344 -178.138795) (xy 419.72484 -178.171856) (xy 419.72484 -195.241926) (xy 420.27043 -195.241926)
			(xy 420.274501 -195.186304) (xy 420.286627 -195.131867) (xy 420.30655 -195.079776) (xy 420.333846 -195.031141)
			(xy 420.367932 -194.986998) (xy 420.408081 -194.948289) (xy 420.453439 -194.915838) (xy 420.503039 -194.890337)
			(xy 420.555823 -194.87233) (xy 420.610666 -194.8622) (xy 420.6664 -194.860163) (xy 420.721837 -194.866263)
			(xy 420.775794 -194.880369) (xy 420.827123 -194.902181) (xy 420.874729 -194.931235) (xy 420.917597 -194.96691)
			(xy 420.954814 -195.008447) (xy 420.985587 -195.05496) (xy 421.009259 -195.105457) (xy 421.025327 -195.158864)
			(xy 421.033447 -195.21404) (xy 421.033956 -195.241926) (xy 421.033447 -195.269812) (xy 421.025327 -195.324988)
			(xy 421.009259 -195.378395) (xy 420.985587 -195.428892) (xy 420.954814 -195.475405) (xy 420.917597 -195.516942)
			(xy 420.874729 -195.552617) (xy 420.827123 -195.581671) (xy 420.775794 -195.603483) (xy 420.721837 -195.617589)
			(xy 420.6664 -195.623689) (xy 420.610666 -195.621652) (xy 420.555823 -195.611522) (xy 420.503039 -195.593515)
			(xy 420.453439 -195.568014) (xy 420.408081 -195.535563) (xy 420.367932 -195.496854) (xy 420.333846 -195.452711)
			(xy 420.30655 -195.404076) (xy 420.286627 -195.351985) (xy 420.274501 -195.297548) (xy 420.27043 -195.241926)
			(xy 419.72484 -195.241926) (xy 419.72484 -196.495416) (xy 420.50665 -196.495416) (xy 420.510721 -196.439794)
			(xy 420.522847 -196.385357) (xy 420.54277 -196.333266) (xy 420.570066 -196.284631) (xy 420.604152 -196.240488)
			(xy 420.644301 -196.201779) (xy 420.689659 -196.169328) (xy 420.739259 -196.143827) (xy 420.792043 -196.12582)
			(xy 420.846886 -196.11569) (xy 420.90262 -196.113653) (xy 420.958057 -196.119753) (xy 421.012014 -196.133859)
			(xy 421.063343 -196.155671) (xy 421.110949 -196.184725) (xy 421.153817 -196.2204) (xy 421.191034 -196.261937)
			(xy 421.221807 -196.30845) (xy 421.245479 -196.358947) (xy 421.261547 -196.412354) (xy 421.269667 -196.46753)
			(xy 421.270176 -196.495416) (xy 421.269667 -196.523302) (xy 421.261547 -196.578478) (xy 421.245479 -196.631885)
			(xy 421.221807 -196.682382) (xy 421.191034 -196.728895) (xy 421.153817 -196.770432) (xy 421.110949 -196.806107)
			(xy 421.063343 -196.835161) (xy 421.012014 -196.856973) (xy 420.958057 -196.871079) (xy 420.90262 -196.877179)
			(xy 420.846886 -196.875142) (xy 420.792043 -196.865012) (xy 420.739259 -196.847005) (xy 420.689659 -196.821504)
			(xy 420.644301 -196.789053) (xy 420.604152 -196.750344) (xy 420.570066 -196.706201) (xy 420.54277 -196.657566)
			(xy 420.522847 -196.605475) (xy 420.510721 -196.551038) (xy 420.50665 -196.495416) (xy 419.72484 -196.495416)
			(xy 419.72484 -205.914244) (xy 419.725272 -205.92431) (xy 419.733003 -205.942899) (xy 419.739826 -205.950312)
			(xy 423.169914 -209.380582) (xy 445.04356 -209.380582) (xy 445.044005 -209.344849) (xy 445.051245 -209.273752)
			(xy 445.06567 -209.203757) (xy 445.087129 -209.135589) (xy 445.1154 -209.069954) (xy 445.150193 -209.00753)
			(xy 445.170306 -208.977992) (xy 445.175898 -208.96919) (xy 445.180114 -208.948785) (xy 445.175887 -208.928383)
			(xy 445.170306 -208.919572) (xy 445.150234 -208.890059) (xy 445.115486 -208.827709) (xy 445.087236 -208.762159)
			(xy 445.065775 -208.694084) (xy 445.051323 -208.624184) (xy 445.044029 -208.553179) (xy 445.04356 -208.51749)
			(xy 445.04356 -208.467198) (xy 445.044061 -208.430399) (xy 445.051752 -208.357205) (xy 445.06705 -208.285215)
			(xy 445.089788 -208.215218) (xy 445.119716 -208.14798) (xy 445.156506 -208.084238) (xy 445.199757 -208.024689)
			(xy 445.248993 -207.969987) (xy 445.303676 -207.920729) (xy 445.363208 -207.877456) (xy 445.426936 -207.84064)
			(xy 445.494162 -207.810686) (xy 445.56415 -207.787921) (xy 445.636134 -207.772595) (xy 445.709325 -207.764875)
			(xy 445.746124 -207.76438) (xy 445.782917 -207.76487) (xy 445.856101 -207.772558) (xy 445.928081 -207.787847)
			(xy 445.998071 -207.810571) (xy 446.065305 -207.840481) (xy 446.129047 -207.877249) (xy 446.1886 -207.920473)
			(xy 446.216278 -207.94472) (xy 446.223089 -207.950324) (xy 446.239423 -207.956951) (xy 446.257034 -207.957672)
			(xy 446.265554 -207.955388) (xy 446.293482 -207.947198) (xy 446.351009 -207.938394) (xy 446.380108 -207.937862)
			(xy 446.405929 -207.938285) (xy 446.457102 -207.945236) (xy 446.50687 -207.959026) (xy 446.554324 -207.9794)
			(xy 446.598596 -208.005987) (xy 446.638879 -208.038302) (xy 446.656968 -208.056734) (xy 446.664308 -208.063775)
			(xy 446.682927 -208.071918) (xy 446.703246 -208.072206) (xy 446.722088 -208.064594) (xy 446.729612 -208.05775)
			(xy 446.779904 -208.007458) (xy 446.808181 -207.979969) (xy 446.869819 -207.930769) (xy 446.936578 -207.888781)
			(xy 447.007619 -207.854532) (xy 447.082048 -207.828454) (xy 447.158929 -207.810873) (xy 447.237295 -207.802012)
			(xy 447.276728 -207.801464) (xy 447.316078 -207.802022) (xy 447.39428 -207.810867) (xy 447.471007 -207.828385)
			(xy 447.545298 -207.854359) (xy 447.616225 -207.888464) (xy 447.649854 -207.908906) (xy 447.658115 -207.913602)
			(xy 447.676778 -207.91711) (xy 447.695441 -207.913602) (xy 447.703702 -207.908906) (xy 447.737324 -207.88845)
			(xy 447.808245 -207.854328) (xy 447.882538 -207.828351) (xy 447.959269 -207.810842) (xy 448.037477 -207.802023)
			(xy 448.076828 -207.801464) (xy 448.11626 -207.80204) (xy 448.194624 -207.810903) (xy 448.271503 -207.828483)
			(xy 448.345932 -207.854556) (xy 448.416975 -207.888797) (xy 448.483739 -207.930774) (xy 448.545385 -207.97996)
			(xy 448.573652 -208.007458) (xy 448.662044 -208.09585) (xy 448.669441 -208.102695) (xy 448.688042 -208.110413)
			(xy 448.698112 -208.110836) (xy 451.824852 -208.110836) (xy 451.834921 -208.110403) (xy 451.85352 -208.102689)
			(xy 451.86092 -208.09585) (xy 452.50481 -207.45196) (xy 452.531175 -207.426289) (xy 452.588375 -207.379991)
			(xy 452.650099 -207.339922) (xy 452.715673 -207.306524) (xy 452.784378 -207.28016) (xy 452.855461 -207.261119)
			(xy 452.928145 -207.249611) (xy 453.001634 -207.245761) (xy 453.075123 -207.249611) (xy 453.147807 -207.261119)
			(xy 453.21889 -207.28016) (xy 453.287595 -207.306524) (xy 453.353169 -207.339922) (xy 453.414893 -207.379991)
			(xy 453.472093 -207.426289) (xy 453.498458 -207.45196) (xy 454.142348 -208.09585) (xy 454.149778 -208.102653)
			(xy 454.168354 -208.110396) (xy 454.178416 -208.110836) (xy 454.379076 -208.110836) (xy 454.389505 -208.110344)
			(xy 454.408658 -208.102093) (xy 454.41616 -208.094834) (xy 454.474072 -208.032858) (xy 454.481184 -208.013046)
			(xy 454.480422 -208.002632) (xy 454.47966 -207.974184) (xy 454.47966 -207.973676) (xy 454.480146 -207.944577)
			(xy 454.48776 -207.88688) (xy 454.502842 -207.830671) (xy 454.525133 -207.776912) (xy 454.554251 -207.726523)
			(xy 454.589699 -207.680367) (xy 454.609962 -207.659478) (xy 454.613772 -207.655668) (xy 454.634667 -207.635368)
			(xy 454.680847 -207.599851) (xy 454.731272 -207.570672) (xy 454.785077 -207.548333) (xy 454.841339 -207.533216)
			(xy 454.899095 -207.525581) (xy 454.928224 -207.525112) (xy 456.294998 -207.525112) (xy 456.323993 -207.525597)
			(xy 456.381493 -207.533128) (xy 456.437524 -207.548074) (xy 456.491135 -207.570182) (xy 456.541414 -207.599077)
			(xy 456.564746 -207.616298) (xy 456.571553 -207.621143) (xy 456.587382 -207.626463) (xy 456.595734 -207.626712)
			(xy 457.044298 -207.626712) (xy 457.060956 -207.627289) (xy 457.093139 -207.635899) (xy 457.122004 -207.652534)
			(xy 457.145588 -207.676065) (xy 457.16229 -207.704892) (xy 457.170973 -207.737056) (xy 457.171552 -207.753712)
			(xy 457.171552 -208.18602) (xy 457.171025 -208.203688) (xy 457.161491 -208.23771) (xy 457.152756 -208.253076)
			(xy 457.149243 -208.259179) (xy 457.145365 -208.272709) (xy 457.145136 -208.279746) (xy 457.145136 -208.31048)
			(xy 457.145377 -208.317515) (xy 457.14925 -208.331045) (xy 457.152756 -208.33715) (xy 457.161528 -208.3525)
			(xy 457.171059 -208.386533) (xy 457.171552 -208.404206) (xy 457.171552 -208.836006) (xy 457.17102 -208.853673)
			(xy 457.16149 -208.887696) (xy 457.152756 -208.903062) (xy 457.149212 -208.909149) (xy 457.145353 -208.922691)
			(xy 457.145136 -208.929732) (xy 457.145136 -208.960466) (xy 457.145383 -208.967501) (xy 457.149252 -208.981031)
			(xy 457.152756 -208.987136) (xy 457.161572 -209.002479) (xy 457.171236 -209.036506) (xy 457.171806 -209.054192)
			(xy 457.171806 -210.135978) (xy 457.171292 -210.152699) (xy 457.162642 -210.185001) (xy 457.145924 -210.213964)
			(xy 457.12228 -210.237612) (xy 457.09332 -210.254334) (xy 457.061019 -210.26299) (xy 457.044298 -210.263486)
			(xy 455.545698 -210.263486) (xy 455.528975 -210.263013) (xy 455.496668 -210.254355) (xy 455.467704 -210.23763)
			(xy 455.444056 -210.213977) (xy 455.427336 -210.18501) (xy 455.418684 -210.152701) (xy 455.41819 -210.135978)
			(xy 455.41819 -209.957416) (xy 455.417764 -209.947637) (xy 455.410477 -209.929487) (xy 455.396948 -209.915363)
			(xy 455.388218 -209.910934) (xy 455.357604 -209.896705) (xy 455.298995 -209.863191) (xy 455.243868 -209.824214)
			(xy 455.218038 -209.802476) (xy 455.210892 -209.796864) (xy 455.193844 -209.790612) (xy 455.184764 -209.790284)
			(xy 454.17486 -209.790284) (xy 454.164785 -209.790666) (xy 454.146187 -209.798415) (xy 454.138792 -209.80527)
			(xy 453.498458 -210.445604) (xy 453.472093 -210.471275) (xy 453.414893 -210.517573) (xy 453.353169 -210.557642)
			(xy 453.287595 -210.59104) (xy 453.21889 -210.617404) (xy 453.147807 -210.636445) (xy 453.075123 -210.647953)
			(xy 453.001634 -210.651803) (xy 452.928145 -210.647953) (xy 452.855461 -210.636445) (xy 452.784378 -210.617404)
			(xy 452.715673 -210.59104) (xy 452.650099 -210.557642) (xy 452.588375 -210.517573) (xy 452.531175 -210.471275)
			(xy 452.50481 -210.445604) (xy 452.368666 -210.30946) (xy 452.328026 -210.308698) (xy 452.31304 -210.322668)
			(xy 452.289497 -210.343676) (xy 452.23817 -210.380376) (xy 452.182697 -210.410444) (xy 452.12393 -210.433419)
			(xy 452.062773 -210.448948) (xy 452.000165 -210.456793) (xy 451.968616 -210.457288) (xy 451.681088 -210.457288)
			(xy 451.671081 -210.457778) (xy 451.652591 -210.465439) (xy 451.638439 -210.479591) (xy 451.630778 -210.498081)
			(xy 451.630288 -210.508088) (xy 451.630288 -211.663026) (xy 451.629808 -211.693963) (xy 451.622298 -211.75538)
			(xy 451.607392 -211.815431) (xy 451.585311 -211.873231) (xy 451.55638 -211.927925) (xy 451.521028 -211.978705)
			(xy 451.479775 -212.02482) (xy 451.456806 -212.04555) (xy 451.43928 -212.06079) (xy 451.43928 -212.065616)
			(xy 451.433184 -212.065616) (xy 451.419976 -212.07476) (xy 451.419468 -212.075268) (xy 451.393403 -212.093458)
			(xy 451.337616 -212.123918) (xy 451.278468 -212.147189) (xy 451.216881 -212.162908) (xy 451.153815 -212.170829)
			(xy 451.090253 -212.170829) (xy 451.027187 -212.162908) (xy 450.9656 -212.147189) (xy 450.906452 -212.123918)
			(xy 450.850665 -212.093458) (xy 450.8246 -212.075268) (xy 450.824092 -212.07476) (xy 450.810884 -212.065616)
			(xy 450.804788 -212.065616) (xy 450.804788 -212.06079) (xy 450.787262 -212.04555) (xy 450.764312 -212.024798)
			(xy 450.723049 -211.978691) (xy 450.687688 -211.927918) (xy 450.658749 -211.873228) (xy 450.636662 -211.81543)
			(xy 450.621752 -211.75538) (xy 450.61424 -211.693963) (xy 450.61378 -211.663026) (xy 450.61378 -210.091274)
			(xy 450.611748 -210.08467) (xy 450.60316 -210.051357) (xy 450.593981 -209.983178) (xy 450.59346 -209.94878)
			(xy 450.593487 -209.936953) (xy 450.594502 -209.913321) (xy 450.595492 -209.901536) (xy 450.595922 -209.890953)
			(xy 450.589235 -209.87088) (xy 450.582538 -209.862674) (xy 450.531992 -209.807048) (xy 450.524478 -209.799385)
			(xy 450.504871 -209.790702) (xy 450.494146 -209.790284) (xy 448.694556 -209.790284) (xy 448.684481 -209.790664)
			(xy 448.665882 -209.798414) (xy 448.658488 -209.80527) (xy 448.573652 -209.890106) (xy 448.545406 -209.917628)
			(xy 448.483761 -209.966823) (xy 448.416996 -210.008806) (xy 448.34595 -210.04305) (xy 448.271516 -210.069123)
			(xy 448.194631 -210.086699) (xy 448.116262 -210.095555) (xy 448.076828 -210.0961) (xy 448.037479 -210.095505)
			(xy 447.959278 -210.086668) (xy 447.882553 -210.069157) (xy 447.808261 -210.043191) (xy 447.737332 -210.009095)
			(xy 447.703702 -209.988658) (xy 447.695441 -209.983962) (xy 447.676778 -209.980454) (xy 447.658115 -209.983962)
			(xy 447.649854 -209.988658) (xy 447.616241 -210.009128) (xy 447.545317 -210.043248) (xy 447.471022 -210.069223)
			(xy 447.394289 -210.086728) (xy 447.31608 -210.095543) (xy 447.276728 -210.0961) (xy 447.237295 -210.095563)
			(xy 447.158929 -210.086694) (xy 447.082049 -210.069109) (xy 447.007619 -210.04303) (xy 446.936577 -210.008783)
			(xy 446.869814 -209.9668) (xy 446.80817 -209.917607) (xy 446.779904 -209.890106) (xy 446.729612 -209.839814)
			(xy 446.722096 -209.832959) (xy 446.703248 -209.82535) (xy 446.682924 -209.825638) (xy 446.664299 -209.833777)
			(xy 446.656968 -209.84083) (xy 446.638882 -209.859263) (xy 446.598593 -209.891569) (xy 446.554318 -209.91815)
			(xy 446.506865 -209.938522) (xy 446.457099 -209.952315) (xy 446.405929 -209.959275) (xy 446.380108 -209.959702)
			(xy 446.354199 -209.959259) (xy 446.302861 -209.952218) (xy 446.252942 -209.938318) (xy 446.228978 -209.92846)
			(xy 446.220489 -209.925231) (xy 446.202364 -209.924323) (xy 446.185058 -209.929783) (xy 446.17767 -209.935064)
			(xy 446.146787 -209.958459) (xy 446.080799 -209.999064) (xy 446.010743 -210.032162) (xy 445.937471 -210.05735)
			(xy 445.861872 -210.074323) (xy 445.784864 -210.082873) (xy 445.746124 -210.0834) (xy 445.709322 -210.082876)
			(xy 445.63612 -210.075183) (xy 445.564124 -210.059879) (xy 445.494123 -210.037131) (xy 445.426884 -210.00719)
			(xy 445.363143 -209.970382) (xy 445.303601 -209.927113) (xy 445.248908 -209.877855) (xy 445.199665 -209.823148)
			(xy 445.156412 -209.763594) (xy 445.119622 -209.699843) (xy 445.089699 -209.632596) (xy 445.066971 -209.562588)
			(xy 445.051687 -209.490588) (xy 445.044014 -209.417384) (xy 445.04356 -209.380582) (xy 423.169914 -209.380582)
			(xy 424.535854 -210.746594) (xy 424.558072 -210.769445) (xy 424.59781 -210.819278) (xy 424.631722 -210.873245)
			(xy 424.65938 -210.930669) (xy 424.680438 -210.990827) (xy 424.69463 -211.052964) (xy 424.701778 -211.116299)
			(xy 424.702224 -211.148168) (xy 424.702224 -216.618063) (xy 454.507341 -216.618063) (xy 454.507341 -216.502737)
			(xy 454.515386 -216.387691) (xy 454.531436 -216.273487) (xy 454.555414 -216.160681) (xy 454.587202 -216.049822)
			(xy 454.626646 -215.94145) (xy 454.673554 -215.836094) (xy 454.727696 -215.734267) (xy 454.78881 -215.636465)
			(xy 454.856597 -215.543164) (xy 454.930727 -215.454819) (xy 455.01084 -215.37186) (xy 455.096544 -215.294691)
			(xy 455.187423 -215.223689) (xy 455.283033 -215.159199) (xy 455.382908 -215.101536) (xy 455.486563 -215.05098)
			(xy 455.593492 -215.007778) (xy 455.703174 -214.97214) (xy 455.815075 -214.94424) (xy 455.928649 -214.924214)
			(xy 456.043344 -214.912159) (xy 456.1586 -214.908135) (xy 456.273856 -214.912159) (xy 456.388551 -214.924214)
			(xy 456.502125 -214.94424) (xy 456.614026 -214.97214) (xy 456.723708 -215.007778) (xy 456.830637 -215.05098)
			(xy 456.934292 -215.101536) (xy 457.034167 -215.159199) (xy 457.129777 -215.223689) (xy 457.220656 -215.294691)
			(xy 457.30636 -215.37186) (xy 457.386473 -215.454819) (xy 457.460603 -215.543164) (xy 457.52839 -215.636465)
			(xy 457.589504 -215.734267) (xy 457.643646 -215.836094) (xy 457.690554 -215.94145) (xy 457.729998 -216.049822)
			(xy 457.761786 -216.160681) (xy 457.785764 -216.273487) (xy 457.801814 -216.387691) (xy 457.809859 -216.502737)
			(xy 457.810362 -216.5604) (xy 457.809859 -216.618063) (xy 457.801814 -216.733109) (xy 457.785764 -216.847313)
			(xy 457.761786 -216.960119) (xy 457.729998 -217.070978) (xy 457.690554 -217.17935) (xy 457.643646 -217.284706)
			(xy 457.589504 -217.386533) (xy 457.52839 -217.484335) (xy 457.460603 -217.577636) (xy 457.386473 -217.665981)
			(xy 457.30636 -217.74894) (xy 457.220656 -217.826109) (xy 457.129777 -217.897111) (xy 457.034167 -217.961601)
			(xy 456.934292 -218.019264) (xy 456.830637 -218.06982) (xy 456.723708 -218.113022) (xy 456.614026 -218.14866)
			(xy 456.502125 -218.17656) (xy 456.388551 -218.196586) (xy 456.273856 -218.208641) (xy 456.1586 -218.212666)
			(xy 456.043344 -218.208641) (xy 455.928649 -218.196586) (xy 455.815075 -218.17656) (xy 455.703174 -218.14866)
			(xy 455.593492 -218.113022) (xy 455.486563 -218.06982) (xy 455.382908 -218.019264) (xy 455.283033 -217.961601)
			(xy 455.187423 -217.897111) (xy 455.096544 -217.826109) (xy 455.01084 -217.74894) (xy 454.930727 -217.665981)
			(xy 454.856597 -217.577636) (xy 454.78881 -217.484335) (xy 454.727696 -217.386533) (xy 454.673554 -217.284706)
			(xy 454.626646 -217.17935) (xy 454.587202 -217.070978) (xy 454.555414 -216.960119) (xy 454.531436 -216.847313)
			(xy 454.515386 -216.733109) (xy 454.507341 -216.618063) (xy 424.702224 -216.618063) (xy 424.702224 -243.562124)
			(xy 424.701797 -243.593995) (xy 424.694666 -243.657338) (xy 424.680485 -243.719482) (xy 424.659432 -243.779648)
			(xy 424.631772 -243.837077) (xy 424.597855 -243.891046) (xy 424.558105 -243.940876) (xy 424.535854 -243.963698)
			(xy 419.864032 -248.635774) (xy 419.859294 -248.641783) (xy 419.853336 -248.655872) (xy 419.852348 -248.66346)
			(xy 419.852348 -248.857262) (xy 419.852784 -248.867326) (xy 419.860519 -248.88591) (xy 419.867334 -248.89333)
			(xy 419.86835 -248.894346) (xy 419.872922 -248.898664) (xy 419.895387 -248.921778) (xy 419.935565 -248.972181)
			(xy 419.96985 -249.026764) (xy 419.997809 -249.084843) (xy 420.019091 -249.145686) (xy 420.03343 -249.208528)
			(xy 420.040644 -249.272581) (xy 420.04107 -249.30481) (xy 420.040054 -249.338084) (xy 420.039038 -249.351546)
			(xy 420.03589 -249.384307) (xy 420.023043 -249.448858) (xy 420.002906 -249.511518) (xy 419.975741 -249.571468)
			(xy 419.941905 -249.627922) (xy 419.901841 -249.68014) (xy 419.856074 -249.72744) (xy 419.805203 -249.769201)
			(xy 419.749893 -249.804877) (xy 419.69087 -249.834) (xy 419.628907 -249.856189) (xy 419.564814 -249.871154)
			(xy 419.49943 -249.878699) (xy 419.466522 -249.879104) (xy 419.466522 -249.879358) (xy 419.434293 -249.878908)
			(xy 419.37024 -249.871697) (xy 419.307396 -249.857365) (xy 419.246551 -249.836089) (xy 419.188469 -249.808139)
			(xy 419.133879 -249.773865) (xy 419.083467 -249.733697) (xy 419.060376 -249.71121) (xy 419.012878 -249.663712)
			(xy 419.01237 -249.663204) (xy 418.99967 -249.65025) (xy 418.992286 -249.643402) (xy 418.973723 -249.63563)
			(xy 418.953598 -249.635566) (xy 418.934986 -249.643219) (xy 418.927534 -249.649996) (xy 418.918898 -249.658632)
			(xy 418.887656 -249.690128) (xy 418.864543 -249.712593) (xy 418.81414 -249.752773) (xy 418.759556 -249.787059)
			(xy 418.701478 -249.81502) (xy 418.640635 -249.836305) (xy 418.577792 -249.850645) (xy 418.513739 -249.857861)
			(xy 418.48151 -249.858276) (xy 418.446802 -249.857773) (xy 418.377892 -249.849407) (xy 418.310493 -249.832795)
			(xy 418.245588 -249.808181) (xy 418.184123 -249.775922) (xy 418.126995 -249.736489) (xy 418.075037 -249.690457)
			(xy 418.029006 -249.638498) (xy 417.989574 -249.58137) (xy 417.957316 -249.519905) (xy 417.932702 -249.454999)
			(xy 417.916091 -249.3876) (xy 417.907726 -249.31869) (xy 417.907216 -249.283982) (xy 417.906962 -249.283728)
			(xy 417.907412 -249.251499) (xy 417.914622 -249.187446) (xy 417.928955 -249.124602) (xy 417.95023 -249.063757)
			(xy 417.978181 -249.005675) (xy 418.012456 -248.951085) (xy 418.052624 -248.900674) (xy 418.07511 -248.877582)
			(xy 418.137594 -248.815098) (xy 418.154612 -248.798334) (xy 418.161563 -248.790909) (xy 418.169431 -248.772173)
			(xy 418.169852 -248.762012) (xy 418.169852 -248.667016) (xy 418.169308 -248.65707) (xy 418.161633 -248.63871)
			(xy 418.147576 -248.624625) (xy 418.13861 -248.62028) (xy 418.124132 -248.614184) (xy 418.09416 -248.62028)
			(xy 416.021266 -250.69292) (xy 416.003497 -250.710043) (xy 415.963578 -250.73905) (xy 415.919611 -250.761454)
			(xy 415.872681 -250.776701) (xy 415.823943 -250.784418) (xy 415.79927 -250.784868) (xy 394.853414 -250.784868)
			(xy 394.843364 -250.785375) (xy 394.824804 -250.793097) (xy 394.817346 -250.799854) (xy 394.697966 -250.919234)
			(xy 394.691118 -250.926631) (xy 394.683385 -250.94523) (xy 394.68298 -250.955302) (xy 394.68298 -252.424184)
			(xy 419.466268 -252.424184) (xy 419.466767 -252.396394) (xy 419.474833 -252.341403) (xy 419.490793 -252.288164)
			(xy 419.514309 -252.237804) (xy 419.544883 -252.191389) (xy 419.581868 -252.149902) (xy 419.624481 -252.114219)
			(xy 419.67182 -252.085097) (xy 419.697154 -252.073664) (xy 419.710619 -252.067418) (xy 419.733398 -252.048401)
			(xy 419.749744 -252.023634) (xy 419.758273 -251.995213) (xy 419.758266 -251.96554) (xy 419.749723 -251.937122)
			(xy 419.733366 -251.912364) (xy 419.7223 -251.902468) (xy 419.701324 -251.884218) (xy 419.664322 -251.842721)
			(xy 419.633732 -251.796295) (xy 419.610202 -251.745922) (xy 419.59423 -251.692667) (xy 419.586154 -251.637659)
			(xy 419.585648 -251.60986) (xy 419.586134 -251.582609) (xy 419.59389 -251.528661) (xy 419.609245 -251.476366)
			(xy 419.631887 -251.426789) (xy 419.661353 -251.380939) (xy 419.697044 -251.339748) (xy 419.738235 -251.304057)
			(xy 419.784085 -251.274591) (xy 419.833662 -251.251949) (xy 419.885957 -251.236594) (xy 419.939905 -251.228838)
			(xy 419.994407 -251.228838) (xy 420.048355 -251.236594) (xy 420.10065 -251.251949) (xy 420.150227 -251.274591)
			(xy 420.196077 -251.304057) (xy 420.237268 -251.339748) (xy 420.272959 -251.380939) (xy 420.302425 -251.426789)
			(xy 420.325067 -251.476366) (xy 420.340422 -251.528661) (xy 420.348178 -251.582609) (xy 420.348664 -251.60986)
			(xy 420.348158 -251.63765) (xy 420.340098 -251.692643) (xy 420.324142 -251.745884) (xy 420.300629 -251.796245)
			(xy 420.270056 -251.842661) (xy 420.23307 -251.884149) (xy 420.190455 -251.91983) (xy 420.143113 -251.948949)
			(xy 420.117778 -251.96038) (xy 420.104353 -251.966698) (xy 420.081593 -251.985709) (xy 420.065258 -252.01046)
			(xy 420.05673 -252.038863) (xy 420.056727 -252.068519) (xy 420.06525 -252.096923) (xy 420.08158 -252.121677)
			(xy 420.092632 -252.131576) (xy 420.113636 -252.149796) (xy 420.150635 -252.191299) (xy 420.18122 -252.237732)
			(xy 420.204745 -252.288112) (xy 420.220711 -252.341371) (xy 420.228781 -252.396383) (xy 420.229284 -252.424184)
			(xy 420.228798 -252.451435) (xy 420.221042 -252.505383) (xy 420.205687 -252.557678) (xy 420.183045 -252.607255)
			(xy 420.153579 -252.653105) (xy 420.117888 -252.694296) (xy 420.076697 -252.729987) (xy 420.030847 -252.759453)
			(xy 419.98127 -252.782095) (xy 419.928975 -252.79745) (xy 419.875027 -252.805206) (xy 419.820525 -252.805206)
			(xy 419.766577 -252.79745) (xy 419.714282 -252.782095) (xy 419.664705 -252.759453) (xy 419.618855 -252.729987)
			(xy 419.577664 -252.694296) (xy 419.541973 -252.653105) (xy 419.512507 -252.607255) (xy 419.489865 -252.557678)
			(xy 419.47451 -252.505383) (xy 419.466754 -252.451435) (xy 419.466268 -252.424184) (xy 394.68298 -252.424184)
			(xy 394.68298 -252.487938) (xy 394.683409 -252.498006) (xy 394.691131 -252.516602) (xy 394.697966 -252.524006)
			(xy 395.678914 -253.504954) (xy 395.686311 -253.511803) (xy 395.70491 -253.51954) (xy 395.714982 -253.51994)
			(xy 431.551588 -253.51994) (xy 431.561658 -253.519517) (xy 431.58026 -253.511799) (xy 431.587656 -253.504954)
			(xy 435.26583 -249.82678) (xy 435.272681 -249.819384) (xy 435.280419 -249.800785) (xy 435.280816 -249.790712)
			(xy 435.280816 -245.431564) (xy 435.281246 -245.421497) (xy 435.288971 -245.402904) (xy 435.295802 -245.395496)
			(xy 440.67222 -240.019078) (xy 440.679616 -240.012226) (xy 440.698215 -240.004487) (xy 440.708288 -240.004092)
			(xy 456.482958 -240.004092) (xy 456.493024 -240.004525) (xy 456.511614 -240.012254) (xy 456.519026 -240.019078)
			(xy 460.621888 -244.12194) (xy 460.628729 -244.12934) (xy 460.636451 -244.147938) (xy 460.636874 -244.158008)
			(xy 460.636874 -246.183912) (xy 460.637299 -246.193982) (xy 460.645013 -246.212586) (xy 460.65186 -246.21998)
			(xy 461.119728 -246.687848) (xy 461.126575 -246.695246) (xy 461.134303 -246.713845) (xy 461.134714 -246.723916)
			(xy 461.134714 -247.535954) (xy 461.134282 -247.54602) (xy 461.126555 -247.564612) (xy 461.119728 -247.572022)
			(xy 460.65186 -248.03989) (xy 460.645005 -248.047285) (xy 460.637258 -248.065884) (xy 460.636874 -248.075958)
			(xy 460.636874 -251.39904) (xy 460.636443 -251.409106) (xy 460.628715 -251.427698) (xy 460.621888 -251.435108)
			(xy 459.758288 -252.298708) (xy 459.750888 -252.305552) (xy 459.732291 -252.313281) (xy 459.72222 -252.313694)
			(xy 457.418694 -252.313694) (xy 457.408624 -252.31327) (xy 457.390022 -252.305553) (xy 457.382626 -252.298708)
			(xy 457.066396 -251.982478) (xy 457.059554 -251.975078) (xy 457.051828 -251.95648) (xy 457.05141 -251.94641)
			(xy 457.05141 -248.516394) (xy 457.050986 -248.506324) (xy 457.043271 -248.48772) (xy 457.036424 -248.480326)
			(xy 457.029566 -248.473468) (xy 457.022717 -248.466071) (xy 457.014984 -248.447472) (xy 457.01458 -248.4374)
			(xy 457.01458 -248.137426) (xy 457.015094 -248.127525) (xy 457.022666 -248.109222) (xy 457.029312 -248.101866)
			(xy 457.036932 -248.093992) (xy 457.043523 -248.086614) (xy 457.050993 -248.068315) (xy 457.05141 -248.058432)
			(xy 457.05141 -248.007886) (xy 457.050985 -247.997817) (xy 457.043268 -247.979215) (xy 457.036424 -247.971818)
			(xy 457.03236 -247.967754) (xy 457.02855 -247.95861) (xy 457.026775 -247.953982) (xy 457.024853 -247.944261)
			(xy 457.02474 -247.939306) (xy 457.02474 -247.847104) (xy 457.024486 -247.841262) (xy 457.024486 -247.838468)
			(xy 457.024232 -247.83415) (xy 457.024232 -244.41023) (xy 457.023728 -244.400179) (xy 457.01601 -244.381615)
			(xy 457.009246 -244.374162) (xy 456.821286 -244.186202) (xy 456.813887 -244.179358) (xy 456.795289 -244.171628)
			(xy 456.785218 -244.171216) (xy 451.933564 -244.171216) (xy 451.9236 -244.171697) (xy 451.905169 -244.179279)
			(xy 451.89775 -244.185948) (xy 451.771766 -244.311932) (xy 451.764917 -244.319329) (xy 451.757184 -244.337928)
			(xy 451.75678 -244.348) (xy 451.75678 -246.550942) (xy 451.75721 -246.561009) (xy 451.764933 -246.579605)
			(xy 451.771766 -246.58701) (xy 451.965314 -246.780558) (xy 451.972711 -246.787407) (xy 451.99131 -246.795143)
			(xy 452.001382 -246.795544) (xy 453.634856 -246.795544) (xy 453.64492 -246.795109) (xy 453.663505 -246.787374)
			(xy 453.670924 -246.780558) (xy 453.77481 -246.676672) (xy 453.781662 -246.669276) (xy 453.7894 -246.650677)
			(xy 453.789796 -246.640604) (xy 453.789796 -245.163594) (xy 453.79022 -245.153524) (xy 453.797936 -245.134921)
			(xy 453.804782 -245.127526) (xy 453.973184 -244.959124) (xy 453.980586 -244.952288) (xy 453.999184 -244.944581)
			(xy 454.009252 -244.944138) (xy 455.011282 -244.944138) (xy 455.021345 -244.944577) (xy 455.039924 -244.952316)
			(xy 455.04735 -244.959124) (xy 455.302366 -245.21414) (xy 455.30921 -245.221539) (xy 455.316935 -245.240138)
			(xy 455.317352 -245.250208) (xy 455.317352 -249.290586) (xy 455.316912 -249.300648) (xy 455.30917 -249.319225)
			(xy 455.302366 -249.326654) (xy 455.046842 -249.582178) (xy 455.040003 -249.589579) (xy 455.032291 -249.608177)
			(xy 455.031856 -249.618246) (xy 455.031856 -250.440444) (xy 455.032289 -250.450509) (xy 455.040021 -250.469097)
			(xy 455.046842 -250.476512) (xy 455.338688 -250.768358) (xy 455.346084 -250.775211) (xy 455.364682 -250.782956)
			(xy 455.374756 -250.783344) (xy 455.58964 -250.783344) (xy 455.599706 -250.783776) (xy 455.618296 -250.791505)
			(xy 455.625708 -250.79833) (xy 455.763122 -250.935744) (xy 455.76997 -250.943141) (xy 455.777701 -250.96174)
			(xy 455.778108 -250.971812) (xy 455.778108 -252.906784) (xy 455.77767 -252.916848) (xy 455.769935 -252.935431)
			(xy 455.763122 -252.942852) (xy 455.424286 -253.281688) (xy 455.416887 -253.288533) (xy 455.398289 -253.296265)
			(xy 455.388218 -253.296674) (xy 451.699884 -253.296674) (xy 451.689816 -253.296247) (xy 451.671218 -253.288526)
			(xy 451.663816 -253.281688) (xy 451.358508 -252.97638) (xy 451.351664 -252.968981) (xy 451.343936 -252.950383)
			(xy 451.343522 -252.940312) (xy 451.343522 -251.150628) (xy 451.343086 -251.140563) (xy 451.335356 -251.121976)
			(xy 451.328536 -251.11456) (xy 449.660772 -249.446796) (xy 449.653372 -249.439955) (xy 449.634774 -249.432231)
			(xy 449.624704 -249.43181) (xy 443.411356 -249.43181) (xy 443.40129 -249.432241) (xy 443.382698 -249.439968)
			(xy 443.375288 -249.446796) (xy 442.936376 -249.885708) (xy 442.929523 -249.893103) (xy 442.921779 -249.911702)
			(xy 442.92139 -249.921776) (xy 442.92139 -250.712732) (xy 443.057278 -250.712732) (xy 443.061349 -250.65711)
			(xy 443.073475 -250.602673) (xy 443.093398 -250.550582) (xy 443.120694 -250.501947) (xy 443.15478 -250.457804)
			(xy 443.194929 -250.419095) (xy 443.240287 -250.386644) (xy 443.289887 -250.361143) (xy 443.342671 -250.343136)
			(xy 443.397514 -250.333006) (xy 443.453248 -250.330969) (xy 443.508685 -250.337069) (xy 443.562642 -250.351175)
			(xy 443.613971 -250.372987) (xy 443.661577 -250.402041) (xy 443.704445 -250.437716) (xy 443.741662 -250.479253)
			(xy 443.772435 -250.525766) (xy 443.796107 -250.576263) (xy 443.812175 -250.62967) (xy 443.820295 -250.684846)
			(xy 443.820804 -250.712732) (xy 443.820295 -250.740618) (xy 443.812175 -250.795794) (xy 443.796107 -250.849201)
			(xy 443.772435 -250.899698) (xy 443.753964 -250.927616) (xy 443.943738 -250.927616) (xy 443.947809 -250.871994)
			(xy 443.959935 -250.817557) (xy 443.979858 -250.765466) (xy 444.007154 -250.716831) (xy 444.04124 -250.672688)
			(xy 444.081389 -250.633979) (xy 444.126747 -250.601528) (xy 444.176347 -250.576027) (xy 444.229131 -250.55802)
			(xy 444.283974 -250.54789) (xy 444.339708 -250.545853) (xy 444.395145 -250.551953) (xy 444.449102 -250.566059)
			(xy 444.500431 -250.587871) (xy 444.548037 -250.616925) (xy 444.590905 -250.6526) (xy 444.628122 -250.694137)
			(xy 444.658895 -250.74065) (xy 444.682567 -250.791147) (xy 444.698635 -250.844554) (xy 444.706755 -250.89973)
			(xy 444.707264 -250.927616) (xy 444.706755 -250.955502) (xy 444.698635 -251.010678) (xy 444.682567 -251.064085)
			(xy 444.658895 -251.114582) (xy 444.628122 -251.161095) (xy 444.590905 -251.202632) (xy 444.548037 -251.238307)
			(xy 444.500431 -251.267361) (xy 444.449102 -251.289173) (xy 444.395145 -251.303279) (xy 444.339708 -251.309379)
			(xy 444.283974 -251.307342) (xy 444.229131 -251.297212) (xy 444.176347 -251.279205) (xy 444.126747 -251.253704)
			(xy 444.081389 -251.221253) (xy 444.04124 -251.182544) (xy 444.007154 -251.138401) (xy 443.979858 -251.089766)
			(xy 443.959935 -251.037675) (xy 443.947809 -250.983238) (xy 443.943738 -250.927616) (xy 443.753964 -250.927616)
			(xy 443.741662 -250.946211) (xy 443.704445 -250.987748) (xy 443.661577 -251.023423) (xy 443.613971 -251.052477)
			(xy 443.562642 -251.074289) (xy 443.508685 -251.088395) (xy 443.453248 -251.094495) (xy 443.397514 -251.092458)
			(xy 443.342671 -251.082328) (xy 443.289887 -251.064321) (xy 443.240287 -251.03882) (xy 443.194929 -251.006369)
			(xy 443.15478 -250.96766) (xy 443.120694 -250.923517) (xy 443.093398 -250.874882) (xy 443.073475 -250.822791)
			(xy 443.061349 -250.768354) (xy 443.057278 -250.712732) (xy 442.92139 -250.712732) (xy 442.92139 -251.789438)
			(xy 444.588898 -251.789438) (xy 444.592969 -251.733816) (xy 444.605095 -251.679379) (xy 444.625018 -251.627288)
			(xy 444.652314 -251.578653) (xy 444.6864 -251.53451) (xy 444.726549 -251.495801) (xy 444.771907 -251.46335)
			(xy 444.821507 -251.437849) (xy 444.874291 -251.419842) (xy 444.929134 -251.409712) (xy 444.984868 -251.407675)
			(xy 445.040305 -251.413775) (xy 445.094262 -251.427881) (xy 445.145591 -251.449693) (xy 445.193197 -251.478747)
			(xy 445.236065 -251.514422) (xy 445.273282 -251.555959) (xy 445.304055 -251.602472) (xy 445.327727 -251.652969)
			(xy 445.343795 -251.706376) (xy 445.351915 -251.761552) (xy 445.352424 -251.789438) (xy 445.351915 -251.817324)
			(xy 445.343795 -251.8725) (xy 445.327727 -251.925907) (xy 445.304055 -251.976404) (xy 445.273282 -252.022917)
			(xy 445.23872 -252.061491) (xy 446.710002 -252.061491) (xy 446.717753 -252.007532) (xy 446.733105 -251.955225)
			(xy 446.755744 -251.905635) (xy 446.78521 -251.859772) (xy 446.820904 -251.81857) (xy 446.862098 -251.782866)
			(xy 446.907953 -251.753389) (xy 446.957537 -251.730737) (xy 447.00984 -251.715373) (xy 447.063798 -251.707608)
			(xy 447.091054 -251.707142) (xy 447.112189 -251.707444) (xy 447.154196 -251.712159) (xy 447.174874 -251.71654)
			(xy 447.189052 -251.719147) (xy 447.217804 -251.71737) (xy 447.244913 -251.707622) (xy 447.268213 -251.690682)
			(xy 447.285847 -251.667901) (xy 447.296405 -251.641098) (xy 447.299046 -251.612412) (xy 447.296794 -251.598176)
			(xy 447.293599 -251.580377) (xy 447.290162 -251.544376) (xy 447.289936 -251.526294) (xy 447.289936 -251.52604)
			(xy 447.290335 -251.498786) (xy 447.298087 -251.444832) (xy 447.313438 -251.39253) (xy 447.336076 -251.342945)
			(xy 447.36554 -251.297087) (xy 447.401231 -251.255889) (xy 447.442422 -251.220189) (xy 447.488274 -251.190715)
			(xy 447.537854 -251.168066) (xy 447.590152 -251.152704) (xy 447.644105 -251.144941) (xy 447.698613 -251.144935)
			(xy 447.752567 -251.152686) (xy 447.804869 -251.168037) (xy 447.854453 -251.190675) (xy 447.900312 -251.22014)
			(xy 447.94151 -251.25583) (xy 447.97721 -251.297021) (xy 448.006684 -251.342873) (xy 448.029333 -251.392453)
			(xy 448.044696 -251.444751) (xy 448.052459 -251.498703) (xy 448.052465 -251.553211) (xy 448.044714 -251.607166)
			(xy 448.029363 -251.659467) (xy 448.025223 -251.668534) (xy 450.165722 -251.668534) (xy 450.169793 -251.612912)
			(xy 450.181919 -251.558475) (xy 450.201842 -251.506384) (xy 450.229138 -251.457749) (xy 450.263224 -251.413606)
			(xy 450.303373 -251.374897) (xy 450.348731 -251.342446) (xy 450.398331 -251.316945) (xy 450.451115 -251.298938)
			(xy 450.505958 -251.288808) (xy 450.561692 -251.286771) (xy 450.617129 -251.292871) (xy 450.671086 -251.306977)
			(xy 450.722415 -251.328789) (xy 450.770021 -251.357843) (xy 450.812889 -251.393518) (xy 450.850106 -251.435055)
			(xy 450.880879 -251.481568) (xy 450.904551 -251.532065) (xy 450.920619 -251.585472) (xy 450.928739 -251.640648)
			(xy 450.929248 -251.668534) (xy 450.928739 -251.69642) (xy 450.920619 -251.751596) (xy 450.904551 -251.805003)
			(xy 450.880879 -251.8555) (xy 450.850106 -251.902013) (xy 450.812889 -251.94355) (xy 450.770021 -251.979225)
			(xy 450.722415 -252.008279) (xy 450.671086 -252.030091) (xy 450.617129 -252.044197) (xy 450.561692 -252.050297)
			(xy 450.505958 -252.04826) (xy 450.451115 -252.03813) (xy 450.398331 -252.020123) (xy 450.348731 -251.994622)
			(xy 450.303373 -251.962171) (xy 450.263224 -251.923462) (xy 450.229138 -251.879319) (xy 450.201842 -251.830684)
			(xy 450.181919 -251.778593) (xy 450.169793 -251.724156) (xy 450.165722 -251.668534) (xy 448.025223 -251.668534)
			(xy 448.006725 -251.709052) (xy 447.977261 -251.754911) (xy 447.941571 -251.796109) (xy 447.90038 -251.831809)
			(xy 447.854528 -251.861284) (xy 447.804949 -251.883933) (xy 447.75265 -251.899295) (xy 447.698698 -251.907059)
			(xy 447.671444 -251.907548) (xy 447.650309 -251.907246) (xy 447.608302 -251.902531) (xy 447.587624 -251.89815)
			(xy 447.57346 -251.895435) (xy 447.544687 -251.897213) (xy 447.51756 -251.906971) (xy 447.494248 -251.923929)
			(xy 447.476612 -251.946733) (xy 447.466061 -251.973561) (xy 447.463439 -252.00227) (xy 447.465704 -252.016514)
			(xy 447.468898 -252.034313) (xy 447.472335 -252.070314) (xy 447.472562 -252.088396) (xy 447.472562 -252.08865)
			(xy 447.472199 -252.115907) (xy 447.464448 -252.169866) (xy 447.449096 -252.222173) (xy 447.426457 -252.271762)
			(xy 447.396991 -252.317625) (xy 447.361298 -252.358828) (xy 447.320105 -252.394532) (xy 447.274249 -252.42401)
			(xy 447.224665 -252.446662) (xy 447.172362 -252.462027) (xy 447.118405 -252.469792) (xy 447.063892 -252.469799)
			(xy 447.009933 -252.462047) (xy 446.957626 -252.446696) (xy 446.908036 -252.424057) (xy 446.862173 -252.39459)
			(xy 446.820971 -252.358897) (xy 446.785267 -252.317704) (xy 446.755789 -252.271848) (xy 446.733138 -252.222264)
			(xy 446.717773 -252.169961) (xy 446.710008 -252.116004) (xy 446.710002 -252.061491) (xy 445.23872 -252.061491)
			(xy 445.236065 -252.064454) (xy 445.193197 -252.100129) (xy 445.145591 -252.129183) (xy 445.094262 -252.150995)
			(xy 445.040305 -252.165101) (xy 444.984868 -252.171201) (xy 444.929134 -252.169164) (xy 444.874291 -252.159034)
			(xy 444.821507 -252.141027) (xy 444.771907 -252.115526) (xy 444.726549 -252.083075) (xy 444.6864 -252.044366)
			(xy 444.652314 -252.000223) (xy 444.625018 -251.951588) (xy 444.605095 -251.899497) (xy 444.592969 -251.84506)
			(xy 444.588898 -251.789438) (xy 442.92139 -251.789438) (xy 442.92139 -252.472444) (xy 443.78194 -252.472444)
			(xy 443.786011 -252.416822) (xy 443.798137 -252.362385) (xy 443.81806 -252.310294) (xy 443.845356 -252.261659)
			(xy 443.879442 -252.217516) (xy 443.919591 -252.178807) (xy 443.964949 -252.146356) (xy 444.014549 -252.120855)
			(xy 444.067333 -252.102848) (xy 444.122176 -252.092718) (xy 444.17791 -252.090681) (xy 444.233347 -252.096781)
			(xy 444.287304 -252.110887) (xy 444.338633 -252.132699) (xy 444.386239 -252.161753) (xy 444.429107 -252.197428)
			(xy 444.466324 -252.238965) (xy 444.497097 -252.285478) (xy 444.520769 -252.335975) (xy 444.536837 -252.389382)
			(xy 444.544957 -252.444558) (xy 444.545466 -252.472444) (xy 444.544957 -252.50033) (xy 444.536837 -252.555506)
			(xy 444.520769 -252.608913) (xy 444.497097 -252.65941) (xy 444.466324 -252.705923) (xy 444.429107 -252.74746)
			(xy 444.386239 -252.783135) (xy 444.338633 -252.812189) (xy 444.287304 -252.834001) (xy 444.233347 -252.848107)
			(xy 444.17791 -252.854207) (xy 444.122176 -252.85217) (xy 444.067333 -252.84204) (xy 444.014549 -252.824033)
			(xy 443.964949 -252.798532) (xy 443.919591 -252.766081) (xy 443.879442 -252.727372) (xy 443.845356 -252.683229)
			(xy 443.81806 -252.634594) (xy 443.798137 -252.582503) (xy 443.786011 -252.528066) (xy 443.78194 -252.472444)
			(xy 442.92139 -252.472444) (xy 442.92139 -252.890782) (xy 446.373756 -252.890782) (xy 446.377827 -252.83516)
			(xy 446.389953 -252.780723) (xy 446.409876 -252.728632) (xy 446.437172 -252.679997) (xy 446.471258 -252.635854)
			(xy 446.511407 -252.597145) (xy 446.556765 -252.564694) (xy 446.606365 -252.539193) (xy 446.659149 -252.521186)
			(xy 446.713992 -252.511056) (xy 446.769726 -252.509019) (xy 446.825163 -252.515119) (xy 446.87912 -252.529225)
			(xy 446.930449 -252.551037) (xy 446.978055 -252.580091) (xy 447.020923 -252.615766) (xy 447.05814 -252.657303)
			(xy 447.088913 -252.703816) (xy 447.107022 -252.742446) (xy 450.334886 -252.742446) (xy 450.338957 -252.686824)
			(xy 450.351083 -252.632387) (xy 450.371006 -252.580296) (xy 450.398302 -252.531661) (xy 450.432388 -252.487518)
			(xy 450.472537 -252.448809) (xy 450.517895 -252.416358) (xy 450.567495 -252.390857) (xy 450.620279 -252.37285)
			(xy 450.675122 -252.36272) (xy 450.730856 -252.360683) (xy 450.786293 -252.366783) (xy 450.84025 -252.380889)
			(xy 450.891579 -252.402701) (xy 450.939185 -252.431755) (xy 450.982053 -252.46743) (xy 451.01927 -252.508967)
			(xy 451.050043 -252.55548) (xy 451.073715 -252.605977) (xy 451.089783 -252.659384) (xy 451.097903 -252.71456)
			(xy 451.098412 -252.742446) (xy 451.097903 -252.770332) (xy 451.089783 -252.825508) (xy 451.073715 -252.878915)
			(xy 451.050043 -252.929412) (xy 451.01927 -252.975925) (xy 450.982053 -253.017462) (xy 450.939185 -253.053137)
			(xy 450.891579 -253.082191) (xy 450.84025 -253.104003) (xy 450.786293 -253.118109) (xy 450.730856 -253.124209)
			(xy 450.675122 -253.122172) (xy 450.620279 -253.112042) (xy 450.567495 -253.094035) (xy 450.517895 -253.068534)
			(xy 450.472537 -253.036083) (xy 450.432388 -252.997374) (xy 450.398302 -252.953231) (xy 450.371006 -252.904596)
			(xy 450.351083 -252.852505) (xy 450.338957 -252.798068) (xy 450.334886 -252.742446) (xy 447.107022 -252.742446)
			(xy 447.112585 -252.754313) (xy 447.128653 -252.80772) (xy 447.136773 -252.862896) (xy 447.137282 -252.890782)
			(xy 447.136773 -252.918668) (xy 447.128653 -252.973844) (xy 447.112585 -253.027251) (xy 447.088913 -253.077748)
			(xy 447.05814 -253.124261) (xy 447.020923 -253.165798) (xy 446.978055 -253.201473) (xy 446.930449 -253.230527)
			(xy 446.87912 -253.252339) (xy 446.825163 -253.266445) (xy 446.769726 -253.272545) (xy 446.713992 -253.270508)
			(xy 446.659149 -253.260378) (xy 446.606365 -253.242371) (xy 446.556765 -253.21687) (xy 446.511407 -253.184419)
			(xy 446.471258 -253.14571) (xy 446.437172 -253.101567) (xy 446.409876 -253.052932) (xy 446.389953 -253.000841)
			(xy 446.377827 -252.946404) (xy 446.373756 -252.890782) (xy 442.92139 -252.890782) (xy 442.92139 -253.306834)
			(xy 445.098422 -253.306834) (xy 445.102493 -253.251212) (xy 445.114619 -253.196775) (xy 445.134542 -253.144684)
			(xy 445.161838 -253.096049) (xy 445.195924 -253.051906) (xy 445.236073 -253.013197) (xy 445.281431 -252.980746)
			(xy 445.331031 -252.955245) (xy 445.383815 -252.937238) (xy 445.438658 -252.927108) (xy 445.494392 -252.925071)
			(xy 445.549829 -252.931171) (xy 445.603786 -252.945277) (xy 445.655115 -252.967089) (xy 445.702721 -252.996143)
			(xy 445.745589 -253.031818) (xy 445.782806 -253.073355) (xy 445.813579 -253.119868) (xy 445.837251 -253.170365)
			(xy 445.853319 -253.223772) (xy 445.861439 -253.278948) (xy 445.861948 -253.306834) (xy 445.861439 -253.33472)
			(xy 445.853319 -253.389896) (xy 445.837251 -253.443303) (xy 445.813579 -253.4938) (xy 445.782806 -253.540313)
			(xy 445.745589 -253.58185) (xy 445.702721 -253.617525) (xy 445.655115 -253.646579) (xy 445.603786 -253.668391)
			(xy 445.549829 -253.682497) (xy 445.494392 -253.688597) (xy 445.438658 -253.68656) (xy 445.383815 -253.67643)
			(xy 445.331031 -253.658423) (xy 445.281431 -253.632922) (xy 445.236073 -253.600471) (xy 445.195924 -253.561762)
			(xy 445.161838 -253.517619) (xy 445.134542 -253.468984) (xy 445.114619 -253.416893) (xy 445.102493 -253.362456)
			(xy 445.098422 -253.306834) (xy 442.92139 -253.306834) (xy 442.92139 -254.39243) (xy 442.921818 -254.402498)
			(xy 442.929539 -254.421096) (xy 442.936376 -254.428498) (xy 443.292484 -254.784606) (xy 443.299887 -254.791438)
			(xy 443.318486 -254.799141) (xy 443.328552 -254.799592) (xy 447.211196 -254.799592) (xy 447.227918 -254.800088)
			(xy 447.260222 -254.808743) (xy 447.289185 -254.825464) (xy 447.312833 -254.849112) (xy 447.329556 -254.878074)
			(xy 447.338211 -254.910378) (xy 447.338704 -254.9271) (xy 447.338704 -255.619504) (xy 447.339193 -255.629511)
			(xy 447.346853 -255.648001) (xy 447.361006 -255.662151) (xy 447.379497 -255.669809) (xy 447.389504 -255.670304)
			(xy 447.826384 -255.670304) (xy 447.826892 -255.669796) (xy 447.826892 -255.298702) (xy 447.826638 -254.9271)
			(xy 447.827181 -254.910408) (xy 447.835812 -254.87816) (xy 447.852488 -254.84924) (xy 447.876075 -254.825615)
			(xy 447.904967 -254.808892) (xy 447.937201 -254.800208) (xy 447.953892 -254.799592) (xy 448.665346 -254.799592)
			(xy 448.682 -254.800139) (xy 448.714174 -254.808761) (xy 448.743026 -254.825407) (xy 448.766594 -254.848945)
			(xy 448.783277 -254.877776) (xy 448.791939 -254.909938) (xy 448.7926 -254.926592) (xy 448.7926 -255.619504)
			(xy 448.793089 -255.629511) (xy 448.800749 -255.648001) (xy 448.814902 -255.662153) (xy 448.833393 -255.669812)
			(xy 448.8434 -255.670304) (xy 449.169282 -255.670304) (xy 449.179346 -255.669866) (xy 449.197929 -255.662131)
			(xy 449.20535 -255.655318) (xy 449.206874 -255.653794) (xy 449.213722 -255.646396) (xy 449.221459 -255.627798)
			(xy 449.22186 -255.617726) (xy 449.22186 -254.9271) (xy 449.222405 -254.910383) (xy 449.231057 -254.878089)
			(xy 449.247771 -254.849134) (xy 449.271409 -254.82549) (xy 449.30036 -254.808769) (xy 449.332652 -254.800109)
			(xy 449.349368 -254.799592) (xy 450.060568 -254.799592) (xy 450.077292 -254.800085) (xy 450.109602 -254.808735)
			(xy 450.138572 -254.825454) (xy 450.162226 -254.849102) (xy 450.178953 -254.878068) (xy 450.187611 -254.910376)
			(xy 450.188076 -254.9271) (xy 450.188076 -255.619504) (xy 450.188564 -255.629513) (xy 450.196224 -255.648008)
			(xy 450.210376 -255.662165) (xy 450.228867 -255.669832) (xy 450.238876 -255.670304) (xy 450.523864 -255.670304)
			(xy 450.53389 -255.669891) (xy 450.55242 -255.662227) (xy 450.566605 -255.648054) (xy 450.574283 -255.62953)
			(xy 450.574664 -255.619504) (xy 450.574664 -255.366012) (xy 450.575314 -255.329764) (xy 450.586158 -255.258084)
			(xy 450.596254 -255.223264) (xy 450.597778 -255.218692) (xy 450.60108 -255.208532) (xy 450.604636 -255.198372)
			(xy 450.606026 -255.194253) (xy 450.60756 -255.185699) (xy 450.607684 -255.181354) (xy 450.607684 -254.9271)
			(xy 450.60823 -254.910385) (xy 450.616882 -254.878093) (xy 450.633596 -254.849141) (xy 450.657235 -254.825501)
			(xy 450.686186 -254.808785) (xy 450.718477 -254.800131) (xy 450.735192 -254.799592) (xy 451.446392 -254.799592)
			(xy 451.463114 -254.800088) (xy 451.495419 -254.808742) (xy 451.524383 -254.825463) (xy 451.548032 -254.84911)
			(xy 451.564755 -254.878074) (xy 451.573411 -254.910378) (xy 451.5739 -254.9271) (xy 451.5739 -255.619504)
			(xy 451.574389 -255.629511) (xy 451.582049 -255.648001) (xy 451.596202 -255.662153) (xy 451.614693 -255.669812)
			(xy 451.6247 -255.670304) (xy 451.923404 -255.670304) (xy 451.933411 -255.669815) (xy 451.951902 -255.662155)
			(xy 451.966055 -255.648002) (xy 451.973715 -255.629511) (xy 451.974204 -255.619504) (xy 451.974204 -255.349248)
			(xy 451.974637 -255.319866) (xy 451.981763 -255.261535) (xy 451.988428 -255.232916) (xy 451.989952 -255.22682)
			(xy 451.989952 -255.077214) (xy 451.989698 -254.9271) (xy 451.990241 -254.910406) (xy 451.998872 -254.878154)
			(xy 452.015546 -254.849229) (xy 452.039132 -254.825598) (xy 452.068024 -254.808867) (xy 452.10026 -254.800174)
			(xy 452.116952 -254.799592) (xy 452.828406 -254.799592) (xy 452.845064 -254.800134) (xy 452.877246 -254.80875)
			(xy 452.906107 -254.825393) (xy 452.929684 -254.848932) (xy 452.946373 -254.877766) (xy 452.955039 -254.909935)
			(xy 452.95566 -254.926592) (xy 452.95566 -255.619504) (xy 452.956148 -255.629514) (xy 452.963807 -255.648011)
			(xy 452.977958 -255.662173) (xy 452.99645 -255.669845) (xy 453.00646 -255.670304) (xy 453.308212 -255.670304)
			(xy 453.318218 -255.669814) (xy 453.336707 -255.662152) (xy 453.350857 -255.648) (xy 453.358515 -255.62951)
			(xy 453.359012 -255.619504) (xy 453.359012 -255.273556) (xy 453.358758 -254.9271) (xy 453.3593 -254.910404)
			(xy 453.36793 -254.878148) (xy 453.384604 -254.849218) (xy 453.408188 -254.82558) (xy 453.437081 -254.808841)
			(xy 453.469318 -254.800138) (xy 453.486012 -254.799592) (xy 454.197466 -254.799592) (xy 454.214127 -254.80013)
			(xy 454.246319 -254.808738) (xy 454.275189 -254.825378) (xy 454.298774 -254.848919) (xy 454.315469 -254.877757)
			(xy 454.324139 -254.909932) (xy 454.32472 -254.926592) (xy 454.32472 -255.30175) (xy 454.324974 -255.303274)
			(xy 454.325228 -255.308608) (xy 454.325228 -255.311148) (xy 454.325482 -255.313942) (xy 454.325482 -255.315212)
			(xy 454.325736 -255.334008) (xy 454.325736 -255.619504) (xy 454.326157 -255.629522) (xy 454.333829 -255.648031)
			(xy 454.348002 -255.662194) (xy 454.366518 -255.669851) (xy 454.376536 -255.670304) (xy 454.704704 -255.670304)
			(xy 454.714711 -255.669815) (xy 454.733202 -255.662155) (xy 454.747355 -255.648002) (xy 454.755015 -255.629511)
			(xy 454.755504 -255.619504) (xy 454.755504 -254.9271) (xy 454.756001 -254.910379) (xy 454.764656 -254.878077)
			(xy 454.781378 -254.849116) (xy 454.805026 -254.825471) (xy 454.833988 -254.808752) (xy 454.866291 -254.800099)
			(xy 454.883012 -254.799592) (xy 455.594212 -254.799592) (xy 455.610926 -254.800139) (xy 455.643214 -254.808793)
			(xy 455.672162 -254.825509) (xy 455.695798 -254.849147) (xy 455.712511 -254.878097) (xy 455.721163 -254.910386)
			(xy 455.72172 -254.9271) (xy 455.72172 -255.619504) (xy 455.722141 -255.629523) (xy 455.729812 -255.648035)
			(xy 455.743985 -255.662201) (xy 455.762501 -255.669864) (xy 455.77252 -255.670304) (xy 456.066652 -255.670304)
			(xy 456.07668 -255.669893) (xy 456.095214 -255.662232) (xy 456.109402 -255.648058) (xy 456.117083 -255.629532)
			(xy 456.117452 -255.619504) (xy 456.117452 -255.35382) (xy 456.11777 -255.32939) (xy 456.12273 -255.280782)
			(xy 456.127358 -255.256792) (xy 456.13574 -255.22174) (xy 456.137772 -255.215136) (xy 456.137772 -254.9271)
			(xy 456.138318 -254.910384) (xy 456.146969 -254.878091) (xy 456.163684 -254.849138) (xy 456.187322 -254.825496)
			(xy 456.216273 -254.808777) (xy 456.248564 -254.80012) (xy 456.26528 -254.799592) (xy 456.97648 -254.799592)
			(xy 456.993203 -254.800086) (xy 457.025511 -254.808738) (xy 457.054478 -254.825458) (xy 457.078129 -254.849106)
			(xy 457.094854 -254.878071) (xy 457.103511 -254.910377) (xy 457.103988 -254.9271) (xy 457.103988 -255.619504)
			(xy 457.104477 -255.629512) (xy 457.112137 -255.648004) (xy 457.126289 -255.662159) (xy 457.14478 -255.669822)
			(xy 457.154788 -255.670304) (xy 457.28382 -255.670304) (xy 457.293825 -255.669812) (xy 457.312311 -255.662149)
			(xy 457.326458 -255.647997) (xy 457.334116 -255.629509) (xy 457.33462 -255.619504) (xy 457.33462 -255.57099)
			(xy 457.335167 -255.538511) (xy 457.343904 -255.474142) (xy 457.36118 -255.411523) (xy 457.386683 -255.35178)
			(xy 457.419954 -255.295988) (xy 457.439776 -255.270254) (xy 457.444856 -255.263904) (xy 457.453492 -255.240028)
			(xy 457.4549 -255.235849) (xy 457.45643 -255.227165) (xy 457.45654 -255.222756) (xy 457.45654 -254.725678)
			(xy 457.456973 -254.71188) (xy 457.463 -254.684947) (xy 457.474642 -254.659924) (xy 457.482702 -254.648716)
			(xy 457.487782 -254.641858) (xy 457.493116 -254.626364) (xy 457.493116 -254.064516) (xy 457.493116 -254.013716)
			(xy 457.54036 -254.013716) (xy 458.89418 -254.013716) (xy 458.94498 -254.013716) (xy 458.94498 -254.06096)
			(xy 458.94498 -254.612648) (xy 458.945488 -254.620268) (xy 458.946504 -254.626364) (xy 458.956156 -254.649478)
			(xy 458.96405 -254.660601) (xy 458.975392 -254.685399) (xy 458.981199 -254.712043) (xy 458.981556 -254.725678)
			(xy 458.981556 -255.441958) (xy 458.982124 -255.456937) (xy 458.990883 -255.485589) (xy 459.007574 -255.51047)
			(xy 459.030762 -255.529443) (xy 459.058454 -255.540878) (xy 459.088273 -255.543792) (xy 459.117656 -255.537936)
			(xy 459.144079 -255.523812) (xy 459.155038 -255.513586) (xy 459.250542 -255.418082) (xy 459.257392 -255.410685)
			(xy 459.265129 -255.392087) (xy 459.265528 -255.382014) (xy 459.265528 -254.725678) (xy 459.265902 -254.71189)
			(xy 459.271829 -254.684958) (xy 459.283402 -254.659928) (xy 459.291436 -254.648716) (xy 459.292198 -254.647954)
			(xy 459.296283 -254.641997) (xy 459.301307 -254.628463) (xy 459.302104 -254.621284) (xy 459.302104 -254.013716)
			(xy 459.349348 -254.013716) (xy 460.70266 -254.013716) (xy 460.75346 -254.013716) (xy 460.75346 -254.616458)
			(xy 460.753968 -254.620014) (xy 460.754984 -254.62611) (xy 460.764636 -254.649224) (xy 460.770698 -254.657632)
			(xy 460.780274 -254.676013) (xy 460.783686 -254.6858) (xy 460.786666 -254.695563) (xy 460.789848 -254.715726)
			(xy 460.790036 -254.725932) (xy 460.790036 -255.27889) (xy 460.790608 -255.293867) (xy 460.799373 -255.322515)
			(xy 460.816066 -255.347391) (xy 460.839253 -255.366361) (xy 460.866943 -255.377796) (xy 460.896759 -255.380713)
			(xy 460.92614 -255.374863) (xy 460.952564 -255.360748) (xy 460.963518 -255.350518) (xy 460.98587 -255.328166)
			(xy 460.992714 -255.320767) (xy 461.000441 -255.302169) (xy 461.000856 -255.292098) (xy 461.000856 -254.725678)
			(xy 461.00123 -254.71189) (xy 461.007159 -254.684959) (xy 461.018734 -254.659931) (xy 461.026764 -254.648716)
			(xy 461.027526 -254.647954) (xy 461.031609 -254.641997) (xy 461.036631 -254.628462) (xy 461.037432 -254.621284)
			(xy 461.037432 -254.013716) (xy 461.084676 -254.013716) (xy 462.437988 -254.013716) (xy 462.488788 -254.013716)
			(xy 462.488788 -254.616458) (xy 462.489296 -254.620014) (xy 462.490312 -254.62611) (xy 462.499964 -254.649224)
			(xy 462.506025 -254.657632) (xy 462.515599 -254.676014) (xy 462.519014 -254.6858) (xy 462.521996 -254.695563)
			(xy 462.525179 -254.715725) (xy 462.525364 -254.725932) (xy 462.525364 -255.40208) (xy 462.525786 -255.411833)
			(xy 462.53306 -255.429929) (xy 462.546591 -255.443975) (xy 462.555336 -255.448308) (xy 462.55559 -255.448308)
			(xy 462.565133 -255.452095) (xy 462.585642 -255.45251) (xy 462.604665 -255.444833) (xy 462.612232 -255.437894)
			(xy 462.725516 -255.324356) (xy 462.732207 -255.316949) (xy 462.739807 -255.298513) (xy 462.740248 -255.288542)
			(xy 462.740248 -254.734822) (xy 462.741025 -254.716041) (xy 462.752129 -254.68015) (xy 462.762092 -254.66421)
			(xy 462.76641 -254.65786) (xy 462.771236 -254.651764) (xy 462.773776 -254.644398) (xy 462.775167 -254.64028)
			(xy 462.776704 -254.631725) (xy 462.776824 -254.62738) (xy 462.776824 -254.074168) (xy 462.776824 -254.023368)
			(xy 464.228688 -254.023368) (xy 464.228688 -254.070612) (xy 464.228688 -254.622046) (xy 464.229196 -254.629666)
			(xy 464.230212 -254.635762) (xy 464.239864 -254.658876) (xy 464.247758 -254.669999) (xy 464.2591 -254.694798)
			(xy 464.264906 -254.721441) (xy 464.265264 -254.735076) (xy 464.265264 -255.75133) (xy 464.264719 -255.767988)
			(xy 464.256101 -255.800172) (xy 464.239457 -255.829034) (xy 464.21592 -255.852614) (xy 464.187089 -255.86931)
			(xy 464.154921 -255.877988) (xy 464.138264 -255.878584) (xy 463.558636 -255.878584) (xy 463.548571 -255.879018)
			(xy 463.529981 -255.886747) (xy 463.522568 -255.89357) (xy 462.50733 -256.909062) (xy 462.50049 -256.916462)
			(xy 462.492774 -256.935061) (xy 462.492344 -256.94513) (xy 462.492344 -257.25247) (xy 462.491825 -257.283609)
			(xy 462.483762 -257.345363) (xy 462.467845 -257.405573) (xy 462.45653 -257.434588) (xy 462.454752 -257.438652)
			(xy 462.451958 -257.452622) (xy 462.451958 -257.452876) (xy 462.450942 -257.457956) (xy 462.450942 -257.978656)
			(xy 462.450507 -257.98872) (xy 462.442772 -258.007305) (xy 462.435956 -258.014724) (xy 461.938878 -258.511802)
			(xy 461.932024 -258.519197) (xy 461.924278 -258.537796) (xy 461.923892 -258.54787) (xy 461.923892 -269.755112)
			(xy 461.924317 -269.765181) (xy 461.932033 -269.783784) (xy 461.938878 -269.79118) (xy 462.435956 -270.288258)
			(xy 462.440752 -270.293375) (xy 462.447577 -270.305621) (xy 462.449418 -270.312388) (xy 462.451196 -270.319246)
			(xy 462.4578 -270.331184) (xy 464.267804 -272.141188) (xy 464.274652 -272.148586) (xy 464.28239 -272.167184)
			(xy 464.28279 -272.177256) (xy 464.28279 -277.346918) (xy 464.283216 -277.356987) (xy 464.290934 -277.375588)
			(xy 464.297776 -277.382986) (xy 465.059014 -278.144224) (xy 465.065866 -278.15162) (xy 465.073605 -278.170219)
			(xy 465.074 -278.180292) (xy 465.074 -280.902918) (xy 465.074427 -280.912987) (xy 465.082146 -280.931586)
			(xy 465.088986 -280.938986) (xy 465.567014 -281.417014) (xy 465.573868 -281.424409) (xy 465.58161 -281.443008)
			(xy 465.582 -281.453082) (xy 465.582 -282.045918) (xy 465.581573 -282.055987) (xy 465.573854 -282.074586)
			(xy 465.567014 -282.081986) (xy 465.342986 -282.306014) (xy 465.335591 -282.312868) (xy 465.316992 -282.32061)
			(xy 465.306918 -282.321) (xy 464.079082 -282.321) (xy 464.069013 -282.320573) (xy 464.050414 -282.312854)
			(xy 464.043014 -282.306014) (xy 463.945986 -282.208986) (xy 463.938591 -282.202132) (xy 463.919992 -282.19439)
			(xy 463.909918 -282.194) (xy 460.72298 -282.194) (xy 460.704946 -282.201112) (xy 460.697834 -282.20797)
			(xy 460.694532 -282.211018) (xy 460.6925 -282.212542) (xy 460.599028 -282.306014) (xy 460.593948 -282.311856)
			(xy 460.589376 -282.317952) (xy 460.584296 -282.324048) (xy 460.34833 -282.560014) (xy 460.340964 -282.567126)
			(xy 460.333344 -282.585922) (xy 460.333344 -293.39667) (xy 460.332907 -293.406733) (xy 460.325168 -293.425314)
			(xy 460.318358 -293.432738) (xy 459.659482 -294.091614) (xy 459.652087 -294.098467) (xy 459.633488 -294.106208)
			(xy 459.623414 -294.1066) (xy 451.872858 -294.1066) (xy 451.862791 -294.106169) (xy 451.844198 -294.098444)
			(xy 451.83679 -294.091614) (xy 451.753478 -294.008302) (xy 451.746623 -294.000907) (xy 451.738875 -293.982308)
			(xy 451.738492 -293.972234) (xy 451.738492 -285.26994) (xy 451.738058 -285.259875) (xy 451.730327 -285.241287)
			(xy 451.723506 -285.233872) (xy 450.871336 -284.381702) (xy 450.864224 -284.374336) (xy 450.845428 -284.366716)
			(xy 447.427096 -284.366716) (xy 447.417026 -284.36714) (xy 447.398425 -284.374857) (xy 447.391028 -284.381702)
			(xy 447.042794 -284.729936) (xy 447.035428 -284.737048) (xy 447.027808 -284.755844) (xy 447.027808 -295.331388)
			(xy 447.028281 -295.341259) (xy 447.035743 -295.359539) (xy 447.042286 -295.366948) (xy 448.073526 -296.398188)
			(xy 448.074034 -296.398696) (xy 448.081416 -296.405277) (xy 448.099715 -296.412727) (xy 448.109594 -296.413174)
			(xy 459.897734 -296.413174) (xy 459.907802 -296.413603) (xy 459.9264 -296.421323) (xy 459.933802 -296.42816)
			(xy 460.569056 -297.063414) (xy 460.575905 -297.070811) (xy 460.583641 -297.08941) (xy 460.584042 -297.099482)
			(xy 460.584042 -304.103024) (xy 460.584471 -304.113091) (xy 460.592196 -304.131685) (xy 460.599028 -304.139092)
			(xy 461.432402 -304.972466) (xy 461.439799 -304.979316) (xy 461.458397 -304.987055) (xy 461.46847 -304.987452)
		)
		(stroke
			(width 0)
			(type solid)
		)
		(fill yes)
		(layer "F.Cu")
		(net "GND")
	)
	(gr_poly
		(pts
			(xy 398.730978 -215.673432) (xy 398.741029 -215.672927) (xy 398.759591 -215.665207) (xy 398.767046 -215.658446)
			(xy 405.803862 -208.621376) (xy 405.810709 -208.613978) (xy 405.818441 -208.59538) (xy 405.818848 -208.585308)
			(xy 405.818848 -203.527406) (xy 405.819363 -203.502224) (xy 405.827278 -203.452484) (xy 405.842868 -203.404593)
			(xy 405.865749 -203.359725) (xy 405.89536 -203.318984) (xy 405.912828 -203.300838) (xy 406.70353 -202.510136)
			(xy 406.71065 -202.502166) (xy 406.718246 -202.482217) (xy 406.718262 -202.471528) (xy 406.718262 -202.471274)
			(xy 406.717246 -202.441048) (xy 406.717702 -202.410102) (xy 406.72521 -202.348668) (xy 406.740121 -202.2886)
			(xy 406.762215 -202.230787) (xy 406.791164 -202.176083) (xy 406.826541 -202.125299) (xy 406.867821 -202.079186)
			(xy 406.914395 -202.038425) (xy 406.965573 -202.00362) (xy 407.020597 -201.975287) (xy 407.078655 -201.953843)
			(xy 407.10866 -201.946256) (xy 407.109168 -201.946256) (xy 407.125932 -201.942192) (xy 407.147776 -201.914506)
			(xy 407.147776 -193.985388) (xy 407.148293 -193.960207) (xy 407.156211 -193.910469) (xy 407.171804 -193.86258)
			(xy 407.194688 -193.817716) (xy 407.224301 -193.776978) (xy 407.241756 -193.75882) (xy 409.024582 -191.975994)
			(xy 409.042725 -191.958575) (xy 409.08343 -191.929036) (xy 409.128247 -191.906215) (xy 409.176078 -191.890672)
			(xy 409.22575 -191.882787) (xy 409.250896 -191.882268) (xy 411.680914 -191.882268) (xy 411.690982 -191.881842)
			(xy 411.70958 -191.87412) (xy 411.716982 -191.867282) (xy 412.14421 -191.440054) (xy 412.151059 -191.432658)
			(xy 412.158791 -191.414058) (xy 412.159196 -191.403986) (xy 412.159196 -191.252348) (xy 412.158576 -191.240794)
			(xy 412.148388 -191.220043) (xy 412.139638 -191.21247) (xy 412.067248 -191.155828) (xy 412.044896 -191.151002)
			(xy 412.03626 -191.153034) (xy 412.003733 -191.160719) (xy 411.937349 -191.168492) (xy 411.903926 -191.168528)
			(xy 411.872901 -191.167579) (xy 411.811417 -191.159067) (xy 411.751424 -191.14314) (xy 411.693812 -191.120036)
			(xy 411.639438 -191.090098) (xy 411.589109 -191.053769) (xy 411.54357 -191.01159) (xy 411.52318 -190.988188)
			(xy 411.51302 -190.980568) (xy 410.886656 -190.980568) (xy 410.879544 -190.983362) (xy 410.870951 -190.987049)
			(xy 410.853275 -190.993152) (xy 410.844238 -190.995554) (xy 410.828832 -190.999267) (xy 410.797346 -191.00284)
			(xy 410.7815 -191.002666) (xy 410.780484 -191.002412) (xy 410.487876 -191.002412) (xy 410.487876 -191.002666)
			(xy 410.465559 -191.002304) (xy 410.421736 -190.993864) (xy 410.380417 -190.977002) (xy 410.343202 -190.95237)
			(xy 410.311535 -190.920924) (xy 410.286644 -190.883883) (xy 410.269493 -190.842682) (xy 410.260747 -190.79892)
			(xy 410.260292 -190.776606) (xy 410.260292 -190.559944) (xy 410.260704 -190.549916) (xy 410.268366 -190.531383)
			(xy 410.282539 -190.517195) (xy 410.301065 -190.509514) (xy 410.311092 -190.509144) (xy 410.320236 -190.509144)
			(xy 410.320236 -190.034672) (xy 410.320236 -190.032132) (xy 410.319263 -190.022491) (xy 410.311112 -190.004928)
			(xy 410.297073 -189.991593) (xy 410.279114 -189.984355) (xy 410.269436 -189.983872) (xy 410.260292 -189.983872)
			(xy 410.260292 -189.71641) (xy 410.260707 -189.696925) (xy 410.267395 -189.658533) (xy 410.280559 -189.621853)
			(xy 410.299809 -189.587969) (xy 410.311854 -189.572646) (xy 410.317188 -189.564772) (xy 410.317188 -189.31509)
			(xy 410.31541 -189.312042) (xy 410.301873 -189.289945) (xy 410.280242 -189.242855) (xy 410.265187 -189.193269)
			(xy 410.256986 -189.142102) (xy 410.255974 -189.116208) (xy 410.255974 -189.102492) (xy 410.256786 -189.075466)
			(xy 410.265096 -189.022039) (xy 410.280865 -188.970321) (xy 410.303777 -188.921348) (xy 410.333374 -188.876099)
			(xy 410.369063 -188.835482) (xy 410.410128 -188.80031) (xy 410.455747 -188.771288) (xy 410.505007 -188.748997)
			(xy 410.556921 -188.733883) (xy 410.610448 -188.72625) (xy 410.664516 -188.72625) (xy 410.718043 -188.733883)
			(xy 410.769957 -188.748997) (xy 410.819217 -188.771288) (xy 410.864836 -188.80031) (xy 410.905901 -188.835482)
			(xy 410.94159 -188.876099) (xy 410.971187 -188.921348) (xy 410.994099 -188.970321) (xy 411.009868 -189.022039)
			(xy 411.018178 -189.075466) (xy 411.01899 -189.102492) (xy 411.01899 -189.107826) (xy 411.018508 -189.134781)
			(xy 411.010885 -189.188151) (xy 410.995822 -189.239915) (xy 410.973619 -189.289042) (xy 410.959554 -189.312042)
			(xy 410.957776 -189.31509) (xy 410.957776 -189.564772) (xy 410.96311 -189.572646) (xy 410.975193 -189.587943)
			(xy 410.994462 -189.621827) (xy 411.007627 -189.658516) (xy 411.0143 -189.69692) (xy 411.014672 -189.71641)
			(xy 411.014672 -189.933072) (xy 411.014257 -189.943095) (xy 411.006591 -189.961617) (xy 410.992417 -189.975791)
			(xy 410.973895 -189.983457) (xy 410.963872 -189.983872) (xy 410.954728 -189.983872) (xy 410.954728 -190.295276)
			(xy 410.954728 -190.297562) (xy 410.955185 -190.303703) (xy 410.95865 -190.315517) (xy 410.961586 -190.32093)
			(xy 410.965249 -190.326645) (xy 410.975028 -190.336052) (xy 410.98089 -190.339472) (xy 411.51302 -190.339472)
			(xy 411.52318 -190.331852) (xy 411.543944 -190.308031) (xy 411.590404 -190.265197) (xy 411.641811 -190.228446)
			(xy 411.697375 -190.198345) (xy 411.756238 -190.175357) (xy 411.817495 -190.159837) (xy 411.880203 -190.152023)
			(xy 411.9118 -190.151512) (xy 411.9434 -190.151973) (xy 412.006115 -190.159773) (xy 412.06738 -190.175289)
			(xy 412.126248 -190.198282) (xy 412.18181 -190.228396) (xy 412.233209 -190.265169) (xy 412.279652 -190.30803)
			(xy 412.30042 -190.331852) (xy 412.31058 -190.339472) (xy 412.910274 -190.339472) (xy 412.918145 -190.339171)
			(xy 412.933138 -190.334374) (xy 412.939738 -190.330074) (xy 412.942278 -190.328296) (xy 412.94939 -190.31077)
			(xy 412.949898 -190.309754) (xy 412.955802 -190.295552) (xy 412.973296 -190.270266) (xy 412.996321 -190.249889)
			(xy 413.023547 -190.235601) (xy 413.053397 -190.228227) (xy 413.06877 -190.227712) (xy 413.210502 -190.227712)
			(xy 413.219592 -190.227285) (xy 413.236595 -190.220833) (xy 413.250275 -190.208851) (xy 413.254952 -190.201042)
			(xy 413.256984 -190.195962) (xy 413.259704 -190.18893) (xy 413.261253 -190.173938) (xy 413.260032 -190.166498)
			(xy 413.258762 -190.159894) (xy 413.25165 -190.146686) (xy 413.024828 -189.920118) (xy 413.000593 -189.895001)
			(xy 412.958874 -189.839047) (xy 412.925646 -189.777669) (xy 412.913068 -189.745112) (xy 412.903697 -189.718346)
			(xy 412.890564 -189.663175) (xy 412.883988 -189.606845) (xy 412.883604 -189.578488) (xy 412.883604 -189.056518)
			(xy 412.88412 -189.024902) (xy 412.892371 -188.962211) (xy 412.908733 -188.901133) (xy 412.932928 -188.842714)
			(xy 412.964541 -188.787952) (xy 413.003031 -188.737785) (xy 413.04774 -188.693071) (xy 413.097902 -188.654574)
			(xy 413.15266 -188.622955) (xy 413.211077 -188.598753) (xy 413.272152 -188.582382) (xy 413.334842 -188.574124)
			(xy 413.366458 -188.573664) (xy 413.366966 -188.573664) (xy 413.399518 -188.574221) (xy 413.464027 -188.583011)
			(xy 413.526772 -188.600383) (xy 413.586616 -188.626022) (xy 413.642476 -188.659464) (xy 413.69334 -188.700103)
			(xy 413.716216 -188.72327) (xy 413.719293 -188.726389) (xy 413.726319 -188.731623) (xy 413.730186 -188.733684)
			(xy 413.735614 -188.736263) (xy 413.747293 -188.739078) (xy 413.7533 -188.739272) (xy 413.978344 -188.739272)
			(xy 413.980884 -188.739272) (xy 413.990518 -188.738295) (xy 414.008065 -188.730139) (xy 414.021379 -188.716098)
			(xy 414.028594 -188.698144) (xy 414.029144 -188.688472) (xy 414.029144 -188.679328) (xy 414.296606 -188.679328)
			(xy 414.317731 -188.679793) (xy 414.359248 -188.687622) (xy 414.398589 -188.703026) (xy 414.434384 -188.725469)
			(xy 414.465388 -188.75417) (xy 414.490522 -188.78813) (xy 414.508912 -188.826167) (xy 414.514792 -188.84646)
			(xy 414.516824 -188.853826) (xy 414.51915 -188.861439) (xy 414.527822 -188.87478) (xy 414.533842 -188.879988)
			(xy 414.539176 -188.884052) (xy 414.782 -188.884052) (xy 414.790382 -188.877956) (xy 414.816544 -188.853318)
			(xy 414.817052 -188.853318) (xy 414.842706 -188.82868) (xy 414.846121 -188.825294) (xy 414.851744 -188.817494)
			(xy 414.853882 -188.813186) (xy 414.857946 -188.80455) (xy 414.858454 -188.794644) (xy 414.860991 -188.760281)
			(xy 414.87417 -188.692648) (xy 414.896352 -188.627412) (xy 414.927133 -188.565764) (xy 414.965949 -188.508833)
			(xy 415.012091 -188.45766) (xy 415.038032 -188.43498) (xy 415.045652 -188.42482) (xy 415.045652 -187.995306)
			(xy 415.041152 -187.988051) (xy 415.028314 -187.97681) (xy 415.0125 -187.970401) (xy 415.003996 -187.969652)
			(xy 414.868614 -187.969652) (xy 414.852412 -187.969162) (xy 414.821052 -187.961003) (xy 414.792746 -187.945231)
			(xy 414.769307 -187.922856) (xy 414.752237 -187.895313) (xy 414.746948 -187.87999) (xy 414.74644 -187.878466)
			(xy 414.745678 -187.87618) (xy 414.742945 -187.869105) (xy 414.734033 -187.85684) (xy 414.728152 -187.85205)
			(xy 414.723834 -187.848748) (xy 414.5788 -187.848748) (xy 414.553618 -187.848232) (xy 414.503879 -187.840316)
			(xy 414.455988 -187.824726) (xy 414.411121 -187.801844) (xy 414.370381 -187.772232) (xy 414.352232 -187.754768)
			(xy 414.225232 -187.627768) (xy 414.207738 -187.609641) (xy 414.178096 -187.56891) (xy 414.155197 -187.52404)
			(xy 414.139605 -187.476139) (xy 414.131703 -187.426387) (xy 414.131252 -187.4012) (xy 414.131252 -186.944)
			(xy 414.131768 -186.918818) (xy 414.139684 -186.869079) (xy 414.155274 -186.821188) (xy 414.178156 -186.776321)
			(xy 414.207768 -186.735581) (xy 414.225232 -186.717432) (xy 414.38195 -186.560714) (xy 414.400092 -186.543292)
			(xy 414.440795 -186.513747) (xy 414.485612 -186.49092) (xy 414.533444 -186.475371) (xy 414.583117 -186.467482)
			(xy 414.608264 -186.466988) (xy 414.818068 -186.466988) (xy 414.826196 -186.46394) (xy 414.836479 -186.460597)
			(xy 414.857803 -186.457025) (xy 414.868614 -186.456828) (xy 415.478214 -186.456828) (xy 415.494895 -186.457374)
			(xy 415.527121 -186.466011) (xy 415.556013 -186.482693) (xy 415.579604 -186.506284) (xy 415.596287 -186.535176)
			(xy 415.604925 -186.567401) (xy 415.605468 -186.584082) (xy 415.605468 -186.990736) (xy 415.604663 -187.010656)
			(xy 415.592382 -187.048561) (xy 415.581338 -187.065158) (xy 415.581084 -187.065412) (xy 415.576818 -187.071885)
			(xy 415.572042 -187.086624) (xy 415.571686 -187.094368) (xy 415.571686 -187.12815) (xy 415.571686 -187.128658)
			(xy 415.572042 -187.1364) (xy 415.576834 -187.151132) (xy 415.581084 -187.157614) (xy 415.581338 -187.157868)
			(xy 415.592486 -187.174414) (xy 415.604785 -187.21235) (xy 415.605468 -187.23229) (xy 415.605468 -187.508896)
			(xy 415.606484 -187.518294) (xy 415.621505 -187.535931) (xy 415.646845 -187.574715) (xy 415.666343 -187.616739)
			(xy 415.679594 -187.661131) (xy 415.686324 -187.706967) (xy 415.686748 -187.73013) (xy 415.686748 -188.42482)
			(xy 415.694368 -188.43498) (xy 415.718175 -188.455732) (xy 415.760987 -188.502163) (xy 415.797722 -188.553536)
			(xy 415.827817 -188.609061) (xy 415.850807 -188.667884) (xy 415.86634 -188.7291) (xy 415.874176 -188.791768)
			(xy 415.874708 -188.823346) (xy 415.874708 -188.8236) (xy 415.874244 -188.854321) (xy 415.866841 -188.915316)
			(xy 415.852141 -188.974974) (xy 415.83036 -189.032426) (xy 415.801815 -189.086835) (xy 415.766921 -189.137408)
			(xy 415.726188 -189.183408) (xy 415.680208 -189.224164) (xy 415.629653 -189.259083) (xy 415.575258 -189.287656)
			(xy 415.517817 -189.309466) (xy 415.458166 -189.324195) (xy 415.397175 -189.331629) (xy 415.366454 -189.332108)
			(xy 415.365946 -189.332108) (xy 415.333688 -189.330838) (xy 415.332672 -189.330838) (xy 415.31667 -189.330076)
			(xy 415.310574 -189.332362) (xy 415.211768 -189.431168) (xy 415.193641 -189.448662) (xy 415.15291 -189.478304)
			(xy 415.10804 -189.501203) (xy 415.060139 -189.516795) (xy 415.010387 -189.524697) (xy 414.9852 -189.525148)
			(xy 414.31464 -189.525148) (xy 414.291684 -189.524756) (xy 414.246242 -189.518203) (xy 414.202202 -189.505226)
			(xy 414.160468 -189.486091) (xy 414.121895 -189.461191) (xy 414.104328 -189.446408) (xy 414.097172 -189.440631)
			(xy 414.079987 -189.434116) (xy 414.0708 -189.433708) (xy 414.053274 -189.433708) (xy 414.043788 -189.434111)
			(xy 414.026115 -189.441013) (xy 414.012132 -189.453836) (xy 414.007554 -189.462156) (xy 413.994854 -189.488318)
			(xy 413.99122 -189.496523) (xy 413.989328 -189.514358) (xy 413.993656 -189.531762) (xy 413.99841 -189.539372)
			(xy 414.014326 -189.563473) (xy 414.040927 -189.614741) (xy 414.06122 -189.668817) (xy 414.074914 -189.724928)
			(xy 414.081813 -189.782273) (xy 414.08223 -189.811152) (xy 414.081714 -189.843156) (xy 414.073271 -189.906603)
			(xy 414.056525 -189.96838) (xy 414.031769 -190.027406) (xy 413.999438 -190.082647) (xy 413.960097 -190.133137)
			(xy 413.914435 -190.17799) (xy 413.863251 -190.216423) (xy 413.835596 -190.232538) (xy 413.831786 -190.23457)
			(xy 413.82566 -190.23906) (xy 413.816219 -190.25095) (xy 413.813244 -190.257938) (xy 413.80791 -190.27267)
			(xy 413.802068 -190.288926) (xy 413.80064 -190.293166) (xy 413.799103 -190.301979) (xy 413.79902 -190.306452)
			(xy 413.800798 -190.31966) (xy 413.80156 -190.322708) (xy 413.803501 -190.330694) (xy 413.805534 -190.347002)
			(xy 413.805624 -190.35522) (xy 413.805624 -190.965074) (xy 413.804813 -190.984992) (xy 413.79252 -191.022888)
			(xy 413.781494 -191.039496) (xy 413.78124 -191.03975) (xy 413.776962 -191.046219) (xy 413.772162 -191.060958)
			(xy 413.771842 -191.068706) (xy 413.771842 -191.102488) (xy 413.771842 -191.102996) (xy 413.772189 -191.110742)
			(xy 413.776963 -191.125486) (xy 413.78124 -191.131952) (xy 413.781494 -191.132206) (xy 413.79257 -191.148791)
			(xy 413.804873 -191.1867) (xy 413.805624 -191.206628) (xy 413.805624 -191.613282) (xy 413.80513 -191.62997)
			(xy 413.796494 -191.66221) (xy 413.779807 -191.691115) (xy 413.756205 -191.714714) (xy 413.727299 -191.731399)
			(xy 413.695058 -191.740032) (xy 413.67837 -191.740536) (xy 413.06877 -191.740536) (xy 413.057956 -191.740366)
			(xy 413.036628 -191.736795) (xy 413.026352 -191.733424) (xy 413.018224 -191.730376) (xy 412.781242 -191.730376)
			(xy 412.771176 -191.730809) (xy 412.752584 -191.738536) (xy 412.745174 -191.745362) (xy 412.061406 -192.42913)
			(xy 412.043262 -192.446547) (xy 412.002556 -192.476082) (xy 411.957739 -192.4989) (xy 411.909908 -192.51444)
			(xy 411.860238 -192.522322) (xy 411.835092 -192.522856) (xy 409.405074 -192.522856) (xy 409.395007 -192.523285)
			(xy 409.376415 -192.531013) (xy 409.369006 -192.537842) (xy 407.803858 -194.103244) (xy 407.797012 -194.110642)
			(xy 407.789285 -194.129241) (xy 407.788872 -194.139312) (xy 407.788872 -200.951846) (xy 407.789266 -200.961837)
			(xy 407.796887 -200.980307) (xy 407.81102 -200.994431) (xy 407.820114 -200.998582) (xy 407.834338 -201.004678)
			(xy 407.864564 -200.998582) (xy 407.947114 -200.916032) (xy 407.96524 -200.898537) (xy 408.005971 -200.868893)
			(xy 408.050841 -200.845991) (xy 408.098742 -200.830396) (xy 408.148494 -200.822492) (xy 408.173682 -200.822052)
			(xy 408.709876 -200.822052) (xy 408.719905 -200.821609) (xy 408.73847 -200.814023) (xy 408.745944 -200.80732)
			(xy 408.806396 -200.746868) (xy 408.807714 -200.741772) (xy 408.808479 -200.731274) (xy 408.80792 -200.72604)
			(xy 408.763724 -200.681844) (xy 408.759406 -200.680574) (xy 408.734514 -200.686162) (xy 408.706879 -200.691994)
			(xy 408.650741 -200.698232) (xy 408.6225 -200.698608) (xy 408.618944 -200.698608) (xy 408.585813 -200.697842)
			(xy 408.520164 -200.688774) (xy 408.45625 -200.671254) (xy 408.395154 -200.64558) (xy 408.33791 -200.612186)
			(xy 408.28549 -200.571639) (xy 408.238781 -200.524626) (xy 408.198575 -200.471943) (xy 408.165554 -200.414484)
			(xy 408.140277 -200.353222) (xy 408.123172 -200.289196) (xy 408.11453 -200.22349) (xy 408.113992 -200.190354)
			(xy 408.113992 -200.189846) (xy 408.115262 -200.157588) (xy 408.115262 -200.156572) (xy 408.116024 -200.14057)
			(xy 408.113738 -200.134474) (xy 408.078432 -200.099168) (xy 408.060938 -200.081041) (xy 408.031296 -200.04031)
			(xy 408.008397 -199.99544) (xy 407.992805 -199.947539) (xy 407.984903 -199.897787) (xy 407.984452 -199.8726)
			(xy 407.984452 -199.262492) (xy 407.984198 -199.253094) (xy 407.984198 -199.252586) (xy 407.984708 -199.227403)
			(xy 407.992617 -199.177662) (xy 408.008207 -199.12977) (xy 408.031094 -199.084905) (xy 408.060716 -199.04417)
			(xy 408.078178 -199.026018) (xy 408.17546 -198.92899) (xy 408.177492 -198.915274) (xy 408.177492 -198.895462)
			(xy 408.20721 -198.865744) (xy 408.207464 -198.865744) (xy 408.22245 -198.850758) (xy 408.229295 -198.84336)
			(xy 408.237022 -198.824761) (xy 408.237436 -198.81469) (xy 408.237436 -198.391272) (xy 408.237436 -198.388732)
			(xy 408.236463 -198.379091) (xy 408.228312 -198.361528) (xy 408.214273 -198.348193) (xy 408.196314 -198.340955)
			(xy 408.186636 -198.340472) (xy 408.177492 -198.340472) (xy 408.177492 -198.07301) (xy 408.178009 -198.050698)
			(xy 408.186749 -198.006937) (xy 408.203892 -197.965737) (xy 408.228773 -197.928693) (xy 408.26043 -197.897241)
			(xy 408.297634 -197.8726) (xy 408.338945 -197.855725) (xy 408.382761 -197.847269) (xy 408.405076 -197.84695)
			(xy 408.405076 -197.847204) (xy 408.704288 -197.847204) (xy 408.704288 -197.84695) (xy 408.724639 -197.847265)
			(xy 408.764721 -197.854324) (xy 408.80289 -197.86845) (xy 408.82062 -197.878446) (xy 408.828494 -197.882764)
			(xy 408.996642 -197.882764) (xy 409.004615 -197.877994) (xy 409.016724 -197.863923) (xy 409.020264 -197.855332)
			(xy 409.031694 -197.823582) (xy 409.025344 -197.794626) (xy 409.014676 -197.784212) (xy 409.013914 -197.78345)
			(xy 408.733244 -197.50278) (xy 408.724354 -197.500494) (xy 408.696914 -197.493405) (xy 408.64435 -197.472225)
			(xy 408.595498 -197.4435) (xy 408.551433 -197.407863) (xy 408.513127 -197.366099) (xy 408.481421 -197.319127)
			(xy 408.457014 -197.26798) (xy 408.440443 -197.213786) (xy 408.432072 -197.157736) (xy 408.431492 -197.1294)
			(xy 408.431978 -197.102149) (xy 408.439734 -197.048201) (xy 408.455089 -196.995906) (xy 408.477731 -196.946329)
			(xy 408.507197 -196.900479) (xy 408.542888 -196.859288) (xy 408.584079 -196.823597) (xy 408.629929 -196.794131)
			(xy 408.679506 -196.771489) (xy 408.731801 -196.756134) (xy 408.785749 -196.748378) (xy 408.813 -196.747892)
			(xy 408.841339 -196.748409) (xy 408.897393 -196.756792) (xy 408.95159 -196.773374) (xy 409.002739 -196.797789)
			(xy 409.049715 -196.829501) (xy 409.091483 -196.867812) (xy 409.127125 -196.91188) (xy 409.155858 -196.960734)
			(xy 409.177048 -197.013301) (xy 409.184094 -197.040754) (xy 409.18638 -197.049644) (xy 409.358338 -197.221602)
			(xy 409.365739 -197.228442) (xy 409.384337 -197.236162) (xy 409.394406 -197.236588) (xy 410.122624 -197.236588)
			(xy 410.126531 -197.234355) (xy 410.133557 -197.228733) (xy 410.136594 -197.225412) (xy 410.186886 -197.168008)
			(xy 410.190404 -197.163916) (xy 410.19578 -197.154562) (xy 410.197554 -197.149466) (xy 410.200602 -197.139052)
			(xy 410.199332 -197.12813) (xy 410.198316 -197.11162) (xy 410.198316 -196.52361) (xy 410.198316 -196.523102)
			(xy 410.198062 -196.50202) (xy 410.19863 -196.484377) (xy 410.208275 -196.450433) (xy 410.226835 -196.420422)
			(xy 410.252895 -196.396631) (xy 410.26842 -196.388228) (xy 410.268928 -196.38772) (xy 410.27985 -196.383148)
			(xy 410.281374 -196.38264) (xy 410.284676 -196.381116) (xy 410.291396 -196.378133) (xy 410.302895 -196.368981)
			(xy 410.307282 -196.363082) (xy 410.310076 -196.359018) (xy 410.310076 -195.823332) (xy 410.309906 -195.817815)
			(xy 410.307463 -195.807053) (xy 410.30525 -195.801996) (xy 410.2989 -195.788026) (xy 410.291026 -195.780914)
			(xy 410.266887 -195.758588) (xy 410.223984 -195.708762) (xy 410.187861 -195.653822) (xy 410.159121 -195.594684)
			(xy 410.138242 -195.532335) (xy 410.125574 -195.467815) (xy 410.121328 -195.4022) (xy 410.125574 -195.336585)
			(xy 410.138242 -195.272065) (xy 410.159121 -195.209716) (xy 410.187861 -195.150578) (xy 410.223984 -195.095638)
			(xy 410.266887 -195.045812) (xy 410.291026 -195.023486) (xy 410.2989 -195.016374) (xy 410.30525 -195.002404)
			(xy 410.307464 -194.997347) (xy 410.30991 -194.986585) (xy 410.310076 -194.981068) (xy 410.310076 -194.523614)
			(xy 410.309965 -194.518517) (xy 410.307921 -194.50853) (xy 410.306012 -194.503802) (xy 410.301694 -194.493388)
			(xy 410.295344 -194.48653) (xy 410.281267 -194.470694) (xy 410.258697 -194.434843) (xy 410.243202 -194.395414)
			(xy 410.235325 -194.353788) (xy 410.234892 -194.332606) (xy 410.234892 -194.115944) (xy 410.235304 -194.105916)
			(xy 410.242966 -194.087383) (xy 410.257139 -194.073195) (xy 410.275665 -194.065514) (xy 410.285692 -194.065144)
			(xy 410.294836 -194.065144) (xy 410.294836 -193.767456) (xy 410.294836 -193.767202) (xy 410.29441 -193.75811)
			(xy 410.287961 -193.741104) (xy 410.275982 -193.727418) (xy 410.268166 -193.722752) (xy 409.801314 -193.722752)
			(xy 409.798266 -193.72453) (xy 409.776167 -193.738062) (xy 409.729075 -193.759681) (xy 409.67949 -193.774724)
			(xy 409.628323 -193.782914) (xy 409.602432 -193.783966) (xy 409.588716 -193.783966) (xy 409.561691 -193.783156)
			(xy 409.508266 -193.774852) (xy 409.456549 -193.759088) (xy 409.407575 -193.736181) (xy 409.362326 -193.706588)
			(xy 409.321709 -193.670904) (xy 409.286536 -193.629842) (xy 409.257514 -193.584225) (xy 409.235222 -193.534968)
			(xy 409.220108 -193.483057) (xy 409.212475 -193.429533) (xy 409.212475 -193.375466) (xy 409.220108 -193.321941)
			(xy 409.235222 -193.270031) (xy 409.257514 -193.220774) (xy 409.286537 -193.175157) (xy 409.32171 -193.134096)
			(xy 409.362327 -193.098411) (xy 409.407576 -193.068819) (xy 409.45655 -193.045911) (xy 409.508267 -193.030148)
			(xy 409.561692 -193.021844) (xy 409.588716 -193.02095) (xy 409.59405 -193.02095) (xy 409.621005 -193.021433)
			(xy 409.674373 -193.029061) (xy 409.726134 -193.044128) (xy 409.775258 -193.066335) (xy 409.798266 -193.080386)
			(xy 409.801314 -193.082164) (xy 410.33827 -193.082164) (xy 410.346144 -193.077846) (xy 410.36388 -193.067863)
			(xy 410.402049 -193.053752) (xy 410.442127 -193.046689) (xy 410.462476 -193.04635) (xy 410.462476 -193.046604)
			(xy 410.761688 -193.046604) (xy 410.761688 -193.04635) (xy 410.784 -193.046718) (xy 410.827812 -193.055167)
			(xy 410.869119 -193.072035) (xy 410.906321 -193.096669) (xy 410.937976 -193.128115) (xy 410.962856 -193.165152)
			(xy 410.979999 -193.206346) (xy 410.988738 -193.250101) (xy 410.989181 -193.2686) (xy 412.012892 -193.2686)
			(xy 412.013409 -193.236969) (xy 412.021666 -193.174249) (xy 412.038039 -193.113143) (xy 412.062249 -193.054697)
			(xy 412.093879 -192.999912) (xy 412.13239 -192.949723) (xy 412.177123 -192.90499) (xy 412.227312 -192.866479)
			(xy 412.282097 -192.834849) (xy 412.340543 -192.810639) (xy 412.401649 -192.794266) (xy 412.464369 -192.786009)
			(xy 412.496 -192.785492) (xy 412.527635 -192.785963) (xy 412.590363 -192.794212) (xy 412.651478 -192.810582)
			(xy 412.709931 -192.834792) (xy 412.764723 -192.866428) (xy 412.814914 -192.904948) (xy 412.83763 -192.92697)
			(xy 413.142684 -193.232278) (xy 413.150098 -193.239101) (xy 413.168686 -193.246831) (xy 413.178752 -193.247264)
			(xy 413.188658 -193.247264) (xy 413.221245 -193.247773) (xy 413.285823 -193.256562) (xy 413.348632 -193.27396)
			(xy 413.408529 -193.299649) (xy 413.464425 -193.333162) (xy 413.515305 -193.373892) (xy 413.538162 -193.397124)
			(xy 413.545635 -193.404281) (xy 413.564654 -193.412395) (xy 413.574992 -193.412872) (xy 413.851344 -193.412872)
			(xy 413.851344 -193.403728) (xy 413.851744 -193.393703) (xy 413.859413 -193.375178) (xy 413.873592 -193.361004)
			(xy 413.892119 -193.353341) (xy 413.902144 -193.352928) (xy 414.11906 -193.352928) (xy 414.142593 -193.353557)
			(xy 414.18864 -193.363309) (xy 414.231689 -193.382339) (xy 414.25114 -193.3956) (xy 414.257747 -193.400056)
			(xy 414.272894 -193.40498) (xy 414.280858 -193.405252) (xy 414.647888 -193.405252) (xy 414.67532 -193.383662)
			(xy 414.679384 -193.366644) (xy 414.687122 -193.336756) (xy 414.708844 -193.278963) (xy 414.737411 -193.224229)
			(xy 414.772403 -193.173362) (xy 414.813302 -193.127111) (xy 414.836102 -193.106294) (xy 414.843853 -193.098741)
			(xy 414.852677 -193.079006) (xy 414.85312 -193.068194) (xy 414.85312 -192.630298) (xy 414.852694 -192.620187)
			(xy 414.844921 -192.601518) (xy 414.83057 -192.587271) (xy 414.82137 -192.583054) (xy 414.821116 -192.583054)
			(xy 414.804314 -192.575696) (xy 414.775538 -192.552975) (xy 414.754408 -192.523011) (xy 414.747964 -192.505838)
			(xy 414.74263 -192.490344) (xy 414.716468 -192.471548) (xy 414.655 -192.471548) (xy 414.629813 -192.471097)
			(xy 414.580061 -192.463195) (xy 414.53216 -192.447603) (xy 414.48729 -192.424704) (xy 414.446559 -192.395062)
			(xy 414.428432 -192.377568) (xy 414.250632 -192.199768) (xy 414.233168 -192.181619) (xy 414.203556 -192.140879)
			(xy 414.180674 -192.096012) (xy 414.165084 -192.048121) (xy 414.157168 -191.998382) (xy 414.156652 -191.9732)
			(xy 414.156652 -191.5668) (xy 414.157103 -191.541613) (xy 414.165005 -191.491861) (xy 414.180597 -191.44396)
			(xy 414.203496 -191.39909) (xy 414.233138 -191.358359) (xy 414.250632 -191.340232) (xy 414.40735 -191.183514)
			(xy 414.42547 -191.166064) (xy 414.466164 -191.136493) (xy 414.510984 -191.113655) (xy 414.558827 -191.098114)
			(xy 414.608512 -191.090251) (xy 414.633664 -191.089788) (xy 414.818068 -191.089788) (xy 414.826196 -191.08674)
			(xy 414.836475 -191.083381) (xy 414.857801 -191.079802) (xy 414.868614 -191.079628) (xy 415.478214 -191.079628)
			(xy 415.494895 -191.080178) (xy 415.527119 -191.088815) (xy 415.556011 -191.105496) (xy 415.579601 -191.129086)
			(xy 415.596284 -191.157977) (xy 415.604921 -191.190201) (xy 415.605468 -191.206882) (xy 415.605468 -191.61379)
			(xy 415.604776 -191.633729) (xy 415.592484 -191.671665) (xy 415.581338 -191.688212) (xy 415.576897 -191.694828)
			(xy 415.571963 -191.709968) (xy 415.571686 -191.71793) (xy 415.571686 -191.750696) (xy 415.572022 -191.75865)
			(xy 415.576933 -191.773783) (xy 415.581338 -191.780414) (xy 415.592371 -191.797017) (xy 415.604659 -191.834917)
			(xy 415.605468 -191.854836) (xy 415.605468 -192.464944) (xy 415.605009 -192.48009) (xy 415.597905 -192.509537)
			(xy 415.58406 -192.536479) (xy 415.564253 -192.559398) (xy 415.539603 -192.577002) (xy 415.525712 -192.583054)
			(xy 415.525458 -192.583054) (xy 415.516249 -192.587274) (xy 415.501847 -192.601487) (xy 415.494097 -192.620178)
			(xy 415.493708 -192.630298) (xy 415.493708 -193.068194) (xy 415.494173 -193.079) (xy 415.502994 -193.09873)
			(xy 415.510726 -193.106294) (xy 415.533379 -193.127046) (xy 415.574116 -193.173032) (xy 415.609014 -193.223592)
			(xy 415.637564 -193.27799) (xy 415.659349 -193.335433) (xy 415.674051 -193.395082) (xy 415.681458 -193.456069)
			(xy 415.681922 -193.486786) (xy 415.681431 -193.517516) (xy 415.674024 -193.578529) (xy 415.659317 -193.638203)
			(xy 415.637525 -193.69567) (xy 415.608964 -193.750091) (xy 415.574052 -193.800673) (xy 415.533298 -193.846678)
			(xy 415.487295 -193.887435) (xy 415.436715 -193.92235) (xy 415.382296 -193.950913) (xy 415.32483 -193.972709)
			(xy 415.265156 -193.987419) (xy 415.204144 -193.994829) (xy 415.173414 -193.995294) (xy 415.17316 -193.995294)
			(xy 415.12998 -193.993516) (xy 415.122012 -193.993143) (xy 415.106487 -193.996777) (xy 415.0995 -194.000628)
			(xy 415.074377 -194.014976) (xy 415.020237 -194.035358) (xy 414.963325 -194.045726) (xy 414.9344 -194.046348)
			(xy 414.292034 -194.046348) (xy 414.283434 -194.046709) (xy 414.267208 -194.052412) (xy 414.260284 -194.057524)
			(xy 414.245111 -194.069168) (xy 414.211694 -194.087763) (xy 414.175623 -194.100463) (xy 414.137927 -194.106906)
			(xy 414.118806 -194.107308) (xy 413.851344 -194.107308) (xy 413.851344 -194.098164) (xy 413.850843 -194.088159)
			(xy 413.843179 -194.069675) (xy 413.829031 -194.055525) (xy 413.810548 -194.047859) (xy 413.800544 -194.047364)
			(xy 413.574992 -194.047364) (xy 413.564652 -194.047831) (xy 413.545638 -194.055954) (xy 413.538162 -194.063112)
			(xy 413.515306 -194.086346) (xy 413.464433 -194.127082) (xy 413.408537 -194.160598) (xy 413.348638 -194.186283)
			(xy 413.285826 -194.203668) (xy 413.221245 -194.212438) (xy 413.188658 -194.212972) (xy 412.956756 -194.212972)
			(xy 412.925196 -194.212454) (xy 412.86262 -194.204174) (xy 412.801656 -194.187812) (xy 412.743342 -194.163649)
			(xy 412.688674 -194.132094) (xy 412.638582 -194.093687) (xy 412.615888 -194.071748) (xy 412.15437 -193.61023)
			(xy 412.132354 -193.587511) (xy 412.093854 -193.537311) (xy 412.062233 -193.482517) (xy 412.038031 -193.424065)
			(xy 412.021663 -193.362955) (xy 412.013409 -193.300232) (xy 412.012892 -193.2686) (xy 410.989181 -193.2686)
			(xy 410.989272 -193.27241) (xy 410.989272 -193.489072) (xy 410.988857 -193.499095) (xy 410.981191 -193.517617)
			(xy 410.967017 -193.531791) (xy 410.948495 -193.539457) (xy 410.938472 -193.539872) (xy 410.929328 -193.539872)
			(xy 410.929328 -194.014344) (xy 410.929328 -194.016884) (xy 410.930305 -194.026518) (xy 410.938461 -194.044065)
			(xy 410.952502 -194.057379) (xy 410.970456 -194.064594) (xy 410.980128 -194.065144) (xy 410.989272 -194.065144)
			(xy 410.989272 -194.333114) (xy 410.988755 -194.354446) (xy 410.980724 -194.396348) (xy 410.965003 -194.436011)
			(xy 410.953966 -194.454272) (xy 410.950664 -194.459606) (xy 410.950664 -194.981068) (xy 410.950834 -194.986585)
			(xy 410.953274 -194.997348) (xy 410.95549 -195.002404) (xy 410.96184 -195.016374) (xy 410.969714 -195.023486)
			(xy 410.993855 -195.04581) (xy 411.036763 -195.095634) (xy 411.07289 -195.150574) (xy 411.101634 -195.209712)
			(xy 411.122515 -195.272062) (xy 411.135185 -195.336584) (xy 411.139432 -195.4022) (xy 411.135185 -195.467816)
			(xy 411.122515 -195.532338) (xy 411.101634 -195.594688) (xy 411.07289 -195.653826) (xy 411.036763 -195.708766)
			(xy 410.993855 -195.75859) (xy 410.969714 -195.780914) (xy 410.96184 -195.788026) (xy 410.95549 -195.801996)
			(xy 410.953278 -195.807053) (xy 410.950836 -195.817815) (xy 410.950664 -195.823332) (xy 410.950664 -196.34327)
			(xy 410.950965 -196.350935) (xy 410.955629 -196.365539) (xy 410.959808 -196.371972) (xy 410.962094 -196.375528)
			(xy 410.979366 -196.38264) (xy 410.98089 -196.383148) (xy 410.991812 -196.38772) (xy 410.99232 -196.388228)
			(xy 411.007848 -196.396625) (xy 411.033903 -196.420424) (xy 411.052467 -196.450436) (xy 411.062127 -196.484376)
			(xy 411.062678 -196.50202) (xy 411.062424 -196.530468) (xy 411.062424 -197.111874) (xy 411.061613 -197.131792)
			(xy 411.04932 -197.169688) (xy 411.038294 -197.186296) (xy 411.03804 -197.18655) (xy 411.033762 -197.193019)
			(xy 411.028962 -197.207758) (xy 411.028642 -197.215506) (xy 411.028642 -197.249288) (xy 411.028642 -197.249796)
			(xy 411.028989 -197.257542) (xy 411.033763 -197.272286) (xy 411.03804 -197.278752) (xy 411.038294 -197.279006)
			(xy 411.04937 -197.295591) (xy 411.061673 -197.3335) (xy 411.062424 -197.353428) (xy 411.062424 -197.760082)
			(xy 411.06193 -197.77677) (xy 411.053294 -197.80901) (xy 411.036607 -197.837915) (xy 411.013005 -197.861514)
			(xy 410.984099 -197.878199) (xy 410.951858 -197.886832) (xy 410.93517 -197.887336) (xy 410.32557 -197.887336)
			(xy 410.314756 -197.887166) (xy 410.293428 -197.883595) (xy 410.283152 -197.880224) (xy 410.275024 -197.877176)
			(xy 409.753562 -197.877176) (xy 409.747704 -197.880606) (xy 409.73791 -197.889997) (xy 409.734258 -197.895718)
			(xy 409.6893 -197.97141) (xy 409.686139 -197.977153) (xy 409.682549 -197.989756) (xy 409.682188 -197.996302)
			(xy 409.681934 -198.008748) (xy 409.688538 -198.02094) (xy 409.703097 -198.049063) (xy 409.723709 -198.108939)
			(xy 409.734054 -198.1708) (xy 411.438852 -198.1708) (xy 411.438852 -197.6882) (xy 411.439303 -197.663013)
			(xy 411.447205 -197.613261) (xy 411.462797 -197.56536) (xy 411.485696 -197.52049) (xy 411.515338 -197.479759)
			(xy 411.532832 -197.461632) (xy 411.659832 -197.334632) (xy 411.677981 -197.317168) (xy 411.718721 -197.287556)
			(xy 411.763588 -197.264674) (xy 411.811479 -197.249084) (xy 411.861218 -197.241168) (xy 411.8864 -197.240652)
			(xy 412.06547 -197.240652) (xy 412.075122 -197.236588) (xy 412.08714 -197.23181) (xy 412.112484 -197.226685)
			(xy 412.125414 -197.226428) (xy 412.735014 -197.226428) (xy 412.751695 -197.226978) (xy 412.783919 -197.235615)
			(xy 412.812811 -197.252296) (xy 412.836401 -197.275886) (xy 412.853084 -197.304777) (xy 412.861721 -197.337001)
			(xy 412.862268 -197.353682) (xy 412.862268 -197.76059) (xy 412.861576 -197.780529) (xy 412.849284 -197.818465)
			(xy 412.838138 -197.835012) (xy 412.833697 -197.841628) (xy 412.828763 -197.856768) (xy 412.828486 -197.86473)
			(xy 412.828486 -197.897496) (xy 412.828822 -197.90545) (xy 412.833733 -197.920583) (xy 412.838138 -197.927214)
			(xy 412.8426 -197.933657) (xy 412.850118 -197.947409) (xy 412.853124 -197.954646) (xy 412.853124 -197.9549)
			(xy 412.857326 -197.964036) (xy 412.871508 -197.97827) (xy 412.890067 -197.985974) (xy 412.900114 -197.986396)
			(xy 413.267144 -197.986396) (xy 413.292329 -197.986898) (xy 413.342078 -197.99479) (xy 413.389978 -198.010371)
			(xy 413.434848 -198.033259) (xy 413.475583 -198.062888) (xy 413.493712 -198.080376) (xy 413.649668 -198.236332)
			(xy 413.679894 -198.242174) (xy 413.694372 -198.236078) (xy 413.72591 -198.223299) (xy 413.791537 -198.205311)
			(xy 413.858976 -198.196236) (xy 413.893 -198.195692) (xy 413.893254 -198.195692) (xy 413.923945 -198.196162)
			(xy 413.984879 -198.203567) (xy 414.044479 -198.21825) (xy 414.101879 -198.239999) (xy 414.156245 -198.268496)
			(xy 414.206787 -198.303329) (xy 414.25277 -198.34399) (xy 414.273492 -198.366634) (xy 414.280995 -198.374344)
			(xy 414.300592 -198.383166) (xy 414.311338 -198.383652) (xy 414.602676 -198.383652) (xy 414.612746 -198.383227)
			(xy 414.631344 -198.375507) (xy 414.638744 -198.368666) (xy 414.751266 -198.256144) (xy 414.758074 -198.248719)
			(xy 414.765814 -198.230139) (xy 414.766252 -198.220076) (xy 414.766252 -197.88632) (xy 414.765819 -197.875976)
			(xy 414.757671 -197.856963) (xy 414.750504 -197.84949) (xy 414.73422 -197.833268) (xy 414.707896 -197.7956)
			(xy 414.689719 -197.753392) (xy 414.680439 -197.708384) (xy 414.679892 -197.685406) (xy 414.679892 -197.417944)
			(xy 414.689036 -197.417944) (xy 414.699041 -197.417443) (xy 414.717525 -197.409779) (xy 414.731675 -197.395631)
			(xy 414.739341 -197.377148) (xy 414.739836 -197.367144) (xy 414.739836 -197.288912) (xy 414.739303 -197.27891)
			(xy 414.731654 -197.260425) (xy 414.717515 -197.246273) (xy 414.699038 -197.238606) (xy 414.689036 -197.238112)
			(xy 414.103058 -197.238112) (xy 414.071443 -197.237676) (xy 414.008755 -197.229418) (xy 413.94768 -197.213049)
			(xy 413.889265 -197.188848) (xy 413.834508 -197.157229) (xy 413.784346 -197.118735) (xy 413.739637 -197.074023)
			(xy 413.701147 -197.023857) (xy 413.669534 -196.969098) (xy 413.645338 -196.91068) (xy 413.628974 -196.849604)
			(xy 413.620721 -196.786915) (xy 413.620721 -196.723685) (xy 413.628974 -196.660996) (xy 413.645338 -196.59992)
			(xy 413.669534 -196.541502) (xy 413.701147 -196.486743) (xy 413.739637 -196.436577) (xy 413.784346 -196.391865)
			(xy 413.834508 -196.353371) (xy 413.889265 -196.321752) (xy 413.94768 -196.297551) (xy 414.008755 -196.281182)
			(xy 414.071443 -196.272924) (xy 414.103058 -196.272404) (xy 415.057082 -196.272404) (xy 415.088694 -196.27298)
			(xy 415.151377 -196.281229) (xy 415.212447 -196.29759) (xy 415.27086 -196.321782) (xy 415.325615 -196.353391)
			(xy 415.375776 -196.391876) (xy 415.420484 -196.436579) (xy 415.458976 -196.486735) (xy 415.490592 -196.541487)
			(xy 415.514791 -196.599896) (xy 415.531159 -196.660964) (xy 415.539416 -196.723646) (xy 415.539936 -196.755258)
			(xy 415.539427 -196.787845) (xy 415.530638 -196.852423) (xy 415.51324 -196.915232) (xy 415.487551 -196.975129)
			(xy 415.454038 -197.031025) (xy 415.413308 -197.081905) (xy 415.390076 -197.104762) (xy 415.382919 -197.112235)
			(xy 415.374805 -197.131254) (xy 415.374328 -197.141592) (xy 415.374328 -197.367144) (xy 415.374753 -197.377158)
			(xy 415.382432 -197.395656) (xy 415.396604 -197.409808) (xy 415.415113 -197.417461) (xy 415.425128 -197.417944)
			(xy 415.434272 -197.417944) (xy 415.434272 -197.685406) (xy 415.433583 -197.710644) (xy 415.422436 -197.759874)
			(xy 415.412174 -197.782942) (xy 415.412174 -197.783196) (xy 415.409963 -197.788254) (xy 415.407518 -197.799015)
			(xy 415.407348 -197.804532) (xy 415.407348 -198.374) (xy 415.406897 -198.399187) (xy 415.398995 -198.448939)
			(xy 415.383403 -198.49684) (xy 415.360504 -198.54171) (xy 415.330862 -198.582441) (xy 415.313368 -198.600568)
			(xy 414.983168 -198.930768) (xy 414.965019 -198.948232) (xy 414.924279 -198.977844) (xy 414.879412 -199.000726)
			(xy 414.831521 -199.016316) (xy 414.781782 -199.024232) (xy 414.7566 -199.024748) (xy 414.311338 -199.024748)
			(xy 414.300617 -199.025348) (xy 414.281058 -199.034147) (xy 414.273492 -199.041766) (xy 414.252764 -199.064407)
			(xy 414.206794 -199.105086) (xy 414.156258 -199.139932) (xy 414.101893 -199.168436) (xy 414.04449 -199.190184)
			(xy 413.984885 -199.20486) (xy 413.923946 -199.212248) (xy 413.893254 -199.212708) (xy 413.893 -199.212708)
			(xy 413.862085 -199.212208) (xy 413.800713 -199.204704) (xy 413.740702 -199.18982) (xy 413.682936 -199.167773)
			(xy 413.628268 -199.138891) (xy 413.577501 -199.103597) (xy 413.531385 -199.062412) (xy 413.490599 -199.015943)
			(xy 413.455744 -198.964874) (xy 413.441134 -198.937626) (xy 413.437578 -198.930514) (xy 413.149288 -198.642478)
			(xy 413.141889 -198.635637) (xy 413.123289 -198.627918) (xy 413.11322 -198.627492) (xy 412.88462 -198.627492)
			(xy 412.858966 -198.644764) (xy 412.853124 -198.658988) (xy 412.853124 -198.659496) (xy 412.847062 -198.673381)
			(xy 412.829449 -198.698024) (xy 412.806531 -198.71783) (xy 412.779597 -198.731687) (xy 412.750159 -198.738817)
			(xy 412.735014 -198.739252) (xy 412.125414 -198.739252) (xy 412.110254 -198.738779) (xy 412.080791 -198.731616)
			(xy 412.053845 -198.717713) (xy 412.030933 -198.697853) (xy 412.013345 -198.673154) (xy 412.007304 -198.659242)
			(xy 412.007304 -198.658988) (xy 412.003087 -198.649861) (xy 411.98891 -198.635628) (xy 411.970359 -198.627919)
			(xy 411.960314 -198.627492) (xy 411.895544 -198.627492) (xy 411.870358 -198.627001) (xy 411.820609 -198.619107)
			(xy 411.772709 -198.603523) (xy 411.727839 -198.580633) (xy 411.687105 -198.551002) (xy 411.668976 -198.533512)
			(xy 411.532832 -198.397368) (xy 411.515368 -198.379219) (xy 411.485756 -198.338479) (xy 411.462874 -198.293612)
			(xy 411.447284 -198.245721) (xy 411.439368 -198.195982) (xy 411.438852 -198.1708) (xy 409.734054 -198.1708)
			(xy 409.734154 -198.171396) (xy 409.734766 -198.203058) (xy 409.734292 -198.230089) (xy 409.726653 -198.283609)
			(xy 409.711536 -198.335514) (xy 409.689244 -198.384766) (xy 409.660224 -198.430379) (xy 409.625056 -198.471439)
			(xy 409.584444 -198.507124) (xy 409.539202 -198.536719) (xy 409.490235 -198.559632) (xy 409.438525 -198.575404)
			(xy 409.385106 -198.583719) (xy 409.358084 -198.584566) (xy 409.35275 -198.584566) (xy 409.325795 -198.584083)
			(xy 409.272427 -198.576456) (xy 409.220665 -198.561389) (xy 409.171541 -198.539183) (xy 409.148534 -198.52513)
			(xy 409.145486 -198.523352) (xy 408.898598 -198.523352) (xy 408.890763 -198.527997) (xy 408.878763 -198.541685)
			(xy 408.872303 -198.558703) (xy 408.871928 -198.567802) (xy 408.871928 -198.814944) (xy 408.871928 -198.817484)
			(xy 408.872905 -198.827118) (xy 408.881061 -198.844665) (xy 408.895102 -198.857979) (xy 408.913056 -198.865194)
			(xy 408.922728 -198.865744) (xy 408.931872 -198.865744) (xy 408.931872 -199.133206) (xy 408.931354 -199.155516)
			(xy 408.922611 -199.199271) (xy 408.905466 -199.240466) (xy 408.880583 -199.277503) (xy 408.848926 -199.308948)
			(xy 408.811723 -199.333582) (xy 408.770414 -199.35045) (xy 408.726601 -199.358898) (xy 408.704288 -199.359266)
			(xy 408.704288 -199.359012) (xy 408.663902 -199.359012) (xy 408.650694 -199.36079) (xy 408.640534 -199.37095)
			(xy 408.633692 -199.37835) (xy 408.62597 -199.396948) (xy 408.625548 -199.407018) (xy 408.625548 -199.657716)
			(xy 408.631644 -199.666352) (xy 408.657298 -199.679052) (xy 408.661399 -199.680968) (xy 408.670085 -199.683519)
			(xy 408.67457 -199.684132) (xy 408.712578 -199.688778) (xy 408.786685 -199.708035) (xy 408.822144 -199.722486)
			(xy 408.849242 -199.734486) (xy 408.900698 -199.763897) (xy 408.94839 -199.799082) (xy 408.991676 -199.839566)
			(xy 409.01112 -199.861932) (xy 409.02128 -199.869552) (xy 409.433776 -199.869552) (xy 409.443805 -199.869109)
			(xy 409.46237 -199.861523) (xy 409.469844 -199.85482) (xy 409.518612 -199.806052) (xy 409.53674 -199.78856)
			(xy 409.577474 -199.758924) (xy 409.622343 -199.736028) (xy 409.670243 -199.720436) (xy 409.719993 -199.712534)
			(xy 409.74518 -199.712072) (xy 410.116274 -199.712072) (xy 410.124145 -199.711771) (xy 410.139138 -199.706974)
			(xy 410.145738 -199.702674) (xy 410.148278 -199.700896) (xy 410.15539 -199.68337) (xy 410.155898 -199.682354)
			(xy 410.161802 -199.668152) (xy 410.179296 -199.642866) (xy 410.202321 -199.622489) (xy 410.229547 -199.608201)
			(xy 410.259397 -199.600827) (xy 410.27477 -199.600312) (xy 410.88437 -199.600312) (xy 410.901035 -199.60085)
			(xy 410.933233 -199.609458) (xy 410.962113 -199.626096) (xy 410.985709 -199.649634) (xy 411.00242 -199.678471)
			(xy 411.011108 -199.710648) (xy 411.011624 -199.727312) (xy 411.011624 -200.337674) (xy 411.010813 -200.357592)
			(xy 410.99852 -200.395488) (xy 410.987494 -200.412096) (xy 410.98724 -200.41235) (xy 410.982962 -200.418819)
			(xy 410.978162 -200.433558) (xy 410.977842 -200.441306) (xy 410.977842 -200.475088) (xy 410.977842 -200.475596)
			(xy 410.978189 -200.483342) (xy 410.982963 -200.498086) (xy 410.98724 -200.504552) (xy 410.987494 -200.504806)
			(xy 410.99857 -200.521391) (xy 411.010873 -200.5593) (xy 411.011624 -200.579228) (xy 411.011624 -200.985882)
			(xy 411.01113 -201.00257) (xy 411.002494 -201.03481) (xy 410.985807 -201.063715) (xy 410.962205 -201.087314)
			(xy 410.933299 -201.103999) (xy 410.901058 -201.112632) (xy 410.88437 -201.113136) (xy 410.27477 -201.113136)
			(xy 410.263956 -201.112966) (xy 410.242628 -201.109395) (xy 410.232352 -201.106024) (xy 410.224224 -201.102976)
			(xy 409.377642 -201.102976) (xy 409.367576 -201.103409) (xy 409.348984 -201.111136) (xy 409.341574 -201.117962)
			(xy 409.325064 -201.134472) (xy 409.318222 -201.141871) (xy 409.310503 -201.16047) (xy 409.310078 -201.17054)
			(xy 409.310078 -201.3966) (xy 411.362652 -201.3966) (xy 411.362652 -200.9394) (xy 411.363103 -200.914213)
			(xy 411.371005 -200.864461) (xy 411.386597 -200.81656) (xy 411.409496 -200.77169) (xy 411.439138 -200.730959)
			(xy 411.456632 -200.712832) (xy 411.61335 -200.556114) (xy 411.63147 -200.538664) (xy 411.672164 -200.509093)
			(xy 411.716984 -200.486255) (xy 411.764827 -200.470714) (xy 411.814512 -200.462851) (xy 411.839664 -200.462388)
			(xy 412.024068 -200.462388) (xy 412.032196 -200.45934) (xy 412.042475 -200.455981) (xy 412.063801 -200.452402)
			(xy 412.074614 -200.452228) (xy 412.684214 -200.452228) (xy 412.700895 -200.452778) (xy 412.733119 -200.461415)
			(xy 412.762011 -200.478096) (xy 412.785601 -200.501686) (xy 412.802284 -200.530577) (xy 412.810921 -200.562801)
			(xy 412.811468 -200.579482) (xy 412.811468 -200.98639) (xy 412.810776 -201.006329) (xy 412.798484 -201.044265)
			(xy 412.787338 -201.060812) (xy 412.782897 -201.067428) (xy 412.777963 -201.082568) (xy 412.777686 -201.09053)
			(xy 412.777686 -201.123296) (xy 412.778022 -201.13125) (xy 412.782933 -201.146383) (xy 412.787338 -201.153014)
			(xy 412.796408 -201.166328) (xy 412.808247 -201.196276) (xy 412.810706 -201.212196) (xy 412.835344 -201.212196)
			(xy 412.860529 -201.212698) (xy 412.910278 -201.22059) (xy 412.958178 -201.236171) (xy 413.003048 -201.259059)
			(xy 413.043783 -201.288688) (xy 413.061912 -201.306176) (xy 413.542988 -201.787252) (xy 413.545274 -201.787252)
			(xy 413.580072 -201.752454) (xy 413.58058 -201.751946) (xy 413.604581 -201.728242) (xy 413.65774 -201.686716)
			(xy 413.715924 -201.652584) (xy 413.778111 -201.626447) (xy 413.843208 -201.608762) (xy 413.910072 -201.599842)
			(xy 413.9438 -201.599292) (xy 413.978242 -201.599903) (xy 414.046493 -201.609219) (xy 414.11286 -201.627668)
			(xy 414.176128 -201.654912) (xy 414.205928 -201.67219) (xy 414.213769 -201.67652) (xy 414.231344 -201.679914)
			(xy 414.249013 -201.677041) (xy 414.256982 -201.672952) (xy 414.333944 -201.629264) (xy 414.341601 -201.624554)
			(xy 414.353279 -201.610903) (xy 414.359498 -201.59405) (xy 414.359852 -201.585068) (xy 414.359852 -201.084434)
			(xy 414.359491 -201.075834) (xy 414.353788 -201.059608) (xy 414.348676 -201.052684) (xy 414.337032 -201.037511)
			(xy 414.318437 -201.004094) (xy 414.305737 -200.968023) (xy 414.299294 -200.930327) (xy 414.298892 -200.911206)
			(xy 414.298892 -200.643744) (xy 414.308036 -200.643744) (xy 414.318041 -200.643243) (xy 414.336525 -200.635579)
			(xy 414.350675 -200.621431) (xy 414.358341 -200.602948) (xy 414.358836 -200.592944) (xy 414.358836 -200.514712)
			(xy 414.358303 -200.50471) (xy 414.350654 -200.486225) (xy 414.336515 -200.472073) (xy 414.318038 -200.464406)
			(xy 414.308036 -200.463912) (xy 414.001458 -200.463912) (xy 413.969843 -200.463476) (xy 413.907155 -200.455218)
			(xy 413.84608 -200.438849) (xy 413.787665 -200.414648) (xy 413.732908 -200.383029) (xy 413.682746 -200.344535)
			(xy 413.638037 -200.299823) (xy 413.599547 -200.249657) (xy 413.567934 -200.194898) (xy 413.543738 -200.13648)
			(xy 413.527374 -200.075404) (xy 413.519121 -200.012715) (xy 413.519121 -199.949485) (xy 413.527374 -199.886796)
			(xy 413.543738 -199.82572) (xy 413.567934 -199.767302) (xy 413.599547 -199.712543) (xy 413.638037 -199.662377)
			(xy 413.682746 -199.617665) (xy 413.732908 -199.579171) (xy 413.787665 -199.547552) (xy 413.84608 -199.523351)
			(xy 413.907155 -199.506982) (xy 413.969843 -199.498724) (xy 414.001458 -199.498204) (xy 414.676082 -199.498204)
			(xy 414.707694 -199.49878) (xy 414.770377 -199.507029) (xy 414.831447 -199.52339) (xy 414.88986 -199.547582)
			(xy 414.944615 -199.579191) (xy 414.994776 -199.617676) (xy 415.039484 -199.662379) (xy 415.077976 -199.712535)
			(xy 415.109592 -199.767287) (xy 415.133791 -199.825696) (xy 415.150159 -199.886764) (xy 415.158416 -199.949446)
			(xy 415.158936 -199.981058) (xy 415.158427 -200.013645) (xy 415.149638 -200.078223) (xy 415.13224 -200.141032)
			(xy 415.106551 -200.200929) (xy 415.073038 -200.256825) (xy 415.032308 -200.307705) (xy 415.009076 -200.330562)
			(xy 415.001919 -200.338035) (xy 414.993805 -200.357054) (xy 414.993328 -200.367392) (xy 414.993328 -200.643744)
			(xy 415.002472 -200.643744) (xy 415.012497 -200.644144) (xy 415.031022 -200.651813) (xy 415.045196 -200.665992)
			(xy 415.052859 -200.684519) (xy 415.053272 -200.694544) (xy 415.053272 -200.91146) (xy 415.052643 -200.934993)
			(xy 415.042891 -200.98104) (xy 415.023861 -201.024089) (xy 415.0106 -201.04354) (xy 415.006144 -201.050147)
			(xy 415.00122 -201.065294) (xy 415.000948 -201.073258) (xy 415.000948 -201.9046) (xy 415.000497 -201.929787)
			(xy 414.992595 -201.979539) (xy 414.977003 -202.02744) (xy 414.954104 -202.07231) (xy 414.924462 -202.113041)
			(xy 414.906968 -202.131168) (xy 414.703768 -202.334368) (xy 414.685619 -202.351832) (xy 414.644879 -202.381444)
			(xy 414.600012 -202.404326) (xy 414.552121 -202.419916) (xy 414.502382 -202.427832) (xy 414.4772 -202.428348)
			(xy 414.362138 -202.428348) (xy 414.351417 -202.428948) (xy 414.331858 -202.437747) (xy 414.324292 -202.445366)
			(xy 414.303552 -202.46802) (xy 414.257551 -202.50872) (xy 414.20698 -202.543579) (xy 414.152577 -202.572088)
			(xy 414.095134 -202.593833) (xy 414.035488 -202.608496) (xy 413.974511 -202.615863) (xy 413.9438 -202.616308)
			(xy 413.913091 -202.615852) (xy 413.852118 -202.608469) (xy 413.792477 -202.593798) (xy 413.735037 -202.572053)
			(xy 413.680633 -202.543551) (xy 413.630056 -202.508705) (xy 413.584043 -202.468022) (xy 413.563308 -202.445366)
			(xy 413.555805 -202.437656) (xy 413.536208 -202.428834) (xy 413.525462 -202.428348) (xy 413.410146 -202.428348)
			(xy 413.383765 -202.427799) (xy 413.331708 -202.419203) (xy 413.281766 -202.402187) (xy 413.23529 -202.377212)
			(xy 413.193539 -202.344954) (xy 413.175196 -202.325986) (xy 413.173926 -202.324462) (xy 412.794704 -201.94524)
			(xy 412.761176 -201.940414) (xy 412.74619 -201.948796) (xy 412.731803 -201.956299) (xy 412.700431 -201.964537)
			(xy 412.684214 -201.965052) (xy 412.074614 -201.965052) (xy 412.059454 -201.964579) (xy 412.029991 -201.957416)
			(xy 412.003045 -201.943513) (xy 411.980133 -201.923653) (xy 411.962545 -201.898954) (xy 411.956504 -201.885042)
			(xy 411.956504 -201.884788) (xy 411.952287 -201.875661) (xy 411.93811 -201.861428) (xy 411.919559 -201.853719)
			(xy 411.909514 -201.853292) (xy 411.819344 -201.853292) (xy 411.794158 -201.852801) (xy 411.744409 -201.844907)
			(xy 411.696509 -201.829323) (xy 411.651639 -201.806433) (xy 411.610905 -201.776802) (xy 411.592776 -201.759312)
			(xy 411.456632 -201.623168) (xy 411.439168 -201.605019) (xy 411.409556 -201.564279) (xy 411.386674 -201.519412)
			(xy 411.371084 -201.471521) (xy 411.363168 -201.421782) (xy 411.362652 -201.3966) (xy 409.310078 -201.3966)
			(xy 409.310078 -201.47915) (xy 409.31051 -201.489217) (xy 409.318234 -201.50781) (xy 409.325064 -201.515218)
			(xy 409.383484 -201.573384) (xy 409.40228 -201.58075) (xy 409.415742 -201.58075) (xy 409.442992 -201.581239)
			(xy 409.496938 -201.589) (xy 409.54923 -201.604358) (xy 409.598805 -201.627001) (xy 409.644653 -201.656468)
			(xy 409.685841 -201.692159) (xy 409.721532 -201.733347) (xy 409.750999 -201.779195) (xy 409.773642 -201.82877)
			(xy 409.789 -201.881062) (xy 409.796761 -201.935008) (xy 409.79725 -201.962258) (xy 409.796776 -201.989289)
			(xy 409.789137 -202.042807) (xy 409.77402 -202.094712) (xy 409.751728 -202.143963) (xy 409.722707 -202.189575)
			(xy 409.687539 -202.230633) (xy 409.646927 -202.266317) (xy 409.601685 -202.29591) (xy 409.552718 -202.318821)
			(xy 409.501008 -202.334591) (xy 409.44759 -202.342904) (xy 409.420568 -202.343766) (xy 409.415234 -202.343766)
			(xy 409.38828 -202.343282) (xy 409.334913 -202.335653) (xy 409.283152 -202.320584) (xy 409.234029 -202.298376)
			(xy 409.211018 -202.28433) (xy 409.20797 -202.282552) (xy 408.873198 -202.282552) (xy 408.865363 -202.287197)
			(xy 408.853363 -202.300885) (xy 408.846903 -202.317903) (xy 408.846528 -202.327002) (xy 408.846528 -202.574144)
			(xy 408.846528 -202.576684) (xy 408.847505 -202.586318) (xy 408.855661 -202.603865) (xy 408.869702 -202.617179)
			(xy 408.887656 -202.624394) (xy 408.897328 -202.624944) (xy 408.906472 -202.624944) (xy 408.906472 -202.892406)
			(xy 408.906065 -202.911894) (xy 408.899391 -202.950295) (xy 408.88624 -202.986985) (xy 408.867002 -203.020883)
			(xy 408.85491 -203.03617) (xy 408.849576 -203.044044) (xy 408.849576 -203.623672) (xy 408.849918 -203.632365)
			(xy 408.855759 -203.648738) (xy 408.861006 -203.655676) (xy 408.86634 -203.66228) (xy 408.890216 -203.667106)
			(xy 408.923315 -203.674478) (xy 408.987334 -203.696835) (xy 409.04781 -203.727508) (xy 409.103669 -203.765954)
			(xy 409.153918 -203.811488) (xy 409.17622 -203.837032) (xy 409.18638 -203.844652) (xy 409.31973 -203.844652)
			(xy 409.329797 -203.844222) (xy 409.348389 -203.836495) (xy 409.355798 -203.829666) (xy 409.798266 -203.387452)
			(xy 409.816395 -203.369963) (xy 409.85713 -203.340334) (xy 409.902 -203.317445) (xy 409.9499 -203.301862)
			(xy 409.999649 -203.293968) (xy 410.024834 -203.293472) (xy 410.040074 -203.293472) (xy 410.047945 -203.293171)
			(xy 410.062938 -203.288374) (xy 410.069538 -203.284074) (xy 410.072078 -203.282296) (xy 410.07919 -203.26477)
			(xy 410.079698 -203.263754) (xy 410.085602 -203.249552) (xy 410.103096 -203.224266) (xy 410.126121 -203.203889)
			(xy 410.153347 -203.189601) (xy 410.183197 -203.182227) (xy 410.19857 -203.181712) (xy 410.80817 -203.181712)
			(xy 410.824835 -203.18225) (xy 410.857033 -203.190858) (xy 410.885913 -203.207496) (xy 410.909509 -203.231034)
			(xy 410.92622 -203.259871) (xy 410.934908 -203.292048) (xy 410.935424 -203.308712) (xy 410.935424 -203.919074)
			(xy 410.934613 -203.938992) (xy 410.92232 -203.976888) (xy 410.911294 -203.993496) (xy 410.91104 -203.99375)
			(xy 410.906762 -204.000219) (xy 410.901962 -204.014958) (xy 410.901642 -204.022706) (xy 410.901642 -204.056488)
			(xy 410.901642 -204.056996) (xy 410.901989 -204.064742) (xy 410.906763 -204.079486) (xy 410.91104 -204.085952)
			(xy 410.911294 -204.086206) (xy 410.92237 -204.102791) (xy 410.934673 -204.1407) (xy 410.935424 -204.160628)
			(xy 410.935424 -204.567282) (xy 410.93493 -204.58397) (xy 410.926294 -204.61621) (xy 410.909607 -204.645115)
			(xy 410.886005 -204.668714) (xy 410.857099 -204.685399) (xy 410.824858 -204.694032) (xy 410.80817 -204.694536)
			(xy 410.19857 -204.694536) (xy 410.187756 -204.694366) (xy 410.166428 -204.690795) (xy 410.156152 -204.687424)
			(xy 410.148024 -204.684376) (xy 410.114242 -204.684376) (xy 410.104176 -204.684809) (xy 410.085584 -204.692536)
			(xy 410.078174 -204.699362) (xy 409.640786 -205.13675) (xy 409.621161 -205.155609) (xy 409.576719 -205.187023)
			(xy 409.552394 -205.199234) (xy 409.540202 -205.205076) (xy 409.530296 -205.213204) (xy 409.527502 -205.217014)
			(xy 409.512008 -205.310486) (xy 409.511222 -205.316084) (xy 409.511855 -205.327368) (xy 409.513278 -205.332838)
			(xy 409.59151 -205.41107) (xy 409.604953 -205.424953) (xy 409.628769 -205.455387) (xy 409.639008 -205.471776)
			(xy 409.64231 -205.47711) (xy 410.132784 -205.96733) (xy 410.140184 -205.974171) (xy 410.158783 -205.981886)
			(xy 410.168852 -205.982316) (xy 412.513526 -205.982316) (xy 412.520083 -205.978295) (xy 412.53057 -205.967051)
			(xy 412.5341 -205.960218) (xy 412.57093 -205.86954) (xy 412.57355 -205.862413) (xy 412.574842 -205.84729)
			(xy 412.57347 -205.839822) (xy 412.572454 -205.834488) (xy 412.550102 -205.814168) (xy 412.284418 -205.548484)
			(xy 412.270448 -205.546452) (xy 411.998414 -205.546452) (xy 411.981741 -205.545912) (xy 411.949527 -205.537296)
			(xy 411.920636 -205.520645) (xy 411.89703 -205.497093) (xy 411.888178 -205.482952) (xy 411.865572 -205.443836)
			(xy 411.847538 -205.431136) (xy 411.839664 -205.429612) (xy 411.815676 -205.424889) (xy 411.769393 -205.409142)
			(xy 411.726036 -205.386554) (xy 411.68661 -205.357647) (xy 411.668976 -205.340712) (xy 411.507432 -205.179168)
			(xy 411.489938 -205.161041) (xy 411.460296 -205.12031) (xy 411.437397 -205.07544) (xy 411.421805 -205.027539)
			(xy 411.413903 -204.977787) (xy 411.413452 -204.9526) (xy 411.413452 -204.4192) (xy 411.413968 -204.394018)
			(xy 411.421884 -204.344279) (xy 411.437474 -204.296388) (xy 411.460356 -204.251521) (xy 411.489968 -204.210781)
			(xy 411.507432 -204.192632) (xy 411.56255 -204.137514) (xy 411.580692 -204.120092) (xy 411.621395 -204.090547)
			(xy 411.666212 -204.06772) (xy 411.714044 -204.052171) (xy 411.763717 -204.044282) (xy 411.788864 -204.043788)
			(xy 411.947868 -204.043788) (xy 411.955996 -204.04074) (xy 411.966279 -204.037397) (xy 411.987603 -204.033825)
			(xy 411.998414 -204.033628) (xy 412.608014 -204.033628) (xy 412.624695 -204.034174) (xy 412.656921 -204.042811)
			(xy 412.685813 -204.059493) (xy 412.709404 -204.083084) (xy 412.726087 -204.111976) (xy 412.734725 -204.144201)
			(xy 412.735268 -204.160882) (xy 412.735268 -204.567536) (xy 412.734463 -204.587456) (xy 412.722182 -204.625361)
			(xy 412.711138 -204.641958) (xy 412.710884 -204.642212) (xy 412.706618 -204.648685) (xy 412.701842 -204.663424)
			(xy 412.701486 -204.671168) (xy 412.701486 -204.70495) (xy 412.701486 -204.705458) (xy 412.701842 -204.7132)
			(xy 412.706634 -204.727932) (xy 412.710884 -204.734414) (xy 412.711138 -204.734668) (xy 412.722286 -204.751214)
			(xy 412.734585 -204.78915) (xy 412.735268 -204.80909) (xy 412.735268 -205.08087) (xy 412.737046 -205.093824)
			(xy 412.7373 -205.095094) (xy 412.894526 -205.25232) (xy 412.901953 -205.259091) (xy 412.920549 -205.266673)
			(xy 412.930594 -205.267052) (xy 413.21482 -205.267052) (xy 413.22498 -205.259432) (xy 413.245732 -205.235625)
			(xy 413.292163 -205.192813) (xy 413.343536 -205.156078) (xy 413.399061 -205.125983) (xy 413.457884 -205.102993)
			(xy 413.5191 -205.08746) (xy 413.581768 -205.079624) (xy 413.613346 -205.079092) (xy 413.6136 -205.079092)
			(xy 413.645982 -205.079598) (xy 413.710223 -205.087817) (xy 413.772901 -205.104121) (xy 413.833004 -205.128247)
			(xy 413.889559 -205.159805) (xy 413.941653 -205.198284) (xy 413.96539 -205.220316) (xy 413.969962 -205.224888)
			(xy 413.97739 -205.231345) (xy 413.995686 -205.238548) (xy 414.005522 -205.238858) (xy 414.016952 -205.238858)
			(xy 414.040066 -205.215744) (xy 414.046907 -205.208344) (xy 414.054627 -205.189746) (xy 414.055052 -205.179676)
			(xy 414.055052 -204.648816) (xy 414.050734 -204.642466) (xy 414.037527 -204.626841) (xy 414.016405 -204.591808)
			(xy 414.00192 -204.553551) (xy 413.994543 -204.513314) (xy 413.994092 -204.49286) (xy 413.994092 -204.275944)
			(xy 413.994504 -204.265916) (xy 414.002166 -204.247383) (xy 414.016339 -204.233195) (xy 414.034865 -204.225514)
			(xy 414.044892 -204.225144) (xy 414.054036 -204.225144) (xy 414.054036 -204.096112) (xy 414.054036 -204.093572)
			(xy 414.053077 -204.084256) (xy 414.045404 -204.067189) (xy 414.032165 -204.053964) (xy 414.01509 -204.04631)
			(xy 414.005776 -204.045312) (xy 413.518858 -204.045312) (xy 413.487248 -204.044793) (xy 413.424571 -204.036536)
			(xy 413.363507 -204.020169) (xy 413.305102 -203.995972) (xy 413.250354 -203.96436) (xy 413.200201 -203.925872)
			(xy 413.155501 -203.881167) (xy 413.117017 -203.831011) (xy 413.085409 -203.77626) (xy 413.061217 -203.717853)
			(xy 413.044856 -203.656788) (xy 413.036605 -203.59411) (xy 413.036605 -203.53089) (xy 413.044856 -203.468212)
			(xy 413.061217 -203.407147) (xy 413.085409 -203.34874) (xy 413.117017 -203.293989) (xy 413.155501 -203.243833)
			(xy 413.200201 -203.199128) (xy 413.250354 -203.16064) (xy 413.305102 -203.129028) (xy 413.363507 -203.104831)
			(xy 413.424571 -203.088464) (xy 413.487249 -203.080207) (xy 413.518858 -203.079604) (xy 414.371282 -203.079604)
			(xy 414.402898 -203.08012) (xy 414.465589 -203.088371) (xy 414.526667 -203.104733) (xy 414.585086 -203.128928)
			(xy 414.639848 -203.160541) (xy 414.690015 -203.199031) (xy 414.734729 -203.24374) (xy 414.773226 -203.293902)
			(xy 414.804845 -203.34866) (xy 414.829047 -203.407077) (xy 414.845418 -203.468152) (xy 414.853676 -203.530842)
			(xy 414.854136 -203.562458) (xy 414.854136 -203.562966) (xy 414.853579 -203.595518) (xy 414.844789 -203.660027)
			(xy 414.827417 -203.722772) (xy 414.801778 -203.782616) (xy 414.768336 -203.838476) (xy 414.727697 -203.88934)
			(xy 414.70453 -203.912216) (xy 414.701411 -203.915293) (xy 414.696177 -203.922319) (xy 414.694116 -203.926186)
			(xy 414.691537 -203.931614) (xy 414.688722 -203.943293) (xy 414.688528 -203.9493) (xy 414.688528 -204.174344)
			(xy 414.688528 -204.176884) (xy 414.689505 -204.186518) (xy 414.697661 -204.204065) (xy 414.711702 -204.217379)
			(xy 414.729656 -204.224594) (xy 414.739328 -204.225144) (xy 414.748472 -204.225144) (xy 414.748472 -204.49286)
			(xy 414.748037 -204.512064) (xy 414.741497 -204.549913) (xy 414.728667 -204.586116) (xy 414.709914 -204.619637)
			(xy 414.69818 -204.634846) (xy 414.696148 -204.638148) (xy 414.696148 -205.3336) (xy 414.695632 -205.358782)
			(xy 414.687716 -205.408521) (xy 414.672126 -205.456412) (xy 414.649244 -205.501279) (xy 414.619632 -205.542019)
			(xy 414.602168 -205.560168) (xy 414.348168 -205.814168) (xy 414.330041 -205.831662) (xy 414.28931 -205.861304)
			(xy 414.24444 -205.884203) (xy 414.196539 -205.899795) (xy 414.146787 -205.907697) (xy 414.1216 -205.908148)
			(xy 414.012126 -205.908148) (xy 414.006792 -205.910688) (xy 413.993838 -205.925166) (xy 413.973125 -205.947822)
			(xy 413.927154 -205.988505) (xy 413.876617 -206.023353) (xy 413.82225 -206.051859) (xy 413.764844 -206.073607)
			(xy 413.705235 -206.088279) (xy 413.644294 -206.095663) (xy 413.6136 -206.096108) (xy 413.613346 -206.096108)
			(xy 413.581765 -206.095632) (xy 413.519088 -206.08781) (xy 413.457864 -206.072282) (xy 413.399036 -206.049286)
			(xy 413.343511 -206.019177) (xy 413.292145 -205.98242) (xy 413.245731 -205.939581) (xy 413.22498 -205.915768)
			(xy 413.21482 -205.908148) (xy 412.994094 -205.908148) (xy 412.987549 -205.91218) (xy 412.977091 -205.923437)
			(xy 412.97352 -205.930246) (xy 412.93669 -206.020924) (xy 412.934068 -206.028051) (xy 412.932768 -206.043175)
			(xy 412.93415 -206.050642) (xy 412.935166 -206.055976) (xy 412.957518 -206.076296) (xy 413.615378 -206.733902)
			(xy 413.622781 -206.740736) (xy 413.641379 -206.748441) (xy 413.651446 -206.748888) (xy 417.394898 -206.748888)
			(xy 417.404968 -206.748465) (xy 417.423572 -206.74075) (xy 417.430966 -206.733902) (xy 418.018722 -206.146146)
			(xy 418.025569 -206.138748) (xy 418.033296 -206.120149) (xy 418.033708 -206.110078) (xy 418.033708 -178.565302)
			(xy 418.033286 -178.555231) (xy 418.025573 -178.536626) (xy 418.018722 -178.529234) (xy 417.098226 -177.608738)
			(xy 417.090825 -177.601899) (xy 417.072227 -177.594186) (xy 417.062158 -177.593752) (xy 413.780224 -177.593752)
			(xy 413.77021 -177.594235) (xy 413.751701 -177.601889) (xy 413.737529 -177.616041) (xy 413.729849 -177.634538)
			(xy 413.729424 -177.644552) (xy 413.729424 -178.087274) (xy 413.728613 -178.107192) (xy 413.71632 -178.145088)
			(xy 413.705294 -178.161696) (xy 413.70504 -178.16195) (xy 413.700762 -178.168419) (xy 413.695962 -178.183158)
			(xy 413.695642 -178.190906) (xy 413.695642 -178.224688) (xy 413.695642 -178.225196) (xy 413.695989 -178.232942)
			(xy 413.700763 -178.247686) (xy 413.70504 -178.254152) (xy 413.705294 -178.254406) (xy 413.71637 -178.270991)
			(xy 413.728673 -178.3089) (xy 413.729424 -178.328828) (xy 413.729424 -178.735482) (xy 413.72893 -178.75217)
			(xy 413.720294 -178.78441) (xy 413.703607 -178.813315) (xy 413.680005 -178.836914) (xy 413.651099 -178.853599)
			(xy 413.618858 -178.862232) (xy 413.60217 -178.862736) (xy 412.99257 -178.862736) (xy 412.981756 -178.862566)
			(xy 412.960428 -178.858995) (xy 412.950152 -178.855624) (xy 412.942024 -178.852576) (xy 412.552642 -178.852576)
			(xy 412.542576 -178.853009) (xy 412.523984 -178.860736) (xy 412.516574 -178.867562) (xy 412.00578 -179.378356)
			(xy 412.003494 -179.387246) (xy 411.996405 -179.414686) (xy 411.975225 -179.46725) (xy 411.9465 -179.516102)
			(xy 411.910863 -179.560167) (xy 411.869099 -179.598473) (xy 411.822127 -179.630179) (xy 411.77098 -179.654586)
			(xy 411.716786 -179.671157) (xy 411.660736 -179.679528) (xy 411.6324 -179.680108) (xy 411.605149 -179.679622)
			(xy 411.551201 -179.671866) (xy 411.498906 -179.656511) (xy 411.449329 -179.633869) (xy 411.403479 -179.604403)
			(xy 411.362288 -179.568712) (xy 411.326597 -179.527521) (xy 411.297131 -179.481671) (xy 411.274489 -179.432094)
			(xy 411.259134 -179.379799) (xy 411.251378 -179.325851) (xy 411.250892 -179.2986) (xy 411.251409 -179.270261)
			(xy 411.259792 -179.214207) (xy 411.276374 -179.16001) (xy 411.300789 -179.108861) (xy 411.332501 -179.061885)
			(xy 411.370812 -179.020117) (xy 411.41488 -178.984475) (xy 411.463734 -178.955742) (xy 411.516301 -178.934552)
			(xy 411.543754 -178.927506) (xy 411.552644 -178.92522) (xy 411.627066 -178.850798) (xy 411.633916 -178.843401)
			(xy 411.641655 -178.824803) (xy 411.642052 -178.81473) (xy 411.642052 -178.36007) (xy 411.641645 -178.350458)
			(xy 411.634604 -178.332569) (xy 411.628336 -178.325272) (xy 411.60827 -178.303682) (xy 411.60181 -178.297244)
			(xy 411.585538 -178.289038) (xy 411.57652 -178.28768) (xy 411.544566 -178.28367) (xy 411.481952 -178.268605)
			(xy 411.421743 -178.245749) (xy 411.364904 -178.215469) (xy 411.312348 -178.178249) (xy 411.264916 -178.134686)
			(xy 411.24378 -178.110388) (xy 411.23362 -178.102768) (xy 410.278072 -178.102768) (xy 410.274262 -178.105054)
			(xy 410.259036 -178.11698) (xy 410.225361 -178.135998) (xy 410.188947 -178.149023) (xy 410.15085 -178.155676)
			(xy 410.131514 -178.156108) (xy 409.914344 -178.156108) (xy 409.904316 -178.155696) (xy 409.885783 -178.148034)
			(xy 409.871595 -178.133861) (xy 409.863914 -178.115335) (xy 409.863544 -178.105308) (xy 409.863544 -178.096164)
			(xy 409.565856 -178.096164) (xy 409.565602 -178.096164) (xy 409.55651 -178.09659) (xy 409.539504 -178.103039)
			(xy 409.525818 -178.115018) (xy 409.521152 -178.122834) (xy 409.521152 -178.694334) (xy 409.521583 -178.7044)
			(xy 409.529312 -178.722991) (xy 409.536138 -178.730402) (xy 409.730956 -178.92522) (xy 409.739846 -178.927506)
			(xy 409.767286 -178.934595) (xy 409.81985 -178.955775) (xy 409.868702 -178.9845) (xy 409.912767 -179.020137)
			(xy 409.951073 -179.061901) (xy 409.982779 -179.108873) (xy 410.007186 -179.16002) (xy 410.023757 -179.214214)
			(xy 410.032128 -179.270264) (xy 410.032708 -179.2986) (xy 410.032222 -179.325851) (xy 410.024466 -179.379799)
			(xy 410.009111 -179.432094) (xy 409.986469 -179.481671) (xy 409.957003 -179.527521) (xy 409.921312 -179.568712)
			(xy 409.880121 -179.604403) (xy 409.834271 -179.633869) (xy 409.784694 -179.656511) (xy 409.732399 -179.671866)
			(xy 409.678451 -179.679622) (xy 409.6512 -179.680108) (xy 409.622861 -179.679591) (xy 409.566807 -179.671208)
			(xy 409.51261 -179.654626) (xy 409.461461 -179.630211) (xy 409.414485 -179.598499) (xy 409.372717 -179.560188)
			(xy 409.337075 -179.51612) (xy 409.308342 -179.467266) (xy 409.287152 -179.414699) (xy 409.280106 -179.387246)
			(xy 409.27782 -179.378356) (xy 408.97429 -179.074826) (xy 408.956871 -179.056683) (xy 408.927331 -179.015978)
			(xy 408.904509 -178.971161) (xy 408.888965 -178.92333) (xy 408.88108 -178.873658) (xy 408.880564 -178.848512)
			(xy 408.880564 -178.641756) (xy 408.878024 -178.637438) (xy 408.833828 -178.618896) (xy 408.818842 -178.617372)
			(xy 408.811222 -178.618896) (xy 408.67711 -178.753008) (xy 408.669712 -178.759855) (xy 408.651114 -178.767592)
			(xy 408.641042 -178.767994) (xy 403.065488 -178.767994) (xy 403.059477 -178.768157) (xy 403.047791 -178.770972)
			(xy 403.042374 -178.773582) (xy 403.0389 -178.775421) (xy 403.03252 -178.780014) (xy 403.029674 -178.782726)
			(xy 401.080887 -180.731513) (xy 413.080481 -180.731513) (xy 413.080481 -180.668287) (xy 413.088734 -180.605602)
			(xy 413.105098 -180.544531) (xy 413.129293 -180.486118) (xy 413.160906 -180.431363) (xy 413.199395 -180.381203)
			(xy 413.244103 -180.336495) (xy 413.294263 -180.298006) (xy 413.349018 -180.266393) (xy 413.407431 -180.242198)
			(xy 413.468502 -180.225834) (xy 413.531187 -180.217581) (xy 413.5628 -180.217064) (xy 414.280858 -180.217064)
			(xy 414.313445 -180.217573) (xy 414.378023 -180.226362) (xy 414.440832 -180.24376) (xy 414.500729 -180.269449)
			(xy 414.556625 -180.302962) (xy 414.607505 -180.343692) (xy 414.630362 -180.366924) (xy 414.637835 -180.374081)
			(xy 414.656854 -180.382195) (xy 414.667192 -180.382672) (xy 414.943544 -180.382672) (xy 414.943544 -180.373528)
			(xy 414.943944 -180.363503) (xy 414.951613 -180.344978) (xy 414.965792 -180.330804) (xy 414.984319 -180.323141)
			(xy 414.994344 -180.322728) (xy 415.21126 -180.322728) (xy 415.232977 -180.323229) (xy 415.275613 -180.331511)
			(xy 415.315877 -180.347795) (xy 415.352283 -180.371481) (xy 415.368232 -180.386228) (xy 415.375599 -180.392685)
			(xy 415.393752 -180.400003) (xy 415.403538 -180.400452) (xy 415.820606 -180.400452) (xy 415.833143 -180.399745)
			(xy 415.855251 -180.387902) (xy 415.86277 -180.377846) (xy 415.90976 -180.307234) (xy 415.916156 -180.296302)
			(xy 415.918441 -180.271116) (xy 415.914078 -180.259228) (xy 415.901299 -180.22769) (xy 415.883311 -180.162063)
			(xy 415.874236 -180.094624) (xy 415.873692 -180.0606) (xy 415.874226 -180.026872) (xy 415.883156 -179.960008)
			(xy 415.900846 -179.894912) (xy 415.926985 -179.832726) (xy 415.961116 -179.77454) (xy 416.002638 -179.721377)
			(xy 416.026346 -179.69738) (xy 416.026854 -179.696872) (xy 416.061652 -179.662074) (xy 416.061652 -179.659788)
			(xy 416.019488 -179.617624) (xy 416.012005 -179.610933) (xy 415.993447 -179.603342) (xy 415.98342 -179.602892)
			(xy 415.55162 -179.602892) (xy 415.525966 -179.620164) (xy 415.520124 -179.634388) (xy 415.520124 -179.634896)
			(xy 415.514062 -179.648781) (xy 415.496449 -179.673424) (xy 415.473531 -179.69323) (xy 415.446597 -179.707087)
			(xy 415.417159 -179.714217) (xy 415.402014 -179.714652) (xy 414.792414 -179.714652) (xy 414.77653 -179.714198)
			(xy 414.74574 -179.706383) (xy 414.717832 -179.691209) (xy 414.694534 -179.669615) (xy 414.677288 -179.642938)
			(xy 414.671764 -179.628038) (xy 414.66643 -179.612544) (xy 414.640268 -179.593748) (xy 414.6042 -179.593748)
			(xy 414.579013 -179.593297) (xy 414.529261 -179.585395) (xy 414.48136 -179.569803) (xy 414.43649 -179.546904)
			(xy 414.395759 -179.517262) (xy 414.377632 -179.499768) (xy 414.199832 -179.321968) (xy 414.182368 -179.303819)
			(xy 414.152756 -179.263079) (xy 414.129874 -179.218212) (xy 414.114284 -179.170321) (xy 414.106368 -179.120582)
			(xy 414.105852 -179.0954) (xy 414.105852 -178.6636) (xy 414.106303 -178.638413) (xy 414.114205 -178.588661)
			(xy 414.129797 -178.54076) (xy 414.152696 -178.49589) (xy 414.182338 -178.455159) (xy 414.199832 -178.437032)
			(xy 414.33115 -178.305714) (xy 414.34927 -178.288264) (xy 414.389964 -178.258693) (xy 414.434784 -178.235855)
			(xy 414.482627 -178.220314) (xy 414.532312 -178.212451) (xy 414.557464 -178.211988) (xy 414.741868 -178.211988)
			(xy 414.749996 -178.20894) (xy 414.760275 -178.205581) (xy 414.781601 -178.202002) (xy 414.792414 -178.201828)
			(xy 415.402014 -178.201828) (xy 415.418695 -178.202378) (xy 415.450919 -178.211015) (xy 415.479811 -178.227696)
			(xy 415.503401 -178.251286) (xy 415.520084 -178.280177) (xy 415.528721 -178.312401) (xy 415.529268 -178.329082)
			(xy 415.529268 -178.73599) (xy 415.528576 -178.755929) (xy 415.516284 -178.793865) (xy 415.505138 -178.810412)
			(xy 415.500697 -178.817028) (xy 415.495763 -178.832168) (xy 415.495486 -178.84013) (xy 415.495486 -178.872896)
			(xy 415.495822 -178.88085) (xy 415.500733 -178.895983) (xy 415.505138 -178.902614) (xy 415.5096 -178.909057)
			(xy 415.517118 -178.922809) (xy 415.520124 -178.930046) (xy 415.520124 -178.9303) (xy 415.524326 -178.939436)
			(xy 415.538508 -178.95367) (xy 415.557067 -178.961374) (xy 415.567114 -178.961796) (xy 416.137344 -178.961796)
			(xy 416.162529 -178.962298) (xy 416.212278 -178.97019) (xy 416.260178 -178.985771) (xy 416.305048 -179.008659)
			(xy 416.345783 -179.038288) (xy 416.363912 -179.055776) (xy 416.598862 -179.290726) (xy 416.600386 -179.291996)
			(xy 416.619308 -179.31038) (xy 416.651541 -179.35214) (xy 416.676513 -179.398607) (xy 416.693553 -179.448532)
			(xy 416.702202 -179.50057) (xy 416.702748 -179.526946) (xy 416.702748 -179.642262) (xy 416.703348 -179.652983)
			(xy 416.712147 -179.672542) (xy 416.719766 -179.680108) (xy 416.742407 -179.700836) (xy 416.783086 -179.746806)
			(xy 416.817932 -179.797342) (xy 416.846436 -179.851707) (xy 416.868184 -179.90911) (xy 416.88286 -179.968715)
			(xy 416.890248 -180.029654) (xy 416.890708 -180.060346) (xy 416.890708 -180.0606) (xy 416.890263 -180.091294)
			(xy 416.882879 -180.152235) (xy 416.868207 -180.211844) (xy 416.846459 -180.26925) (xy 416.817953 -180.323617)
			(xy 416.783105 -180.374154) (xy 416.742422 -180.420125) (xy 416.719766 -180.440838) (xy 416.712035 -180.448322)
			(xy 416.703225 -180.467934) (xy 416.702748 -180.478684) (xy 416.702748 -180.5686) (xy 416.702297 -180.593787)
			(xy 416.694395 -180.643539) (xy 416.678803 -180.69144) (xy 416.655904 -180.73631) (xy 416.626262 -180.777041)
			(xy 416.608768 -180.795168) (xy 416.456368 -180.947568) (xy 416.438219 -180.965032) (xy 416.397479 -180.994644)
			(xy 416.352612 -181.017526) (xy 416.304721 -181.033116) (xy 416.254982 -181.041032) (xy 416.2298 -181.041548)
			(xy 415.340038 -181.041548) (xy 415.3281 -181.044596) (xy 415.322258 -181.047644) (xy 415.32175 -181.048152)
			(xy 415.304733 -181.057269) (xy 415.268351 -181.070171) (xy 415.230307 -181.076717) (xy 415.211006 -181.077108)
			(xy 414.943544 -181.077108) (xy 414.943544 -181.067964) (xy 414.943043 -181.057959) (xy 414.935379 -181.039475)
			(xy 414.921231 -181.025325) (xy 414.902748 -181.017659) (xy 414.892744 -181.017164) (xy 414.667192 -181.017164)
			(xy 414.656852 -181.017631) (xy 414.637838 -181.025754) (xy 414.630362 -181.032912) (xy 414.607506 -181.056146)
			(xy 414.556633 -181.096882) (xy 414.500737 -181.130398) (xy 414.440838 -181.156083) (xy 414.378026 -181.173468)
			(xy 414.313445 -181.182238) (xy 414.280858 -181.182772) (xy 413.5628 -181.182772) (xy 413.531187 -181.182219)
			(xy 413.468502 -181.173966) (xy 413.407431 -181.157602) (xy 413.349018 -181.133407) (xy 413.294263 -181.101794)
			(xy 413.244103 -181.063305) (xy 413.199395 -181.018597) (xy 413.160906 -180.968437) (xy 413.129293 -180.913682)
			(xy 413.105098 -180.855269) (xy 413.088734 -180.794198) (xy 413.080481 -180.731513) (xy 401.080887 -180.731513)
			(xy 400.62658 -181.18582) (xy 400.619184 -181.192672) (xy 400.600585 -181.200412) (xy 400.590512 -181.200806)
			(xy 389.341106 -181.200806) (xy 389.336229 -181.200906) (xy 389.326644 -181.202704) (xy 389.322056 -181.204362)
			(xy 389.312912 -181.208172) (xy 387.714744 -182.80634) (xy 387.71204 -182.809192) (xy 387.70745 -182.815572)
			(xy 387.7056 -182.81904) (xy 387.703017 -182.824467) (xy 387.700192 -182.836146) (xy 387.700012 -182.842154)
			(xy 387.700012 -183.496458) (xy 408.81935 -183.496458) (xy 408.819795 -183.470805) (xy 408.826743 -183.41997)
			(xy 408.84044 -183.370525) (xy 408.86064 -183.323361) (xy 408.873452 -183.301132) (xy 408.876752 -183.2951)
			(xy 408.880367 -183.281842) (xy 408.880564 -183.27497) (xy 408.880564 -182.605934) (xy 408.877008 -182.593234)
			(xy 408.87396 -182.587646) (xy 408.8647 -182.570359) (xy 408.851606 -182.533396) (xy 408.845063 -182.494733)
			(xy 408.84475 -182.475124) (xy 408.845004 -182.475124) (xy 408.845004 -182.175912) (xy 408.84475 -182.175912)
			(xy 408.845102 -182.153598) (xy 408.853551 -182.109783) (xy 408.87042 -182.068473) (xy 408.895056 -182.031268)
			(xy 408.926504 -181.999611) (xy 408.963544 -181.974729) (xy 409.004741 -181.957585) (xy 409.048499 -181.948845)
			(xy 409.07081 -181.948328) (xy 409.338272 -181.948328) (xy 409.338272 -181.957472) (xy 409.33881 -181.967474)
			(xy 409.346455 -181.98596) (xy 409.360593 -182.000113) (xy 409.37907 -182.007779) (xy 409.389072 -182.008272)
			(xy 409.863544 -182.008272) (xy 409.863544 -181.999128) (xy 409.863944 -181.989103) (xy 409.871613 -181.970578)
			(xy 409.885792 -181.956404) (xy 409.904319 -181.948741) (xy 409.914344 -181.948328) (xy 410.13126 -181.948328)
			(xy 410.150188 -181.948746) (xy 410.187503 -181.95513) (xy 410.223238 -181.967627) (xy 410.256399 -181.985889)
			(xy 410.271468 -181.99735) (xy 410.278412 -182.002398) (xy 410.294637 -182.00798) (xy 410.303218 -182.008272)
			(xy 411.188662 -182.008272) (xy 411.199382 -182.007666) (xy 411.218941 -181.998871) (xy 411.226508 -181.991254)
			(xy 411.247253 -181.968604) (xy 411.293252 -181.927903) (xy 411.343822 -181.893043) (xy 411.398225 -181.864533)
			(xy 411.455667 -181.842788) (xy 411.515312 -181.828124) (xy 411.576289 -181.820757) (xy 411.607 -181.820312)
			(xy 411.63771 -181.820761) (xy 411.698683 -181.828144) (xy 411.758324 -181.842816) (xy 411.815764 -181.864562)
			(xy 411.870169 -181.893066) (xy 411.920745 -181.927913) (xy 411.966757 -181.968597) (xy 411.987492 -181.991254)
			(xy 411.995006 -181.998952) (xy 412.014594 -182.007784) (xy 412.025338 -182.008272) (xy 412.842964 -182.008272)
			(xy 412.868618 -181.991) (xy 412.87446 -181.976776) (xy 412.87446 -181.976268) (xy 412.880517 -181.962381)
			(xy 412.898134 -181.937741) (xy 412.921053 -181.917937) (xy 412.947987 -181.90408) (xy 412.977425 -181.896948)
			(xy 412.99257 -181.896512) (xy 413.60217 -181.896512) (xy 413.618826 -181.897113) (xy 413.651009 -181.905717)
			(xy 413.679874 -181.922347) (xy 413.703459 -181.945873) (xy 413.720161 -181.974696) (xy 413.728845 -182.006857)
			(xy 413.729424 -182.023512) (xy 413.729424 -182.634128) (xy 413.728654 -182.654054) (xy 413.716364 -182.691964)
			(xy 413.705294 -182.70855) (xy 413.700834 -182.715154) (xy 413.695913 -182.730303) (xy 413.695642 -182.738268)
			(xy 413.695642 -182.771034) (xy 413.695952 -182.77899) (xy 413.70088 -182.794124) (xy 413.705294 -182.800752)
			(xy 413.716338 -182.817349) (xy 413.72862 -182.855254) (xy 413.729424 -182.875174) (xy 413.729424 -183.282082)
			(xy 413.728942 -183.298772) (xy 413.720306 -183.331014) (xy 413.703616 -183.359922) (xy 413.680012 -183.383524)
			(xy 413.651103 -183.40021) (xy 413.61886 -183.408844) (xy 413.60217 -183.409336) (xy 412.99257 -183.409336)
			(xy 412.981758 -183.409152) (xy 412.960435 -183.405571) (xy 412.950152 -183.402224) (xy 412.942024 -183.399176)
			(xy 412.374842 -183.399176) (xy 412.364772 -183.399603) (xy 412.346173 -183.40732) (xy 412.338774 -183.414162)
			(xy 412.060136 -183.6928) (xy 414.029652 -183.6928) (xy 414.029652 -183.261) (xy 414.030103 -183.235813)
			(xy 414.038005 -183.186061) (xy 414.053597 -183.13816) (xy 414.076496 -183.09329) (xy 414.106138 -183.052559)
			(xy 414.123632 -183.034432) (xy 414.30575 -182.852314) (xy 414.32387 -182.834864) (xy 414.364564 -182.805293)
			(xy 414.409384 -182.782455) (xy 414.457227 -182.766914) (xy 414.506912 -182.759051) (xy 414.532064 -182.758588)
			(xy 414.741868 -182.758588) (xy 414.749996 -182.75554) (xy 414.760275 -182.752181) (xy 414.781601 -182.748602)
			(xy 414.792414 -182.748428) (xy 415.402014 -182.748428) (xy 415.418695 -182.748978) (xy 415.450919 -182.757615)
			(xy 415.479811 -182.774296) (xy 415.503401 -182.797886) (xy 415.520084 -182.826777) (xy 415.528721 -182.859001)
			(xy 415.529268 -182.875682) (xy 415.529268 -183.28259) (xy 415.528576 -183.302529) (xy 415.516284 -183.340465)
			(xy 415.505138 -183.357012) (xy 415.500697 -183.363628) (xy 415.495763 -183.378768) (xy 415.495486 -183.38673)
			(xy 415.495486 -183.419496) (xy 415.495822 -183.42745) (xy 415.500733 -183.442583) (xy 415.505138 -183.449214)
			(xy 415.51225 -183.46039) (xy 415.515806 -183.466232) (xy 415.520632 -183.471058) (xy 415.528044 -183.477742)
			(xy 415.546477 -183.485339) (xy 415.566415 -183.485339) (xy 415.584848 -183.477742) (xy 415.59226 -183.471058)
			(xy 415.597086 -183.466232) (xy 415.615255 -183.44879) (xy 415.65599 -183.419175) (xy 415.700852 -183.396289)
			(xy 415.748738 -183.380694) (xy 415.798473 -183.372771) (xy 415.823654 -183.372252) (xy 416.167062 -183.372252)
			(xy 416.177783 -183.371652) (xy 416.197342 -183.362853) (xy 416.204908 -183.355234) (xy 416.225636 -183.332593)
			(xy 416.271606 -183.291914) (xy 416.322142 -183.257068) (xy 416.376507 -183.228564) (xy 416.43391 -183.206816)
			(xy 416.493515 -183.19214) (xy 416.554454 -183.184752) (xy 416.585146 -183.184292) (xy 416.5854 -183.184292)
			(xy 416.616131 -183.184756) (xy 416.677145 -183.192165) (xy 416.736821 -183.206873) (xy 416.794289 -183.228668)
			(xy 416.848711 -183.257231) (xy 416.899293 -183.292145) (xy 416.945298 -183.332902) (xy 416.986055 -183.378907)
			(xy 417.020969 -183.429489) (xy 417.049532 -183.483911) (xy 417.071327 -183.541379) (xy 417.086035 -183.601055)
			(xy 417.093444 -183.662069) (xy 417.093908 -183.6928) (xy 417.093908 -183.700928) (xy 417.093654 -183.711088)
			(xy 417.101274 -183.730138) (xy 417.187126 -183.81599) (xy 417.204603 -183.834085) (xy 417.234168 -183.874787)
			(xy 417.257 -183.919614) (xy 417.272536 -183.967461) (xy 417.280392 -184.017151) (xy 417.280852 -184.042304)
			(xy 417.280852 -184.661302) (xy 417.284408 -184.674002) (xy 417.287456 -184.67959) (xy 417.296731 -184.69687)
			(xy 417.309819 -184.733836) (xy 417.316356 -184.772503) (xy 417.316666 -184.792112) (xy 417.316412 -184.792112)
			(xy 417.316412 -185.091324) (xy 417.316666 -185.091324) (xy 417.316331 -185.113638) (xy 417.307876 -185.157452)
			(xy 417.291002 -185.198761) (xy 417.266363 -185.235965) (xy 417.234914 -185.267621) (xy 417.197873 -185.292503)
			(xy 417.156675 -185.309648) (xy 417.112917 -185.31839) (xy 417.090606 -185.318908) (xy 416.823144 -185.318908)
			(xy 416.823144 -185.309764) (xy 416.822643 -185.299759) (xy 416.814979 -185.281275) (xy 416.800831 -185.267125)
			(xy 416.782348 -185.259459) (xy 416.772344 -185.258964) (xy 416.546792 -185.258964) (xy 416.536452 -185.259431)
			(xy 416.517438 -185.267554) (xy 416.509962 -185.274712) (xy 416.487106 -185.297946) (xy 416.436233 -185.338682)
			(xy 416.380337 -185.372198) (xy 416.320438 -185.397883) (xy 416.257626 -185.415268) (xy 416.193045 -185.424038)
			(xy 416.160458 -185.424572) (xy 415.361882 -185.424572) (xy 415.33027 -185.424018) (xy 415.267587 -185.415763)
			(xy 415.206517 -185.399398) (xy 415.148107 -185.375201) (xy 415.093354 -185.343588) (xy 415.043195 -185.305098)
			(xy 414.99849 -185.260391) (xy 414.960002 -185.210231) (xy 414.928391 -185.155477) (xy 414.904196 -185.097065)
			(xy 414.887833 -185.035995) (xy 414.879581 -184.973312) (xy 414.879581 -184.910088) (xy 414.887833 -184.847405)
			(xy 414.904196 -184.786335) (xy 414.928391 -184.727923) (xy 414.960002 -184.673169) (xy 414.99849 -184.623009)
			(xy 415.043195 -184.578302) (xy 415.093354 -184.539812) (xy 415.148107 -184.508199) (xy 415.206517 -184.484002)
			(xy 415.267587 -184.467637) (xy 415.33027 -184.459382) (xy 415.361882 -184.458864) (xy 416.160966 -184.458864)
			(xy 416.193523 -184.459379) (xy 416.258044 -184.468144) (xy 416.320801 -184.485505) (xy 416.380653 -184.511147)
			(xy 416.436514 -184.544605) (xy 416.487367 -184.585271) (xy 416.510216 -184.60847) (xy 416.517328 -184.61609)
			(xy 416.536632 -184.624472) (xy 416.589464 -184.624472) (xy 416.599486 -184.62405) (xy 416.618008 -184.616387)
			(xy 416.632182 -184.602215) (xy 416.639849 -184.583694) (xy 416.640264 -184.573672) (xy 416.640264 -184.27319)
			(xy 416.639853 -184.263119) (xy 416.632123 -184.244521) (xy 416.625278 -184.237122) (xy 416.588956 -184.201308)
			(xy 416.5854 -184.201308) (xy 416.554691 -184.200852) (xy 416.493718 -184.193469) (xy 416.434077 -184.178798)
			(xy 416.376637 -184.157053) (xy 416.322233 -184.128551) (xy 416.271656 -184.093705) (xy 416.225643 -184.053022)
			(xy 416.204908 -184.030366) (xy 416.197405 -184.022656) (xy 416.177808 -184.013834) (xy 416.167062 -184.013348)
			(xy 415.977324 -184.013348) (xy 415.967357 -184.013824) (xy 415.948921 -184.0214) (xy 415.94151 -184.02808)
			(xy 415.914078 -184.055512) (xy 415.895932 -184.072979) (xy 415.85519 -184.102589) (xy 415.810322 -184.125469)
			(xy 415.762431 -184.141059) (xy 415.712692 -184.148976) (xy 415.68751 -184.149492) (xy 415.55162 -184.149492)
			(xy 415.525966 -184.166764) (xy 415.520124 -184.180988) (xy 415.520124 -184.181496) (xy 415.514062 -184.195381)
			(xy 415.496449 -184.220024) (xy 415.473531 -184.23983) (xy 415.446597 -184.253687) (xy 415.417159 -184.260817)
			(xy 415.402014 -184.261252) (xy 414.792414 -184.261252) (xy 414.775061 -184.260647) (xy 414.741634 -184.251315)
			(xy 414.711949 -184.233336) (xy 414.688194 -184.208034) (xy 414.679638 -184.192926) (xy 414.673034 -184.18048)
			(xy 414.648904 -184.165748) (xy 414.5026 -184.165748) (xy 414.477413 -184.165297) (xy 414.427661 -184.157395)
			(xy 414.37976 -184.141803) (xy 414.33489 -184.118904) (xy 414.294159 -184.089262) (xy 414.276032 -184.071768)
			(xy 414.123632 -183.919368) (xy 414.106168 -183.901219) (xy 414.076556 -183.860479) (xy 414.053674 -183.815612)
			(xy 414.038084 -183.767721) (xy 414.030168 -183.717982) (xy 414.029652 -183.6928) (xy 412.060136 -183.6928)
			(xy 411.990286 -183.76265) (xy 411.985556 -183.767593) (xy 411.978737 -183.779449) (xy 411.976824 -183.786018)
			(xy 411.976824 -183.786526) (xy 411.969446 -183.813589) (xy 411.947853 -183.865358) (xy 411.918912 -183.913408)
			(xy 411.883247 -183.956702) (xy 411.841627 -183.994308) (xy 411.79495 -184.025413) (xy 411.744221 -184.049349)
			(xy 411.690534 -184.065599) (xy 411.635046 -184.073812) (xy 411.607 -184.074308) (xy 411.579749 -184.073822)
			(xy 411.525801 -184.066066) (xy 411.473506 -184.050711) (xy 411.423929 -184.028069) (xy 411.378079 -183.998603)
			(xy 411.336888 -183.962912) (xy 411.301197 -183.921721) (xy 411.271731 -183.875871) (xy 411.249089 -183.826294)
			(xy 411.233734 -183.773999) (xy 411.225978 -183.720051) (xy 411.225492 -183.6928) (xy 411.226029 -183.664745)
			(xy 411.23426 -183.609242) (xy 411.250532 -183.555542) (xy 411.274492 -183.504805) (xy 411.305624 -183.458123)
			(xy 411.343256 -183.416504) (xy 411.386578 -183.380845) (xy 411.434656 -183.351915) (xy 411.486451 -183.330337)
			(xy 411.513528 -183.322976) (xy 411.513782 -183.322976) (xy 411.520329 -183.321011) (xy 411.532174 -183.3142)
			(xy 411.53715 -183.309514) (xy 411.642306 -183.204358) (xy 411.649158 -183.196967) (xy 411.65687 -183.178361)
			(xy 411.657292 -183.16829) (xy 411.657292 -182.90921) (xy 411.656863 -182.899141) (xy 411.649145 -182.880543)
			(xy 411.642306 -182.873142) (xy 411.62097 -182.851806) (xy 411.613947 -182.845315) (xy 411.596464 -182.837605)
			(xy 411.586934 -182.83682) (xy 411.552828 -182.83494) (xy 411.485543 -182.823162) (xy 411.42044 -182.802487)
			(xy 411.358688 -182.773286) (xy 411.3014 -182.736085) (xy 411.249605 -182.691551) (xy 411.226508 -182.666386)
			(xy 411.219003 -182.658679) (xy 411.199408 -182.649854) (xy 411.188662 -182.649368) (xy 410.294582 -182.649368)
			(xy 410.286533 -182.649663) (xy 410.27125 -182.654716) (xy 410.26461 -182.659274) (xy 410.245041 -182.672733)
			(xy 410.201686 -182.692102) (xy 410.155255 -182.702047) (xy 410.131514 -182.702708) (xy 409.863544 -182.702708)
			(xy 409.863544 -182.693564) (xy 409.863043 -182.683559) (xy 409.855379 -182.665075) (xy 409.841231 -182.650925)
			(xy 409.822748 -182.643259) (xy 409.812744 -182.642764) (xy 409.571952 -182.642764) (xy 409.561946 -182.643248)
			(xy 409.54346 -182.650917) (xy 409.52931 -182.66507) (xy 409.521646 -182.683558) (xy 409.521152 -182.693564)
			(xy 409.521152 -183.27497) (xy 409.521349 -183.281843) (xy 409.524953 -183.295106) (xy 409.528264 -183.301132)
			(xy 409.54106 -183.32337) (xy 409.561264 -183.37053) (xy 409.574963 -183.419973) (xy 409.581913 -183.470806)
			(xy 409.582366 -183.496458) (xy 409.58188 -183.523709) (xy 409.574124 -183.577657) (xy 409.558769 -183.629952)
			(xy 409.536127 -183.679529) (xy 409.506661 -183.725379) (xy 409.47097 -183.76657) (xy 409.429779 -183.802261)
			(xy 409.383929 -183.831727) (xy 409.334352 -183.854369) (xy 409.282057 -183.869724) (xy 409.228109 -183.87748)
			(xy 409.173607 -183.87748) (xy 409.119659 -183.869724) (xy 409.067364 -183.854369) (xy 409.017787 -183.831727)
			(xy 408.971937 -183.802261) (xy 408.930746 -183.76657) (xy 408.895055 -183.725379) (xy 408.865589 -183.679529)
			(xy 408.842947 -183.629952) (xy 408.827592 -183.577657) (xy 408.819836 -183.523709) (xy 408.81935 -183.496458)
			(xy 387.700012 -183.496458) (xy 387.700012 -186.937142) (xy 408.89555 -186.937142) (xy 408.895988 -186.911489)
			(xy 408.902938 -186.860654) (xy 408.916638 -186.811209) (xy 408.936839 -186.764045) (xy 408.949652 -186.741816)
			(xy 408.952957 -186.735787) (xy 408.956569 -186.722527) (xy 408.956764 -186.715654) (xy 408.956764 -186.314334)
			(xy 408.953208 -186.301634) (xy 408.95016 -186.296046) (xy 408.9409 -186.278759) (xy 408.927806 -186.241796)
			(xy 408.921263 -186.203133) (xy 408.92095 -186.183524) (xy 408.921204 -186.183524) (xy 408.921204 -185.884312)
			(xy 408.92095 -185.884312) (xy 408.921302 -185.861998) (xy 408.929751 -185.818183) (xy 408.94662 -185.776873)
			(xy 408.971256 -185.739668) (xy 409.002704 -185.708011) (xy 409.039744 -185.683129) (xy 409.080941 -185.665985)
			(xy 409.124699 -185.657245) (xy 409.14701 -185.656728) (xy 409.414472 -185.656728) (xy 409.414472 -185.665872)
			(xy 409.41501 -185.675874) (xy 409.422655 -185.69436) (xy 409.436793 -185.708513) (xy 409.45527 -185.716179)
			(xy 409.465272 -185.716672) (xy 409.939744 -185.716672) (xy 409.939744 -185.707528) (xy 409.940144 -185.697503)
			(xy 409.947813 -185.678978) (xy 409.961992 -185.664804) (xy 409.980519 -185.657141) (xy 409.990544 -185.656728)
			(xy 410.20746 -185.656728) (xy 410.226388 -185.657146) (xy 410.263703 -185.66353) (xy 410.299438 -185.676027)
			(xy 410.332599 -185.694289) (xy 410.347668 -185.70575) (xy 410.354612 -185.710798) (xy 410.370837 -185.71638)
			(xy 410.379418 -185.716672) (xy 411.366462 -185.716672) (xy 411.377182 -185.716066) (xy 411.396741 -185.707271)
			(xy 411.404308 -185.699654) (xy 411.425053 -185.677004) (xy 411.471052 -185.636303) (xy 411.521622 -185.601443)
			(xy 411.576025 -185.572933) (xy 411.633467 -185.551188) (xy 411.693112 -185.536524) (xy 411.754089 -185.529157)
			(xy 411.7848 -185.528712) (xy 411.81551 -185.529161) (xy 411.876483 -185.536544) (xy 411.936124 -185.551216)
			(xy 411.993564 -185.572962) (xy 412.047969 -185.601466) (xy 412.098545 -185.636313) (xy 412.144557 -185.676997)
			(xy 412.165292 -185.699654) (xy 412.172806 -185.707352) (xy 412.192394 -185.716184) (xy 412.203138 -185.716672)
			(xy 412.919164 -185.716672) (xy 412.944818 -185.6994) (xy 412.95066 -185.685176) (xy 412.95066 -185.684668)
			(xy 412.956717 -185.670781) (xy 412.974334 -185.646141) (xy 412.997253 -185.626337) (xy 413.024187 -185.61248)
			(xy 413.053625 -185.605348) (xy 413.06877 -185.604912) (xy 413.67837 -185.604912) (xy 413.695026 -185.605513)
			(xy 413.727209 -185.614117) (xy 413.756074 -185.630747) (xy 413.779659 -185.654273) (xy 413.796361 -185.683096)
			(xy 413.805045 -185.715257) (xy 413.805624 -185.731912) (xy 413.805624 -186.342528) (xy 413.804854 -186.362454)
			(xy 413.792564 -186.400364) (xy 413.781494 -186.41695) (xy 413.777034 -186.423554) (xy 413.772113 -186.438703)
			(xy 413.771842 -186.446668) (xy 413.771842 -186.479434) (xy 413.772152 -186.48739) (xy 413.77708 -186.502524)
			(xy 413.781494 -186.509152) (xy 413.792538 -186.525749) (xy 413.80482 -186.563654) (xy 413.805624 -186.583574)
			(xy 413.805624 -186.990482) (xy 413.805142 -187.007172) (xy 413.796506 -187.039414) (xy 413.779816 -187.068322)
			(xy 413.756212 -187.091924) (xy 413.727303 -187.10861) (xy 413.69506 -187.117244) (xy 413.67837 -187.117736)
			(xy 413.06877 -187.117736) (xy 413.057958 -187.117552) (xy 413.036635 -187.113971) (xy 413.026352 -187.110624)
			(xy 413.018224 -187.107576) (xy 412.400242 -187.107576) (xy 412.390172 -187.108003) (xy 412.371573 -187.11572)
			(xy 412.364174 -187.122562) (xy 411.888686 -187.59805) (xy 411.883956 -187.602993) (xy 411.877137 -187.614849)
			(xy 411.875224 -187.621418) (xy 411.875224 -187.621926) (xy 411.867846 -187.648989) (xy 411.846253 -187.700758)
			(xy 411.817312 -187.748808) (xy 411.781647 -187.792102) (xy 411.740027 -187.829708) (xy 411.69335 -187.860813)
			(xy 411.642621 -187.884749) (xy 411.588934 -187.900999) (xy 411.533446 -187.909212) (xy 411.5054 -187.909708)
			(xy 411.478149 -187.909222) (xy 411.424201 -187.901466) (xy 411.371906 -187.886111) (xy 411.322329 -187.863469)
			(xy 411.276479 -187.834003) (xy 411.235288 -187.798312) (xy 411.199597 -187.757121) (xy 411.170131 -187.711271)
			(xy 411.147489 -187.661694) (xy 411.132134 -187.609399) (xy 411.124378 -187.555451) (xy 411.123892 -187.5282)
			(xy 411.124429 -187.500145) (xy 411.13266 -187.444642) (xy 411.148932 -187.390942) (xy 411.172892 -187.340205)
			(xy 411.204024 -187.293523) (xy 411.241656 -187.251904) (xy 411.284978 -187.216245) (xy 411.333056 -187.187315)
			(xy 411.384851 -187.165737) (xy 411.411928 -187.158376) (xy 411.412182 -187.158376) (xy 411.418729 -187.156411)
			(xy 411.430574 -187.1496) (xy 411.43555 -187.144914) (xy 411.861254 -186.71921) (xy 411.868136 -186.71183)
			(xy 411.875846 -186.693196) (xy 411.87573 -186.67303) (xy 411.872176 -186.663584) (xy 411.836108 -186.57697)
			(xy 411.831731 -186.567924) (xy 411.817472 -186.553799) (xy 411.798901 -186.546187) (xy 411.788864 -186.545728)
			(xy 411.7848 -186.545728) (xy 411.754091 -186.545266) (xy 411.693118 -186.537883) (xy 411.633478 -186.523213)
			(xy 411.576038 -186.501469) (xy 411.521634 -186.472967) (xy 411.471057 -186.438122) (xy 411.425044 -186.397442)
			(xy 411.404308 -186.374786) (xy 411.396803 -186.367079) (xy 411.377208 -186.358254) (xy 411.366462 -186.357768)
			(xy 410.370782 -186.357768) (xy 410.362733 -186.358063) (xy 410.34745 -186.363116) (xy 410.34081 -186.367674)
			(xy 410.321241 -186.381133) (xy 410.277886 -186.400502) (xy 410.231455 -186.410447) (xy 410.207714 -186.411108)
			(xy 409.939744 -186.411108) (xy 409.939744 -186.401964) (xy 409.939243 -186.391959) (xy 409.931579 -186.373475)
			(xy 409.917431 -186.359325) (xy 409.898948 -186.351659) (xy 409.888944 -186.351164) (xy 409.648152 -186.351164)
			(xy 409.638146 -186.351648) (xy 409.61966 -186.359317) (xy 409.60551 -186.37347) (xy 409.597846 -186.391958)
			(xy 409.597352 -186.401964) (xy 409.597352 -186.715654) (xy 409.597555 -186.722527) (xy 409.601155 -186.73579)
			(xy 409.604464 -186.741816) (xy 409.617294 -186.764035) (xy 409.637489 -186.811202) (xy 409.651179 -186.860651)
			(xy 409.658118 -186.911488) (xy 409.658566 -186.937142) (xy 409.65808 -186.964393) (xy 409.650324 -187.018341)
			(xy 409.634969 -187.070636) (xy 409.612327 -187.120213) (xy 409.582861 -187.166063) (xy 409.54717 -187.207254)
			(xy 409.505979 -187.242945) (xy 409.460129 -187.272411) (xy 409.410552 -187.295053) (xy 409.358257 -187.310408)
			(xy 409.304309 -187.318164) (xy 409.249807 -187.318164) (xy 409.195859 -187.310408) (xy 409.143564 -187.295053)
			(xy 409.093987 -187.272411) (xy 409.048137 -187.242945) (xy 409.006946 -187.207254) (xy 408.971255 -187.166063)
			(xy 408.941789 -187.120213) (xy 408.919147 -187.070636) (xy 408.903792 -187.018341) (xy 408.896036 -186.964393)
			(xy 408.89555 -186.937142) (xy 387.700012 -186.937142) (xy 387.700012 -209.665316) (xy 387.700489 -209.675282)
			(xy 387.708066 -209.693718) (xy 387.714744 -209.70113) (xy 387.755384 -209.742024) (xy 387.777029 -209.76421)
			(xy 387.815876 -209.81251) (xy 387.849237 -209.864751) (xy 387.876715 -209.920312) (xy 387.887718 -209.949288)
			(xy 387.898573 -209.980521) (xy 387.913828 -210.044861) (xy 387.921524 -210.110536) (xy 387.922008 -210.143598)
			(xy 387.922008 -215.508586) (xy 387.923024 -215.518238) (xy 387.92465 -215.525483) (xy 387.931488 -215.538656)
			(xy 387.936486 -215.544146) (xy 388.050786 -215.658446) (xy 388.058187 -215.665285) (xy 388.076786 -215.672996)
			(xy 388.086854 -215.673432)
		)
		(stroke
			(width 0)
			(type solid)
		)
		(fill yes)
		(layer "F.Cu")
		(net "GND")
	)
	(gr_poly
		(pts
			(xy 89.393522 -258.015486) (xy 89.403398 -258.015025) (xy 89.421695 -258.007579) (xy 89.429082 -258.001008)
			(xy 92.40901 -255.02108) (xy 92.409518 -255.020572) (xy 92.416108 -255.013194) (xy 92.423573 -254.994894)
			(xy 92.423996 -254.985012) (xy 92.423996 -246.41048) (xy 92.423858 -246.405447) (xy 92.421815 -246.395591)
			(xy 92.419932 -246.390922) (xy 92.408585 -246.361926) (xy 92.3963 -246.300892) (xy 92.395548 -246.269764)
			(xy 92.395548 -242.082574) (xy 92.395004 -242.07259) (xy 92.387279 -242.05417) (xy 92.380562 -242.04676)
			(xy 91.490038 -241.155982) (xy 91.467554 -241.132877) (xy 91.427336 -241.082486) (xy 91.393013 -241.027909)
			(xy 91.365016 -240.969833) (xy 91.343697 -240.908987) (xy 91.329325 -240.846136) (xy 91.322081 -240.782072)
			(xy 91.321636 -240.749836) (xy 91.321636 -238.942372) (xy 91.322101 -238.910136) (xy 91.329343 -238.846073)
			(xy 91.343712 -238.783223) (xy 91.365026 -238.722376) (xy 91.393018 -238.664298) (xy 91.427336 -238.609718)
			(xy 91.467547 -238.559324) (xy 91.490038 -238.536226) (xy 91.678506 -238.347758) (xy 91.701613 -238.325276)
			(xy 91.752005 -238.285063) (xy 91.806583 -238.250743) (xy 91.864659 -238.222749) (xy 91.925504 -238.201432)
			(xy 91.988354 -238.187061) (xy 92.052417 -238.179816) (xy 92.084652 -238.179356) (xy 92.759784 -238.179356)
			(xy 92.769744 -238.178865) (xy 92.788159 -238.171268) (xy 92.795598 -238.164624) (xy 93.060266 -237.899956)
			(xy 93.064285 -237.895669) (xy 93.070439 -237.885663) (xy 93.072458 -237.880144) (xy 93.072458 -237.87989)
			(xy 93.074394 -237.873401) (xy 93.075172 -237.859886) (xy 93.073982 -237.85322) (xy 93.0529 -237.756954)
			(xy 93.036136 -237.73765) (xy 93.023944 -237.733078) (xy 92.997011 -237.722451) (xy 92.946452 -237.694239)
			(xy 92.900736 -237.658713) (xy 92.860911 -237.616689) (xy 92.827891 -237.56913) (xy 92.802436 -237.517129)
			(xy 92.785129 -237.461879) (xy 92.776367 -237.404648) (xy 92.775786 -237.3757) (xy 92.776272 -237.348449)
			(xy 92.784028 -237.294501) (xy 92.799383 -237.242205) (xy 92.822024 -237.192628) (xy 92.851491 -237.146777)
			(xy 92.887182 -237.105586) (xy 92.928372 -237.069894) (xy 92.974223 -237.040427) (xy 93.0238 -237.017785)
			(xy 93.076095 -237.00243) (xy 93.130043 -236.994672) (xy 93.157294 -236.994192) (xy 93.186244 -236.99473)
			(xy 93.24348 -237.003483) (xy 93.298734 -237.020788) (xy 93.350736 -237.046249) (xy 93.398292 -237.079279)
			(xy 93.440307 -237.119119) (xy 93.475816 -237.164854) (xy 93.504001 -237.215431) (xy 93.514672 -237.24235)
			(xy 93.519244 -237.254542) (xy 93.538548 -237.271306) (xy 93.634814 -237.292388) (xy 93.641479 -237.293606)
			(xy 93.655 -237.29283) (xy 93.661484 -237.290864) (xy 93.661738 -237.290864) (xy 93.667264 -237.288861)
			(xy 93.677274 -237.282705) (xy 93.68155 -237.278672) (xy 94.897702 -236.06252) (xy 94.89821 -236.062012)
			(xy 94.904792 -236.054631) (xy 94.912236 -236.036331) (xy 94.912688 -236.026452) (xy 94.912688 -219.222066)
			(xy 94.913117 -219.211998) (xy 94.920839 -219.193402) (xy 94.927674 -219.185998) (xy 99.186238 -214.927434)
			(xy 99.186746 -214.926926) (xy 99.193326 -214.919544) (xy 99.20077 -214.901245) (xy 99.201224 -214.891366)
			(xy 99.201224 -211.384896) (xy 99.201648 -211.374827) (xy 99.209367 -211.356225) (xy 99.21621 -211.348828)
			(xy 101.21138 -209.353658) (xy 101.21878 -209.346818) (xy 101.237379 -209.339104) (xy 101.247448 -209.338672)
			(xy 114.45494 -209.338672) (xy 114.465008 -209.339102) (xy 114.483604 -209.346823) (xy 114.491008 -209.353658)
			(xy 115.600226 -210.462876) (xy 121.397774 -210.462876) (xy 121.401845 -210.407254) (xy 121.413971 -210.352817)
			(xy 121.433894 -210.300726) (xy 121.46119 -210.252091) (xy 121.495276 -210.207948) (xy 121.535425 -210.169239)
			(xy 121.580783 -210.136788) (xy 121.630383 -210.111287) (xy 121.683167 -210.09328) (xy 121.73801 -210.08315)
			(xy 121.793744 -210.081113) (xy 121.849181 -210.087213) (xy 121.903138 -210.101319) (xy 121.954467 -210.123131)
			(xy 122.002073 -210.152185) (xy 122.044941 -210.18786) (xy 122.082158 -210.229397) (xy 122.112931 -210.27591)
			(xy 122.136603 -210.326407) (xy 122.152671 -210.379814) (xy 122.160791 -210.43499) (xy 122.1613 -210.462876)
			(xy 122.160791 -210.490762) (xy 122.152671 -210.545938) (xy 122.136603 -210.599345) (xy 122.112931 -210.649842)
			(xy 122.082158 -210.696355) (xy 122.044941 -210.737892) (xy 122.002073 -210.773567) (xy 121.954467 -210.802621)
			(xy 121.903138 -210.824433) (xy 121.849181 -210.838539) (xy 121.793744 -210.844639) (xy 121.73801 -210.842602)
			(xy 121.683167 -210.832472) (xy 121.630383 -210.814465) (xy 121.580783 -210.788964) (xy 121.535425 -210.756513)
			(xy 121.495276 -210.717804) (xy 121.46119 -210.673661) (xy 121.433894 -210.625026) (xy 121.413971 -210.572935)
			(xy 121.401845 -210.518498) (xy 121.397774 -210.462876) (xy 115.600226 -210.462876) (xy 115.9637 -210.82635)
			(xy 115.970539 -210.833751) (xy 115.978255 -210.852349) (xy 115.978686 -210.862418) (xy 115.978686 -213.249764)
			(xy 119.607328 -213.249764) (xy 119.611399 -213.194142) (xy 119.623525 -213.139705) (xy 119.643448 -213.087614)
			(xy 119.670744 -213.038979) (xy 119.70483 -212.994836) (xy 119.744979 -212.956127) (xy 119.790337 -212.923676)
			(xy 119.839937 -212.898175) (xy 119.892721 -212.880168) (xy 119.947564 -212.870038) (xy 120.003298 -212.868001)
			(xy 120.058735 -212.874101) (xy 120.112692 -212.888207) (xy 120.164021 -212.910019) (xy 120.211627 -212.939073)
			(xy 120.254495 -212.974748) (xy 120.291712 -213.016285) (xy 120.322485 -213.062798) (xy 120.346157 -213.113295)
			(xy 120.362225 -213.166702) (xy 120.370345 -213.221878) (xy 120.370854 -213.249764) (xy 120.370345 -213.27765)
			(xy 120.362225 -213.332826) (xy 120.346157 -213.386233) (xy 120.322485 -213.43673) (xy 120.291712 -213.483243)
			(xy 120.254495 -213.52478) (xy 120.211627 -213.560455) (xy 120.164021 -213.589509) (xy 120.112692 -213.611321)
			(xy 120.058735 -213.625427) (xy 120.003298 -213.631527) (xy 119.947564 -213.62949) (xy 119.892721 -213.61936)
			(xy 119.839937 -213.601353) (xy 119.790337 -213.575852) (xy 119.744979 -213.543401) (xy 119.70483 -213.504692)
			(xy 119.670744 -213.460549) (xy 119.643448 -213.411914) (xy 119.623525 -213.359823) (xy 119.611399 -213.305386)
			(xy 119.607328 -213.249764) (xy 115.978686 -213.249764) (xy 115.978686 -215.10498) (xy 117.322598 -215.10498)
			(xy 117.326669 -215.049358) (xy 117.338795 -214.994921) (xy 117.358718 -214.94283) (xy 117.386014 -214.894195)
			(xy 117.4201 -214.850052) (xy 117.460249 -214.811343) (xy 117.505607 -214.778892) (xy 117.555207 -214.753391)
			(xy 117.607991 -214.735384) (xy 117.662834 -214.725254) (xy 117.718568 -214.723217) (xy 117.774005 -214.729317)
			(xy 117.827962 -214.743423) (xy 117.879291 -214.765235) (xy 117.926897 -214.794289) (xy 117.969765 -214.829964)
			(xy 118.006982 -214.871501) (xy 118.037755 -214.918014) (xy 118.061427 -214.968511) (xy 118.077495 -215.021918)
			(xy 118.085615 -215.077094) (xy 118.086124 -215.10498) (xy 118.085615 -215.132866) (xy 118.077495 -215.188042)
			(xy 118.061427 -215.241449) (xy 118.03848 -215.2904) (xy 121.461782 -215.2904) (xy 121.465853 -215.234778)
			(xy 121.477979 -215.180341) (xy 121.497902 -215.12825) (xy 121.525198 -215.079615) (xy 121.559284 -215.035472)
			(xy 121.599433 -214.996763) (xy 121.644791 -214.964312) (xy 121.694391 -214.938811) (xy 121.747175 -214.920804)
			(xy 121.802018 -214.910674) (xy 121.857752 -214.908637) (xy 121.913189 -214.914737) (xy 121.967146 -214.928843)
			(xy 122.018475 -214.950655) (xy 122.066081 -214.979709) (xy 122.108949 -215.015384) (xy 122.146166 -215.056921)
			(xy 122.176939 -215.103434) (xy 122.200611 -215.153931) (xy 122.216679 -215.207338) (xy 122.224799 -215.262514)
			(xy 122.225308 -215.2904) (xy 122.224799 -215.318286) (xy 122.216679 -215.373462) (xy 122.200611 -215.426869)
			(xy 122.176939 -215.477366) (xy 122.146166 -215.523879) (xy 122.108949 -215.565416) (xy 122.066081 -215.601091)
			(xy 122.018475 -215.630145) (xy 121.967146 -215.651957) (xy 121.913189 -215.666063) (xy 121.857752 -215.672163)
			(xy 121.802018 -215.670126) (xy 121.747175 -215.659996) (xy 121.694391 -215.641989) (xy 121.644791 -215.616488)
			(xy 121.599433 -215.584037) (xy 121.559284 -215.545328) (xy 121.525198 -215.501185) (xy 121.497902 -215.45255)
			(xy 121.477979 -215.400459) (xy 121.465853 -215.346022) (xy 121.461782 -215.2904) (xy 118.03848 -215.2904)
			(xy 118.037755 -215.291946) (xy 118.006982 -215.338459) (xy 117.969765 -215.379996) (xy 117.926897 -215.415671)
			(xy 117.879291 -215.444725) (xy 117.827962 -215.466537) (xy 117.774005 -215.480643) (xy 117.718568 -215.486743)
			(xy 117.662834 -215.484706) (xy 117.607991 -215.474576) (xy 117.555207 -215.456569) (xy 117.505607 -215.431068)
			(xy 117.460249 -215.398617) (xy 117.4201 -215.359908) (xy 117.386014 -215.315765) (xy 117.358718 -215.26713)
			(xy 117.338795 -215.215039) (xy 117.326669 -215.160602) (xy 117.322598 -215.10498) (xy 115.978686 -215.10498)
			(xy 115.978686 -218.94038) (xy 117.85295 -218.94038) (xy 117.857021 -218.884758) (xy 117.869147 -218.830321)
			(xy 117.88907 -218.77823) (xy 117.916366 -218.729595) (xy 117.950452 -218.685452) (xy 117.990601 -218.646743)
			(xy 118.035959 -218.614292) (xy 118.085559 -218.588791) (xy 118.138343 -218.570784) (xy 118.193186 -218.560654)
			(xy 118.24892 -218.558617) (xy 118.304357 -218.564717) (xy 118.358314 -218.578823) (xy 118.409643 -218.600635)
			(xy 118.457249 -218.629689) (xy 118.478062 -218.64701) (xy 120.921778 -218.64701) (xy 120.925849 -218.591388)
			(xy 120.937975 -218.536951) (xy 120.957898 -218.48486) (xy 120.985194 -218.436225) (xy 121.01928 -218.392082)
			(xy 121.059429 -218.353373) (xy 121.104787 -218.320922) (xy 121.154387 -218.295421) (xy 121.207171 -218.277414)
			(xy 121.262014 -218.267284) (xy 121.317748 -218.265247) (xy 121.373185 -218.271347) (xy 121.427142 -218.285453)
			(xy 121.478471 -218.307265) (xy 121.526077 -218.336319) (xy 121.568945 -218.371994) (xy 121.606162 -218.413531)
			(xy 121.636935 -218.460044) (xy 121.660607 -218.510541) (xy 121.676675 -218.563948) (xy 121.684795 -218.619124)
			(xy 121.685304 -218.64701) (xy 121.684795 -218.674896) (xy 121.676675 -218.730072) (xy 121.660607 -218.783479)
			(xy 121.636935 -218.833976) (xy 121.606162 -218.880489) (xy 121.568945 -218.922026) (xy 121.526077 -218.957701)
			(xy 121.478471 -218.986755) (xy 121.427142 -219.008567) (xy 121.373185 -219.022673) (xy 121.317748 -219.028773)
			(xy 121.262014 -219.026736) (xy 121.207171 -219.016606) (xy 121.154387 -218.998599) (xy 121.104787 -218.973098)
			(xy 121.059429 -218.940647) (xy 121.01928 -218.901938) (xy 120.985194 -218.857795) (xy 120.957898 -218.80916)
			(xy 120.937975 -218.757069) (xy 120.925849 -218.702632) (xy 120.921778 -218.64701) (xy 118.478062 -218.64701)
			(xy 118.500117 -218.665364) (xy 118.537334 -218.706901) (xy 118.568107 -218.753414) (xy 118.591779 -218.803911)
			(xy 118.607847 -218.857318) (xy 118.615967 -218.912494) (xy 118.616476 -218.94038) (xy 118.615967 -218.968266)
			(xy 118.607847 -219.023442) (xy 118.591779 -219.076849) (xy 118.568107 -219.127346) (xy 118.537334 -219.173859)
			(xy 118.500117 -219.215396) (xy 118.457249 -219.251071) (xy 118.409643 -219.280125) (xy 118.358314 -219.301937)
			(xy 118.304357 -219.316043) (xy 118.24892 -219.322143) (xy 118.193186 -219.320106) (xy 118.138343 -219.309976)
			(xy 118.085559 -219.291969) (xy 118.035959 -219.266468) (xy 117.990601 -219.234017) (xy 117.950452 -219.195308)
			(xy 117.916366 -219.151165) (xy 117.88907 -219.10253) (xy 117.869147 -219.050439) (xy 117.857021 -218.996002)
			(xy 117.85295 -218.94038) (xy 115.978686 -218.94038) (xy 115.978686 -221.064836) (xy 116.584474 -221.064836)
			(xy 116.588545 -221.009214) (xy 116.600671 -220.954777) (xy 116.620594 -220.902686) (xy 116.64789 -220.854051)
			(xy 116.681976 -220.809908) (xy 116.722125 -220.771199) (xy 116.767483 -220.738748) (xy 116.817083 -220.713247)
			(xy 116.869867 -220.69524) (xy 116.92471 -220.68511) (xy 116.980444 -220.683073) (xy 117.035881 -220.689173)
			(xy 117.089838 -220.703279) (xy 117.141167 -220.725091) (xy 117.188773 -220.754145) (xy 117.231641 -220.78982)
			(xy 117.268858 -220.831357) (xy 117.299631 -220.87787) (xy 117.323303 -220.928367) (xy 117.339371 -220.981774)
			(xy 117.347491 -221.03695) (xy 117.348 -221.064836) (xy 117.347491 -221.092722) (xy 117.339371 -221.147898)
			(xy 117.323303 -221.201305) (xy 117.299631 -221.251802) (xy 117.268858 -221.298315) (xy 117.231641 -221.339852)
			(xy 117.188773 -221.375527) (xy 117.141167 -221.404581) (xy 117.089838 -221.426393) (xy 117.035881 -221.440499)
			(xy 116.980444 -221.446599) (xy 116.92471 -221.444562) (xy 116.869867 -221.434432) (xy 116.817083 -221.416425)
			(xy 116.767483 -221.390924) (xy 116.722125 -221.358473) (xy 116.681976 -221.319764) (xy 116.64789 -221.275621)
			(xy 116.620594 -221.226986) (xy 116.600671 -221.174895) (xy 116.588545 -221.120458) (xy 116.584474 -221.064836)
			(xy 115.978686 -221.064836) (xy 115.978686 -224.46107) (xy 119.436386 -224.46107) (xy 119.440457 -224.405448)
			(xy 119.452583 -224.351011) (xy 119.472506 -224.29892) (xy 119.499802 -224.250285) (xy 119.533888 -224.206142)
			(xy 119.574037 -224.167433) (xy 119.619395 -224.134982) (xy 119.668995 -224.109481) (xy 119.721779 -224.091474)
			(xy 119.776622 -224.081344) (xy 119.832356 -224.079307) (xy 119.887793 -224.085407) (xy 119.94175 -224.099513)
			(xy 119.993079 -224.121325) (xy 120.040685 -224.150379) (xy 120.083553 -224.186054) (xy 120.12077 -224.227591)
			(xy 120.151543 -224.274104) (xy 120.175215 -224.324601) (xy 120.191283 -224.378008) (xy 120.199403 -224.433184)
			(xy 120.199912 -224.46107) (xy 120.199403 -224.488956) (xy 120.191283 -224.544132) (xy 120.175215 -224.597539)
			(xy 120.151543 -224.648036) (xy 120.12077 -224.694549) (xy 120.083553 -224.736086) (xy 120.040685 -224.771761)
			(xy 119.993079 -224.800815) (xy 119.94175 -224.822627) (xy 119.887793 -224.836733) (xy 119.832356 -224.842833)
			(xy 119.776622 -224.840796) (xy 119.721779 -224.830666) (xy 119.668995 -224.812659) (xy 119.619395 -224.787158)
			(xy 119.574037 -224.754707) (xy 119.533888 -224.715998) (xy 119.499802 -224.671855) (xy 119.472506 -224.62322)
			(xy 119.452583 -224.571129) (xy 119.440457 -224.516692) (xy 119.436386 -224.46107) (xy 115.978686 -224.46107)
			(xy 115.978686 -234.080558) (xy 119.279922 -234.080558) (xy 119.283993 -234.024936) (xy 119.296119 -233.970499)
			(xy 119.316042 -233.918408) (xy 119.343338 -233.869773) (xy 119.377424 -233.82563) (xy 119.417573 -233.786921)
			(xy 119.462931 -233.75447) (xy 119.512531 -233.728969) (xy 119.565315 -233.710962) (xy 119.620158 -233.700832)
			(xy 119.675892 -233.698795) (xy 119.731329 -233.704895) (xy 119.785286 -233.719001) (xy 119.836615 -233.740813)
			(xy 119.884221 -233.769867) (xy 119.927089 -233.805542) (xy 119.964306 -233.847079) (xy 119.995079 -233.893592)
			(xy 120.018751 -233.944089) (xy 120.034819 -233.997496) (xy 120.042939 -234.052672) (xy 120.043448 -234.080558)
			(xy 120.042939 -234.108444) (xy 120.034819 -234.16362) (xy 120.018751 -234.217027) (xy 119.995079 -234.267524)
			(xy 119.964306 -234.314037) (xy 119.927089 -234.355574) (xy 119.884221 -234.391249) (xy 119.836615 -234.420303)
			(xy 119.785286 -234.442115) (xy 119.731329 -234.456221) (xy 119.675892 -234.462321) (xy 119.620158 -234.460284)
			(xy 119.565315 -234.450154) (xy 119.512531 -234.432147) (xy 119.462931 -234.406646) (xy 119.417573 -234.374195)
			(xy 119.377424 -234.335486) (xy 119.343338 -234.291343) (xy 119.316042 -234.242708) (xy 119.296119 -234.190617)
			(xy 119.283993 -234.13618) (xy 119.279922 -234.080558) (xy 115.978686 -234.080558) (xy 115.978686 -235.544614)
			(xy 120.151142 -235.544614) (xy 120.155213 -235.488992) (xy 120.167339 -235.434555) (xy 120.187262 -235.382464)
			(xy 120.214558 -235.333829) (xy 120.248644 -235.289686) (xy 120.288793 -235.250977) (xy 120.334151 -235.218526)
			(xy 120.383751 -235.193025) (xy 120.436535 -235.175018) (xy 120.491378 -235.164888) (xy 120.547112 -235.162851)
			(xy 120.602549 -235.168951) (xy 120.656506 -235.183057) (xy 120.707835 -235.204869) (xy 120.755441 -235.233923)
			(xy 120.798309 -235.269598) (xy 120.835526 -235.311135) (xy 120.866299 -235.357648) (xy 120.889971 -235.408145)
			(xy 120.906039 -235.461552) (xy 120.914159 -235.516728) (xy 120.914668 -235.544614) (xy 120.914159 -235.5725)
			(xy 120.906039 -235.627676) (xy 120.889971 -235.681083) (xy 120.866299 -235.73158) (xy 120.835526 -235.778093)
			(xy 120.798309 -235.81963) (xy 120.755441 -235.855305) (xy 120.707835 -235.884359) (xy 120.656506 -235.906171)
			(xy 120.602549 -235.920277) (xy 120.547112 -235.926377) (xy 120.491378 -235.92434) (xy 120.436535 -235.91421)
			(xy 120.383751 -235.896203) (xy 120.334151 -235.870702) (xy 120.288793 -235.838251) (xy 120.248644 -235.799542)
			(xy 120.214558 -235.755399) (xy 120.187262 -235.706764) (xy 120.167339 -235.654673) (xy 120.155213 -235.600236)
			(xy 120.151142 -235.544614) (xy 115.978686 -235.544614) (xy 115.978686 -236.27969) (xy 119.269254 -236.27969)
			(xy 119.273325 -236.224068) (xy 119.285451 -236.169631) (xy 119.305374 -236.11754) (xy 119.33267 -236.068905)
			(xy 119.366756 -236.024762) (xy 119.406905 -235.986053) (xy 119.452263 -235.953602) (xy 119.501863 -235.928101)
			(xy 119.554647 -235.910094) (xy 119.60949 -235.899964) (xy 119.665224 -235.897927) (xy 119.720661 -235.904027)
			(xy 119.774618 -235.918133) (xy 119.825947 -235.939945) (xy 119.873553 -235.968999) (xy 119.916421 -236.004674)
			(xy 119.953638 -236.046211) (xy 119.984411 -236.092724) (xy 120.008083 -236.143221) (xy 120.024151 -236.196628)
			(xy 120.032271 -236.251804) (xy 120.03278 -236.27969) (xy 120.032271 -236.307576) (xy 120.024151 -236.362752)
			(xy 120.008083 -236.416159) (xy 119.984411 -236.466656) (xy 119.953638 -236.513169) (xy 119.916421 -236.554706)
			(xy 119.873553 -236.590381) (xy 119.825947 -236.619435) (xy 119.774618 -236.641247) (xy 119.720661 -236.655353)
			(xy 119.665224 -236.661453) (xy 119.60949 -236.659416) (xy 119.554647 -236.649286) (xy 119.501863 -236.631279)
			(xy 119.452263 -236.605778) (xy 119.406905 -236.573327) (xy 119.366756 -236.534618) (xy 119.33267 -236.490475)
			(xy 119.305374 -236.44184) (xy 119.285451 -236.389749) (xy 119.273325 -236.335312) (xy 119.269254 -236.27969)
			(xy 115.978686 -236.27969) (xy 115.978686 -238.057944) (xy 119.474486 -238.057944) (xy 119.478557 -238.002322)
			(xy 119.490683 -237.947885) (xy 119.510606 -237.895794) (xy 119.537902 -237.847159) (xy 119.571988 -237.803016)
			(xy 119.612137 -237.764307) (xy 119.657495 -237.731856) (xy 119.707095 -237.706355) (xy 119.759879 -237.688348)
			(xy 119.814722 -237.678218) (xy 119.870456 -237.676181) (xy 119.925893 -237.682281) (xy 119.97985 -237.696387)
			(xy 120.031179 -237.718199) (xy 120.078785 -237.747253) (xy 120.121653 -237.782928) (xy 120.15887 -237.824465)
			(xy 120.189643 -237.870978) (xy 120.213315 -237.921475) (xy 120.229383 -237.974882) (xy 120.237503 -238.030058)
			(xy 120.238012 -238.057944) (xy 120.237503 -238.08583) (xy 120.229383 -238.141006) (xy 120.213315 -238.194413)
			(xy 120.189643 -238.24491) (xy 120.15887 -238.291423) (xy 120.121653 -238.33296) (xy 120.078785 -238.368635)
			(xy 120.031179 -238.397689) (xy 119.97985 -238.419501) (xy 119.925893 -238.433607) (xy 119.870456 -238.439707)
			(xy 119.814722 -238.43767) (xy 119.759879 -238.42754) (xy 119.707095 -238.409533) (xy 119.657495 -238.384032)
			(xy 119.612137 -238.351581) (xy 119.571988 -238.312872) (xy 119.537902 -238.268729) (xy 119.510606 -238.220094)
			(xy 119.490683 -238.168003) (xy 119.478557 -238.113566) (xy 119.474486 -238.057944) (xy 115.978686 -238.057944)
			(xy 115.978686 -238.447834) (xy 124.488446 -238.447834) (xy 124.492517 -238.392212) (xy 124.504643 -238.337775)
			(xy 124.524566 -238.285684) (xy 124.551862 -238.237049) (xy 124.585948 -238.192906) (xy 124.626097 -238.154197)
			(xy 124.671455 -238.121746) (xy 124.721055 -238.096245) (xy 124.773839 -238.078238) (xy 124.828682 -238.068108)
			(xy 124.884416 -238.066071) (xy 124.939853 -238.072171) (xy 124.99381 -238.086277) (xy 125.045139 -238.108089)
			(xy 125.092745 -238.137143) (xy 125.135613 -238.172818) (xy 125.17283 -238.214355) (xy 125.203603 -238.260868)
			(xy 125.227275 -238.311365) (xy 125.243343 -238.364772) (xy 125.251463 -238.419948) (xy 125.251972 -238.447834)
			(xy 125.251463 -238.47572) (xy 125.243343 -238.530896) (xy 125.227275 -238.584303) (xy 125.203603 -238.6348)
			(xy 125.17283 -238.681313) (xy 125.135613 -238.72285) (xy 125.092745 -238.758525) (xy 125.045139 -238.787579)
			(xy 124.99381 -238.809391) (xy 124.939853 -238.823497) (xy 124.884416 -238.829597) (xy 124.828682 -238.82756)
			(xy 124.773839 -238.81743) (xy 124.721055 -238.799423) (xy 124.671455 -238.773922) (xy 124.626097 -238.741471)
			(xy 124.585948 -238.702762) (xy 124.551862 -238.658619) (xy 124.524566 -238.609984) (xy 124.504643 -238.557893)
			(xy 124.492517 -238.503456) (xy 124.488446 -238.447834) (xy 115.978686 -238.447834) (xy 115.978686 -239.067848)
			(xy 125.173992 -239.067848) (xy 125.178063 -239.012226) (xy 125.190189 -238.957789) (xy 125.210112 -238.905698)
			(xy 125.237408 -238.857063) (xy 125.271494 -238.81292) (xy 125.311643 -238.774211) (xy 125.357001 -238.74176)
			(xy 125.406601 -238.716259) (xy 125.459385 -238.698252) (xy 125.514228 -238.688122) (xy 125.569962 -238.686085)
			(xy 125.625399 -238.692185) (xy 125.679356 -238.706291) (xy 125.730685 -238.728103) (xy 125.778291 -238.757157)
			(xy 125.821159 -238.792832) (xy 125.858376 -238.834369) (xy 125.889149 -238.880882) (xy 125.912821 -238.931379)
			(xy 125.928889 -238.984786) (xy 125.937009 -239.039962) (xy 125.937518 -239.067848) (xy 125.937009 -239.095734)
			(xy 125.928889 -239.15091) (xy 125.912821 -239.204317) (xy 125.889149 -239.254814) (xy 125.858376 -239.301327)
			(xy 125.821159 -239.342864) (xy 125.778291 -239.378539) (xy 125.730685 -239.407593) (xy 125.679356 -239.429405)
			(xy 125.625399 -239.443511) (xy 125.569962 -239.449611) (xy 125.514228 -239.447574) (xy 125.459385 -239.437444)
			(xy 125.406601 -239.419437) (xy 125.357001 -239.393936) (xy 125.311643 -239.361485) (xy 125.271494 -239.322776)
			(xy 125.237408 -239.278633) (xy 125.210112 -239.229998) (xy 125.190189 -239.177907) (xy 125.178063 -239.12347)
			(xy 125.173992 -239.067848) (xy 115.978686 -239.067848) (xy 115.978686 -241.973951) (xy 120.012962 -241.973951)
			(xy 120.012962 -241.919449) (xy 120.020718 -241.865502) (xy 120.036072 -241.813207) (xy 120.058712 -241.76363)
			(xy 120.088176 -241.71778) (xy 120.123866 -241.676588) (xy 120.165054 -241.640895) (xy 120.210902 -241.611427)
			(xy 120.260477 -241.588783) (xy 120.312771 -241.573425) (xy 120.366717 -241.565664) (xy 120.393968 -241.565176)
			(xy 120.422514 -241.56573) (xy 120.478967 -241.574244) (xy 120.533522 -241.59107) (xy 120.584963 -241.615835)
			(xy 120.608852 -241.63147) (xy 120.616726 -241.636804) (xy 120.634252 -241.641122) (xy 120.719088 -241.630962)
			(xy 120.73509 -241.62258) (xy 120.74144 -241.615468) (xy 120.759642 -241.596066) (xy 120.800453 -241.561942)
			(xy 120.845605 -241.533814) (xy 120.894224 -241.512224) (xy 120.94537 -241.497593) (xy 120.998051 -241.490202)
			(xy 121.02465 -241.489738) (xy 121.050587 -241.490183) (xy 121.101982 -241.497206) (xy 121.151952 -241.511129)
			(xy 121.199574 -241.531696) (xy 121.24397 -241.558526) (xy 121.28432 -241.591126) (xy 121.31988 -241.628893)
			(xy 121.335292 -241.649758) (xy 121.342658 -241.660172) (xy 121.364756 -241.671348) (xy 121.47423 -241.669062)
			(xy 121.49582 -241.657124) (xy 121.502932 -241.646456) (xy 121.518144 -241.624182) (xy 121.553818 -241.583727)
			(xy 121.594835 -241.548701) (xy 121.640378 -241.519803) (xy 121.689538 -241.497609) (xy 121.741334 -241.482563)
			(xy 121.794733 -241.474964) (xy 121.821702 -241.474498) (xy 121.848954 -241.474972) (xy 121.902902 -241.482729)
			(xy 121.955197 -241.498084) (xy 122.004775 -241.520726) (xy 122.050626 -241.550193) (xy 122.091817 -241.585885)
			(xy 122.127508 -241.627076) (xy 122.156975 -241.672927) (xy 122.179616 -241.722505) (xy 122.194972 -241.7748)
			(xy 122.202728 -241.828748) (xy 122.202728 -241.883252) (xy 122.194972 -241.9372) (xy 122.179616 -241.989495)
			(xy 122.156975 -242.039073) (xy 122.127508 -242.084924) (xy 122.091817 -242.126115) (xy 122.050626 -242.161807)
			(xy 122.004775 -242.191274) (xy 121.955197 -242.213916) (xy 121.902902 -242.229271) (xy 121.848954 -242.237028)
			(xy 121.821702 -242.237514) (xy 121.795765 -242.237083) (xy 121.74437 -242.230055) (xy 121.6944 -242.216127)
			(xy 121.646779 -242.195558) (xy 121.602384 -242.168726) (xy 121.562034 -242.136126) (xy 121.526473 -242.098359)
			(xy 121.51106 -242.077494) (xy 121.503694 -242.06708) (xy 121.481596 -242.055904) (xy 121.372122 -242.05819)
			(xy 121.350532 -242.070128) (xy 121.34342 -242.080796) (xy 121.328223 -242.103081) (xy 121.292549 -242.143539)
			(xy 121.25153 -242.178566) (xy 121.205984 -242.207463) (xy 121.156821 -242.229655) (xy 121.105022 -242.244697)
			(xy 121.05162 -242.252291) (xy 121.02465 -242.252754) (xy 120.996104 -242.252203) (xy 120.93965 -242.243691)
			(xy 120.885095 -242.226863) (xy 120.833654 -242.202097) (xy 120.809766 -242.18646) (xy 120.801892 -242.181126)
			(xy 120.784366 -242.176808) (xy 120.69953 -242.186968) (xy 120.683528 -242.19535) (xy 120.677178 -242.202462)
			(xy 120.658974 -242.221861) (xy 120.618163 -242.255984) (xy 120.573011 -242.284113) (xy 120.524392 -242.305702)
			(xy 120.473247 -242.320335) (xy 120.420566 -242.327727) (xy 120.393968 -242.328192) (xy 120.366717 -242.327736)
			(xy 120.312771 -242.319975) (xy 120.260477 -242.304617) (xy 120.210902 -242.281973) (xy 120.165054 -242.252505)
			(xy 120.123866 -242.216812) (xy 120.088176 -242.17562) (xy 120.058712 -242.12977) (xy 120.036072 -242.080193)
			(xy 120.020718 -242.027898) (xy 120.012962 -241.973951) (xy 115.978686 -241.973951) (xy 115.978686 -245.662704)
			(xy 115.979109 -245.672774) (xy 115.986823 -245.691379) (xy 115.993672 -245.698772) (xy 116.189252 -245.894352)
			(xy 116.196651 -245.901195) (xy 116.21525 -245.908918) (xy 116.22532 -245.909338) (xy 123.556268 -245.909338)
			(xy 123.566331 -245.908901) (xy 123.584912 -245.901162) (xy 123.592336 -245.894352) (xy 126.797562 -242.689126)
			(xy 126.804401 -242.681725) (xy 126.812114 -242.663127) (xy 126.812548 -242.653058) (xy 126.812548 -231.024176)
			(xy 126.812119 -231.014109) (xy 126.804393 -230.995516) (xy 126.797562 -230.988108) (xy 122.5296 -226.719892)
			(xy 122.50748 -226.697143) (xy 122.467918 -226.647532) (xy 122.434159 -226.593804) (xy 122.406628 -226.536634)
			(xy 122.385671 -226.476741) (xy 122.371552 -226.414878) (xy 122.364448 -226.351823) (xy 122.363992 -226.320096)
			(xy 122.363992 -211.303362) (xy 122.364439 -211.271635) (xy 122.371547 -211.208581) (xy 122.385671 -211.14672)
			(xy 122.406631 -211.086829) (xy 122.434166 -211.029661) (xy 122.467928 -210.975935) (xy 122.507492 -210.926327)
			(xy 122.5296 -210.903566) (xy 122.743214 -210.689698) (xy 122.750069 -210.682303) (xy 122.757817 -210.663705)
			(xy 122.7582 -210.65363) (xy 122.7582 -209.825082) (xy 122.758627 -209.815013) (xy 122.766346 -209.796414)
			(xy 122.773186 -209.789014) (xy 125.459236 -207.102964) (xy 125.466084 -207.095567) (xy 125.473815 -207.076968)
			(xy 125.474222 -207.066896) (xy 125.474222 -205.640178) (xy 125.474312 -205.635158) (xy 125.476227 -205.625305)
			(xy 125.478032 -205.62062) (xy 125.485398 -205.603348) (xy 125.487201 -205.598662) (xy 125.489128 -205.58881)
			(xy 125.489208 -205.58379) (xy 125.489208 -196.918326) (xy 125.488872 -196.909339) (xy 125.482686 -196.892466)
			(xy 125.471035 -196.878783) (xy 125.455365 -196.869985) (xy 125.446536 -196.868288) (xy 125.347984 -196.852032)
			(xy 125.341634 -196.851524) (xy 125.330631 -196.851617) (xy 125.310304 -196.859981) (xy 125.29532 -196.876062)
			(xy 125.291342 -196.886322) (xy 125.250257 -197.008164) (xy 125.161264 -197.249436) (xy 125.064563 -197.487724)
			(xy 124.960254 -197.722781) (xy 124.848445 -197.954365) (xy 124.729251 -198.182235) (xy 124.602796 -198.406158)
			(xy 124.469211 -198.625901) (xy 124.328632 -198.841238) (xy 124.181206 -199.051945) (xy 124.027084 -199.257806)
			(xy 123.866427 -199.458608) (xy 123.699399 -199.654143) (xy 123.526174 -199.844209) (xy 123.34693 -200.028611)
			(xy 123.161853 -200.207156) (xy 122.971133 -200.379662) (xy 122.774968 -200.54595) (xy 122.573561 -200.705847)
			(xy 122.367119 -200.85919) (xy 122.155855 -201.005819) (xy 121.939989 -201.145582) (xy 121.719743 -201.278337)
			(xy 121.495344 -201.403945) (xy 121.267024 -201.522276) (xy 121.03502 -201.633209) (xy 120.79957 -201.736629)
			(xy 120.560919 -201.832429) (xy 120.319312 -201.92051) (xy 120.074999 -202.000781) (xy 119.951754 -202.037442)
			(xy 119.945404 -202.03922) (xy 119.934736 -202.04557) (xy 119.783098 -202.197208) (xy 119.776253 -202.204607)
			(xy 119.768522 -202.223205) (xy 119.768112 -202.233276) (xy 119.768112 -202.579732) (xy 123.927106 -202.579732)
			(xy 123.931177 -202.52411) (xy 123.943303 -202.469673) (xy 123.963226 -202.417582) (xy 123.990522 -202.368947)
			(xy 124.024608 -202.324804) (xy 124.064757 -202.286095) (xy 124.110115 -202.253644) (xy 124.159715 -202.228143)
			(xy 124.212499 -202.210136) (xy 124.267342 -202.200006) (xy 124.323076 -202.197969) (xy 124.378513 -202.204069)
			(xy 124.43247 -202.218175) (xy 124.483799 -202.239987) (xy 124.531405 -202.269041) (xy 124.574273 -202.304716)
			(xy 124.61149 -202.346253) (xy 124.642263 -202.392766) (xy 124.665935 -202.443263) (xy 124.682003 -202.49667)
			(xy 124.690123 -202.551846) (xy 124.690632 -202.579732) (xy 124.690123 -202.607618) (xy 124.682003 -202.662794)
			(xy 124.665935 -202.716201) (xy 124.642263 -202.766698) (xy 124.61149 -202.813211) (xy 124.574273 -202.854748)
			(xy 124.531405 -202.890423) (xy 124.483799 -202.919477) (xy 124.43247 -202.941289) (xy 124.378513 -202.955395)
			(xy 124.323076 -202.961495) (xy 124.267342 -202.959458) (xy 124.212499 -202.949328) (xy 124.159715 -202.931321)
			(xy 124.110115 -202.90582) (xy 124.064757 -202.873369) (xy 124.024608 -202.83466) (xy 123.990522 -202.790517)
			(xy 123.963226 -202.741882) (xy 123.943303 -202.689791) (xy 123.931177 -202.635354) (xy 123.927106 -202.579732)
			(xy 119.768112 -202.579732) (xy 119.768112 -202.974448) (xy 119.768874 -202.978512) (xy 119.772561 -203.00196)
			(xy 119.776501 -203.049265) (xy 119.776748 -203.073) (xy 119.776224 -203.107722) (xy 119.767853 -203.17666)
			(xy 119.751234 -203.244086) (xy 119.726609 -203.309017) (xy 119.694337 -203.370507) (xy 119.654888 -203.427658)
			(xy 119.608838 -203.479638) (xy 119.556858 -203.525688) (xy 119.499707 -203.565137) (xy 119.438217 -203.597409)
			(xy 119.373286 -203.622034) (xy 119.30586 -203.638653) (xy 119.236922 -203.647024) (xy 119.2022 -203.647548)
			(xy 111.247936 -203.647548) (xy 111.237906 -203.647989) (xy 111.219338 -203.655572) (xy 111.211868 -203.66228)
			(xy 110.277402 -204.596746) (xy 110.254295 -204.619228) (xy 110.203903 -204.659442) (xy 110.149326 -204.693762)
			(xy 110.091249 -204.721757) (xy 110.030404 -204.743074) (xy 109.967555 -204.757446) (xy 109.903492 -204.764692)
			(xy 109.871256 -204.765148) (xy 98.840544 -204.765148) (xy 98.808308 -204.764682) (xy 98.744245 -204.757437)
			(xy 98.681396 -204.743068) (xy 98.620549 -204.721753) (xy 98.562471 -204.693763) (xy 98.50789 -204.659448)
			(xy 98.457494 -204.619239) (xy 98.434398 -204.596746) (xy 97.933764 -204.096366) (xy 97.926049 -204.089301)
			(xy 97.906643 -204.081549) (xy 97.885756 -204.082173) (xy 97.876106 -204.086206) (xy 97.775014 -204.134212)
			(xy 97.759266 -204.162152) (xy 97.761044 -204.178154) (xy 97.762822 -204.216) (xy 97.762359 -204.243254)
			(xy 97.754602 -204.297207) (xy 97.739245 -204.349508) (xy 97.716601 -204.39909) (xy 97.687132 -204.444945)
			(xy 97.651436 -204.486139) (xy 97.610241 -204.521834) (xy 97.564386 -204.551303) (xy 97.514803 -204.573947)
			(xy 97.462503 -204.589303) (xy 97.408549 -204.597059) (xy 97.354041 -204.597059) (xy 97.300088 -204.589301)
			(xy 97.247788 -204.573943) (xy 97.198206 -204.551299) (xy 97.152351 -204.521829) (xy 97.111157 -204.486133)
			(xy 97.075463 -204.444938) (xy 97.045994 -204.399082) (xy 97.023352 -204.349499) (xy 97.007996 -204.297198)
			(xy 97.00024 -204.243245) (xy 97.000242 -204.188737) (xy 97.008 -204.134783) (xy 97.023358 -204.082484)
			(xy 97.046003 -204.032902) (xy 97.075474 -203.987047) (xy 97.11117 -203.945854) (xy 97.152366 -203.91016)
			(xy 97.198222 -203.880692) (xy 97.247805 -203.85805) (xy 97.300106 -203.842695) (xy 97.35406 -203.83494)
			(xy 97.381314 -203.834492) (xy 97.41916 -203.83627) (xy 97.435162 -203.838048) (xy 97.463102 -203.8223)
			(xy 97.511108 -203.721208) (xy 97.515085 -203.711542) (xy 97.515709 -203.690672) (xy 97.507994 -203.671269)
			(xy 97.500948 -203.66355) (xy 95.950532 -202.113134) (xy 95.943185 -202.10633) (xy 95.924722 -202.098617)
			(xy 95.914718 -202.098148) (xy 94.979236 -202.098148) (xy 94.969172 -202.097712) (xy 94.95059 -202.089975)
			(xy 94.943168 -202.083162) (xy 94.857062 -201.997056) (xy 94.842076 -201.98969) (xy 94.83344 -201.988674)
			(xy 94.8017 -201.984267) (xy 94.739679 -201.96815) (xy 94.680332 -201.943978) (xy 94.6247 -201.912173)
			(xy 94.57376 -201.873295) (xy 94.550738 -201.851006) (xy 94.003114 -201.303382) (xy 93.981097 -201.280664)
			(xy 93.942586 -201.23047) (xy 93.910959 -201.175677) (xy 93.886758 -201.117224) (xy 93.870396 -201.056111)
			(xy 93.862154 -200.993385) (xy 93.861636 -200.961752) (xy 93.862111 -200.931144) (xy 93.869851 -200.87042)
			(xy 93.885201 -200.81116) (xy 93.907915 -200.754314) (xy 93.937628 -200.700793) (xy 93.973866 -200.651456)
			(xy 94.016046 -200.607091) (xy 94.063493 -200.568412) (xy 94.115447 -200.536036) (xy 94.143068 -200.52284)
			(xy 94.156784 -200.51649) (xy 94.172786 -200.491598) (xy 94.172786 -199.385936) (xy 94.172351 -199.375871)
			(xy 94.164619 -199.357285) (xy 94.1578 -199.349868) (xy 93.870018 -199.061832) (xy 93.849779 -199.040819)
			(xy 93.815447 -198.993653) (xy 93.788916 -198.941697) (xy 93.770838 -198.88623) (xy 93.761659 -198.828619)
			(xy 93.761052 -198.79945) (xy 93.761052 -197.964552) (xy 93.760568 -197.954589) (xy 93.752979 -197.936165)
			(xy 93.74632 -197.928738) (xy 92.725748 -196.908166) (xy 92.721176 -196.905118) (xy 92.698324 -196.890037)
			(xy 92.656789 -196.854363) (xy 92.620785 -196.813114) (xy 92.591054 -196.767138) (xy 92.568207 -196.717381)
			(xy 92.552714 -196.664867) (xy 92.544894 -196.610676) (xy 92.544392 -196.5833) (xy 92.544392 -196.583046)
			(xy 92.544884 -196.555371) (xy 92.552887 -196.500602) (xy 92.56873 -196.447567) (xy 92.579952 -196.422264)
			(xy 92.584778 -196.412104) (xy 92.584778 -196.172836) (xy 92.585212 -196.16277) (xy 92.59294 -196.144181)
			(xy 92.599764 -196.136768) (xy 93.794834 -194.941698) (xy 93.801558 -194.93437) (xy 93.809286 -194.916067)
			(xy 93.80982 -194.906138) (xy 93.810074 -194.875658) (xy 93.809772 -194.866423) (xy 93.803391 -194.849098)
			(xy 93.797628 -194.841876) (xy 93.78004 -194.820948) (xy 93.750409 -194.775009) (xy 93.727636 -194.725311)
			(xy 93.71219 -194.672872) (xy 93.704384 -194.618765) (xy 93.703902 -194.591432) (xy 93.704438 -194.562084)
			(xy 93.713424 -194.504079) (xy 93.731188 -194.448134) (xy 93.757311 -194.395571) (xy 93.791177 -194.347629)
			(xy 93.831987 -194.30544) (xy 93.878776 -194.27) (xy 93.930443 -194.242144) (xy 93.957902 -194.231768)
			(xy 93.968824 -194.227958) (xy 94.276418 -193.920618) (xy 94.293512 -193.903999) (xy 94.331226 -193.87483)
			(xy 94.351602 -193.862452) (xy 94.359041 -193.857695) (xy 94.370366 -193.844165) (xy 94.376401 -193.827586)
			(xy 94.376748 -193.818764) (xy 94.376748 -190.86068) (xy 94.376067 -190.848041) (xy 94.364061 -190.825796)
			(xy 94.353888 -190.818262) (xy 94.331698 -190.803045) (xy 94.291423 -190.767369) (xy 94.25656 -190.726388)
			(xy 94.227802 -190.680915) (xy 94.205719 -190.631852) (xy 94.190748 -190.580172) (xy 94.183188 -190.526902)
			(xy 94.183188 -190.473098) (xy 94.190748 -190.419828) (xy 94.205719 -190.368148) (xy 94.227802 -190.319085)
			(xy 94.25656 -190.273612) (xy 94.291423 -190.232631) (xy 94.331698 -190.196955) (xy 94.353888 -190.181738)
			(xy 94.364071 -190.174218) (xy 94.37606 -190.15196) (xy 94.376748 -190.13932) (xy 94.376748 -189.902592)
			(xy 94.376105 -189.890947) (xy 94.365786 -189.870057) (xy 94.356936 -189.86246) (xy 94.335922 -189.845727)
			(xy 94.298353 -189.807334) (xy 94.266544 -189.764049) (xy 94.241126 -189.716727) (xy 94.222602 -189.666305)
			(xy 94.211339 -189.613783) (xy 94.20756 -189.5602) (xy 94.211339 -189.506617) (xy 94.222602 -189.454095)
			(xy 94.241126 -189.403673) (xy 94.266544 -189.356351) (xy 94.298353 -189.313066) (xy 94.335922 -189.274673)
			(xy 94.356936 -189.25794) (xy 94.365836 -189.250385) (xy 94.376146 -189.229469) (xy 94.376748 -189.217808)
			(xy 94.376748 -188.508894) (xy 94.377174 -188.498825) (xy 94.384895 -188.480227) (xy 94.391734 -188.472826)
			(xy 95.448374 -187.416186) (xy 95.455772 -187.409342) (xy 95.474372 -187.401621) (xy 95.484442 -187.4012)
			(xy 113.038636 -187.4012) (xy 113.048703 -187.40077) (xy 113.067298 -187.393047) (xy 113.074704 -187.386214)
			(xy 113.445036 -187.015882) (xy 113.451886 -187.008485) (xy 113.459624 -186.989887) (xy 113.460022 -186.979814)
			(xy 113.460022 -185.762392) (xy 113.459598 -185.752322) (xy 113.451884 -185.733717) (xy 113.445036 -185.726324)
			(xy 112.92205 -185.203338) (xy 112.914651 -185.196495) (xy 112.896052 -185.188773) (xy 112.885982 -185.188352)
			(xy 108.298488 -185.188352) (xy 108.286412 -185.189011) (xy 108.264907 -185.200003) (xy 108.25734 -185.209434)
			(xy 108.240685 -185.231617) (xy 108.202015 -185.271384) (xy 108.157994 -185.305132) (xy 108.109548 -185.332148)
			(xy 108.057701 -185.351863) (xy 108.003545 -185.363861) (xy 107.948222 -185.367888) (xy 107.892899 -185.363861)
			(xy 107.838743 -185.351863) (xy 107.786896 -185.332148) (xy 107.73845 -185.305132) (xy 107.694429 -185.271384)
			(xy 107.655759 -185.231617) (xy 107.639104 -185.209434) (xy 107.631495 -185.200045) (xy 107.610021 -185.189031)
			(xy 107.597956 -185.188352) (xy 101.548184 -185.188352) (xy 101.538116 -185.187925) (xy 101.519521 -185.180201)
			(xy 101.512116 -185.173366) (xy 100.489004 -184.150254) (xy 100.482164 -184.142853) (xy 100.474446 -184.124255)
			(xy 100.474018 -184.114186) (xy 100.474018 -166.776654) (xy 100.473587 -166.766587) (xy 100.465863 -166.747993)
			(xy 100.459032 -166.740586) (xy 94.320106 -160.60166) (xy 94.312994 -160.594294) (xy 94.294198 -160.586674)
			(xy 71.980298 -160.586674) (xy 71.970487 -160.58712) (xy 71.952293 -160.594471) (xy 71.938177 -160.608102)
			(xy 71.933816 -160.6169) (xy 71.914899 -160.658437) (xy 71.870954 -160.73844) (xy 71.820339 -160.814399)
			(xy 71.763424 -160.885759) (xy 71.700624 -160.952) (xy 71.632398 -161.012637) (xy 71.559245 -161.067228)
			(xy 71.481697 -161.115374) (xy 71.400323 -161.156724) (xy 71.315715 -161.190975) (xy 71.228492 -161.217878)
			(xy 71.13929 -161.237236) (xy 71.048761 -161.248908) (xy 70.957567 -161.252808) (xy 70.866373 -161.248908)
			(xy 70.775844 -161.237236) (xy 70.686642 -161.217878) (xy 70.599419 -161.190975) (xy 70.514811 -161.156724)
			(xy 70.433437 -161.115374) (xy 70.355889 -161.067228) (xy 70.282736 -161.012637) (xy 70.21451 -160.952)
			(xy 70.15171 -160.885759) (xy 70.094795 -160.814399) (xy 70.04418 -160.73844) (xy 70.000235 -160.658437)
			(xy 69.981318 -160.6169) (xy 69.976941 -160.608106) (xy 69.962845 -160.594451) (xy 69.944649 -160.587096)
			(xy 69.934836 -160.586674) (xy 66.188336 -160.586674) (xy 66.17827 -160.587108) (xy 66.15968 -160.594836)
			(xy 66.152268 -160.60166) (xy 65.27927 -161.474658) (xy 65.271904 -161.48177) (xy 65.264284 -161.500566)
			(xy 65.264284 -172.377354) (xy 65.263851 -172.387419) (xy 65.256121 -172.406008) (xy 65.249298 -172.413422)
			(xy 64.301116 -173.361604) (xy 64.293713 -173.368437) (xy 64.275115 -173.37614) (xy 64.265048 -173.37659)
			(xy 60.319666 -173.37659) (xy 60.309599 -173.37616) (xy 60.291004 -173.368436) (xy 60.283598 -173.361604)
			(xy 58.282332 -171.360338) (xy 58.275492 -171.352938) (xy 58.267775 -171.334339) (xy 58.267346 -171.32427)
			(xy 58.267346 -162.714432) (xy 58.266909 -162.704369) (xy 58.259171 -162.685787) (xy 58.25236 -162.678364)
			(xy 56.175656 -160.60166) (xy 56.168544 -160.594294) (xy 56.149748 -160.586674) (xy 47.615094 -160.586674)
			(xy 47.605283 -160.587121) (xy 47.58709 -160.594472) (xy 47.572976 -160.608103) (xy 47.568612 -160.6169)
			(xy 47.549701 -160.658436) (xy 47.505769 -160.738437) (xy 47.455166 -160.814395) (xy 47.398262 -160.885755)
			(xy 47.335472 -160.951996) (xy 47.267256 -161.012633) (xy 47.194112 -161.067225) (xy 47.116574 -161.115372)
			(xy 47.035208 -161.156722) (xy 46.950608 -161.190974) (xy 46.863392 -161.217877) (xy 46.774198 -161.237236)
			(xy 46.683677 -161.248908) (xy 46.59249 -161.252808) (xy 46.501303 -161.248908) (xy 46.410782 -161.237236)
			(xy 46.321588 -161.217877) (xy 46.234372 -161.190974) (xy 46.149772 -161.156722) (xy 46.068406 -161.115372)
			(xy 45.990868 -161.067225) (xy 45.917724 -161.012633) (xy 45.849508 -160.951996) (xy 45.786718 -160.885755)
			(xy 45.729814 -160.814395) (xy 45.679211 -160.738437) (xy 45.635279 -160.658436) (xy 45.616368 -160.6169)
			(xy 45.611988 -160.608112) (xy 45.59789 -160.59447) (xy 45.579696 -160.587133) (xy 45.569886 -160.586674)
			(xy 44.29506 -160.586674) (xy 44.284992 -160.587104) (xy 44.266396 -160.594825) (xy 44.258992 -160.60166)
			(xy 39.699438 -165.161214) (xy 39.69204 -165.16806) (xy 39.673441 -165.175785) (xy 39.66337 -165.1762)
			(xy 38.690042 -165.1762) (xy 38.679977 -165.175766) (xy 38.661387 -165.168037) (xy 38.653974 -165.161214)
			(xy 36.87826 -163.3855) (xy 36.871407 -163.378104) (xy 36.863663 -163.359506) (xy 36.863274 -163.349432)
			(xy 36.863274 -153.0604) (xy 37.393118 -152.530556) (xy 38.334696 -152.530556) (xy 38.443408 -152.421844)
			(xy 38.443408 -149.79777) (xy 38.723824 -149.517354) (xy 39.434262 -149.517354) (xy 39.583106 -149.36851)
			(xy 39.583106 -148.389086) (xy 39.491412 -148.297392) (xy 35.980116 -148.297392) (xy 24.397208 -148.297392)
			(xy 22.987 -149.7076) (xy 22.987 -153.736294) (xy 22.564852 -154.158442) (xy 22.557486 -154.165554)
			(xy 22.549866 -154.18435) (xy 22.549866 -158.049214) (xy 21.282406 -159.316674) (xy 15.962884 -159.316674)
			(xy 15.875762 -159.403796) (xy 15.875762 -160.53435) (xy 16.015716 -160.674304) (xy 17.05483 -160.674304)
			(xy 17.183862 -160.803336) (xy 17.183862 -162.762692) (xy 17.442434 -163.021264) (xy 21.154136 -163.021264)
			(xy 21.16201 -163.01339) (xy 22.998684 -163.01339) (xy 23.008748 -163.013828) (xy 23.027331 -163.021563)
			(xy 23.034752 -163.028376) (xy 25.907238 -165.900862) (xy 25.914082 -165.908261) (xy 25.921803 -165.92686)
			(xy 25.922224 -165.93693) (xy 25.922224 -169.909236) (xy 51.926996 -169.909236) (xy 51.931067 -169.853614)
			(xy 51.943193 -169.799177) (xy 51.963116 -169.747086) (xy 51.990412 -169.698451) (xy 52.024498 -169.654308)
			(xy 52.064647 -169.615599) (xy 52.110005 -169.583148) (xy 52.159605 -169.557647) (xy 52.212389 -169.53964)
			(xy 52.267232 -169.52951) (xy 52.322966 -169.527473) (xy 52.378403 -169.533573) (xy 52.43236 -169.547679)
			(xy 52.483689 -169.569491) (xy 52.531295 -169.598545) (xy 52.574163 -169.63422) (xy 52.61138 -169.675757)
			(xy 52.642153 -169.72227) (xy 52.665825 -169.772767) (xy 52.681893 -169.826174) (xy 52.690013 -169.88135)
			(xy 52.690522 -169.909236) (xy 52.690013 -169.937122) (xy 52.681893 -169.992298) (xy 52.665825 -170.045705)
			(xy 52.642153 -170.096202) (xy 52.61138 -170.142715) (xy 52.574163 -170.184252) (xy 52.531295 -170.219927)
			(xy 52.483689 -170.248981) (xy 52.43236 -170.270793) (xy 52.378403 -170.284899) (xy 52.322966 -170.290999)
			(xy 52.267232 -170.288962) (xy 52.212389 -170.278832) (xy 52.159605 -170.260825) (xy 52.110005 -170.235324)
			(xy 52.064647 -170.202873) (xy 52.024498 -170.164164) (xy 51.990412 -170.120021) (xy 51.963116 -170.071386)
			(xy 51.943193 -170.019295) (xy 51.931067 -169.964858) (xy 51.926996 -169.909236) (xy 25.922224 -169.909236)
			(xy 25.922224 -175.542956) (xy 62.632842 -175.542956) (xy 62.636913 -175.487334) (xy 62.649039 -175.432897)
			(xy 62.668962 -175.380806) (xy 62.696258 -175.332171) (xy 62.730344 -175.288028) (xy 62.770493 -175.249319)
			(xy 62.815851 -175.216868) (xy 62.865451 -175.191367) (xy 62.918235 -175.17336) (xy 62.973078 -175.16323)
			(xy 63.028812 -175.161193) (xy 63.084249 -175.167293) (xy 63.138206 -175.181399) (xy 63.189535 -175.203211)
			(xy 63.237141 -175.232265) (xy 63.280009 -175.26794) (xy 63.317226 -175.309477) (xy 63.347999 -175.35599)
			(xy 63.371671 -175.406487) (xy 63.387739 -175.459894) (xy 63.395859 -175.51507) (xy 63.396368 -175.542956)
			(xy 63.395859 -175.570842) (xy 63.387739 -175.626018) (xy 63.371671 -175.679425) (xy 63.347999 -175.729922)
			(xy 63.317226 -175.776435) (xy 63.280009 -175.817972) (xy 63.237141 -175.853647) (xy 63.189535 -175.882701)
			(xy 63.138206 -175.904513) (xy 63.084249 -175.918619) (xy 63.028812 -175.924719) (xy 62.973078 -175.922682)
			(xy 62.918235 -175.912552) (xy 62.865451 -175.894545) (xy 62.815851 -175.869044) (xy 62.770493 -175.836593)
			(xy 62.730344 -175.797884) (xy 62.696258 -175.753741) (xy 62.668962 -175.705106) (xy 62.649039 -175.653015)
			(xy 62.636913 -175.598578) (xy 62.632842 -175.542956) (xy 25.922224 -175.542956) (xy 25.922224 -176.704855)
			(xy 50.702129 -176.704855) (xy 50.702129 -176.650345) (xy 50.709887 -176.596389) (xy 50.725244 -176.544087)
			(xy 50.747889 -176.494503) (xy 50.77736 -176.448646) (xy 50.813057 -176.40745) (xy 50.854254 -176.371754)
			(xy 50.900112 -176.342284) (xy 50.949696 -176.319641) (xy 51.001999 -176.304285) (xy 51.055955 -176.296528)
			(xy 51.08321 -176.296066) (xy 51.089052 -176.296066) (xy 51.102338 -176.295857) (xy 51.128101 -176.289393)
			(xy 51.151322 -176.276498) (xy 51.170429 -176.258047) (xy 51.184126 -176.23529) (xy 51.191485 -176.209768)
			(xy 51.192176 -176.196498) (xy 51.193121 -176.169592) (xy 51.201734 -176.116446) (xy 51.217731 -176.065038)
			(xy 51.240794 -176.016389) (xy 51.270465 -175.971464) (xy 51.306156 -175.931155) (xy 51.347157 -175.896262)
			(xy 51.392656 -175.867477) (xy 51.441748 -175.845373) (xy 51.49346 -175.830388) (xy 51.546764 -175.822819)
			(xy 51.573684 -175.822356) (xy 51.600935 -175.82289) (xy 51.654883 -175.830645) (xy 51.707177 -175.845998)
			(xy 51.756755 -175.868637) (xy 51.802606 -175.898102) (xy 51.843796 -175.933792) (xy 51.879488 -175.974981)
			(xy 51.908955 -176.020831) (xy 51.931597 -176.070408) (xy 51.946952 -176.122702) (xy 51.954709 -176.176649)
			(xy 51.954709 -176.231151) (xy 51.946952 -176.285098) (xy 51.931597 -176.337392) (xy 51.908955 -176.386969)
			(xy 51.879488 -176.432819) (xy 51.843796 -176.474008) (xy 51.802606 -176.509698) (xy 51.756755 -176.539163)
			(xy 51.707177 -176.561802) (xy 51.654883 -176.577155) (xy 51.600935 -176.58491) (xy 51.573684 -176.585372)
			(xy 51.567842 -176.585372) (xy 51.55456 -176.585636) (xy 51.528806 -176.592097) (xy 51.505591 -176.604983)
			(xy 51.486486 -176.623422) (xy 51.472785 -176.646166) (xy 51.465416 -176.671675) (xy 51.464718 -176.68494)
			(xy 51.463814 -176.711848) (xy 51.455195 -176.764996) (xy 51.439193 -176.816404) (xy 51.416126 -176.865054)
			(xy 51.38645 -176.909979) (xy 51.350755 -176.950288) (xy 51.30975 -176.98518) (xy 51.264248 -177.013964)
			(xy 51.261072 -177.015394) (xy 61.6618 -177.015394) (xy 61.665871 -176.959772) (xy 61.677997 -176.905335)
			(xy 61.69792 -176.853244) (xy 61.725216 -176.804609) (xy 61.759302 -176.760466) (xy 61.799451 -176.721757)
			(xy 61.844809 -176.689306) (xy 61.894409 -176.663805) (xy 61.947193 -176.645798) (xy 62.002036 -176.635668)
			(xy 62.05777 -176.633631) (xy 62.113207 -176.639731) (xy 62.167164 -176.653837) (xy 62.218493 -176.675649)
			(xy 62.266099 -176.704703) (xy 62.308967 -176.740378) (xy 62.346184 -176.781915) (xy 62.376957 -176.828428)
			(xy 62.400629 -176.878925) (xy 62.416697 -176.932332) (xy 62.424817 -176.987508) (xy 62.425326 -177.015394)
			(xy 62.424817 -177.04328) (xy 62.416697 -177.098456) (xy 62.400629 -177.151863) (xy 62.376957 -177.20236)
			(xy 62.346184 -177.248873) (xy 62.308967 -177.29041) (xy 62.266099 -177.326085) (xy 62.221647 -177.353214)
			(xy 64.295018 -177.353214) (xy 64.299089 -177.297592) (xy 64.311215 -177.243155) (xy 64.331138 -177.191064)
			(xy 64.358434 -177.142429) (xy 64.39252 -177.098286) (xy 64.432669 -177.059577) (xy 64.478027 -177.027126)
			(xy 64.527627 -177.001625) (xy 64.580411 -176.983618) (xy 64.635254 -176.973488) (xy 64.690988 -176.971451)
			(xy 64.746425 -176.977551) (xy 64.800382 -176.991657) (xy 64.851711 -177.013469) (xy 64.899317 -177.042523)
			(xy 64.942185 -177.078198) (xy 64.979402 -177.119735) (xy 65.010175 -177.166248) (xy 65.033847 -177.216745)
			(xy 65.049915 -177.270152) (xy 65.058035 -177.325328) (xy 65.058544 -177.353214) (xy 65.058035 -177.3811)
			(xy 65.049915 -177.436276) (xy 65.033847 -177.489683) (xy 65.010175 -177.54018) (xy 64.979402 -177.586693)
			(xy 64.942185 -177.62823) (xy 64.899317 -177.663905) (xy 64.851711 -177.692959) (xy 64.800382 -177.714771)
			(xy 64.746425 -177.728877) (xy 64.690988 -177.734977) (xy 64.635254 -177.73294) (xy 64.580411 -177.72281)
			(xy 64.527627 -177.704803) (xy 64.478027 -177.679302) (xy 64.432669 -177.646851) (xy 64.39252 -177.608142)
			(xy 64.358434 -177.563999) (xy 64.331138 -177.515364) (xy 64.311215 -177.463273) (xy 64.299089 -177.408836)
			(xy 64.295018 -177.353214) (xy 62.221647 -177.353214) (xy 62.218493 -177.355139) (xy 62.167164 -177.376951)
			(xy 62.113207 -177.391057) (xy 62.05777 -177.397157) (xy 62.002036 -177.39512) (xy 61.947193 -177.38499)
			(xy 61.894409 -177.366983) (xy 61.844809 -177.341482) (xy 61.799451 -177.309031) (xy 61.759302 -177.270322)
			(xy 61.725216 -177.226179) (xy 61.69792 -177.177544) (xy 61.677997 -177.125453) (xy 61.665871 -177.071016)
			(xy 61.6618 -177.015394) (xy 51.261072 -177.015394) (xy 51.215152 -177.036067) (xy 51.163438 -177.051051)
			(xy 51.110131 -177.058619) (xy 51.08321 -177.059082) (xy 51.055955 -177.058672) (xy 51.001999 -177.050915)
			(xy 50.949696 -177.035559) (xy 50.900112 -177.012916) (xy 50.854254 -176.983446) (xy 50.813057 -176.94775)
			(xy 50.77736 -176.906554) (xy 50.747889 -176.860697) (xy 50.725244 -176.811113) (xy 50.709887 -176.758811)
			(xy 50.702129 -176.704855) (xy 25.922224 -176.704855) (xy 25.922224 -180.365908) (xy 28.064204 -180.365908)
			(xy 28.068275 -180.310286) (xy 28.080401 -180.255849) (xy 28.100324 -180.203758) (xy 28.12762 -180.155123)
			(xy 28.161706 -180.11098) (xy 28.201855 -180.072271) (xy 28.247213 -180.03982) (xy 28.296813 -180.014319)
			(xy 28.349597 -179.996312) (xy 28.40444 -179.986182) (xy 28.460174 -179.984145) (xy 28.515611 -179.990245)
			(xy 28.569568 -180.004351) (xy 28.620897 -180.026163) (xy 28.668503 -180.055217) (xy 28.711371 -180.090892)
			(xy 28.748588 -180.132429) (xy 28.779361 -180.178942) (xy 28.803033 -180.229439) (xy 28.819101 -180.282846)
			(xy 28.827221 -180.338022) (xy 28.82773 -180.365908) (xy 28.827221 -180.393794) (xy 28.819101 -180.44897)
			(xy 28.815797 -180.459953) (xy 91.824765 -180.459953) (xy 91.824765 -180.405447) (xy 91.832522 -180.351497)
			(xy 91.847879 -180.2992) (xy 91.870521 -180.24962) (xy 91.899989 -180.203768) (xy 91.935683 -180.162576)
			(xy 91.976876 -180.126883) (xy 92.022729 -180.097416) (xy 92.072309 -180.074775) (xy 92.124607 -180.05942)
			(xy 92.178557 -180.051665) (xy 92.20581 -180.051202) (xy 92.232634 -180.051673) (xy 92.285755 -180.059185)
			(xy 92.3373 -180.074059) (xy 92.386256 -180.096004) (xy 92.431657 -180.124586) (xy 92.47261 -180.159242)
			(xy 92.490798 -180.178964) (xy 92.498164 -180.187346) (xy 92.517976 -180.196236) (xy 92.61729 -180.194966)
			(xy 92.636848 -180.185568) (xy 92.644214 -180.177186) (xy 92.662401 -180.156397) (xy 92.703771 -180.119799)
			(xy 92.74999 -180.089556) (xy 92.800091 -180.066302) (xy 92.853024 -180.050522) (xy 92.907681 -180.042549)
			(xy 92.935298 -180.042058) (xy 92.962549 -180.042589) (xy 93.016495 -180.050345) (xy 93.068788 -180.0657)
			(xy 93.118364 -180.08834) (xy 93.164214 -180.117805) (xy 93.205403 -180.153496) (xy 93.241093 -180.194685)
			(xy 93.270559 -180.240534) (xy 93.2932 -180.29011) (xy 93.308554 -180.342403) (xy 93.316311 -180.396349)
			(xy 93.316311 -180.450851) (xy 93.308554 -180.504797) (xy 93.2932 -180.55709) (xy 93.270559 -180.606666)
			(xy 93.241093 -180.652515) (xy 93.205403 -180.693704) (xy 93.164214 -180.729395) (xy 93.118364 -180.75886)
			(xy 93.068788 -180.7815) (xy 93.016495 -180.796855) (xy 92.962549 -180.804611) (xy 92.935298 -180.805074)
			(xy 92.908473 -180.804606) (xy 92.855353 -180.797094) (xy 92.803807 -180.78222) (xy 92.754851 -180.760275)
			(xy 92.70945 -180.731692) (xy 92.668498 -180.697034) (xy 92.65031 -180.677312) (xy 92.642944 -180.66893)
			(xy 92.623132 -180.66004) (xy 92.523818 -180.66131) (xy 92.50426 -180.670708) (xy 92.496894 -180.67909)
			(xy 92.478698 -180.69987) (xy 92.43733 -180.73647) (xy 92.391113 -180.766715) (xy 92.341014 -180.789971)
			(xy 92.288082 -180.805752) (xy 92.233427 -180.813726) (xy 92.20581 -180.814218) (xy 92.178557 -180.813735)
			(xy 92.124607 -180.80598) (xy 92.072309 -180.790625) (xy 92.022729 -180.767984) (xy 91.976876 -180.738517)
			(xy 91.935683 -180.702824) (xy 91.899989 -180.661632) (xy 91.870521 -180.61578) (xy 91.847879 -180.5662)
			(xy 91.832522 -180.513903) (xy 91.824765 -180.459953) (xy 28.815797 -180.459953) (xy 28.803033 -180.502377)
			(xy 28.779361 -180.552874) (xy 28.748588 -180.599387) (xy 28.711371 -180.640924) (xy 28.668503 -180.676599)
			(xy 28.620897 -180.705653) (xy 28.569568 -180.727465) (xy 28.515611 -180.741571) (xy 28.460174 -180.747671)
			(xy 28.40444 -180.745634) (xy 28.349597 -180.735504) (xy 28.296813 -180.717497) (xy 28.247213 -180.691996)
			(xy 28.201855 -180.659545) (xy 28.161706 -180.620836) (xy 28.12762 -180.576693) (xy 28.100324 -180.528058)
			(xy 28.080401 -180.475967) (xy 28.068275 -180.42153) (xy 28.064204 -180.365908) (xy 25.922224 -180.365908)
			(xy 25.922224 -185.674) (xy 96.382584 -185.674) (xy 96.386655 -185.618378) (xy 96.398781 -185.563941)
			(xy 96.418704 -185.51185) (xy 96.446 -185.463215) (xy 96.480086 -185.419072) (xy 96.520235 -185.380363)
			(xy 96.565593 -185.347912) (xy 96.615193 -185.322411) (xy 96.667977 -185.304404) (xy 96.72282 -185.294274)
			(xy 96.778554 -185.292237) (xy 96.833991 -185.298337) (xy 96.887948 -185.312443) (xy 96.939277 -185.334255)
			(xy 96.986883 -185.363309) (xy 97.029751 -185.398984) (xy 97.066968 -185.440521) (xy 97.097741 -185.487034)
			(xy 97.121413 -185.537531) (xy 97.137481 -185.590938) (xy 97.145601 -185.646114) (xy 97.14611 -185.674)
			(xy 97.145601 -185.701886) (xy 97.137481 -185.757062) (xy 97.121413 -185.810469) (xy 97.097741 -185.860966)
			(xy 97.066968 -185.907479) (xy 97.029751 -185.949016) (xy 96.986883 -185.984691) (xy 96.939277 -186.013745)
			(xy 96.887948 -186.035557) (xy 96.833991 -186.049663) (xy 96.778554 -186.055763) (xy 96.72282 -186.053726)
			(xy 96.667977 -186.043596) (xy 96.615193 -186.025589) (xy 96.565593 -186.000088) (xy 96.520235 -185.967637)
			(xy 96.480086 -185.928928) (xy 96.446 -185.884785) (xy 96.418704 -185.83615) (xy 96.398781 -185.784059)
			(xy 96.386655 -185.729622) (xy 96.382584 -185.674) (xy 25.922224 -185.674) (xy 25.922224 -186.14771)
			(xy 99.051362 -186.14771) (xy 99.055433 -186.092088) (xy 99.067559 -186.037651) (xy 99.087482 -185.98556)
			(xy 99.114778 -185.936925) (xy 99.148864 -185.892782) (xy 99.189013 -185.854073) (xy 99.234371 -185.821622)
			(xy 99.283971 -185.796121) (xy 99.336755 -185.778114) (xy 99.391598 -185.767984) (xy 99.447332 -185.765947)
			(xy 99.502769 -185.772047) (xy 99.556726 -185.786153) (xy 99.608055 -185.807965) (xy 99.655661 -185.837019)
			(xy 99.698529 -185.872694) (xy 99.735746 -185.914231) (xy 99.766519 -185.960744) (xy 99.790191 -186.011241)
			(xy 99.806259 -186.064648) (xy 99.814379 -186.119824) (xy 99.814888 -186.14771) (xy 99.814379 -186.175596)
			(xy 99.806259 -186.230772) (xy 99.790191 -186.284179) (xy 99.766519 -186.334676) (xy 99.735746 -186.381189)
			(xy 99.698529 -186.422726) (xy 99.655661 -186.458401) (xy 99.608055 -186.487455) (xy 99.556726 -186.509267)
			(xy 99.502769 -186.523373) (xy 99.447332 -186.529473) (xy 99.391598 -186.527436) (xy 99.336755 -186.517306)
			(xy 99.283971 -186.499299) (xy 99.234371 -186.473798) (xy 99.189013 -186.441347) (xy 99.148864 -186.402638)
			(xy 99.114778 -186.358495) (xy 99.087482 -186.30986) (xy 99.067559 -186.257769) (xy 99.055433 -186.203332)
			(xy 99.051362 -186.14771) (xy 25.922224 -186.14771) (xy 25.922224 -187.806838) (xy 25.922688 -187.816713)
			(xy 25.930139 -187.835004) (xy 25.936702 -187.842398) (xy 29.742384 -191.64808) (xy 29.751527 -191.656274)
			(xy 29.774889 -191.663699) (xy 29.787088 -191.662304) (xy 29.868876 -191.64808) (xy 29.880817 -191.64536)
			(xy 29.900329 -191.630626) (xy 29.906214 -191.619886) (xy 29.918169 -191.595756) (xy 29.947853 -191.550824)
			(xy 29.983556 -191.510509) (xy 30.024569 -191.475611) (xy 30.070078 -191.446822) (xy 30.119182 -191.424712)
			(xy 30.170904 -191.409722) (xy 30.22422 -191.402148) (xy 30.251146 -191.4017) (xy 30.278395 -191.402189)
			(xy 30.332337 -191.409951) (xy 30.384626 -191.42531) (xy 30.434197 -191.447954) (xy 30.480041 -191.477422)
			(xy 30.521225 -191.513113) (xy 30.556911 -191.554302) (xy 30.586372 -191.600151) (xy 30.586453 -191.600328)
			(xy 59.508642 -191.600328) (xy 59.512713 -191.544706) (xy 59.524839 -191.490269) (xy 59.544762 -191.438178)
			(xy 59.572058 -191.389543) (xy 59.606144 -191.3454) (xy 59.646293 -191.306691) (xy 59.691651 -191.27424)
			(xy 59.741251 -191.248739) (xy 59.794035 -191.230732) (xy 59.848878 -191.220602) (xy 59.904612 -191.218565)
			(xy 59.960049 -191.224665) (xy 60.014006 -191.238771) (xy 60.065335 -191.260583) (xy 60.112941 -191.289637)
			(xy 60.155809 -191.325312) (xy 60.193026 -191.366849) (xy 60.223799 -191.413362) (xy 60.247471 -191.463859)
			(xy 60.263539 -191.517266) (xy 60.271659 -191.572442) (xy 60.272168 -191.600328) (xy 60.271659 -191.628214)
			(xy 60.263539 -191.68339) (xy 60.247471 -191.736797) (xy 60.223799 -191.787294) (xy 60.193026 -191.833807)
			(xy 60.155809 -191.875344) (xy 60.112941 -191.911019) (xy 60.065335 -191.940073) (xy 60.014006 -191.961885)
			(xy 59.960049 -191.975991) (xy 59.904612 -191.982091) (xy 59.848878 -191.980054) (xy 59.794035 -191.969924)
			(xy 59.741251 -191.951917) (xy 59.691651 -191.926416) (xy 59.646293 -191.893965) (xy 59.606144 -191.855256)
			(xy 59.572058 -191.811113) (xy 59.544762 -191.762478) (xy 59.524839 -191.710387) (xy 59.512713 -191.65595)
			(xy 59.508642 -191.600328) (xy 30.586453 -191.600328) (xy 30.609009 -191.649725) (xy 30.624361 -191.702016)
			(xy 30.632115 -191.755959) (xy 30.632654 -191.783208) (xy 30.632908 -191.783208) (xy 30.632445 -191.810133)
			(xy 30.624876 -191.863448) (xy 30.609889 -191.915169) (xy 30.587781 -191.964271) (xy 30.558991 -192.009779)
			(xy 30.524092 -192.050788) (xy 30.483775 -192.086486) (xy 30.438841 -192.116163) (xy 30.414722 -192.12814)
			(xy 30.403927 -192.134005) (xy 30.389058 -192.153513) (xy 30.386274 -192.165478) (xy 30.37205 -192.247266)
			(xy 30.370673 -192.259462) (xy 30.378101 -192.282815) (xy 30.386274 -192.29197) (xy 30.447996 -192.353692)
			(xy 30.456704 -192.361438) (xy 30.478811 -192.368736) (xy 30.490414 -192.367662) (xy 30.503618 -192.365957)
			(xy 30.530186 -192.364179) (xy 30.5435 -192.364106) (xy 30.570752 -192.364569) (xy 30.624703 -192.372326)
			(xy 30.677 -192.387683) (xy 30.726579 -192.410325) (xy 30.772431 -192.439793) (xy 30.813623 -192.475487)
			(xy 30.849315 -192.51668) (xy 30.878781 -192.562533) (xy 30.901422 -192.612113) (xy 30.916777 -192.664411)
			(xy 30.924532 -192.718361) (xy 30.925008 -192.745614) (xy 30.924925 -192.758927) (xy 30.923143 -192.785494)
			(xy 30.921452 -192.7987) (xy 30.919674 -192.810638) (xy 30.92704 -192.832736) (xy 43.110912 -205.016608)
			(xy 116.266212 -205.016608) (xy 116.270283 -204.960986) (xy 116.282409 -204.906549) (xy 116.302332 -204.854458)
			(xy 116.329628 -204.805823) (xy 116.363714 -204.76168) (xy 116.403863 -204.722971) (xy 116.449221 -204.69052)
			(xy 116.498821 -204.665019) (xy 116.551605 -204.647012) (xy 116.606448 -204.636882) (xy 116.662182 -204.634845)
			(xy 116.717619 -204.640945) (xy 116.771576 -204.655051) (xy 116.822905 -204.676863) (xy 116.870511 -204.705917)
			(xy 116.913379 -204.741592) (xy 116.950596 -204.783129) (xy 116.981369 -204.829642) (xy 117.005041 -204.880139)
			(xy 117.021109 -204.933546) (xy 117.029229 -204.988722) (xy 117.029738 -205.016608) (xy 117.029229 -205.044494)
			(xy 117.021109 -205.09967) (xy 117.005041 -205.153077) (xy 116.981369 -205.203574) (xy 116.950596 -205.250087)
			(xy 116.913379 -205.291624) (xy 116.870511 -205.327299) (xy 116.822905 -205.356353) (xy 116.771576 -205.378165)
			(xy 116.717619 -205.392271) (xy 116.662182 -205.398371) (xy 116.606448 -205.396334) (xy 116.551605 -205.386204)
			(xy 116.498821 -205.368197) (xy 116.449221 -205.342696) (xy 116.403863 -205.310245) (xy 116.363714 -205.271536)
			(xy 116.329628 -205.227393) (xy 116.302332 -205.178758) (xy 116.282409 -205.126667) (xy 116.270283 -205.07223)
			(xy 116.266212 -205.016608) (xy 43.110912 -205.016608) (xy 44.352972 -206.258668) (xy 62.738506 -206.258668)
			(xy 62.742577 -206.203046) (xy 62.754703 -206.148609) (xy 62.774626 -206.096518) (xy 62.801922 -206.047883)
			(xy 62.836008 -206.00374) (xy 62.876157 -205.965031) (xy 62.921515 -205.93258) (xy 62.971115 -205.907079)
			(xy 63.023899 -205.889072) (xy 63.078742 -205.878942) (xy 63.134476 -205.876905) (xy 63.189913 -205.883005)
			(xy 63.24387 -205.897111) (xy 63.295199 -205.918923) (xy 63.342805 -205.947977) (xy 63.385673 -205.983652)
			(xy 63.42289 -206.025189) (xy 63.453663 -206.071702) (xy 63.477335 -206.122199) (xy 63.493403 -206.175606)
			(xy 63.501523 -206.230782) (xy 63.502032 -206.258668) (xy 63.501523 -206.286554) (xy 63.497702 -206.312516)
			(xy 64.718944 -206.312516) (xy 64.723015 -206.256894) (xy 64.735141 -206.202457) (xy 64.755064 -206.150366)
			(xy 64.78236 -206.101731) (xy 64.816446 -206.057588) (xy 64.856595 -206.018879) (xy 64.901953 -205.986428)
			(xy 64.951553 -205.960927) (xy 65.004337 -205.94292) (xy 65.05918 -205.93279) (xy 65.114914 -205.930753)
			(xy 65.170351 -205.936853) (xy 65.224308 -205.950959) (xy 65.275637 -205.972771) (xy 65.323243 -206.001825)
			(xy 65.366111 -206.0375) (xy 65.403328 -206.079037) (xy 65.434101 -206.12555) (xy 65.457773 -206.176047)
			(xy 65.473841 -206.229454) (xy 65.481961 -206.28463) (xy 65.48247 -206.312516) (xy 65.481961 -206.340402)
			(xy 65.473841 -206.395578) (xy 65.457773 -206.448985) (xy 65.434101 -206.499482) (xy 65.403328 -206.545995)
			(xy 65.366111 -206.587532) (xy 65.323243 -206.623207) (xy 65.275637 -206.652261) (xy 65.224308 -206.674073)
			(xy 65.170351 -206.688179) (xy 65.114914 -206.694279) (xy 65.05918 -206.692242) (xy 65.004337 -206.682112)
			(xy 64.951553 -206.664105) (xy 64.901953 -206.638604) (xy 64.856595 -206.606153) (xy 64.816446 -206.567444)
			(xy 64.78236 -206.523301) (xy 64.755064 -206.474666) (xy 64.735141 -206.422575) (xy 64.723015 -206.368138)
			(xy 64.718944 -206.312516) (xy 63.497702 -206.312516) (xy 63.493403 -206.34173) (xy 63.477335 -206.395137)
			(xy 63.453663 -206.445634) (xy 63.42289 -206.492147) (xy 63.385673 -206.533684) (xy 63.342805 -206.569359)
			(xy 63.295199 -206.598413) (xy 63.24387 -206.620225) (xy 63.189913 -206.634331) (xy 63.134476 -206.640431)
			(xy 63.078742 -206.638394) (xy 63.023899 -206.628264) (xy 62.971115 -206.610257) (xy 62.921515 -206.584756)
			(xy 62.876157 -206.552305) (xy 62.836008 -206.513596) (xy 62.801922 -206.469453) (xy 62.774626 -206.420818)
			(xy 62.754703 -206.368727) (xy 62.742577 -206.31429) (xy 62.738506 -206.258668) (xy 44.352972 -206.258668)
			(xy 45.171868 -207.077564) (xy 59.966096 -207.077564) (xy 59.970167 -207.021942) (xy 59.982293 -206.967505)
			(xy 60.002216 -206.915414) (xy 60.029512 -206.866779) (xy 60.063598 -206.822636) (xy 60.103747 -206.783927)
			(xy 60.149105 -206.751476) (xy 60.198705 -206.725975) (xy 60.251489 -206.707968) (xy 60.306332 -206.697838)
			(xy 60.362066 -206.695801) (xy 60.417503 -206.701901) (xy 60.47146 -206.716007) (xy 60.522789 -206.737819)
			(xy 60.570395 -206.766873) (xy 60.613263 -206.802548) (xy 60.65048 -206.844085) (xy 60.681253 -206.890598)
			(xy 60.704925 -206.941095) (xy 60.713505 -206.969614) (xy 60.883798 -206.969614) (xy 60.887869 -206.913992)
			(xy 60.899995 -206.859555) (xy 60.919918 -206.807464) (xy 60.947214 -206.758829) (xy 60.9813 -206.714686)
			(xy 61.021449 -206.675977) (xy 61.066807 -206.643526) (xy 61.116407 -206.618025) (xy 61.169191 -206.600018)
			(xy 61.224034 -206.589888) (xy 61.279768 -206.587851) (xy 61.335205 -206.593951) (xy 61.389162 -206.608057)
			(xy 61.440491 -206.629869) (xy 61.488097 -206.658923) (xy 61.530965 -206.694598) (xy 61.568182 -206.736135)
			(xy 61.598955 -206.782648) (xy 61.622627 -206.833145) (xy 61.638695 -206.886552) (xy 61.646815 -206.941728)
			(xy 61.647004 -206.952088) (xy 91.57665 -206.952088) (xy 91.580721 -206.896466) (xy 91.592847 -206.842029)
			(xy 91.61277 -206.789938) (xy 91.640066 -206.741303) (xy 91.674152 -206.69716) (xy 91.714301 -206.658451)
			(xy 91.759659 -206.626) (xy 91.809259 -206.600499) (xy 91.862043 -206.582492) (xy 91.916886 -206.572362)
			(xy 91.97262 -206.570325) (xy 92.028057 -206.576425) (xy 92.082014 -206.590531) (xy 92.133343 -206.612343)
			(xy 92.180949 -206.641397) (xy 92.223817 -206.677072) (xy 92.261034 -206.718609) (xy 92.291807 -206.765122)
			(xy 92.315479 -206.815619) (xy 92.331547 -206.869026) (xy 92.339667 -206.924202) (xy 92.340176 -206.952088)
			(xy 92.339667 -206.979974) (xy 92.331547 -207.03515) (xy 92.329408 -207.042258) (xy 92.503496 -207.042258)
			(xy 92.507567 -206.986636) (xy 92.519693 -206.932199) (xy 92.539616 -206.880108) (xy 92.566912 -206.831473)
			(xy 92.600998 -206.78733) (xy 92.641147 -206.748621) (xy 92.686505 -206.71617) (xy 92.736105 -206.690669)
			(xy 92.788889 -206.672662) (xy 92.843732 -206.662532) (xy 92.899466 -206.660495) (xy 92.954903 -206.666595)
			(xy 93.00886 -206.680701) (xy 93.060189 -206.702513) (xy 93.107795 -206.731567) (xy 93.150663 -206.767242)
			(xy 93.18788 -206.808779) (xy 93.218653 -206.855292) (xy 93.242325 -206.905789) (xy 93.258393 -206.959196)
			(xy 93.266513 -207.014372) (xy 93.267022 -207.042258) (xy 93.266513 -207.070144) (xy 93.264038 -207.086962)
			(xy 93.98076 -207.086962) (xy 93.984831 -207.03134) (xy 93.996957 -206.976903) (xy 94.01688 -206.924812)
			(xy 94.044176 -206.876177) (xy 94.078262 -206.832034) (xy 94.118411 -206.793325) (xy 94.163769 -206.760874)
			(xy 94.213369 -206.735373) (xy 94.266153 -206.717366) (xy 94.320996 -206.707236) (xy 94.37673 -206.705199)
			(xy 94.432167 -206.711299) (xy 94.486124 -206.725405) (xy 94.537453 -206.747217) (xy 94.585059 -206.776271)
			(xy 94.627927 -206.811946) (xy 94.635633 -206.820547) (xy 96.553316 -206.820547) (xy 96.553316 -206.766053)
			(xy 96.561071 -206.712113) (xy 96.576423 -206.659825) (xy 96.59906 -206.610255) (xy 96.628521 -206.56441)
			(xy 96.664206 -206.523225) (xy 96.705389 -206.487537) (xy 96.751232 -206.458073) (xy 96.800801 -206.435433)
			(xy 96.853087 -206.420077) (xy 96.907027 -206.412318) (xy 96.934274 -206.41183) (xy 96.963191 -206.412356)
			(xy 97.020362 -206.421082) (xy 97.075561 -206.438337) (xy 97.127523 -206.463727) (xy 97.175057 -206.49667)
			(xy 97.217074 -206.536411) (xy 97.235264 -206.558896) (xy 97.24263 -206.568548) (xy 97.263966 -206.578708)
			(xy 97.369376 -206.577184) (xy 97.390204 -206.566516) (xy 97.397316 -206.55661) (xy 97.415454 -206.53289)
			(xy 97.457838 -206.490833) (xy 97.506252 -206.455885) (xy 97.559515 -206.428899) (xy 97.616329 -206.410533)
			(xy 97.675309 -206.401233) (xy 97.705164 -206.400654) (xy 97.734969 -206.40125) (xy 97.793851 -206.410536)
			(xy 97.85057 -206.42887) (xy 97.903747 -206.455807) (xy 97.952084 -206.49069) (xy 97.994404 -206.53267)
			(xy 98.012504 -206.556356) (xy 98.020886 -206.567532) (xy 98.045778 -206.578454) (xy 98.161602 -206.56423)
			(xy 98.183192 -206.54772) (xy 98.188526 -206.534766) (xy 98.199728 -206.508917) (xy 98.228558 -206.46052)
			(xy 98.264194 -206.416892) (xy 98.305861 -206.378981) (xy 98.352652 -206.347613) (xy 98.40355 -206.32347)
			(xy 98.457445 -206.307079) (xy 98.513166 -206.298795) (xy 98.541332 -206.298292) (xy 98.568582 -206.29878)
			(xy 98.622526 -206.30654) (xy 98.674817 -206.321898) (xy 98.72439 -206.344541) (xy 98.770237 -206.374008)
			(xy 98.811423 -206.4097) (xy 98.847111 -206.450889) (xy 98.876574 -206.496738) (xy 98.899213 -206.546313)
			(xy 98.914567 -206.598605) (xy 98.922322 -206.65255) (xy 98.922322 -206.70705) (xy 98.914567 -206.760995)
			(xy 98.899213 -206.813287) (xy 98.876574 -206.862862) (xy 98.847111 -206.908711) (xy 98.811423 -206.9499)
			(xy 98.770237 -206.985592) (xy 98.72439 -207.015059) (xy 98.674817 -207.037702) (xy 98.622526 -207.05306)
			(xy 98.568582 -207.06082) (xy 98.541332 -207.061308) (xy 98.511529 -207.060689) (xy 98.452649 -207.051405)
			(xy 98.395931 -207.033073) (xy 98.342755 -207.006141) (xy 98.294417 -206.971263) (xy 98.252094 -206.929289)
			(xy 98.233992 -206.905606) (xy 98.22561 -206.89443) (xy 98.200718 -206.883508) (xy 98.084894 -206.897732)
			(xy 98.063304 -206.914242) (xy 98.05797 -206.927196) (xy 98.046802 -206.95306) (xy 98.017965 -207.001455)
			(xy 97.982323 -207.045081) (xy 97.94065 -207.08299) (xy 97.893854 -207.114355) (xy 97.842953 -207.138495)
			(xy 97.789055 -207.154885) (xy 97.733332 -207.163167) (xy 97.705164 -207.16367) (xy 97.676248 -207.163117)
			(xy 97.619078 -207.154397) (xy 97.563879 -207.137147) (xy 97.511917 -207.111762) (xy 97.464383 -207.078824)
			(xy 97.422365 -207.039087) (xy 97.404174 -207.016604) (xy 97.396808 -207.006952) (xy 97.375472 -206.996792)
			(xy 97.270062 -206.998316) (xy 97.249234 -207.008984) (xy 97.242122 -207.01889) (xy 97.22402 -207.04264)
			(xy 97.181629 -207.084695) (xy 97.133208 -207.119639) (xy 97.079938 -207.14662) (xy 97.023117 -207.16498)
			(xy 96.964131 -207.174271) (xy 96.934274 -207.174846) (xy 96.907027 -207.174282) (xy 96.853087 -207.166523)
			(xy 96.800801 -207.151167) (xy 96.751232 -207.128527) (xy 96.705389 -207.099063) (xy 96.664206 -207.063375)
			(xy 96.628521 -207.02219) (xy 96.59906 -206.976345) (xy 96.576423 -206.926775) (xy 96.561071 -206.874487)
			(xy 96.553316 -206.820547) (xy 94.635633 -206.820547) (xy 94.665144 -206.853483) (xy 94.695917 -206.899996)
			(xy 94.719589 -206.950493) (xy 94.735657 -207.0039) (xy 94.743777 -207.059076) (xy 94.744286 -207.086962)
			(xy 94.743777 -207.114848) (xy 94.735657 -207.170024) (xy 94.719589 -207.223431) (xy 94.695917 -207.273928)
			(xy 94.665144 -207.320441) (xy 94.627927 -207.361978) (xy 94.585059 -207.397653) (xy 94.537453 -207.426707)
			(xy 94.486124 -207.448519) (xy 94.432167 -207.462625) (xy 94.37673 -207.468725) (xy 94.320996 -207.466688)
			(xy 94.266153 -207.456558) (xy 94.213369 -207.438551) (xy 94.163769 -207.41305) (xy 94.118411 -207.380599)
			(xy 94.078262 -207.34189) (xy 94.044176 -207.297747) (xy 94.01688 -207.249112) (xy 93.996957 -207.197021)
			(xy 93.984831 -207.142584) (xy 93.98076 -207.086962) (xy 93.264038 -207.086962) (xy 93.258393 -207.12532)
			(xy 93.242325 -207.178727) (xy 93.218653 -207.229224) (xy 93.18788 -207.275737) (xy 93.150663 -207.317274)
			(xy 93.107795 -207.352949) (xy 93.060189 -207.382003) (xy 93.00886 -207.403815) (xy 92.954903 -207.417921)
			(xy 92.899466 -207.424021) (xy 92.843732 -207.421984) (xy 92.788889 -207.411854) (xy 92.736105 -207.393847)
			(xy 92.686505 -207.368346) (xy 92.641147 -207.335895) (xy 92.600998 -207.297186) (xy 92.566912 -207.253043)
			(xy 92.539616 -207.204408) (xy 92.519693 -207.152317) (xy 92.507567 -207.09788) (xy 92.503496 -207.042258)
			(xy 92.329408 -207.042258) (xy 92.315479 -207.088557) (xy 92.291807 -207.139054) (xy 92.261034 -207.185567)
			(xy 92.223817 -207.227104) (xy 92.180949 -207.262779) (xy 92.133343 -207.291833) (xy 92.082014 -207.313645)
			(xy 92.028057 -207.327751) (xy 91.97262 -207.333851) (xy 91.916886 -207.331814) (xy 91.862043 -207.321684)
			(xy 91.809259 -207.303677) (xy 91.759659 -207.278176) (xy 91.714301 -207.245725) (xy 91.674152 -207.207016)
			(xy 91.640066 -207.162873) (xy 91.61277 -207.114238) (xy 91.592847 -207.062147) (xy 91.580721 -207.00771)
			(xy 91.57665 -206.952088) (xy 61.647004 -206.952088) (xy 61.647324 -206.969614) (xy 61.646815 -206.9975)
			(xy 61.638695 -207.052676) (xy 61.622627 -207.106083) (xy 61.598955 -207.15658) (xy 61.568182 -207.203093)
			(xy 61.530965 -207.24463) (xy 61.488097 -207.280305) (xy 61.440491 -207.309359) (xy 61.389162 -207.331171)
			(xy 61.335205 -207.345277) (xy 61.279768 -207.351377) (xy 61.224034 -207.34934) (xy 61.169191 -207.33921)
			(xy 61.116407 -207.321203) (xy 61.066807 -207.295702) (xy 61.021449 -207.263251) (xy 60.9813 -207.224542)
			(xy 60.947214 -207.180399) (xy 60.919918 -207.131764) (xy 60.899995 -207.079673) (xy 60.887869 -207.025236)
			(xy 60.883798 -206.969614) (xy 60.713505 -206.969614) (xy 60.720993 -206.994502) (xy 60.729113 -207.049678)
			(xy 60.729622 -207.077564) (xy 60.729113 -207.10545) (xy 60.720993 -207.160626) (xy 60.704925 -207.214033)
			(xy 60.681253 -207.26453) (xy 60.65048 -207.311043) (xy 60.613263 -207.35258) (xy 60.570395 -207.388255)
			(xy 60.522789 -207.417309) (xy 60.47146 -207.439121) (xy 60.417503 -207.453227) (xy 60.362066 -207.459327)
			(xy 60.306332 -207.45729) (xy 60.251489 -207.44716) (xy 60.198705 -207.429153) (xy 60.149105 -207.403652)
			(xy 60.103747 -207.371201) (xy 60.063598 -207.332492) (xy 60.029512 -207.288349) (xy 60.002216 -207.239714)
			(xy 59.982293 -207.187623) (xy 59.970167 -207.133186) (xy 59.966096 -207.077564) (xy 45.171868 -207.077564)
			(xy 47.800514 -209.70621) (xy 47.807368 -209.713605) (xy 47.815113 -209.732204) (xy 47.8155 -209.742278)
			(xy 47.8155 -210.6676) (xy 58.62574 -210.6676) (xy 58.62574 -209.3976) (xy 58.626189 -209.380875)
			(xy 58.634849 -209.348564) (xy 58.651578 -209.319597) (xy 58.675235 -209.295948) (xy 58.704209 -209.27923)
			(xy 58.736522 -209.270583) (xy 58.753248 -209.270092) (xy 62.1411 -209.270092) (xy 62.151122 -209.26968)
			(xy 62.169641 -209.262009) (xy 62.183813 -209.247834) (xy 62.191482 -209.229314) (xy 62.1919 -209.219292)
			(xy 62.1919 -208.114138) (xy 62.19063 -208.108804) (xy 62.186367 -208.088368) (xy 62.181782 -208.046873)
			(xy 62.181486 -208.026) (xy 62.181772 -208.005126) (xy 62.186358 -207.96363) (xy 62.19063 -207.943196)
			(xy 62.1919 -207.937862) (xy 62.1919 -207.3402) (xy 62.192266 -207.315193) (xy 62.198895 -207.26562)
			(xy 62.205108 -207.241394) (xy 62.20714 -207.23479) (xy 62.20714 -207.190594) (xy 62.206886 -207.190594)
			(xy 62.207305 -207.168268) (xy 62.215709 -207.124423) (xy 62.232545 -207.083076) (xy 62.25716 -207.045831)
			(xy 62.288599 -207.014134) (xy 62.325641 -206.989216) (xy 62.366849 -206.972042) (xy 62.410624 -206.96328)
			(xy 62.432946 -206.962756) (xy 62.700408 -206.962756) (xy 62.700408 -206.977234) (xy 62.715648 -207.001364)
			(xy 62.728602 -207.007968) (xy 62.74435 -207.01635) (xy 62.750134 -207.019328) (xy 62.762738 -207.022538)
			(xy 62.769242 -207.0227) (xy 63.156846 -207.0227) (xy 63.163351 -207.022554) (xy 63.175955 -207.019334)
			(xy 63.181738 -207.01635) (xy 63.197486 -207.007968) (xy 63.22568 -206.993998) (xy 63.22568 -206.992728)
			(xy 63.255144 -206.962756) (xy 63.493142 -206.962756) (xy 63.513198 -206.963263) (xy 63.552678 -206.970366)
			(xy 63.590285 -206.984324) (xy 63.624839 -207.004698) (xy 63.655256 -207.03085) (xy 63.68058 -207.061959)
			(xy 63.700019 -207.097048) (xy 63.71296 -207.135017) (xy 63.716408 -207.15478) (xy 63.717678 -207.162908)
			(xy 63.72479 -207.177132) (xy 63.940182 -207.392524) (xy 63.960453 -207.413511) (xy 63.994804 -207.460674)
			(xy 64.021345 -207.512635) (xy 64.039422 -207.568111) (xy 64.048588 -207.625733) (xy 64.049148 -207.654906)
			(xy 64.049148 -208.166462) (xy 64.050164 -208.171796) (xy 64.053212 -208.186782) (xy 64.055519 -208.196798)
			(xy 64.066731 -208.213995) (xy 64.08378 -208.225431) (xy 64.103946 -208.229279) (xy 64.124008 -208.224925)
			(xy 64.140765 -208.213065) (xy 64.151541 -208.195591) (xy 64.153542 -208.185512) (xy 64.158044 -208.158754)
			(xy 64.173606 -208.106773) (xy 64.196379 -208.057523) (xy 64.225902 -208.011998) (xy 64.261581 -207.971117)
			(xy 64.302693 -207.935707) (xy 64.34841 -207.906481) (xy 64.397808 -207.88403) (xy 64.449889 -207.868808)
			(xy 64.503602 -207.861122) (xy 64.530732 -207.860646) (xy 64.557978 -207.861226) (xy 64.611916 -207.868986)
			(xy 64.664201 -207.884342) (xy 64.713768 -207.906982) (xy 64.759609 -207.936445) (xy 64.80079 -207.972133)
			(xy 64.836474 -208.013317) (xy 64.865933 -208.05916) (xy 64.88857 -208.108729) (xy 64.903921 -208.161015)
			(xy 64.911676 -208.214954) (xy 64.911676 -208.269446) (xy 64.903921 -208.323385) (xy 64.88857 -208.375671)
			(xy 64.865934 -208.42524) (xy 64.840929 -208.46415) (xy 69.238366 -208.46415) (xy 69.242437 -208.408528)
			(xy 69.254563 -208.354091) (xy 69.274486 -208.302) (xy 69.301782 -208.253365) (xy 69.335868 -208.209222)
			(xy 69.376017 -208.170513) (xy 69.421375 -208.138062) (xy 69.470975 -208.112561) (xy 69.523759 -208.094554)
			(xy 69.578602 -208.084424) (xy 69.634336 -208.082387) (xy 69.689773 -208.088487) (xy 69.74373 -208.102593)
			(xy 69.795059 -208.124405) (xy 69.842665 -208.153459) (xy 69.885533 -208.189134) (xy 69.92275 -208.230671)
			(xy 69.953523 -208.277184) (xy 69.977195 -208.327681) (xy 69.993263 -208.381088) (xy 70.001383 -208.436264)
			(xy 70.001892 -208.46415) (xy 70.001383 -208.492036) (xy 69.993263 -208.547212) (xy 69.979356 -208.593436)
			(xy 119.926098 -208.593436) (xy 119.930169 -208.537814) (xy 119.942295 -208.483377) (xy 119.962218 -208.431286)
			(xy 119.989514 -208.382651) (xy 120.0236 -208.338508) (xy 120.063749 -208.299799) (xy 120.109107 -208.267348)
			(xy 120.158707 -208.241847) (xy 120.211491 -208.22384) (xy 120.266334 -208.21371) (xy 120.322068 -208.211673)
			(xy 120.377505 -208.217773) (xy 120.431462 -208.231879) (xy 120.482791 -208.253691) (xy 120.530397 -208.282745)
			(xy 120.573265 -208.31842) (xy 120.610482 -208.359957) (xy 120.641255 -208.40647) (xy 120.664927 -208.456967)
			(xy 120.680995 -208.510374) (xy 120.689115 -208.56555) (xy 120.689624 -208.593436) (xy 120.689115 -208.621322)
			(xy 120.680995 -208.676498) (xy 120.664927 -208.729905) (xy 120.641255 -208.780402) (xy 120.610482 -208.826915)
			(xy 120.573265 -208.868452) (xy 120.530397 -208.904127) (xy 120.482791 -208.933181) (xy 120.431462 -208.954993)
			(xy 120.377505 -208.969099) (xy 120.322068 -208.975199) (xy 120.266334 -208.973162) (xy 120.211491 -208.963032)
			(xy 120.158707 -208.945025) (xy 120.109107 -208.919524) (xy 120.063749 -208.887073) (xy 120.0236 -208.848364)
			(xy 119.989514 -208.804221) (xy 119.962218 -208.755586) (xy 119.942295 -208.703495) (xy 119.930169 -208.649058)
			(xy 119.926098 -208.593436) (xy 69.979356 -208.593436) (xy 69.977195 -208.600619) (xy 69.953523 -208.651116)
			(xy 69.92275 -208.697629) (xy 69.885533 -208.739166) (xy 69.842665 -208.774841) (xy 69.795059 -208.803895)
			(xy 69.74373 -208.825707) (xy 69.689773 -208.839813) (xy 69.634336 -208.845913) (xy 69.578602 -208.843876)
			(xy 69.523759 -208.833746) (xy 69.470975 -208.815739) (xy 69.421375 -208.790238) (xy 69.376017 -208.757787)
			(xy 69.335868 -208.719078) (xy 69.301782 -208.674935) (xy 69.274486 -208.6263) (xy 69.254563 -208.574209)
			(xy 69.242437 -208.519772) (xy 69.238366 -208.46415) (xy 64.840929 -208.46415) (xy 64.836474 -208.471083)
			(xy 64.80079 -208.512267) (xy 64.759609 -208.547955) (xy 64.713768 -208.577418) (xy 64.664201 -208.600058)
			(xy 64.611916 -208.615414) (xy 64.557978 -208.623174) (xy 64.530732 -208.623662) (xy 64.501632 -208.623082)
			(xy 64.444106 -208.614252) (xy 64.388587 -208.596793) (xy 64.336362 -208.571107) (xy 64.288641 -208.537792)
			(xy 64.24653 -208.497619) (xy 64.211005 -208.451519) (xy 64.196468 -208.426304) (xy 64.18961 -208.413604)
			(xy 64.16548 -208.399634) (xy 64.04737 -208.401412) (xy 64.023748 -208.416144) (xy 64.017144 -208.428844)
			(xy 64.00481 -208.451911) (xy 63.974792 -208.494748) (xy 63.939203 -208.533081) (xy 63.898709 -208.566191)
			(xy 63.85407 -208.593457) (xy 63.806124 -208.614367) (xy 63.75577 -208.628529) (xy 63.703954 -208.635677)
			(xy 63.6778 -208.636108) (xy 63.650549 -208.635622) (xy 63.596601 -208.627866) (xy 63.544306 -208.612511)
			(xy 63.494729 -208.589869) (xy 63.448879 -208.560403) (xy 63.407688 -208.524712) (xy 63.371997 -208.483521)
			(xy 63.342531 -208.437671) (xy 63.319889 -208.388094) (xy 63.304534 -208.335799) (xy 63.296778 -208.281851)
			(xy 63.296292 -208.2546) (xy 63.296578 -208.233726) (xy 63.301164 -208.19223) (xy 63.305436 -208.171796)
			(xy 63.306452 -208.166462) (xy 63.306452 -207.829658) (xy 63.30601 -207.819687) (xy 63.298411 -207.801252)
			(xy 63.29172 -207.793844) (xy 63.170308 -207.672432) (xy 63.162905 -207.665742) (xy 63.144462 -207.658173)
			(xy 63.134494 -207.6577) (xy 62.984888 -207.6577) (xy 62.97488 -207.658178) (xy 62.956388 -207.665842)
			(xy 62.942235 -207.679998) (xy 62.934576 -207.698491) (xy 62.934088 -207.7085) (xy 62.934088 -207.937862)
			(xy 62.935358 -207.943196) (xy 62.939621 -207.963632) (xy 62.944206 -208.005127) (xy 62.944502 -208.026)
			(xy 62.944216 -208.046874) (xy 62.93963 -208.08837) (xy 62.935358 -208.108804) (xy 62.934088 -208.114138)
			(xy 62.934088 -208.82356) (xy 62.934774 -208.834873) (xy 62.944501 -208.855306) (xy 62.952884 -208.86293)
			(xy 63.022988 -208.92008) (xy 63.044832 -208.925414) (xy 63.056262 -208.923128) (xy 63.075292 -208.919461)
			(xy 63.113846 -208.915516) (xy 63.133224 -208.915254) (xy 63.160471 -208.915818) (xy 63.214411 -208.923576)
			(xy 63.266698 -208.938932) (xy 63.316267 -208.961572) (xy 63.36211 -208.991036) (xy 63.403293 -209.026724)
			(xy 63.438978 -209.06791) (xy 63.468439 -209.113754) (xy 63.491076 -209.163325) (xy 63.506429 -209.215612)
			(xy 63.514184 -209.269553) (xy 63.514184 -209.324047) (xy 63.506429 -209.377988) (xy 63.505145 -209.38236)
			(xy 64.461388 -209.38236) (xy 64.465459 -209.326738) (xy 64.477585 -209.272301) (xy 64.497508 -209.22021)
			(xy 64.524804 -209.171575) (xy 64.55889 -209.127432) (xy 64.599039 -209.088723) (xy 64.644397 -209.056272)
			(xy 64.693997 -209.030771) (xy 64.746781 -209.012764) (xy 64.801624 -209.002634) (xy 64.857358 -209.000597)
			(xy 64.912795 -209.006697) (xy 64.966752 -209.020803) (xy 65.018081 -209.042615) (xy 65.065687 -209.071669)
			(xy 65.108555 -209.107344) (xy 65.145772 -209.148881) (xy 65.176545 -209.195394) (xy 65.200217 -209.245891)
			(xy 65.216285 -209.299298) (xy 65.224405 -209.354474) (xy 65.224914 -209.38236) (xy 65.224405 -209.410246)
			(xy 65.216285 -209.465422) (xy 65.200217 -209.518829) (xy 65.176545 -209.569326) (xy 65.145772 -209.615839)
			(xy 65.108555 -209.657376) (xy 65.065687 -209.693051) (xy 65.018081 -209.722105) (xy 64.966752 -209.743917)
			(xy 64.912795 -209.758023) (xy 64.857358 -209.764123) (xy 64.801624 -209.762086) (xy 64.746781 -209.751956)
			(xy 64.693997 -209.733949) (xy 64.644397 -209.708448) (xy 64.599039 -209.675997) (xy 64.55889 -209.637288)
			(xy 64.524804 -209.593145) (xy 64.497508 -209.54451) (xy 64.477585 -209.492419) (xy 64.465459 -209.437982)
			(xy 64.461388 -209.38236) (xy 63.505145 -209.38236) (xy 63.491076 -209.430275) (xy 63.468439 -209.479846)
			(xy 63.438978 -209.52569) (xy 63.403293 -209.566876) (xy 63.36211 -209.602564) (xy 63.316267 -209.632028)
			(xy 63.266698 -209.654668) (xy 63.214411 -209.670024) (xy 63.160471 -209.677782) (xy 63.133224 -209.67827)
			(xy 63.113845 -209.678034) (xy 63.075288 -209.674086) (xy 63.056262 -209.670396) (xy 63.044832 -209.66811)
			(xy 63.022988 -209.673444) (xy 62.952884 -209.730594) (xy 62.944453 -209.738186) (xy 62.934694 -209.758634)
			(xy 62.934088 -209.769964) (xy 62.934088 -209.775806) (xy 62.933497 -209.804964) (xy 62.924363 -209.862561)
			(xy 62.906337 -209.918021) (xy 62.879861 -209.969981) (xy 62.845587 -210.017163) (xy 62.825376 -210.038188)
			(xy 62.568582 -210.294982) (xy 62.546626 -210.316114) (xy 62.497096 -210.351608) (xy 62.442425 -210.37852)
			(xy 62.384088 -210.396123) (xy 62.353952 -210.400646) (xy 62.334902 -210.403186) (xy 62.309756 -210.431888)
			(xy 62.309756 -210.6676) (xy 62.309163 -210.684311) (xy 62.300515 -210.716595) (xy 62.283807 -210.745541)
			(xy 62.260179 -210.769178) (xy 62.231239 -210.785896) (xy 62.198959 -210.794557) (xy 62.182248 -210.795108)
			(xy 58.753248 -210.795108) (xy 58.736529 -210.794569) (xy 58.704227 -210.785925) (xy 58.675265 -210.769213)
			(xy 58.651616 -210.745573) (xy 58.634894 -210.716617) (xy 58.626237 -210.684319) (xy 58.62574 -210.6676)
			(xy 47.8155 -210.6676) (xy 47.8155 -211.078572) (xy 63.703452 -211.078572) (xy 63.707523 -211.02295)
			(xy 63.719649 -210.968513) (xy 63.739572 -210.916422) (xy 63.766868 -210.867787) (xy 63.800954 -210.823644)
			(xy 63.841103 -210.784935) (xy 63.886461 -210.752484) (xy 63.936061 -210.726983) (xy 63.988845 -210.708976)
			(xy 64.043688 -210.698846) (xy 64.099422 -210.696809) (xy 64.154859 -210.702909) (xy 64.208816 -210.717015)
			(xy 64.260145 -210.738827) (xy 64.307751 -210.767881) (xy 64.350619 -210.803556) (xy 64.387836 -210.845093)
			(xy 64.418609 -210.891606) (xy 64.442281 -210.942103) (xy 64.458349 -210.99551) (xy 64.466469 -211.050686)
			(xy 64.466667 -211.061554) (xy 69.39102 -211.061554) (xy 69.395091 -211.005932) (xy 69.407217 -210.951495)
			(xy 69.42714 -210.899404) (xy 69.454436 -210.850769) (xy 69.488522 -210.806626) (xy 69.528671 -210.767917)
			(xy 69.574029 -210.735466) (xy 69.623629 -210.709965) (xy 69.676413 -210.691958) (xy 69.731256 -210.681828)
			(xy 69.78699 -210.679791) (xy 69.842427 -210.685891) (xy 69.896384 -210.699997) (xy 69.947713 -210.721809)
			(xy 69.995319 -210.750863) (xy 70.038187 -210.786538) (xy 70.075404 -210.828075) (xy 70.106177 -210.874588)
			(xy 70.129849 -210.925085) (xy 70.145917 -210.978492) (xy 70.154037 -211.033668) (xy 70.154546 -211.061554)
			(xy 70.154037 -211.08944) (xy 70.145917 -211.144616) (xy 70.129849 -211.198023) (xy 70.106177 -211.24852)
			(xy 70.075404 -211.295033) (xy 70.038187 -211.33657) (xy 69.995319 -211.372245) (xy 69.947713 -211.401299)
			(xy 69.896384 -211.423111) (xy 69.842427 -211.437217) (xy 69.78699 -211.443317) (xy 69.731256 -211.44128)
			(xy 69.676413 -211.43115) (xy 69.623629 -211.413143) (xy 69.574029 -211.387642) (xy 69.528671 -211.355191)
			(xy 69.488522 -211.316482) (xy 69.454436 -211.272339) (xy 69.42714 -211.223704) (xy 69.407217 -211.171613)
			(xy 69.395091 -211.117176) (xy 69.39102 -211.061554) (xy 64.466667 -211.061554) (xy 64.466978 -211.078572)
			(xy 64.466469 -211.106458) (xy 64.458349 -211.161634) (xy 64.442281 -211.215041) (xy 64.418609 -211.265538)
			(xy 64.387836 -211.312051) (xy 64.350619 -211.353588) (xy 64.307751 -211.389263) (xy 64.260145 -211.418317)
			(xy 64.208816 -211.440129) (xy 64.154859 -211.454235) (xy 64.099422 -211.460335) (xy 64.043688 -211.458298)
			(xy 63.988845 -211.448168) (xy 63.936061 -211.430161) (xy 63.886461 -211.40466) (xy 63.841103 -211.372209)
			(xy 63.800954 -211.3335) (xy 63.766868 -211.289357) (xy 63.739572 -211.240722) (xy 63.719649 -211.188631)
			(xy 63.707523 -211.134194) (xy 63.703452 -211.078572) (xy 47.8155 -211.078572) (xy 47.8155 -213.2076)
			(xy 55.705756 -213.2076) (xy 55.705756 -211.9376) (xy 55.706337 -211.920888) (xy 55.714986 -211.888603)
			(xy 55.731696 -211.859655) (xy 55.755326 -211.836018) (xy 55.784269 -211.8193) (xy 55.816552 -211.810642)
			(xy 55.833264 -211.810092) (xy 59.262264 -211.810092) (xy 59.278984 -211.81062) (xy 59.311286 -211.819267)
			(xy 59.340248 -211.835982) (xy 59.363896 -211.859623) (xy 59.380619 -211.888581) (xy 59.389275 -211.92088)
			(xy 59.389772 -211.9376) (xy 59.389772 -212.150706) (xy 59.390394 -212.16063) (xy 59.398059 -212.178947)
			(xy 59.412089 -212.192998) (xy 59.430395 -212.20069) (xy 59.440318 -212.201252) (xy 60.443872 -212.201252)
			(xy 60.452254 -212.198204) (xy 60.48291 -212.187824) (xy 60.546643 -212.17658) (xy 60.579 -212.175852)
			(xy 62.126622 -212.175852) (xy 62.131956 -212.174836) (xy 62.143563 -212.172496) (xy 62.167107 -212.169952)
			(xy 62.178946 -212.169756) (xy 62.446408 -212.169756) (xy 62.446408 -212.184234) (xy 62.461648 -212.208364)
			(xy 62.474602 -212.214968) (xy 62.49035 -212.22335) (xy 62.496134 -212.226328) (xy 62.508738 -212.229538)
			(xy 62.515242 -212.2297) (xy 62.902846 -212.2297) (xy 62.909351 -212.229554) (xy 62.921955 -212.226334)
			(xy 62.927738 -212.22335) (xy 62.943486 -212.214968) (xy 62.97168 -212.200998) (xy 62.97168 -212.199728)
			(xy 63.001144 -212.169756) (xy 63.239142 -212.169756) (xy 63.250982 -212.169942) (xy 63.274527 -212.172483)
			(xy 63.286132 -212.174836) (xy 63.291466 -212.175852) (xy 63.945262 -212.175852) (xy 63.950596 -212.174836)
			(xy 63.971032 -212.170573) (xy 64.012527 -212.165988) (xy 64.0334 -212.165692) (xy 64.060651 -212.166178)
			(xy 64.114599 -212.173934) (xy 64.166894 -212.189289) (xy 64.216471 -212.211931) (xy 64.262321 -212.241397)
			(xy 64.303512 -212.277088) (xy 64.339203 -212.318279) (xy 64.368669 -212.364129) (xy 64.391311 -212.413706)
			(xy 64.4053 -212.461348) (xy 90.60256 -212.461348) (xy 90.606631 -212.405726) (xy 90.618757 -212.351289)
			(xy 90.63868 -212.299198) (xy 90.665976 -212.250563) (xy 90.700062 -212.20642) (xy 90.740211 -212.167711)
			(xy 90.785569 -212.13526) (xy 90.835169 -212.109759) (xy 90.887953 -212.091752) (xy 90.942796 -212.081622)
			(xy 90.99853 -212.079585) (xy 91.053967 -212.085685) (xy 91.107924 -212.099791) (xy 91.159253 -212.121603)
			(xy 91.206859 -212.150657) (xy 91.249727 -212.186332) (xy 91.286944 -212.227869) (xy 91.317717 -212.274382)
			(xy 91.341389 -212.324879) (xy 91.357457 -212.378286) (xy 91.365577 -212.433462) (xy 91.366086 -212.461348)
			(xy 91.365577 -212.489234) (xy 91.357457 -212.54441) (xy 91.341389 -212.597817) (xy 91.317717 -212.648314)
			(xy 91.286944 -212.694827) (xy 91.249727 -212.736364) (xy 91.206859 -212.772039) (xy 91.159253 -212.801093)
			(xy 91.107924 -212.822905) (xy 91.053967 -212.837011) (xy 90.99853 -212.843111) (xy 90.942796 -212.841074)
			(xy 90.887953 -212.830944) (xy 90.835169 -212.812937) (xy 90.785569 -212.787436) (xy 90.740211 -212.754985)
			(xy 90.700062 -212.716276) (xy 90.665976 -212.672133) (xy 90.63868 -212.623498) (xy 90.618757 -212.571407)
			(xy 90.606631 -212.51697) (xy 90.60256 -212.461348) (xy 64.4053 -212.461348) (xy 64.406666 -212.466001)
			(xy 64.414422 -212.519949) (xy 64.414422 -212.574451) (xy 64.406666 -212.628399) (xy 64.391311 -212.680694)
			(xy 64.368669 -212.730271) (xy 64.339203 -212.776121) (xy 64.303512 -212.817312) (xy 64.262321 -212.853003)
			(xy 64.216471 -212.882469) (xy 64.166894 -212.905111) (xy 64.114599 -212.920466) (xy 64.060651 -212.928222)
			(xy 64.0334 -212.928708) (xy 64.012526 -212.928422) (xy 63.97103 -212.923836) (xy 63.950596 -212.919564)
			(xy 63.945262 -212.918548) (xy 63.291466 -212.918548) (xy 63.286132 -212.919564) (xy 63.274525 -212.921906)
			(xy 63.250982 -212.924449) (xy 63.239142 -212.924644) (xy 62.97168 -212.924644) (xy 62.97168 -212.910166)
			(xy 62.95644 -212.886036) (xy 62.943486 -212.879432) (xy 62.927738 -212.87105) (xy 62.921956 -212.868068)
			(xy 62.90935 -212.864861) (xy 62.902846 -212.8647) (xy 62.515242 -212.8647) (xy 62.508736 -212.864841)
			(xy 62.496132 -212.868064) (xy 62.49035 -212.87105) (xy 62.474602 -212.879432) (xy 62.446408 -212.893402)
			(xy 62.446408 -212.894672) (xy 62.416944 -212.924644) (xy 62.178946 -212.924644) (xy 62.167106 -212.92446)
			(xy 62.143561 -212.921918) (xy 62.131956 -212.919564) (xy 62.126622 -212.918548) (xy 60.715144 -212.918548)
			(xy 60.705492 -212.922612) (xy 60.681458 -212.932545) (xy 60.631375 -212.946554) (xy 60.579856 -212.953647)
			(xy 60.553854 -212.954108) (xy 60.5536 -212.954108) (xy 60.532726 -212.953822) (xy 60.49123 -212.949236)
			(xy 60.470796 -212.944964) (xy 60.465462 -212.943948) (xy 59.440318 -212.943948) (xy 59.430368 -212.944404)
			(xy 59.412001 -212.952079) (xy 59.397936 -212.966165) (xy 59.390289 -212.984543) (xy 59.389772 -212.994494)
			(xy 59.389772 -213.2076) (xy 59.389311 -213.224324) (xy 59.380652 -213.256633) (xy 59.363925 -213.285599)
			(xy 59.34027 -213.309247) (xy 59.3113 -213.325966) (xy 59.278989 -213.334616) (xy 59.262264 -213.335108)
			(xy 55.833264 -213.335108) (xy 55.816547 -213.334594) (xy 55.784255 -213.325934) (xy 55.755304 -213.309211)
			(xy 55.731667 -213.285567) (xy 55.714953 -213.256611) (xy 55.706301 -213.224317) (xy 55.705756 -213.2076)
			(xy 47.8155 -213.2076) (xy 47.8155 -215.359996) (xy 69.499224 -215.359996) (xy 69.503295 -215.304374)
			(xy 69.515421 -215.249937) (xy 69.535344 -215.197846) (xy 69.56264 -215.149211) (xy 69.596726 -215.105068)
			(xy 69.636875 -215.066359) (xy 69.682233 -215.033908) (xy 69.731833 -215.008407) (xy 69.784617 -214.9904)
			(xy 69.83946 -214.98027) (xy 69.895194 -214.978233) (xy 69.950631 -214.984333) (xy 70.004588 -214.998439)
			(xy 70.055917 -215.020251) (xy 70.103523 -215.049305) (xy 70.146391 -215.08498) (xy 70.183608 -215.126517)
			(xy 70.214381 -215.17303) (xy 70.238053 -215.223527) (xy 70.254121 -215.276934) (xy 70.262241 -215.33211)
			(xy 70.26275 -215.359996) (xy 70.262241 -215.387882) (xy 70.254121 -215.443058) (xy 70.238053 -215.496465)
			(xy 70.214381 -215.546962) (xy 70.183608 -215.593475) (xy 70.146391 -215.635012) (xy 70.103523 -215.670687)
			(xy 70.055917 -215.699741) (xy 70.004588 -215.721553) (xy 69.950631 -215.735659) (xy 69.895194 -215.741759)
			(xy 69.83946 -215.739722) (xy 69.784617 -215.729592) (xy 69.731833 -215.711585) (xy 69.682233 -215.686084)
			(xy 69.636875 -215.653633) (xy 69.596726 -215.614924) (xy 69.56264 -215.570781) (xy 69.535344 -215.522146)
			(xy 69.515421 -215.470055) (xy 69.503295 -215.415618) (xy 69.499224 -215.359996) (xy 47.8155 -215.359996)
			(xy 47.8155 -216.714651) (xy 68.122778 -216.714651) (xy 68.122778 -216.660149) (xy 68.130534 -216.606201)
			(xy 68.145889 -216.553906) (xy 68.168531 -216.504329) (xy 68.197997 -216.458479) (xy 68.233688 -216.417288)
			(xy 68.274879 -216.381597) (xy 68.320729 -216.352131) (xy 68.370306 -216.329489) (xy 68.422601 -216.314134)
			(xy 68.476549 -216.306378) (xy 68.5038 -216.305892) (xy 68.524674 -216.306178) (xy 68.56617 -216.310764)
			(xy 68.586604 -216.315036) (xy 68.591938 -216.316052) (xy 70.602094 -216.316052) (xy 70.631264 -216.316631)
			(xy 70.688876 -216.325817) (xy 70.744343 -216.343901) (xy 70.796299 -216.370439) (xy 70.843464 -216.404776)
			(xy 70.864476 -216.425018) (xy 71.410068 -216.97061) (xy 71.424292 -216.977722) (xy 71.43242 -216.978992)
			(xy 71.452192 -216.982401) (xy 71.490162 -216.995354) (xy 71.525253 -217.014801) (xy 71.556365 -217.040131)
			(xy 71.582522 -217.070551) (xy 71.602904 -217.105107) (xy 71.616873 -217.142716) (xy 71.62399 -217.182199)
			(xy 71.624444 -217.202258) (xy 71.624444 -217.46972) (xy 71.609966 -217.46972) (xy 71.585836 -217.48496)
			(xy 71.579232 -217.497914) (xy 71.57085 -217.513662) (xy 71.567868 -217.519444) (xy 71.564661 -217.53205)
			(xy 71.5645 -217.538554) (xy 71.5645 -217.738706) (xy 71.565095 -217.748633) (xy 71.572765 -217.766956)
			(xy 71.586804 -217.781008) (xy 71.605119 -217.788695) (xy 71.615046 -217.789252) (xy 72.476106 -217.789252)
			(xy 72.485208 -217.78887) (xy 72.502259 -217.782488) (xy 72.50938 -217.776806) (xy 72.532556 -217.757244)
			(xy 72.582728 -217.723171) (xy 72.636601 -217.695314) (xy 72.693407 -217.674069) (xy 72.752339 -217.659739)
			(xy 72.812557 -217.652528) (xy 72.842882 -217.652092) (xy 72.84339 -217.652092) (xy 72.873711 -217.652573)
			(xy 72.933922 -217.659803) (xy 72.992846 -217.674138) (xy 73.049649 -217.695374) (xy 73.103526 -217.723211)
			(xy 73.153712 -217.757254) (xy 73.176892 -217.776806) (xy 73.183994 -217.782517) (xy 73.201059 -217.788884)
			(xy 73.210166 -217.789252) (xy 78.996794 -217.789252) (xy 79.00675 -217.788756) (xy 79.025148 -217.781137)
			(xy 79.039231 -217.767059) (xy 79.046853 -217.748662) (xy 79.04734 -217.738706) (xy 79.04734 -217.5256)
			(xy 79.047789 -217.508875) (xy 79.056449 -217.476564) (xy 79.073178 -217.447597) (xy 79.096835 -217.423948)
			(xy 79.125809 -217.40723) (xy 79.158122 -217.398583) (xy 79.174848 -217.398092) (xy 82.603848 -217.398092)
			(xy 82.620565 -217.398595) (xy 82.652858 -217.407259) (xy 82.681809 -217.423983) (xy 82.705446 -217.44763)
			(xy 82.72216 -217.476587) (xy 82.730811 -217.508883) (xy 82.731356 -217.5256) (xy 82.731356 -218.7956)
			(xy 82.730763 -218.812311) (xy 82.722115 -218.844595) (xy 82.705407 -218.873541) (xy 82.681779 -218.897178)
			(xy 82.652839 -218.913896) (xy 82.620559 -218.922557) (xy 82.603848 -218.923108) (xy 79.174848 -218.923108)
			(xy 79.158129 -218.922569) (xy 79.125827 -218.913925) (xy 79.096865 -218.897213) (xy 79.073216 -218.873573)
			(xy 79.056494 -218.844617) (xy 79.047837 -218.812319) (xy 79.04734 -218.7956) (xy 79.04734 -218.582494)
			(xy 79.046965 -218.57251) (xy 79.039359 -218.55405) (xy 79.02524 -218.539934) (xy 79.006778 -218.532333)
			(xy 78.996794 -218.531948) (xy 73.210166 -218.531948) (xy 73.201062 -218.532317) (xy 73.184012 -218.538708)
			(xy 73.176892 -218.544394) (xy 73.153727 -218.563969) (xy 73.103552 -218.598041) (xy 73.049677 -218.625896)
			(xy 72.992869 -218.647138) (xy 72.933935 -218.661466) (xy 72.873715 -218.668674) (xy 72.84339 -218.669108)
			(xy 72.842882 -218.669108) (xy 72.81256 -218.668644) (xy 72.752349 -218.66141) (xy 72.693424 -218.647072)
			(xy 72.636621 -218.625833) (xy 72.582745 -218.597993) (xy 72.532559 -218.563947) (xy 72.50938 -218.544394)
			(xy 72.502257 -218.538713) (xy 72.485208 -218.532328) (xy 72.476106 -218.531948) (xy 71.218806 -218.531948)
			(xy 71.193824 -218.531518) (xy 71.144314 -218.524791) (xy 71.096154 -218.511483) (xy 71.050214 -218.491836)
			(xy 71.02856 -218.47937) (xy 71.01967 -218.475306) (xy 71.000739 -218.468103) (xy 70.965634 -218.447908)
			(xy 70.934689 -218.421779) (xy 70.908897 -218.390554) (xy 70.889082 -218.355231) (xy 70.87588 -218.316943)
			(xy 70.87235 -218.296998) (xy 70.86981 -218.287346) (xy 70.859485 -218.256682) (xy 70.848372 -218.192948)
			(xy 70.847712 -218.1606) (xy 70.848258 -218.130403) (xy 70.857965 -218.070796) (xy 70.867016 -218.041982)
			(xy 70.869556 -218.034108) (xy 70.869556 -217.994992) (xy 70.886574 -217.994992) (xy 70.893859 -217.980796)
			(xy 70.910518 -217.95358) (xy 70.919848 -217.940636) (xy 70.924348 -217.933981) (xy 70.929263 -217.918694)
			(xy 70.9295 -217.910664) (xy 70.9295 -217.560906) (xy 70.929047 -217.550936) (xy 70.921457 -217.532499)
			(xy 70.914768 -217.525092) (xy 70.463156 -217.07348) (xy 70.455731 -217.066818) (xy 70.437305 -217.059231)
			(xy 70.427342 -217.058748) (xy 68.591938 -217.058748) (xy 68.586604 -217.059764) (xy 68.566168 -217.064027)
			(xy 68.524673 -217.068612) (xy 68.5038 -217.068908) (xy 68.476549 -217.068422) (xy 68.422601 -217.060666)
			(xy 68.370306 -217.045311) (xy 68.320729 -217.022669) (xy 68.274879 -216.993203) (xy 68.233688 -216.957512)
			(xy 68.197997 -216.916321) (xy 68.168531 -216.870471) (xy 68.145889 -216.820894) (xy 68.130534 -216.768599)
			(xy 68.122778 -216.714651) (xy 47.8155 -216.714651) (xy 47.8155 -219.584851) (xy 69.570578 -219.584851)
			(xy 69.570578 -219.530349) (xy 69.578334 -219.476401) (xy 69.593689 -219.424106) (xy 69.616331 -219.374529)
			(xy 69.645797 -219.328679) (xy 69.681488 -219.287488) (xy 69.722679 -219.251797) (xy 69.768529 -219.222331)
			(xy 69.818106 -219.199689) (xy 69.870401 -219.184334) (xy 69.924349 -219.176578) (xy 69.9516 -219.176092)
			(xy 69.972474 -219.176378) (xy 70.01397 -219.180964) (xy 70.034404 -219.185236) (xy 70.039738 -219.186252)
			(xy 70.906894 -219.186252) (xy 70.936064 -219.186831) (xy 70.993676 -219.196017) (xy 71.049143 -219.214101)
			(xy 71.101099 -219.240639) (xy 71.148264 -219.274976) (xy 71.169276 -219.295218) (xy 71.410068 -219.53601)
			(xy 71.424292 -219.543122) (xy 71.43242 -219.544392) (xy 71.452192 -219.547801) (xy 71.490162 -219.560754)
			(xy 71.525253 -219.580201) (xy 71.556365 -219.605531) (xy 71.582522 -219.635951) (xy 71.602904 -219.670507)
			(xy 71.616873 -219.708116) (xy 71.62399 -219.747599) (xy 71.624444 -219.767658) (xy 71.624444 -220.03512)
			(xy 71.609966 -220.03512) (xy 71.585836 -220.05036) (xy 71.579232 -220.063314) (xy 71.57085 -220.079062)
			(xy 71.567868 -220.084844) (xy 71.564661 -220.09745) (xy 71.5645 -220.103954) (xy 71.5645 -220.278706)
			(xy 71.565095 -220.288633) (xy 71.572765 -220.306956) (xy 71.586804 -220.321008) (xy 71.605119 -220.328695)
			(xy 71.615046 -220.329252) (xy 72.650604 -220.329252) (xy 72.659706 -220.328869) (xy 72.676757 -220.322488)
			(xy 72.683878 -220.316806) (xy 72.707054 -220.297245) (xy 72.757227 -220.263172) (xy 72.811099 -220.235314)
			(xy 72.867906 -220.21407) (xy 72.926837 -220.199739) (xy 72.987056 -220.192528) (xy 73.01738 -220.192092)
			(xy 73.017888 -220.192092) (xy 73.048209 -220.192574) (xy 73.10842 -220.199804) (xy 73.167344 -220.214138)
			(xy 73.224147 -220.235375) (xy 73.278024 -220.263211) (xy 73.32821 -220.297254) (xy 73.35139 -220.316806)
			(xy 73.358493 -220.322516) (xy 73.375557 -220.328884) (xy 73.384664 -220.329252) (xy 76.07681 -220.329252)
			(xy 76.086767 -220.328768) (xy 76.105166 -220.321145) (xy 76.119247 -220.307062) (xy 76.126869 -220.288664)
			(xy 76.127356 -220.278706) (xy 76.127356 -220.0656) (xy 76.127937 -220.048888) (xy 76.136586 -220.016603)
			(xy 76.153296 -219.987655) (xy 76.176926 -219.964018) (xy 76.205869 -219.9473) (xy 76.238152 -219.938642)
			(xy 76.254864 -219.938092) (xy 79.683864 -219.938092) (xy 79.700584 -219.93862) (xy 79.732886 -219.947267)
			(xy 79.761848 -219.963982) (xy 79.785496 -219.987623) (xy 79.802219 -220.016581) (xy 79.810875 -220.04888)
			(xy 79.811372 -220.0656) (xy 79.811372 -221.3356) (xy 79.810911 -221.352324) (xy 79.802252 -221.384633)
			(xy 79.785525 -221.413599) (xy 79.76187 -221.437247) (xy 79.7329 -221.453966) (xy 79.700589 -221.462616)
			(xy 79.683864 -221.463108) (xy 76.254864 -221.463108) (xy 76.238147 -221.462594) (xy 76.205855 -221.453934)
			(xy 76.176904 -221.437211) (xy 76.153267 -221.413567) (xy 76.136553 -221.384611) (xy 76.127901 -221.352317)
			(xy 76.127356 -221.3356) (xy 76.127356 -221.122494) (xy 76.126965 -221.112512) (xy 76.119362 -221.094055)
			(xy 76.105248 -221.07994) (xy 76.086792 -221.072336) (xy 76.07681 -221.071948) (xy 73.384664 -221.071948)
			(xy 73.37556 -221.072316) (xy 73.35851 -221.078707) (xy 73.35139 -221.084394) (xy 73.328226 -221.10397)
			(xy 73.278051 -221.138042) (xy 73.224175 -221.165897) (xy 73.167367 -221.187139) (xy 73.108433 -221.201466)
			(xy 73.048213 -221.208674) (xy 73.017888 -221.209108) (xy 73.01738 -221.209108) (xy 72.987058 -221.208645)
			(xy 72.926847 -221.201411) (xy 72.867922 -221.187073) (xy 72.811119 -221.165833) (xy 72.757243 -221.137993)
			(xy 72.707057 -221.103948) (xy 72.683878 -221.084394) (xy 72.676755 -221.078712) (xy 72.659707 -221.072328)
			(xy 72.650604 -221.071948) (xy 71.244206 -221.071948) (xy 71.216937 -221.071454) (xy 71.162994 -221.063416)
			(xy 71.136764 -221.055946) (xy 71.129652 -221.05366) (xy 71.097394 -221.05366) (xy 71.097394 -221.053914)
			(xy 71.075068 -221.053495) (xy 71.031223 -221.045091) (xy 70.989876 -221.028255) (xy 70.952631 -221.00364)
			(xy 70.920934 -220.972201) (xy 70.896016 -220.935159) (xy 70.878842 -220.893951) (xy 70.87008 -220.850176)
			(xy 70.869556 -220.827854) (xy 70.869556 -220.560392) (xy 70.882256 -220.560392) (xy 70.90664 -220.545406)
			(xy 70.913244 -220.532452) (xy 70.922896 -220.514926) (xy 70.925973 -220.509033) (xy 70.929316 -220.496171)
			(xy 70.9295 -220.489526) (xy 70.9295 -220.126306) (xy 70.929047 -220.116336) (xy 70.921457 -220.097899)
			(xy 70.914768 -220.090492) (xy 70.767956 -219.94368) (xy 70.760531 -219.937018) (xy 70.742105 -219.929431)
			(xy 70.732142 -219.928948) (xy 70.039738 -219.928948) (xy 70.034404 -219.929964) (xy 70.013968 -219.934227)
			(xy 69.972473 -219.938812) (xy 69.9516 -219.939108) (xy 69.924349 -219.938622) (xy 69.870401 -219.930866)
			(xy 69.818106 -219.915511) (xy 69.768529 -219.892869) (xy 69.722679 -219.863403) (xy 69.681488 -219.827712)
			(xy 69.645797 -219.786521) (xy 69.616331 -219.740671) (xy 69.593689 -219.691094) (xy 69.578334 -219.638799)
			(xy 69.570578 -219.584851) (xy 47.8155 -219.584851) (xy 47.8155 -227.7618) (xy 58.62574 -227.7618)
			(xy 58.62574 -226.4918) (xy 58.626189 -226.475075) (xy 58.634849 -226.442764) (xy 58.651578 -226.413797)
			(xy 58.675235 -226.390148) (xy 58.704209 -226.37343) (xy 58.736522 -226.364783) (xy 58.753248 -226.364292)
			(xy 62.182248 -226.364292) (xy 62.198965 -226.364795) (xy 62.231258 -226.373459) (xy 62.260209 -226.390183)
			(xy 62.283846 -226.41383) (xy 62.30056 -226.442787) (xy 62.309211 -226.475083) (xy 62.309756 -226.4918)
			(xy 62.309756 -226.704906) (xy 62.310297 -226.71484) (xy 62.317978 -226.733173) (xy 62.332034 -226.747227)
			(xy 62.350368 -226.754904) (xy 62.360302 -226.755452) (xy 70.416674 -226.755452) (xy 70.427135 -226.754911)
			(xy 70.446293 -226.746492) (xy 70.460498 -226.731127) (xy 70.464426 -226.721416) (xy 70.501002 -226.61499)
			(xy 70.491858 -226.584002) (xy 70.478904 -226.573842) (xy 70.456485 -226.555621) (xy 70.416808 -226.513635)
			(xy 70.383919 -226.466144) (xy 70.358569 -226.414235) (xy 70.34134 -226.359096) (xy 70.332625 -226.30199)
			(xy 70.332092 -226.273106) (xy 70.332561 -226.245853) (xy 70.340317 -226.191903) (xy 70.355672 -226.139605)
			(xy 70.378314 -226.090025) (xy 70.407782 -226.044172) (xy 70.443475 -226.002979) (xy 70.484667 -225.967285)
			(xy 70.530519 -225.937817) (xy 70.580099 -225.915174) (xy 70.632397 -225.899818) (xy 70.686347 -225.892061)
			(xy 70.7136 -225.891598) (xy 70.734474 -225.891884) (xy 70.77597 -225.89647) (xy 70.796404 -225.900742)
			(xy 70.801738 -225.902012) (xy 72.7202 -225.902012) (xy 72.745207 -225.902378) (xy 72.79478 -225.909007)
			(xy 72.819006 -225.91522) (xy 72.82561 -225.917252) (xy 72.869806 -225.917252) (xy 72.869806 -225.916998)
			(xy 72.892132 -225.917405) (xy 72.935979 -225.92581) (xy 72.977328 -225.942647) (xy 73.014573 -225.967263)
			(xy 73.04627 -225.998704) (xy 73.071188 -226.035748) (xy 73.08836 -226.076958) (xy 73.097121 -226.120736)
			(xy 73.097644 -226.143058) (xy 73.097644 -226.41052) (xy 73.083166 -226.41052) (xy 73.059036 -226.42576)
			(xy 73.052432 -226.438714) (xy 73.04405 -226.454462) (xy 73.041068 -226.460244) (xy 73.037861 -226.47285)
			(xy 73.0377 -226.479354) (xy 73.0377 -226.866958) (xy 73.037841 -226.873464) (xy 73.041064 -226.886068)
			(xy 73.04405 -226.89185) (xy 73.052432 -226.907598) (xy 73.066402 -226.935792) (xy 73.067672 -226.935792)
			(xy 73.097644 -226.965256) (xy 73.097644 -227.203254) (xy 73.097152 -227.224012) (xy 73.08958 -227.264831)
			(xy 73.074682 -227.303581) (xy 73.052958 -227.338959) (xy 73.02514 -227.369775) (xy 72.992162 -227.394994)
			(xy 72.955134 -227.413767) (xy 72.9153 -227.425464) (xy 72.894698 -227.428044) (xy 72.888617 -227.428855)
			(xy 72.877061 -227.432956) (xy 72.871838 -227.436172) (xy 72.848921 -227.450828) (xy 72.79969 -227.473965)
			(xy 72.747614 -227.489685) (xy 72.693804 -227.497653) (xy 72.666606 -227.498148) (xy 71.63943 -227.498148)
			(xy 71.63033 -227.498547) (xy 71.613279 -227.504917) (xy 71.606156 -227.510594) (xy 71.582966 -227.530139)
			(xy 71.532797 -227.564214) (xy 71.478927 -227.592074) (xy 71.422124 -227.613321) (xy 71.363194 -227.627655)
			(xy 71.302978 -227.63487) (xy 71.272654 -227.635308) (xy 71.272146 -227.635308) (xy 71.241824 -227.634865)
			(xy 71.181612 -227.627628) (xy 71.122686 -227.613285) (xy 71.065883 -227.592042) (xy 71.012008 -227.564198)
			(xy 70.961823 -227.530149) (xy 70.938644 -227.510594) (xy 70.931531 -227.504898) (xy 70.914475 -227.498522)
			(xy 70.90537 -227.498148) (xy 62.360302 -227.498148) (xy 62.35035 -227.498591) (xy 62.331984 -227.506272)
			(xy 62.31792 -227.520362) (xy 62.310272 -227.538742) (xy 62.309756 -227.548694) (xy 62.309756 -227.7618)
			(xy 62.309163 -227.778511) (xy 62.300515 -227.810795) (xy 62.283807 -227.839741) (xy 62.260179 -227.863378)
			(xy 62.231239 -227.880096) (xy 62.198959 -227.888757) (xy 62.182248 -227.889308) (xy 58.753248 -227.889308)
			(xy 58.736529 -227.888769) (xy 58.704227 -227.880125) (xy 58.675265 -227.863413) (xy 58.651616 -227.839773)
			(xy 58.634894 -227.810817) (xy 58.626237 -227.778519) (xy 58.62574 -227.7618) (xy 47.8155 -227.7618)
			(xy 47.8155 -230.3018) (xy 55.705756 -230.3018) (xy 55.705756 -229.0318) (xy 55.706337 -229.015088)
			(xy 55.714986 -228.982803) (xy 55.731696 -228.953855) (xy 55.755326 -228.930218) (xy 55.784269 -228.9135)
			(xy 55.816552 -228.904842) (xy 55.833264 -228.904292) (xy 59.262264 -228.904292) (xy 59.278984 -228.90482)
			(xy 59.311286 -228.913467) (xy 59.340248 -228.930182) (xy 59.363896 -228.953823) (xy 59.380619 -228.982781)
			(xy 59.389275 -229.01508) (xy 59.389772 -229.0318) (xy 59.389772 -229.244906) (xy 59.390394 -229.25483)
			(xy 59.398059 -229.273147) (xy 59.412089 -229.287198) (xy 59.430395 -229.29489) (xy 59.440318 -229.295452)
			(xy 70.62597 -229.295452) (xy 70.63507 -229.295053) (xy 70.652121 -229.288683) (xy 70.659244 -229.283006)
			(xy 70.682434 -229.263461) (xy 70.732603 -229.229386) (xy 70.786473 -229.201526) (xy 70.843276 -229.180279)
			(xy 70.902206 -229.165945) (xy 70.962422 -229.15873) (xy 70.992746 -229.158292) (xy 70.993254 -229.158292)
			(xy 71.023576 -229.158735) (xy 71.083788 -229.165972) (xy 71.142714 -229.180315) (xy 71.199517 -229.201558)
			(xy 71.253392 -229.229402) (xy 71.303577 -229.263451) (xy 71.326756 -229.283006) (xy 71.333869 -229.288702)
			(xy 71.350925 -229.295078) (xy 71.36003 -229.295452) (xy 72.352154 -229.295452) (xy 72.362121 -229.294991)
			(xy 72.380544 -229.287376) (xy 72.394646 -229.273287) (xy 72.402281 -229.254873) (xy 72.4027 -229.244906)
			(xy 72.4027 -229.117906) (xy 72.402247 -229.107936) (xy 72.394657 -229.089499) (xy 72.387968 -229.082092)
			(xy 72.139556 -228.83368) (xy 72.132131 -228.827018) (xy 72.113705 -228.819431) (xy 72.103742 -228.818948)
			(xy 70.039738 -228.818948) (xy 70.034404 -228.819964) (xy 70.013968 -228.824227) (xy 69.972473 -228.828812)
			(xy 69.9516 -228.829108) (xy 69.924349 -228.828622) (xy 69.870401 -228.820866) (xy 69.818106 -228.805511)
			(xy 69.768529 -228.782869) (xy 69.722679 -228.753403) (xy 69.681488 -228.717712) (xy 69.645797 -228.676521)
			(xy 69.616331 -228.630671) (xy 69.593689 -228.581094) (xy 69.578334 -228.528799) (xy 69.570578 -228.474851)
			(xy 69.570578 -228.420349) (xy 69.578334 -228.366401) (xy 69.593689 -228.314106) (xy 69.616331 -228.264529)
			(xy 69.645797 -228.218679) (xy 69.681488 -228.177488) (xy 69.722679 -228.141797) (xy 69.768529 -228.112331)
			(xy 69.818106 -228.089689) (xy 69.870401 -228.074334) (xy 69.924349 -228.066578) (xy 69.9516 -228.066092)
			(xy 69.972474 -228.066378) (xy 70.01397 -228.070964) (xy 70.034404 -228.075236) (xy 70.039738 -228.076252)
			(xy 72.278494 -228.076252) (xy 72.307664 -228.076831) (xy 72.365276 -228.086017) (xy 72.420743 -228.104101)
			(xy 72.472699 -228.130639) (xy 72.519864 -228.164976) (xy 72.540876 -228.185218) (xy 72.883268 -228.52761)
			(xy 72.897492 -228.534722) (xy 72.90562 -228.535992) (xy 72.925392 -228.539401) (xy 72.963362 -228.552354)
			(xy 72.998453 -228.571801) (xy 73.029565 -228.597131) (xy 73.055722 -228.627551) (xy 73.076104 -228.662107)
			(xy 73.090073 -228.699716) (xy 73.09719 -228.739199) (xy 73.097644 -228.759258) (xy 73.097644 -229.02672)
			(xy 73.083166 -229.02672) (xy 73.059036 -229.04196) (xy 73.052432 -229.054914) (xy 73.04405 -229.070662)
			(xy 73.041068 -229.076444) (xy 73.037861 -229.08905) (xy 73.0377 -229.095554) (xy 73.0377 -229.483158)
			(xy 73.037841 -229.489664) (xy 73.041064 -229.502268) (xy 73.04405 -229.50805) (xy 73.052432 -229.523798)
			(xy 73.066402 -229.551992) (xy 73.067672 -229.551992) (xy 73.097644 -229.581456) (xy 73.097644 -229.819454)
			(xy 73.097106 -229.84178) (xy 73.088359 -229.885567) (xy 73.071196 -229.926788) (xy 73.046284 -229.963844)
			(xy 73.014588 -229.995295) (xy 72.977341 -230.01992) (xy 72.935988 -230.036764) (xy 72.892135 -230.045172)
			(xy 72.869806 -230.045514) (xy 72.869806 -230.04526) (xy 72.82561 -230.04526) (xy 72.819006 -230.047292)
			(xy 72.79478 -230.053507) (xy 72.745208 -230.060141) (xy 72.7202 -230.0605) (xy 72.695193 -230.060134)
			(xy 72.64562 -230.053505) (xy 72.621394 -230.047292) (xy 72.61479 -230.04526) (xy 72.570594 -230.04526)
			(xy 72.570594 -230.045514) (xy 72.557136 -230.04538) (xy 72.530396 -230.042321) (xy 72.517254 -230.039418)
			(xy 72.511412 -230.038148) (xy 71.36003 -230.038148) (xy 71.35093 -230.038547) (xy 71.333879 -230.044917)
			(xy 71.326756 -230.050594) (xy 71.303566 -230.070139) (xy 71.253397 -230.104214) (xy 71.199527 -230.132074)
			(xy 71.142724 -230.153321) (xy 71.083794 -230.167655) (xy 71.023578 -230.17487) (xy 70.993254 -230.175308)
			(xy 70.992746 -230.175308) (xy 70.962424 -230.174865) (xy 70.902212 -230.167628) (xy 70.843286 -230.153285)
			(xy 70.786483 -230.132042) (xy 70.732608 -230.104198) (xy 70.682423 -230.070149) (xy 70.659244 -230.050594)
			(xy 70.652131 -230.044898) (xy 70.635075 -230.038522) (xy 70.62597 -230.038148) (xy 59.440318 -230.038148)
			(xy 59.430368 -230.038604) (xy 59.412001 -230.046279) (xy 59.397936 -230.060365) (xy 59.390289 -230.078743)
			(xy 59.389772 -230.088694) (xy 59.389772 -230.3018) (xy 59.389311 -230.318524) (xy 59.380652 -230.350833)
			(xy 59.363925 -230.379799) (xy 59.34027 -230.403447) (xy 59.3113 -230.420166) (xy 59.278989 -230.428816)
			(xy 59.262264 -230.429308) (xy 55.833264 -230.429308) (xy 55.816547 -230.428794) (xy 55.784255 -230.420134)
			(xy 55.755304 -230.403411) (xy 55.731667 -230.379767) (xy 55.714953 -230.350811) (xy 55.706301 -230.318517)
			(xy 55.705756 -230.3018) (xy 47.8155 -230.3018) (xy 47.8155 -235.317351) (xy 70.551284 -235.317351)
			(xy 70.551284 -235.262849) (xy 70.55904 -235.208903) (xy 70.574395 -235.15661) (xy 70.597035 -235.107034)
			(xy 70.6265 -235.061184) (xy 70.662191 -235.019995) (xy 70.703379 -234.984304) (xy 70.749228 -234.954838)
			(xy 70.798804 -234.932197) (xy 70.851097 -234.916841) (xy 70.905043 -234.909084) (xy 70.932294 -234.908598)
			(xy 70.953168 -234.908885) (xy 70.994664 -234.91347) (xy 71.015098 -234.917742) (xy 71.020432 -234.919012)
			(xy 71.7042 -234.919012) (xy 71.729207 -234.919378) (xy 71.77878 -234.926007) (xy 71.803006 -234.93222)
			(xy 71.80961 -234.934252) (xy 71.853806 -234.934252) (xy 71.853806 -234.933998) (xy 71.876132 -234.934405)
			(xy 71.919979 -234.94281) (xy 71.961328 -234.959647) (xy 71.998573 -234.984263) (xy 71.998856 -234.984544)
			(xy 93.107 -234.984544) (xy 93.111071 -234.928922) (xy 93.123197 -234.874485) (xy 93.14312 -234.822394)
			(xy 93.170416 -234.773759) (xy 93.204502 -234.729616) (xy 93.244651 -234.690907) (xy 93.290009 -234.658456)
			(xy 93.339609 -234.632955) (xy 93.392393 -234.614948) (xy 93.447236 -234.604818) (xy 93.50297 -234.602781)
			(xy 93.558407 -234.608881) (xy 93.612364 -234.622987) (xy 93.663693 -234.644799) (xy 93.711299 -234.673853)
			(xy 93.754167 -234.709528) (xy 93.791384 -234.751065) (xy 93.822157 -234.797578) (xy 93.845829 -234.848075)
			(xy 93.861897 -234.901482) (xy 93.870017 -234.956658) (xy 93.870526 -234.984544) (xy 93.870017 -235.01243)
			(xy 93.861897 -235.067606) (xy 93.845829 -235.121013) (xy 93.822157 -235.17151) (xy 93.791384 -235.218023)
			(xy 93.754167 -235.25956) (xy 93.711299 -235.295235) (xy 93.663693 -235.324289) (xy 93.612364 -235.346101)
			(xy 93.558407 -235.360207) (xy 93.50297 -235.366307) (xy 93.447236 -235.36427) (xy 93.392393 -235.35414)
			(xy 93.339609 -235.336133) (xy 93.290009 -235.310632) (xy 93.244651 -235.278181) (xy 93.204502 -235.239472)
			(xy 93.170416 -235.195329) (xy 93.14312 -235.146694) (xy 93.123197 -235.094603) (xy 93.111071 -235.040166)
			(xy 93.107 -234.984544) (xy 71.998856 -234.984544) (xy 72.03027 -235.015704) (xy 72.055188 -235.052748)
			(xy 72.07236 -235.093958) (xy 72.081121 -235.137736) (xy 72.081644 -235.160058) (xy 72.081644 -235.42752)
			(xy 72.067166 -235.42752) (xy 72.043036 -235.44276) (xy 72.036432 -235.455714) (xy 72.02805 -235.471462)
			(xy 72.025068 -235.477244) (xy 72.021861 -235.48985) (xy 72.0217 -235.496354) (xy 72.0217 -235.668312)
			(xy 72.022178 -235.67832) (xy 72.029842 -235.696812) (xy 72.043998 -235.710965) (xy 72.062491 -235.718624)
			(xy 72.0725 -235.719112) (xy 72.907906 -235.719112) (xy 72.917808 -235.718597) (xy 72.936109 -235.711026)
			(xy 72.943466 -235.70438) (xy 72.967294 -235.681747) (xy 73.019769 -235.642181) (xy 73.076905 -235.609707)
			(xy 73.13775 -235.584866) (xy 73.201288 -235.568073) (xy 73.26646 -235.559607) (xy 73.29932 -235.559092)
			(xy 73.299574 -235.559092) (xy 73.329897 -235.559523) (xy 73.390109 -235.566763) (xy 73.449035 -235.581107)
			(xy 73.505838 -235.602353) (xy 73.559713 -235.630199) (xy 73.609898 -235.66425) (xy 73.633076 -235.683806)
			(xy 73.640183 -235.68951) (xy 73.657244 -235.695881) (xy 73.66635 -235.696252) (xy 79.250794 -235.696252)
			(xy 79.26075 -235.695756) (xy 79.279148 -235.688137) (xy 79.293231 -235.674059) (xy 79.300853 -235.655662)
			(xy 79.30134 -235.645706) (xy 79.30134 -235.4326) (xy 79.301789 -235.415875) (xy 79.310449 -235.383564)
			(xy 79.327178 -235.354597) (xy 79.350835 -235.330948) (xy 79.379809 -235.31423) (xy 79.412122 -235.305583)
			(xy 79.428848 -235.305092) (xy 82.857848 -235.305092) (xy 82.874565 -235.305595) (xy 82.906858 -235.314259)
			(xy 82.935809 -235.330983) (xy 82.959446 -235.35463) (xy 82.97616 -235.383587) (xy 82.984811 -235.415883)
			(xy 82.985356 -235.4326) (xy 82.985356 -236.561884) (xy 93.248986 -236.561884) (xy 93.253057 -236.506262)
			(xy 93.265183 -236.451825) (xy 93.285106 -236.399734) (xy 93.312402 -236.351099) (xy 93.346488 -236.306956)
			(xy 93.386637 -236.268247) (xy 93.431995 -236.235796) (xy 93.481595 -236.210295) (xy 93.534379 -236.192288)
			(xy 93.589222 -236.182158) (xy 93.644956 -236.180121) (xy 93.700393 -236.186221) (xy 93.75435 -236.200327)
			(xy 93.805679 -236.222139) (xy 93.853285 -236.251193) (xy 93.896153 -236.286868) (xy 93.93337 -236.328405)
			(xy 93.964143 -236.374918) (xy 93.987815 -236.425415) (xy 94.003883 -236.478822) (xy 94.012003 -236.533998)
			(xy 94.012512 -236.561884) (xy 94.012003 -236.58977) (xy 94.003883 -236.644946) (xy 93.987815 -236.698353)
			(xy 93.964143 -236.74885) (xy 93.93337 -236.795363) (xy 93.896153 -236.8369) (xy 93.853285 -236.872575)
			(xy 93.805679 -236.901629) (xy 93.75435 -236.923441) (xy 93.700393 -236.937547) (xy 93.644956 -236.943647)
			(xy 93.589222 -236.94161) (xy 93.534379 -236.93148) (xy 93.481595 -236.913473) (xy 93.431995 -236.887972)
			(xy 93.386637 -236.855521) (xy 93.346488 -236.816812) (xy 93.312402 -236.772669) (xy 93.285106 -236.724034)
			(xy 93.265183 -236.671943) (xy 93.253057 -236.617506) (xy 93.248986 -236.561884) (xy 82.985356 -236.561884)
			(xy 82.985356 -236.7026) (xy 82.984763 -236.719311) (xy 82.976115 -236.751595) (xy 82.959407 -236.780541)
			(xy 82.935779 -236.804178) (xy 82.906839 -236.820896) (xy 82.874559 -236.829557) (xy 82.857848 -236.830108)
			(xy 79.428848 -236.830108) (xy 79.412129 -236.829569) (xy 79.379827 -236.820925) (xy 79.350865 -236.804213)
			(xy 79.327216 -236.780573) (xy 79.310494 -236.751617) (xy 79.301837 -236.719319) (xy 79.30134 -236.7026)
			(xy 79.30134 -236.489494) (xy 79.300965 -236.47951) (xy 79.293359 -236.46105) (xy 79.27924 -236.446934)
			(xy 79.260778 -236.439333) (xy 79.250794 -236.438948) (xy 73.66635 -236.438948) (xy 73.657251 -236.439357)
			(xy 73.6402 -236.44572) (xy 73.633076 -236.451394) (xy 73.609901 -236.47099) (xy 73.559686 -236.50508)
			(xy 73.505768 -236.532945) (xy 73.448913 -236.554186) (xy 73.389933 -236.568502) (xy 73.329667 -236.575689)
			(xy 73.29932 -236.576108) (xy 73.266153 -236.575589) (xy 73.200376 -236.567003) (xy 73.136276 -236.549936)
			(xy 73.074939 -236.524676) (xy 73.017409 -236.491654) (xy 72.99071 -236.471968) (xy 72.983949 -236.467148)
			(xy 72.96827 -236.461709) (xy 72.959976 -236.4613) (xy 71.7042 -236.4613) (xy 71.679193 -236.460934)
			(xy 71.62962 -236.454305) (xy 71.605394 -236.448092) (xy 71.59879 -236.44606) (xy 71.554594 -236.44606)
			(xy 71.554594 -236.446314) (xy 71.532268 -236.445895) (xy 71.488423 -236.437491) (xy 71.447076 -236.420655)
			(xy 71.409831 -236.39604) (xy 71.378134 -236.364601) (xy 71.353216 -236.327559) (xy 71.336042 -236.286351)
			(xy 71.32728 -236.242576) (xy 71.326756 -236.220254) (xy 71.326756 -235.952792) (xy 71.341234 -235.952792)
			(xy 71.365364 -235.937552) (xy 71.371968 -235.924598) (xy 71.38035 -235.90885) (xy 71.383328 -235.903066)
			(xy 71.386538 -235.890462) (xy 71.3867 -235.883958) (xy 71.3867 -235.712) (xy 71.386212 -235.701992)
			(xy 71.378552 -235.683501) (xy 71.364399 -235.669348) (xy 71.345908 -235.661688) (xy 71.3359 -235.6612)
			(xy 71.020432 -235.6612) (xy 71.015098 -235.66247) (xy 70.994663 -235.666734) (xy 70.953168 -235.671318)
			(xy 70.932294 -235.671614) (xy 70.905043 -235.671116) (xy 70.851097 -235.663359) (xy 70.798804 -235.648003)
			(xy 70.749228 -235.625362) (xy 70.703379 -235.595896) (xy 70.662191 -235.560205) (xy 70.6265 -235.519016)
			(xy 70.597035 -235.473166) (xy 70.574395 -235.42359) (xy 70.55904 -235.371297) (xy 70.551284 -235.317351)
			(xy 47.8155 -235.317351) (xy 47.8155 -237.882753) (xy 70.418661 -237.882753) (xy 70.418661 -237.828247)
			(xy 70.426418 -237.774297) (xy 70.441774 -237.721999) (xy 70.464417 -237.672419) (xy 70.493885 -237.626567)
			(xy 70.529579 -237.585375) (xy 70.570772 -237.549682) (xy 70.616625 -237.520214) (xy 70.666205 -237.497572)
			(xy 70.718503 -237.482217) (xy 70.772453 -237.474461) (xy 70.799706 -237.473998) (xy 70.82058 -237.474283)
			(xy 70.862076 -237.47887) (xy 70.88251 -237.483142) (xy 70.887844 -237.484412) (xy 71.7296 -237.484412)
			(xy 71.754607 -237.484778) (xy 71.80418 -237.491407) (xy 71.828406 -237.49762) (xy 71.83501 -237.499652)
			(xy 71.879206 -237.499652) (xy 71.879206 -237.499398) (xy 71.901532 -237.499805) (xy 71.945379 -237.50821)
			(xy 71.986728 -237.525047) (xy 72.023973 -237.549663) (xy 72.05567 -237.581104) (xy 72.080588 -237.618148)
			(xy 72.09776 -237.659358) (xy 72.106521 -237.703136) (xy 72.107044 -237.725458) (xy 72.107044 -237.99292)
			(xy 72.092566 -237.99292) (xy 72.068436 -238.00816) (xy 72.061832 -238.021114) (xy 72.05345 -238.036862)
			(xy 72.050468 -238.042644) (xy 72.047261 -238.05525) (xy 72.0471 -238.061754) (xy 72.0471 -238.233712)
			(xy 72.047578 -238.24372) (xy 72.055242 -238.262212) (xy 72.069398 -238.276365) (xy 72.087891 -238.284024)
			(xy 72.0979 -238.284512) (xy 72.757538 -238.284512) (xy 72.768196 -238.283895) (xy 72.787619 -238.275084)
			(xy 72.79513 -238.267494) (xy 72.815808 -238.245138) (xy 72.861648 -238.205047) (xy 72.911951 -238.170721)
			(xy 72.965996 -238.142653) (xy 73.023007 -238.121244) (xy 73.082169 -238.106803) (xy 73.142633 -238.099535)
			(xy 73.173082 -238.099092) (xy 73.17359 -238.099092) (xy 73.203911 -238.099573) (xy 73.264122 -238.106803)
			(xy 73.323046 -238.121138) (xy 73.379849 -238.142374) (xy 73.433726 -238.170211) (xy 73.483912 -238.204254)
			(xy 73.507092 -238.223806) (xy 73.514194 -238.229517) (xy 73.531259 -238.235884) (xy 73.540366 -238.236252)
			(xy 76.33081 -238.236252) (xy 76.340767 -238.235768) (xy 76.359166 -238.228145) (xy 76.373247 -238.214062)
			(xy 76.380869 -238.195664) (xy 76.381356 -238.185706) (xy 76.381356 -237.9726) (xy 76.381937 -237.955888)
			(xy 76.390586 -237.923603) (xy 76.407296 -237.894655) (xy 76.430926 -237.871018) (xy 76.459869 -237.8543)
			(xy 76.492152 -237.845642) (xy 76.508864 -237.845092) (xy 79.937864 -237.845092) (xy 79.954584 -237.84562)
			(xy 79.986886 -237.854267) (xy 80.015848 -237.870982) (xy 80.039496 -237.894623) (xy 80.056219 -237.923581)
			(xy 80.064875 -237.95588) (xy 80.065372 -237.9726) (xy 80.065372 -239.2426) (xy 80.064911 -239.259324)
			(xy 80.056252 -239.291633) (xy 80.039525 -239.320599) (xy 80.01587 -239.344247) (xy 79.9869 -239.360966)
			(xy 79.954589 -239.369616) (xy 79.937864 -239.370108) (xy 76.508864 -239.370108) (xy 76.492147 -239.369594)
			(xy 76.459855 -239.360934) (xy 76.430904 -239.344211) (xy 76.407267 -239.320567) (xy 76.390553 -239.291611)
			(xy 76.381901 -239.259317) (xy 76.381356 -239.2426) (xy 76.381356 -239.029494) (xy 76.380965 -239.019512)
			(xy 76.373362 -239.001055) (xy 76.359248 -238.98694) (xy 76.340792 -238.979336) (xy 76.33081 -238.978948)
			(xy 73.540366 -238.978948) (xy 73.531262 -238.979317) (xy 73.514212 -238.985708) (xy 73.507092 -238.991394)
			(xy 73.483927 -239.010969) (xy 73.433752 -239.045041) (xy 73.379877 -239.072896) (xy 73.323069 -239.094138)
			(xy 73.264135 -239.108466) (xy 73.203915 -239.115674) (xy 73.17359 -239.116108) (xy 73.173336 -239.116108)
			(xy 73.144198 -239.115693) (xy 73.086304 -239.109018) (xy 73.029555 -239.095764) (xy 72.974694 -239.076104)
			(xy 72.922443 -239.050296) (xy 72.897746 -239.034828) (xy 72.891488 -239.031139) (xy 72.877571 -239.027003)
			(xy 72.870314 -239.0267) (xy 71.7296 -239.0267) (xy 71.704593 -239.026334) (xy 71.65502 -239.019705)
			(xy 71.630794 -239.013492) (xy 71.62419 -239.01146) (xy 71.579994 -239.01146) (xy 71.579994 -239.011714)
			(xy 71.557668 -239.011295) (xy 71.513823 -239.002891) (xy 71.472476 -238.986055) (xy 71.435231 -238.96144)
			(xy 71.403534 -238.930001) (xy 71.378616 -238.892959) (xy 71.361442 -238.851751) (xy 71.35268 -238.807976)
			(xy 71.352156 -238.785654) (xy 71.352156 -238.518192) (xy 71.366634 -238.518192) (xy 71.390764 -238.502952)
			(xy 71.397368 -238.489998) (xy 71.40575 -238.47425) (xy 71.408728 -238.468466) (xy 71.411938 -238.455862)
			(xy 71.4121 -238.449358) (xy 71.4121 -238.2774) (xy 71.411612 -238.267392) (xy 71.403952 -238.248901)
			(xy 71.389799 -238.234748) (xy 71.371308 -238.227088) (xy 71.3613 -238.2266) (xy 70.887844 -238.2266)
			(xy 70.88251 -238.22787) (xy 70.862074 -238.232132) (xy 70.820579 -238.236718) (xy 70.799706 -238.237014)
			(xy 70.772453 -238.236539) (xy 70.718503 -238.228783) (xy 70.666205 -238.213428) (xy 70.616625 -238.190786)
			(xy 70.570772 -238.161318) (xy 70.529579 -238.125625) (xy 70.493885 -238.084433) (xy 70.464417 -238.038581)
			(xy 70.441774 -237.989001) (xy 70.426418 -237.936703) (xy 70.418661 -237.882753) (xy 47.8155 -237.882753)
			(xy 47.8155 -242.297204) (xy 71.240902 -242.297204) (xy 71.244973 -242.241582) (xy 71.257099 -242.187145)
			(xy 71.277022 -242.135054) (xy 71.304318 -242.086419) (xy 71.338404 -242.042276) (xy 71.378553 -242.003567)
			(xy 71.423911 -241.971116) (xy 71.473511 -241.945615) (xy 71.526295 -241.927608) (xy 71.581138 -241.917478)
			(xy 71.636872 -241.915441) (xy 71.692309 -241.921541) (xy 71.746266 -241.935647) (xy 71.797595 -241.957459)
			(xy 71.845201 -241.986513) (xy 71.888069 -242.022188) (xy 71.925286 -242.063725) (xy 71.956059 -242.110238)
			(xy 71.979731 -242.160735) (xy 71.995799 -242.214142) (xy 72.003919 -242.269318) (xy 72.004428 -242.297204)
			(xy 72.003919 -242.32509) (xy 71.995799 -242.380266) (xy 71.979731 -242.433673) (xy 71.956059 -242.48417)
			(xy 71.925286 -242.530683) (xy 71.888069 -242.57222) (xy 71.845201 -242.607895) (xy 71.797595 -242.636949)
			(xy 71.746266 -242.658761) (xy 71.692309 -242.672867) (xy 71.636872 -242.678967) (xy 71.581138 -242.67693)
			(xy 71.526295 -242.6668) (xy 71.473511 -242.648793) (xy 71.423911 -242.623292) (xy 71.378553 -242.590841)
			(xy 71.338404 -242.552132) (xy 71.304318 -242.507989) (xy 71.277022 -242.459354) (xy 71.257099 -242.407263)
			(xy 71.244973 -242.352826) (xy 71.240902 -242.297204) (xy 47.8155 -242.297204) (xy 47.8155 -252.48743)
			(xy 47.816043 -252.497415) (xy 47.823764 -252.515839) (xy 47.830486 -252.523244) (xy 53.307996 -258.0005)
			(xy 53.315341 -258.007311) (xy 53.333803 -258.015045) (xy 53.34381 -258.015486)
		)
		(stroke
			(width 0)
			(type solid)
		)
		(fill yes)
		(layer "F.Cu")
		(net "GND")
	)
	(gr_line
		(start 7.504684 -30.628336)
		(end 7.210552 -30.922468)
		(stroke
			(width 0.06731)
			(type default)
		)
		(layer "F.Cu")
	)
	(gr_line
		(start 9.358122 -28.829)
		(end 9.064752 -29.12237)
		(stroke
			(width 0.06731)
			(type default)
		)
		(layer "F.Cu")
	)
	(gr_line
		(start 9.360662 -28.829)
		(end 9.358122 -28.829)
		(stroke
			(width 0.06731)
			(type default)
		)
		(layer "F.Cu")
	)
	(gr_line
		(start 10.024618 -28.829)
		(end 10.019538 -28.829)
		(stroke
			(width 0.06731)
			(type default)
		)
		(layer "F.Cu")
	)
	(gr_line
		(start 10.182352 -30.790134)
		(end 10.020808 -30.62859)
		(stroke
			(width 0.06731)
			(type default)
		)
		(layer "F.Cu")
	)
	(gr_line
		(start 10.185908 -28.99029)
		(end 10.024618 -28.829)
		(stroke
			(width 0.06731)
			(type default)
		)
		(layer "F.Cu")
	)
	(gr_line
		(start 10.664952 -30.790134)
		(end 10.182352 -30.790134)
		(stroke
			(width 0.06731)
			(type default)
		)
		(layer "F.Cu")
	)
	(gr_line
		(start 10.664952 -28.99029)
		(end 10.185908 -28.99029)
		(stroke
			(width 0.06731)
			(type default)
		)
		(layer "F.Cu")
	)
	(gr_line
		(start 10.664952 -28.990036)
		(end 10.664952 -28.99029)
		(stroke
			(width 0.06731)
			(type default)
		)
		(layer "F.Cu")
	)
	(gr_line
		(start 33.504632 -34.228278)
		(end 33.2105 -34.52241)
		(stroke
			(width 0.06731)
			(type default)
		)
		(layer "F.Cu")
	)
	(gr_line
		(start 35.12566 -120.087898)
		(end 35.4203 -119.793258)
		(stroke
			(width 0.06731)
			(type default)
		)
		(layer "F.Cu")
	)
	(gr_line
		(start 35.12566 -112.784382)
		(end 35.4203 -112.489742)
		(stroke
			(width 0.06731)
			(type default)
		)
		(layer "F.Cu")
	)
	(gr_line
		(start 35.12566 -111.920782)
		(end 35.4203 -112.215422)
		(stroke
			(width 0.06731)
			(type default)
		)
		(layer "F.Cu")
	)
	(gr_line
		(start 35.12566 -109.18444)
		(end 35.4203 -108.8898)
		(stroke
			(width 0.06731)
			(type default)
		)
		(layer "F.Cu")
	)
	(gr_line
		(start 35.12566 -108.32084)
		(end 35.4203 -108.61548)
		(stroke
			(width 0.06731)
			(type default)
		)
		(layer "F.Cu")
	)
	(gr_line
		(start 35.12566 -105.584498)
		(end 35.4203 -105.289858)
		(stroke
			(width 0.06731)
			(type default)
		)
		(layer "F.Cu")
	)
	(gr_line
		(start 35.12566 -104.720898)
		(end 35.4203 -105.015538)
		(stroke
			(width 0.06731)
			(type default)
		)
		(layer "F.Cu")
	)
	(gr_line
		(start 35.73526 -101.984302)
		(end 36.0299 -101.689662)
		(stroke
			(width 0.06731)
			(type default)
		)
		(layer "F.Cu")
	)
	(gr_line
		(start 35.73526 -101.120702)
		(end 36.0299 -101.415342)
		(stroke
			(width 0.06731)
			(type default)
		)
		(layer "F.Cu")
	)
	(gr_line
		(start 36.051744 -119.793258)
		(end 36.371784 -120.113298)
		(stroke
			(width 0.06731)
			(type default)
		)
		(layer "F.Cu")
	)
	(gr_line
		(start 36.051744 -112.489742)
		(end 36.371784 -112.809782)
		(stroke
			(width 0.06731)
			(type default)
		)
		(layer "F.Cu")
	)
	(gr_line
		(start 36.051744 -112.215422)
		(end 36.371784 -111.895382)
		(stroke
			(width 0.06731)
			(type default)
		)
		(layer "F.Cu")
	)
	(gr_line
		(start 36.051744 -108.8898)
		(end 36.371784 -109.20984)
		(stroke
			(width 0.06731)
			(type default)
		)
		(layer "F.Cu")
	)
	(gr_line
		(start 36.051744 -108.61548)
		(end 36.371784 -108.29544)
		(stroke
			(width 0.06731)
			(type default)
		)
		(layer "F.Cu")
	)
	(gr_line
		(start 36.051744 -105.289858)
		(end 36.371784 -105.609898)
		(stroke
			(width 0.06731)
			(type default)
		)
		(layer "F.Cu")
	)
	(gr_line
		(start 36.051744 -105.015538)
		(end 36.371784 -104.695498)
		(stroke
			(width 0.06731)
			(type default)
		)
		(layer "F.Cu")
	)
	(gr_line
		(start 36.1823 -34.390076)
		(end 36.020756 -34.228532)
		(stroke
			(width 0.06731)
			(type default)
		)
		(layer "F.Cu")
	)
	(gr_line
		(start 36.374578 -299.224954)
		(end 36.849558 -299.699934)
		(stroke
			(width 0.05715)
			(type default)
		)
		(layer "F.Cu")
	)
	(gr_line
		(start 36.661344 -101.689662)
		(end 36.981384 -102.009702)
		(stroke
			(width 0.06731)
			(type default)
		)
		(layer "F.Cu")
	)
	(gr_line
		(start 36.661344 -101.415342)
		(end 36.981384 -101.095302)
		(stroke
			(width 0.06731)
			(type default)
		)
		(layer "F.Cu")
	)
	(gr_line
		(start 36.6649 -34.390076)
		(end 36.1823 -34.390076)
		(stroke
			(width 0.06731)
			(type default)
		)
		(layer "F.Cu")
	)
	(gr_line
		(start 36.849812 -299.699934)
		(end 36.849558 -299.699934)
		(stroke
			(width 0.05715)
			(type default)
		)
		(layer "F.Cu")
	)
	(gr_line
		(start 36.905184 -120.113298)
		(end 37.22497 -119.793512)
		(stroke
			(width 0.06731)
			(type default)
		)
		(layer "F.Cu")
	)
	(gr_line
		(start 36.905184 -112.809782)
		(end 37.231574 -112.483392)
		(stroke
			(width 0.06731)
			(type default)
		)
		(layer "F.Cu")
	)
	(gr_line
		(start 36.905184 -111.895382)
		(end 37.217604 -112.207802)
		(stroke
			(width 0.06731)
			(type default)
		)
		(layer "F.Cu")
	)
	(gr_line
		(start 36.905184 -109.20984)
		(end 37.231574 -108.88345)
		(stroke
			(width 0.06731)
			(type default)
		)
		(layer "F.Cu")
	)
	(gr_line
		(start 36.905184 -108.29544)
		(end 37.217604 -108.60786)
		(stroke
			(width 0.06731)
			(type default)
		)
		(layer "F.Cu")
	)
	(gr_line
		(start 36.905184 -105.609898)
		(end 37.231574 -105.283508)
		(stroke
			(width 0.06731)
			(type default)
		)
		(layer "F.Cu")
	)
	(gr_line
		(start 36.905184 -104.695498)
		(end 37.217604 -105.007918)
		(stroke
			(width 0.06731)
			(type default)
		)
		(layer "F.Cu")
	)
	(gr_line
		(start 37.217604 -112.207802)
		(end 37.232844 -112.207802)
		(stroke
			(width 0.06731)
			(type default)
		)
		(layer "F.Cu")
	)
	(gr_line
		(start 37.217604 -108.60786)
		(end 37.232844 -108.60786)
		(stroke
			(width 0.06731)
			(type default)
		)
		(layer "F.Cu")
	)
	(gr_line
		(start 37.217604 -105.007918)
		(end 37.232844 -105.007918)
		(stroke
			(width 0.06731)
			(type default)
		)
		(layer "F.Cu")
	)
	(gr_line
		(start 37.324538 -299.224954)
		(end 37.799518 -299.699934)
		(stroke
			(width 0.05715)
			(type default)
		)
		(layer "F.Cu")
	)
	(gr_line
		(start 37.324538 -297.32478)
		(end 37.799518 -297.79976)
		(stroke
			(width 0.05715)
			(type default)
		)
		(layer "F.Cu")
	)
	(gr_line
		(start 37.514784 -102.009702)
		(end 37.841174 -101.683312)
		(stroke
			(width 0.06731)
			(type default)
		)
		(layer "F.Cu")
	)
	(gr_line
		(start 37.514784 -101.095302)
		(end 37.827204 -101.407722)
		(stroke
			(width 0.06731)
			(type default)
		)
		(layer "F.Cu")
	)
	(gr_line
		(start 37.767768 -136.704324)
		(end 38.062408 -136.409684)
		(stroke
			(width 0.06731)
			(type default)
		)
		(layer "F.Cu")
	)
	(gr_line
		(start 37.767768 -135.840724)
		(end 38.062408 -136.135364)
		(stroke
			(width 0.06731)
			(type default)
		)
		(layer "F.Cu")
	)
	(gr_line
		(start 37.767768 -133.104382)
		(end 38.062408 -132.809742)
		(stroke
			(width 0.06731)
			(type default)
		)
		(layer "F.Cu")
	)
	(gr_line
		(start 37.767768 -132.240782)
		(end 38.062408 -132.535422)
		(stroke
			(width 0.06731)
			(type default)
		)
		(layer "F.Cu")
	)
	(gr_line
		(start 37.767768 -125.494542)
		(end 38.062408 -125.199902)
		(stroke
			(width 0.06731)
			(type default)
		)
		(layer "F.Cu")
	)
	(gr_line
		(start 37.767768 -124.630942)
		(end 38.062408 -124.925582)
		(stroke
			(width 0.06731)
			(type default)
		)
		(layer "F.Cu")
	)
	(gr_line
		(start 37.767768 -121.894346)
		(end 38.062408 -121.599706)
		(stroke
			(width 0.06731)
			(type default)
		)
		(layer "F.Cu")
	)
	(gr_line
		(start 37.767768 -121.030746)
		(end 38.062408 -121.325386)
		(stroke
			(width 0.06731)
			(type default)
		)
		(layer "F.Cu")
	)
	(gr_line
		(start 37.767768 -100.177854)
		(end 38.062408 -99.883214)
		(stroke
			(width 0.06731)
			(type default)
		)
		(layer "F.Cu")
	)
	(gr_line
		(start 37.799772 -299.699934)
		(end 37.799518 -299.699934)
		(stroke
			(width 0.05715)
			(type default)
		)
		(layer "F.Cu")
	)
	(gr_line
		(start 37.799772 -297.79976)
		(end 37.799518 -297.79976)
		(stroke
			(width 0.05715)
			(type default)
		)
		(layer "F.Cu")
	)
	(gr_line
		(start 37.827204 -101.407722)
		(end 37.842444 -101.407722)
		(stroke
			(width 0.06731)
			(type default)
		)
		(layer "F.Cu")
	)
	(gr_line
		(start 37.960808 -356.511606)
		(end 38.280848 -356.831646)
		(stroke
			(width 0.06731)
			(type default)
		)
		(layer "F.Cu")
	)
	(gr_line
		(start 37.986208 -354.732082)
		(end 38.280848 -355.026722)
		(stroke
			(width 0.06731)
			(type default)
		)
		(layer "F.Cu")
	)
	(gr_line
		(start 38.275006 -287.824926)
		(end 38.749986 -288.299906)
		(stroke
			(width 0.06731)
			(type default)
		)
		(layer "F.Cu")
	)
	(gr_line
		(start 38.280848 -357.46309)
		(end 37.986208 -357.75773)
		(stroke
			(width 0.06731)
			(type default)
		)
		(layer "F.Cu")
	)
	(gr_line
		(start 38.280848 -355.658166)
		(end 37.960808 -355.978206)
		(stroke
			(width 0.06731)
			(type default)
		)
		(layer "F.Cu")
	)
	(gr_line
		(start 38.693852 -136.409684)
		(end 39.013892 -136.729724)
		(stroke
			(width 0.06731)
			(type default)
		)
		(layer "F.Cu")
	)
	(gr_line
		(start 38.693852 -136.135364)
		(end 39.013892 -135.815324)
		(stroke
			(width 0.06731)
			(type default)
		)
		(layer "F.Cu")
	)
	(gr_line
		(start 38.693852 -132.809742)
		(end 39.013892 -133.129782)
		(stroke
			(width 0.06731)
			(type default)
		)
		(layer "F.Cu")
	)
	(gr_line
		(start 38.693852 -132.535422)
		(end 39.013892 -132.215382)
		(stroke
			(width 0.06731)
			(type default)
		)
		(layer "F.Cu")
	)
	(gr_line
		(start 38.693852 -125.199902)
		(end 39.013892 -125.519942)
		(stroke
			(width 0.06731)
			(type default)
		)
		(layer "F.Cu")
	)
	(gr_line
		(start 38.693852 -124.925582)
		(end 39.013892 -124.605542)
		(stroke
			(width 0.06731)
			(type default)
		)
		(layer "F.Cu")
	)
	(gr_line
		(start 38.693852 -121.599706)
		(end 39.013892 -121.919746)
		(stroke
			(width 0.06731)
			(type default)
		)
		(layer "F.Cu")
	)
	(gr_line
		(start 38.693852 -121.325386)
		(end 39.013892 -121.005346)
		(stroke
			(width 0.06731)
			(type default)
		)
		(layer "F.Cu")
	)
	(gr_line
		(start 38.693852 -99.883214)
		(end 39.013892 -100.203254)
		(stroke
			(width 0.06731)
			(type default)
		)
		(layer "F.Cu")
	)
	(gr_line
		(start 39.224966 -287.824926)
		(end 39.699946 -288.299906)
		(stroke
			(width 0.06731)
			(type default)
		)
		(layer "F.Cu")
	)
	(gr_line
		(start 39.547292 -136.729724)
		(end 39.873682 -136.403334)
		(stroke
			(width 0.06731)
			(type default)
		)
		(layer "F.Cu")
	)
	(gr_line
		(start 39.547292 -135.815324)
		(end 39.859712 -136.127744)
		(stroke
			(width 0.06731)
			(type default)
		)
		(layer "F.Cu")
	)
	(gr_line
		(start 39.547292 -133.129782)
		(end 39.873682 -132.803392)
		(stroke
			(width 0.06731)
			(type default)
		)
		(layer "F.Cu")
	)
	(gr_line
		(start 39.547292 -132.215382)
		(end 39.859712 -132.527802)
		(stroke
			(width 0.06731)
			(type default)
		)
		(layer "F.Cu")
	)
	(gr_line
		(start 39.547292 -125.519942)
		(end 39.873682 -125.193552)
		(stroke
			(width 0.06731)
			(type default)
		)
		(layer "F.Cu")
	)
	(gr_line
		(start 39.547292 -124.605542)
		(end 39.859712 -124.917962)
		(stroke
			(width 0.06731)
			(type default)
		)
		(layer "F.Cu")
	)
	(gr_line
		(start 39.547292 -121.919746)
		(end 39.873682 -121.593356)
		(stroke
			(width 0.06731)
			(type default)
		)
		(layer "F.Cu")
	)
	(gr_line
		(start 39.547292 -121.005346)
		(end 39.859712 -121.317766)
		(stroke
			(width 0.06731)
			(type default)
		)
		(layer "F.Cu")
	)
	(gr_line
		(start 39.547292 -100.203254)
		(end 39.867078 -99.883468)
		(stroke
			(width 0.06731)
			(type default)
		)
		(layer "F.Cu")
	)
	(gr_line
		(start 39.859712 -136.127744)
		(end 39.874952 -136.127744)
		(stroke
			(width 0.06731)
			(type default)
		)
		(layer "F.Cu")
	)
	(gr_line
		(start 39.859712 -132.527802)
		(end 39.874952 -132.527802)
		(stroke
			(width 0.06731)
			(type default)
		)
		(layer "F.Cu")
	)
	(gr_line
		(start 39.859712 -124.917962)
		(end 39.874952 -124.917962)
		(stroke
			(width 0.06731)
			(type default)
		)
		(layer "F.Cu")
	)
	(gr_line
		(start 39.859712 -121.317766)
		(end 39.874952 -121.317766)
		(stroke
			(width 0.06731)
			(type default)
		)
		(layer "F.Cu")
	)
	(gr_line
		(start 41.069768 -350.365314)
		(end 41.389808 -350.685354)
		(stroke
			(width 0.06731)
			(type default)
		)
		(layer "F.Cu")
	)
	(gr_line
		(start 41.095168 -348.58579)
		(end 41.389808 -348.88043)
		(stroke
			(width 0.06731)
			(type default)
		)
		(layer "F.Cu")
	)
	(gr_line
		(start 41.389808 -351.316798)
		(end 41.095168 -351.611438)
		(stroke
			(width 0.06731)
			(type default)
		)
		(layer "F.Cu")
	)
	(gr_line
		(start 41.389808 -349.511874)
		(end 41.069768 -349.831914)
		(stroke
			(width 0.06731)
			(type default)
		)
		(layer "F.Cu")
	)
	(gr_line
		(start 43.499786 -289.249866)
		(end 43.024806 -288.774886)
		(stroke
			(width 0.06731)
			(type default)
		)
		(layer "F.Cu")
	)
	(gr_line
		(start 44.178728 -356.511606)
		(end 44.498768 -356.831646)
		(stroke
			(width 0.06731)
			(type default)
		)
		(layer "F.Cu")
	)
	(gr_line
		(start 44.178728 -344.219022)
		(end 44.498768 -344.539062)
		(stroke
			(width 0.06731)
			(type default)
		)
		(layer "F.Cu")
	)
	(gr_line
		(start 44.204128 -354.732082)
		(end 44.498768 -355.026722)
		(stroke
			(width 0.06731)
			(type default)
		)
		(layer "F.Cu")
	)
	(gr_line
		(start 44.204128 -342.439498)
		(end 44.498768 -342.734138)
		(stroke
			(width 0.06731)
			(type default)
		)
		(layer "F.Cu")
	)
	(gr_line
		(start 44.449746 -289.249866)
		(end 43.974766 -288.774886)
		(stroke
			(width 0.06731)
			(type default)
		)
		(layer "F.Cu")
	)
	(gr_line
		(start 44.498768 -357.46309)
		(end 44.204128 -357.75773)
		(stroke
			(width 0.06731)
			(type default)
		)
		(layer "F.Cu")
	)
	(gr_line
		(start 44.498768 -355.658166)
		(end 44.178728 -355.978206)
		(stroke
			(width 0.06731)
			(type default)
		)
		(layer "F.Cu")
	)
	(gr_line
		(start 44.498768 -345.170506)
		(end 44.204128 -345.465146)
		(stroke
			(width 0.06731)
			(type default)
		)
		(layer "F.Cu")
	)
	(gr_line
		(start 44.498768 -343.365582)
		(end 44.178728 -343.685622)
		(stroke
			(width 0.06731)
			(type default)
		)
		(layer "F.Cu")
	)
	(gr_line
		(start 44.773088 -345.170506)
		(end 45.067728 -345.465146)
		(stroke
			(width 0.06731)
			(type default)
		)
		(layer "F.Cu")
	)
	(gr_line
		(start 44.773088 -343.365582)
		(end 45.093128 -343.685622)
		(stroke
			(width 0.06731)
			(type default)
		)
		(layer "F.Cu")
	)
	(gr_line
		(start 45.067728 -342.439498)
		(end 44.773088 -342.734138)
		(stroke
			(width 0.06731)
			(type default)
		)
		(layer "F.Cu")
	)
	(gr_line
		(start 45.093128 -344.219022)
		(end 44.773088 -344.539062)
		(stroke
			(width 0.06731)
			(type default)
		)
		(layer "F.Cu")
	)
	(gr_line
		(start 45.391324 -136.402064)
		(end 45.554392 -136.565132)
		(stroke
			(width 0.06731)
			(type default)
		)
		(layer "F.Cu")
	)
	(gr_line
		(start 45.391324 -136.127744)
		(end 45.554138 -135.96493)
		(stroke
			(width 0.06731)
			(type default)
		)
		(layer "F.Cu")
	)
	(gr_line
		(start 45.391324 -101.682042)
		(end 45.554392 -101.84511)
		(stroke
			(width 0.06731)
			(type default)
		)
		(layer "F.Cu")
	)
	(gr_line
		(start 45.391324 -101.407722)
		(end 45.554138 -101.244908)
		(stroke
			(width 0.06731)
			(type default)
		)
		(layer "F.Cu")
	)
	(gr_line
		(start 45.391578 -132.802122)
		(end 45.554392 -132.964936)
		(stroke
			(width 0.06731)
			(type default)
		)
		(layer "F.Cu")
	)
	(gr_line
		(start 45.391578 -132.527802)
		(end 45.554392 -132.364988)
		(stroke
			(width 0.06731)
			(type default)
		)
		(layer "F.Cu")
	)
	(gr_line
		(start 45.391578 -125.192282)
		(end 45.554392 -125.355096)
		(stroke
			(width 0.06731)
			(type default)
		)
		(layer "F.Cu")
	)
	(gr_line
		(start 45.391578 -124.917962)
		(end 45.554392 -124.755148)
		(stroke
			(width 0.06731)
			(type default)
		)
		(layer "F.Cu")
	)
	(gr_line
		(start 45.391578 -121.592086)
		(end 45.554392 -121.7549)
		(stroke
			(width 0.06731)
			(type default)
		)
		(layer "F.Cu")
	)
	(gr_line
		(start 45.391578 -121.317766)
		(end 45.554392 -121.154952)
		(stroke
			(width 0.06731)
			(type default)
		)
		(layer "F.Cu")
	)
	(gr_line
		(start 45.391578 -119.792242)
		(end 45.554392 -119.955056)
		(stroke
			(width 0.06731)
			(type default)
		)
		(layer "F.Cu")
	)
	(gr_line
		(start 45.391578 -112.482122)
		(end 45.554392 -112.644936)
		(stroke
			(width 0.06731)
			(type default)
		)
		(layer "F.Cu")
	)
	(gr_line
		(start 45.391578 -112.207802)
		(end 45.554392 -112.044988)
		(stroke
			(width 0.06731)
			(type default)
		)
		(layer "F.Cu")
	)
	(gr_line
		(start 45.391578 -108.88218)
		(end 45.554392 -109.044994)
		(stroke
			(width 0.06731)
			(type default)
		)
		(layer "F.Cu")
	)
	(gr_line
		(start 45.391578 -108.60786)
		(end 45.554392 -108.445046)
		(stroke
			(width 0.06731)
			(type default)
		)
		(layer "F.Cu")
	)
	(gr_line
		(start 45.391578 -105.282238)
		(end 45.554392 -105.445052)
		(stroke
			(width 0.06731)
			(type default)
		)
		(layer "F.Cu")
	)
	(gr_line
		(start 45.391578 -105.007918)
		(end 45.554392 -104.845104)
		(stroke
			(width 0.06731)
			(type default)
		)
		(layer "F.Cu")
	)
	(gr_line
		(start 45.391578 -99.882198)
		(end 45.554392 -100.045012)
		(stroke
			(width 0.06731)
			(type default)
		)
		(layer "F.Cu")
	)
	(gr_line
		(start 45.554138 -135.96493)
		(end 46.042326 -135.96493)
		(stroke
			(width 0.06731)
			(type default)
		)
		(layer "F.Cu")
	)
	(gr_line
		(start 45.554138 -101.244908)
		(end 46.042326 -101.244908)
		(stroke
			(width 0.06731)
			(type default)
		)
		(layer "F.Cu")
	)
	(gr_line
		(start 45.554392 -136.565132)
		(end 46.042326 -136.565132)
		(stroke
			(width 0.06731)
			(type default)
		)
		(layer "F.Cu")
	)
	(gr_line
		(start 45.554392 -132.964936)
		(end 46.042326 -132.964936)
		(stroke
			(width 0.06731)
			(type default)
		)
		(layer "F.Cu")
	)
	(gr_line
		(start 45.554392 -132.364988)
		(end 46.042326 -132.364988)
		(stroke
			(width 0.06731)
			(type default)
		)
		(layer "F.Cu")
	)
	(gr_line
		(start 45.554392 -125.355096)
		(end 46.042326 -125.355096)
		(stroke
			(width 0.06731)
			(type default)
		)
		(layer "F.Cu")
	)
	(gr_line
		(start 45.554392 -124.755148)
		(end 46.042326 -124.755148)
		(stroke
			(width 0.06731)
			(type default)
		)
		(layer "F.Cu")
	)
	(gr_line
		(start 45.554392 -121.7549)
		(end 46.042326 -121.7549)
		(stroke
			(width 0.06731)
			(type default)
		)
		(layer "F.Cu")
	)
	(gr_line
		(start 45.554392 -121.154952)
		(end 46.042326 -121.154952)
		(stroke
			(width 0.06731)
			(type default)
		)
		(layer "F.Cu")
	)
	(gr_line
		(start 45.554392 -119.955056)
		(end 46.042326 -119.955056)
		(stroke
			(width 0.06731)
			(type default)
		)
		(layer "F.Cu")
	)
	(gr_line
		(start 45.554392 -112.644936)
		(end 46.042326 -112.644936)
		(stroke
			(width 0.06731)
			(type default)
		)
		(layer "F.Cu")
	)
	(gr_line
		(start 45.554392 -112.044988)
		(end 46.042326 -112.044988)
		(stroke
			(width 0.06731)
			(type default)
		)
		(layer "F.Cu")
	)
	(gr_line
		(start 45.554392 -109.044994)
		(end 46.042326 -109.044994)
		(stroke
			(width 0.06731)
			(type default)
		)
		(layer "F.Cu")
	)
	(gr_line
		(start 45.554392 -108.445046)
		(end 46.042326 -108.445046)
		(stroke
			(width 0.06731)
			(type default)
		)
		(layer "F.Cu")
	)
	(gr_line
		(start 45.554392 -105.445052)
		(end 46.042326 -105.445052)
		(stroke
			(width 0.06731)
			(type default)
		)
		(layer "F.Cu")
	)
	(gr_line
		(start 45.554392 -104.845104)
		(end 46.042326 -104.845104)
		(stroke
			(width 0.06731)
			(type default)
		)
		(layer "F.Cu")
	)
	(gr_line
		(start 45.554392 -101.84511)
		(end 46.042326 -101.84511)
		(stroke
			(width 0.06731)
			(type default)
		)
		(layer "F.Cu")
	)
	(gr_line
		(start 45.554392 -100.045012)
		(end 46.042326 -100.045012)
		(stroke
			(width 0.06731)
			(type default)
		)
		(layer "F.Cu")
	)
	(gr_line
		(start 47.287688 -350.365314)
		(end 47.607728 -350.685354)
		(stroke
			(width 0.06731)
			(type default)
		)
		(layer "F.Cu")
	)
	(gr_line
		(start 47.313088 -348.58579)
		(end 47.607728 -348.88043)
		(stroke
			(width 0.06731)
			(type default)
		)
		(layer "F.Cu")
	)
	(gr_line
		(start 47.607728 -351.316798)
		(end 47.313088 -351.611438)
		(stroke
			(width 0.06731)
			(type default)
		)
		(layer "F.Cu")
	)
	(gr_line
		(start 47.607728 -349.511874)
		(end 47.287688 -349.831914)
		(stroke
			(width 0.06731)
			(type default)
		)
		(layer "F.Cu")
	)
	(gr_line
		(start 47.882048 -351.316798)
		(end 48.176688 -351.611438)
		(stroke
			(width 0.06731)
			(type default)
		)
		(layer "F.Cu")
	)
	(gr_line
		(start 47.882048 -349.511874)
		(end 48.202088 -349.831914)
		(stroke
			(width 0.06731)
			(type default)
		)
		(layer "F.Cu")
	)
	(gr_line
		(start 48.176688 -348.58579)
		(end 47.882048 -348.88043)
		(stroke
			(width 0.06731)
			(type default)
		)
		(layer "F.Cu")
	)
	(gr_line
		(start 48.202088 -350.365314)
		(end 47.882048 -350.685354)
		(stroke
			(width 0.06731)
			(type default)
		)
		(layer "F.Cu")
	)
	(gr_line
		(start 50.396648 -356.511606)
		(end 50.716688 -356.831646)
		(stroke
			(width 0.06731)
			(type default)
		)
		(layer "F.Cu")
	)
	(gr_line
		(start 50.396648 -344.219022)
		(end 50.716688 -344.539062)
		(stroke
			(width 0.06731)
			(type default)
		)
		(layer "F.Cu")
	)
	(gr_line
		(start 50.422048 -354.732082)
		(end 50.716688 -355.026722)
		(stroke
			(width 0.06731)
			(type default)
		)
		(layer "F.Cu")
	)
	(gr_line
		(start 50.422048 -342.439498)
		(end 50.716688 -342.734138)
		(stroke
			(width 0.06731)
			(type default)
		)
		(layer "F.Cu")
	)
	(gr_line
		(start 50.716688 -357.46309)
		(end 50.422048 -357.75773)
		(stroke
			(width 0.06731)
			(type default)
		)
		(layer "F.Cu")
	)
	(gr_line
		(start 50.716688 -355.658166)
		(end 50.396648 -355.978206)
		(stroke
			(width 0.06731)
			(type default)
		)
		(layer "F.Cu")
	)
	(gr_line
		(start 50.716688 -345.170506)
		(end 50.422048 -345.465146)
		(stroke
			(width 0.06731)
			(type default)
		)
		(layer "F.Cu")
	)
	(gr_line
		(start 50.716688 -343.365582)
		(end 50.396648 -343.685622)
		(stroke
			(width 0.06731)
			(type default)
		)
		(layer "F.Cu")
	)
	(gr_line
		(start 51.130454 -134.765034)
		(end 50.64252 -134.765034)
		(stroke
			(width 0.06731)
			(type default)
		)
		(layer "F.Cu")
	)
	(gr_line
		(start 51.293268 -134.60222)
		(end 51.130454 -134.765034)
		(stroke
			(width 0.06731)
			(type default)
		)
		(layer "F.Cu")
	)
	(gr_line
		(start 53.80228 -134.601712)
		(end 53.801772 -134.60222)
		(stroke
			(width 0.06731)
			(type default)
		)
		(layer "F.Cu")
	)
	(gr_line
		(start 54.09692 -134.896352)
		(end 53.80228 -134.601712)
		(stroke
			(width 0.06731)
			(type default)
		)
		(layer "F.Cu")
	)
	(gr_line
		(start 54.404514 -364.086648)
		(end 54.404514 -363.780832)
		(stroke
			(width 0.06731)
			(type default)
		)
		(layer "F.Cu")
	)
	(gr_line
		(start 54.640988 -371.0178)
		(end 54.348126 -371.310662)
		(stroke
			(width 0.06731)
			(type default)
		)
		(layer "F.Cu")
	)
	(gr_line
		(start 54.643274 -370.74221)
		(end 54.348126 -370.447062)
		(stroke
			(width 0.06731)
			(type default)
		)
		(layer "F.Cu")
	)
	(gr_line
		(start 54.644544 -371.0178)
		(end 54.640988 -371.0178)
		(stroke
			(width 0.06731)
			(type default)
		)
		(layer "F.Cu")
	)
	(gr_line
		(start 54.89575 -365.767112)
		(end 55.19293 -365.469932)
		(stroke
			(width 0.06731)
			(type default)
		)
		(layer "F.Cu")
	)
	(gr_line
		(start 55.19293 -364.875064)
		(end 54.404514 -364.086648)
		(stroke
			(width 0.06731)
			(type default)
		)
		(layer "F.Cu")
	)
	(gr_line
		(start 55.449724 -371.0178)
		(end 55.446168 -371.0178)
		(stroke
			(width 0.06731)
			(type default)
		)
		(layer "F.Cu")
	)
	(gr_line
		(start 55.46852 -365.476282)
		(end 55.46852 -365.468662)
		(stroke
			(width 0.06731)
			(type default)
		)
		(layer "F.Cu")
	)
	(gr_line
		(start 55.46852 -364.876334)
		(end 55.46852 -364.868714)
		(stroke
			(width 0.06731)
			(type default)
		)
		(layer "F.Cu")
	)
	(gr_line
		(start 55.46852 -364.868714)
		(end 56.271922 -364.065312)
		(stroke
			(width 0.06731)
			(type default)
		)
		(layer "F.Cu")
	)
	(gr_line
		(start 55.75935 -365.767112)
		(end 55.46852 -365.476282)
		(stroke
			(width 0.06731)
			(type default)
		)
		(layer "F.Cu")
	)
	(gr_line
		(start 55.767986 -371.336062)
		(end 55.449724 -371.0178)
		(stroke
			(width 0.06731)
			(type default)
		)
		(layer "F.Cu")
	)
	(gr_line
		(start 55.767986 -370.421662)
		(end 55.447438 -370.74221)
		(stroke
			(width 0.06731)
			(type default)
		)
		(layer "F.Cu")
	)
	(gr_line
		(start 56.271922 -364.065312)
		(end 56.271922 -363.756194)
		(stroke
			(width 0.06731)
			(type default)
		)
		(layer "F.Cu")
	)
	(gr_line
		(start 56.619648 -371.0178)
		(end 56.301386 -371.336062)
		(stroke
			(width 0.06731)
			(type default)
		)
		(layer "F.Cu")
	)
	(gr_line
		(start 56.621934 -370.74221)
		(end 56.301386 -370.421662)
		(stroke
			(width 0.06731)
			(type default)
		)
		(layer "F.Cu")
	)
	(gr_line
		(start 56.623204 -371.0178)
		(end 56.619648 -371.0178)
		(stroke
			(width 0.06731)
			(type default)
		)
		(layer "F.Cu")
	)
	(gr_line
		(start 57.428384 -371.0178)
		(end 57.424828 -371.0178)
		(stroke
			(width 0.06731)
			(type default)
		)
		(layer "F.Cu")
	)
	(gr_line
		(start 57.721246 -371.310662)
		(end 57.428384 -371.0178)
		(stroke
			(width 0.06731)
			(type default)
		)
		(layer "F.Cu")
	)
	(gr_line
		(start 57.721246 -370.447062)
		(end 57.426098 -370.74221)
		(stroke
			(width 0.06731)
			(type default)
		)
		(layer "F.Cu")
	)
	(gr_line
		(start 59.50458 -30.628336)
		(end 59.210448 -30.922468)
		(stroke
			(width 0.06731)
			(type default)
		)
		(layer "F.Cu")
	)
	(gr_line
		(start 62.182248 -30.790134)
		(end 62.020704 -30.62859)
		(stroke
			(width 0.06731)
			(type default)
		)
		(layer "F.Cu")
	)
	(gr_line
		(start 62.664848 -30.790134)
		(end 62.182248 -30.790134)
		(stroke
			(width 0.06731)
			(type default)
		)
		(layer "F.Cu")
	)
	(gr_line
		(start 65.498218 -148.592286)
		(end 65.20307 -148.887434)
		(stroke
			(width 0.06731)
			(type default)
		)
		(layer "F.Cu")
	)
	(gr_line
		(start 65.498218 -135.882126)
		(end 65.20307 -136.177274)
		(stroke
			(width 0.06731)
			(type default)
		)
		(layer "F.Cu")
	)
	(gr_line
		(start 65.498218 -121.072148)
		(end 65.20307 -121.367296)
		(stroke
			(width 0.06731)
			(type default)
		)
		(layer "F.Cu")
	)
	(gr_line
		(start 68.169536 -148.7551)
		(end 68.006722 -148.592286)
		(stroke
			(width 0.06731)
			(type default)
		)
		(layer "F.Cu")
	)
	(gr_line
		(start 68.169536 -136.04494)
		(end 68.006722 -135.882126)
		(stroke
			(width 0.06731)
			(type default)
		)
		(layer "F.Cu")
	)
	(gr_line
		(start 68.169536 -121.234962)
		(end 68.006722 -121.072148)
		(stroke
			(width 0.06731)
			(type default)
		)
		(layer "F.Cu")
	)
	(gr_line
		(start 68.65747 -148.7551)
		(end 68.169536 -148.7551)
		(stroke
			(width 0.06731)
			(type default)
		)
		(layer "F.Cu")
	)
	(gr_line
		(start 68.65747 -136.04494)
		(end 68.169536 -136.04494)
		(stroke
			(width 0.06731)
			(type default)
		)
		(layer "F.Cu")
	)
	(gr_line
		(start 68.65747 -121.234962)
		(end 68.169536 -121.234962)
		(stroke
			(width 0.06731)
			(type default)
		)
		(layer "F.Cu")
	)
	(gr_line
		(start 73.745852 -143.35506)
		(end 73.257664 -143.35506)
		(stroke
			(width 0.06731)
			(type default)
		)
		(layer "F.Cu")
	)
	(gr_line
		(start 73.908666 -143.192246)
		(end 73.745852 -143.35506)
		(stroke
			(width 0.06731)
			(type default)
		)
		(layer "F.Cu")
	)
	(gr_line
		(start 79.440278 -143.192246)
		(end 79.425038 -143.192246)
		(stroke
			(width 0.06731)
			(type default)
		)
		(layer "F.Cu")
	)
	(gr_line
		(start 79.752698 -143.504666)
		(end 79.440278 -143.192246)
		(stroke
			(width 0.06731)
			(type default)
		)
		(layer "F.Cu")
	)
	(gr_line
		(start 80.606138 -143.184626)
		(end 80.286098 -143.504666)
		(stroke
			(width 0.06731)
			(type default)
		)
		(layer "F.Cu")
	)
	(gr_line
		(start 81.532222 -143.479266)
		(end 81.237582 -143.184626)
		(stroke
			(width 0.06731)
			(type default)
		)
		(layer "F.Cu")
	)
	(gr_line
		(start 85.504528 -30.628336)
		(end 85.210396 -30.922468)
		(stroke
			(width 0.06731)
			(type default)
		)
		(layer "F.Cu")
	)
	(gr_line
		(start 85.504528 -30.353)
		(end 85.210396 -30.058868)
		(stroke
			(width 0.06731)
			(type default)
		)
		(layer "F.Cu")
	)
	(gr_line
		(start 85.505544 -30.353)
		(end 85.504528 -30.353)
		(stroke
			(width 0.06731)
			(type default)
		)
		(layer "F.Cu")
	)
	(gr_line
		(start 88.024462 -30.353)
		(end 88.019382 -30.353)
		(stroke
			(width 0.06731)
			(type default)
		)
		(layer "F.Cu")
	)
	(gr_line
		(start 88.182196 -30.790134)
		(end 88.020652 -30.62859)
		(stroke
			(width 0.06731)
			(type default)
		)
		(layer "F.Cu")
	)
	(gr_line
		(start 88.187276 -30.190186)
		(end 88.024462 -30.353)
		(stroke
			(width 0.06731)
			(type default)
		)
		(layer "F.Cu")
	)
	(gr_line
		(start 88.664796 -30.790134)
		(end 88.182196 -30.790134)
		(stroke
			(width 0.06731)
			(type default)
		)
		(layer "F.Cu")
	)
	(gr_line
		(start 88.664796 -30.190186)
		(end 88.187276 -30.190186)
		(stroke
			(width 0.06731)
			(type default)
		)
		(layer "F.Cu")
	)
	(gr_line
		(start 93.764354 -28.990036)
		(end 93.264736 -28.990036)
		(stroke
			(width 0.06731)
			(type default)
		)
		(layer "F.Cu")
	)
	(gr_line
		(start 93.768418 -27.189938)
		(end 93.264736 -27.189938)
		(stroke
			(width 0.06731)
			(type default)
		)
		(layer "F.Cu")
	)
	(gr_line
		(start 93.907356 -27.051)
		(end 93.768418 -27.189938)
		(stroke
			(width 0.06731)
			(type default)
		)
		(layer "F.Cu")
	)
	(gr_line
		(start 93.92539 -28.829)
		(end 93.764354 -28.990036)
		(stroke
			(width 0.06731)
			(type default)
		)
		(layer "F.Cu")
	)
	(gr_line
		(start 93.932502 -28.829)
		(end 93.92539 -28.829)
		(stroke
			(width 0.06731)
			(type default)
		)
		(layer "F.Cu")
	)
	(gr_line
		(start 93.941392 -27.051)
		(end 93.907356 -27.051)
		(stroke
			(width 0.06731)
			(type default)
		)
		(layer "F.Cu")
	)
	(gr_line
		(start 94.689422 -27.051)
		(end 94.683834 -27.051)
		(stroke
			(width 0.06731)
			(type default)
		)
		(layer "F.Cu")
	)
	(gr_line
		(start 94.981268 -27.342846)
		(end 94.689422 -27.051)
		(stroke
			(width 0.06731)
			(type default)
		)
		(layer "F.Cu")
	)
	(gr_line
		(start 95.214948 -28.829)
		(end 95.196152 -28.829)
		(stroke
			(width 0.06731)
			(type default)
		)
		(layer "F.Cu")
	)
	(gr_line
		(start 95.52559 -29.139642)
		(end 95.214948 -28.829)
		(stroke
			(width 0.06731)
			(type default)
		)
		(layer "F.Cu")
	)
	(gr_line
		(start 96.369632 -28.829)
		(end 96.05899 -29.139642)
		(stroke
			(width 0.06731)
			(type default)
		)
		(layer "F.Cu")
	)
	(gr_line
		(start 96.388428 -28.829)
		(end 96.369632 -28.829)
		(stroke
			(width 0.06731)
			(type default)
		)
		(layer "F.Cu")
	)
	(gr_line
		(start 97.019872 -28.829)
		(end 97.001076 -28.829)
		(stroke
			(width 0.06731)
			(type default)
		)
		(layer "F.Cu")
	)
	(gr_line
		(start 97.305114 -29.114242)
		(end 97.019872 -28.829)
		(stroke
			(width 0.06731)
			(type default)
		)
		(layer "F.Cu")
	)
	(gr_line
		(start 99.0981 -201.06386)
		(end 98.80981 -201.35215)
		(stroke
			(width 0.06731)
			(type default)
		)
		(layer "F.Cu")
	)
	(gr_line
		(start 99.0981 -201.05116)
		(end 99.0981 -201.06386)
		(stroke
			(width 0.06731)
			(type default)
		)
		(layer "F.Cu")
	)
	(gr_line
		(start 99.37369 -201.05243)
		(end 99.67341 -201.35215)
		(stroke
			(width 0.06731)
			(type default)
		)
		(layer "F.Cu")
	)
	(gr_line
		(start 99.97948 -386.394452)
		(end 100.786946 -387.201918)
		(stroke
			(width 0.06731)
			(type default)
		)
		(layer "F.Cu")
	)
	(gr_line
		(start 99.97948 -385.977892)
		(end 99.97948 -386.394452)
		(stroke
			(width 0.06731)
			(type default)
		)
		(layer "F.Cu")
	)
	(gr_line
		(start 100.45827 -198.527416)
		(end 100.57511 -198.644256)
		(stroke
			(width 0.06731)
			(type default)
		)
		(layer "F.Cu")
	)
	(gr_line
		(start 100.45827 -198.20128)
		(end 100.45827 -198.527416)
		(stroke
			(width 0.06731)
			(type default)
		)
		(layer "F.Cu")
	)
	(gr_line
		(start 100.8507 -198.6407)
		(end 100.8507 -198.645526)
		(stroke
			(width 0.06731)
			(type default)
		)
		(layer "F.Cu")
	)
	(gr_line
		(start 100.958142 -198.533258)
		(end 100.8507 -198.6407)
		(stroke
			(width 0.06731)
			(type default)
		)
		(layer "F.Cu")
	)
	(gr_line
		(start 100.958142 -198.20128)
		(end 100.958142 -198.533258)
		(stroke
			(width 0.06731)
			(type default)
		)
		(layer "F.Cu")
	)
	(gr_line
		(start 101.062536 -387.200394)
		(end 101.062536 -387.203442)
		(stroke
			(width 0.06731)
			(type default)
		)
		(layer "F.Cu")
	)
	(gr_line
		(start 101.06279 -387.203696)
		(end 101.062536 -387.203442)
		(stroke
			(width 0.06731)
			(type default)
		)
		(layer "F.Cu")
	)
	(gr_line
		(start 101.829362 -386.433568)
		(end 101.062536 -387.200394)
		(stroke
			(width 0.06731)
			(type default)
		)
		(layer "F.Cu")
	)
	(gr_line
		(start 101.829362 -386.005324)
		(end 101.829362 -386.433568)
		(stroke
			(width 0.06731)
			(type default)
		)
		(layer "F.Cu")
	)
	(gr_line
		(start 101.87686 -389.464042)
		(end 101.87686 -389.741918)
		(stroke
			(width 0.06731)
			(type default)
		)
		(layer "F.Cu")
	)
	(gr_line
		(start 101.98354 -389.357362)
		(end 101.87686 -389.464042)
		(stroke
			(width 0.06731)
			(type default)
		)
		(layer "F.Cu")
	)
	(gr_line
		(start 101.98354 -389.32485)
		(end 101.98354 -389.357362)
		(stroke
			(width 0.06731)
			(type default)
		)
		(layer "F.Cu")
	)
	(gr_line
		(start 102.25913 -389.32612)
		(end 102.376986 -389.443976)
		(stroke
			(width 0.06731)
			(type default)
		)
		(layer "F.Cu")
	)
	(gr_line
		(start 102.376986 -389.443976)
		(end 102.376986 -389.741918)
		(stroke
			(width 0.06731)
			(type default)
		)
		(layer "F.Cu")
	)
	(gr_line
		(start 102.877112 -389.464042)
		(end 102.877112 -389.741918)
		(stroke
			(width 0.06731)
			(type default)
		)
		(layer "F.Cu")
	)
	(gr_line
		(start 102.995222 -389.345932)
		(end 102.877112 -389.464042)
		(stroke
			(width 0.06731)
			(type default)
		)
		(layer "F.Cu")
	)
	(gr_line
		(start 103.270812 -389.358632)
		(end 103.376984 -389.464804)
		(stroke
			(width 0.06731)
			(type default)
		)
		(layer "F.Cu")
	)
	(gr_line
		(start 103.270812 -389.344662)
		(end 103.270812 -389.358632)
		(stroke
			(width 0.06731)
			(type default)
		)
		(layer "F.Cu")
	)
	(gr_line
		(start 103.376984 -389.464804)
		(end 103.376984 -389.741918)
		(stroke
			(width 0.06731)
			(type default)
		)
		(layer "F.Cu")
	)
	(gr_line
		(start 104.376982 -389.741918)
		(end 104.376982 -389.464042)
		(stroke
			(width 0.06731)
			(type default)
		)
		(layer "F.Cu")
	)
	(gr_line
		(start 104.376982 -389.464042)
		(end 104.496362 -389.344662)
		(stroke
			(width 0.06731)
			(type default)
		)
		(layer "F.Cu")
	)
	(gr_line
		(start 104.496362 -389.344662)
		(end 104.496362 -389.33755)
		(stroke
			(width 0.06731)
			(type default)
		)
		(layer "F.Cu")
	)
	(gr_line
		(start 104.517698 -381.67691)
		(end 105.320592 -382.479804)
		(stroke
			(width 0.06731)
			(type default)
		)
		(layer "F.Cu")
	)
	(gr_line
		(start 104.517698 -381.323596)
		(end 104.517698 -381.67691)
		(stroke
			(width 0.06731)
			(type default)
		)
		(layer "F.Cu")
	)
	(gr_line
		(start 104.877108 -389.741918)
		(end 104.877108 -389.443976)
		(stroke
			(width 0.06731)
			(type default)
		)
		(layer "F.Cu")
	)
	(gr_line
		(start 104.877108 -389.443976)
		(end 104.771952 -389.33882)
		(stroke
			(width 0.06731)
			(type default)
		)
		(layer "F.Cu")
	)
	(gr_line
		(start 105.099104 -386.917184)
		(end 105.38841 -386.627878)
		(stroke
			(width 0.06731)
			(type default)
		)
		(layer "F.Cu")
	)
	(gr_line
		(start 105.320592 -382.479804)
		(end 105.320592 -382.491742)
		(stroke
			(width 0.06731)
			(type default)
		)
		(layer "F.Cu")
	)
	(gr_line
		(start 105.379266 -387.214364)
		(end 105.379266 -387.197346)
		(stroke
			(width 0.06731)
			(type default)
		)
		(layer "F.Cu")
	)
	(gr_line
		(start 105.379266 -387.197346)
		(end 105.099104 -386.917184)
		(stroke
			(width 0.06731)
			(type default)
		)
		(layer "F.Cu")
	)
	(gr_line
		(start 105.38841 -385.584192)
		(end 105.093262 -385.289044)
		(stroke
			(width 0.06731)
			(type default)
		)
		(layer "F.Cu")
	)
	(gr_line
		(start 105.654856 -387.213094)
		(end 105.950766 -386.917184)
		(stroke
			(width 0.06731)
			(type default)
		)
		(layer "F.Cu")
	)
	(gr_line
		(start 105.664 -386.630418)
		(end 105.664 -386.626608)
		(stroke
			(width 0.06731)
			(type default)
		)
		(layer "F.Cu")
	)
	(gr_line
		(start 105.664 -385.585462)
		(end 105.664 -385.581906)
		(stroke
			(width 0.06731)
			(type default)
		)
		(layer "F.Cu")
	)
	(gr_line
		(start 105.664 -385.581906)
		(end 105.956862 -385.289044)
		(stroke
			(width 0.06731)
			(type default)
		)
		(layer "F.Cu")
	)
	(gr_line
		(start 105.950766 -386.917184)
		(end 105.664 -386.630418)
		(stroke
			(width 0.06731)
			(type default)
		)
		(layer "F.Cu")
	)
	(gr_line
		(start 106.385106 -381.701548)
		(end 105.596182 -382.490472)
		(stroke
			(width 0.06731)
			(type default)
		)
		(layer "F.Cu")
	)
	(gr_line
		(start 106.385106 -381.298958)
		(end 106.385106 -381.701548)
		(stroke
			(width 0.06731)
			(type default)
		)
		(layer "F.Cu")
	)
	(gr_line
		(start 110.170976 -93.758766)
		(end 110.470696 -94.058486)
		(stroke
			(width 0.06731)
			(type default)
		)
		(layer "F.Cu")
	)
	(gr_line
		(start 110.182406 -91.619832)
		(end 110.496096 -91.933522)
		(stroke
			(width 0.06731)
			(type default)
		)
		(layer "F.Cu")
	)
	(gr_line
		(start 110.182406 -91.607132)
		(end 110.182406 -91.619832)
		(stroke
			(width 0.06731)
			(type default)
		)
		(layer "F.Cu")
	)
	(gr_line
		(start 110.182406 -89.412064)
		(end 110.182406 -89.42578)
		(stroke
			(width 0.06731)
			(type default)
		)
		(layer "F.Cu")
	)
	(gr_line
		(start 110.239048 -89.355422)
		(end 110.182406 -89.412064)
		(stroke
			(width 0.06731)
			(type default)
		)
		(layer "F.Cu")
	)
	(gr_line
		(start 110.239048 -88.928956)
		(end 110.239048 -89.355422)
		(stroke
			(width 0.06731)
			(type default)
		)
		(layer "F.Cu")
	)
	(gr_line
		(start 110.496096 -92.733622)
		(end 110.170976 -93.058742)
		(stroke
			(width 0.06731)
			(type default)
		)
		(layer "F.Cu")
	)
	(gr_line
		(start 111.788956 -88.178894)
		(end 112.216692 -88.178894)
		(stroke
			(width 0.06731)
			(type default)
		)
		(layer "F.Cu")
	)
	(gr_line
		(start 111.788956 -87.779098)
		(end 112.215676 -87.779098)
		(stroke
			(width 0.06731)
			(type default)
		)
		(layer "F.Cu")
	)
	(gr_line
		(start 111.788956 -86.578948)
		(end 112.215422 -86.578948)
		(stroke
			(width 0.06731)
			(type default)
		)
		(layer "F.Cu")
	)
	(gr_line
		(start 111.788956 -83.779106)
		(end 112.215676 -83.779106)
		(stroke
			(width 0.06731)
			(type default)
		)
		(layer "F.Cu")
	)
	(gr_line
		(start 112.215422 -86.578948)
		(end 112.283494 -86.64702)
		(stroke
			(width 0.06731)
			(type default)
		)
		(layer "F.Cu")
	)
	(gr_line
		(start 112.215676 -87.779098)
		(end 112.283494 -87.846916)
		(stroke
			(width 0.06731)
			(type default)
		)
		(layer "F.Cu")
	)
	(gr_line
		(start 112.215676 -83.779106)
		(end 112.272064 -83.835494)
		(stroke
			(width 0.06731)
			(type default)
		)
		(layer "F.Cu")
	)
	(gr_line
		(start 112.216692 -88.178894)
		(end 112.27308 -88.122506)
		(stroke
			(width 0.06731)
			(type default)
		)
		(layer "F.Cu")
	)
	(gr_line
		(start 112.272064 -83.835494)
		(end 112.28578 -83.835494)
		(stroke
			(width 0.06731)
			(type default)
		)
		(layer "F.Cu")
	)
	(gr_line
		(start 112.27308 -88.122506)
		(end 112.284764 -88.122506)
		(stroke
			(width 0.06731)
			(type default)
		)
		(layer "F.Cu")
	)
	(gr_line
		(start 114.629946 -89.070688)
		(end 114.642646 -89.070688)
		(stroke
			(width 0.06731)
			(type default)
		)
		(layer "F.Cu")
	)
	(gr_line
		(start 114.629946 -82.78368)
		(end 114.642646 -82.78368)
		(stroke
			(width 0.06731)
			(type default)
		)
		(layer "F.Cu")
	)
	(gr_line
		(start 114.631216 -88.795098)
		(end 114.956336 -88.469978)
		(stroke
			(width 0.06731)
			(type default)
		)
		(layer "F.Cu")
	)
	(gr_line
		(start 114.635788 -86.79053)
		(end 114.956336 -86.469982)
		(stroke
			(width 0.06731)
			(type default)
		)
		(layer "F.Cu")
	)
	(gr_line
		(start 114.642646 -89.070688)
		(end 114.956336 -89.384378)
		(stroke
			(width 0.06731)
			(type default)
		)
		(layer "F.Cu")
	)
	(gr_line
		(start 114.642646 -82.78368)
		(end 114.956336 -82.46999)
		(stroke
			(width 0.06731)
			(type default)
		)
		(layer "F.Cu")
	)
	(gr_line
		(start 115.756436 -89.384378)
		(end 116.087144 -89.05367)
		(stroke
			(width 0.06731)
			(type default)
		)
		(layer "F.Cu")
	)
	(gr_line
		(start 115.756436 -88.469978)
		(end 116.064538 -88.77808)
		(stroke
			(width 0.06731)
			(type default)
		)
		(layer "F.Cu")
	)
	(gr_line
		(start 115.756436 -86.469982)
		(end 116.082064 -86.79561)
		(stroke
			(width 0.06731)
			(type default)
		)
		(layer "F.Cu")
	)
	(gr_line
		(start 115.756436 -82.46999)
		(end 116.070126 -82.78368)
		(stroke
			(width 0.06731)
			(type default)
		)
		(layer "F.Cu")
	)
	(gr_line
		(start 116.064538 -88.77808)
		(end 116.088414 -88.77808)
		(stroke
			(width 0.06731)
			(type default)
		)
		(layer "F.Cu")
	)
	(gr_line
		(start 116.070126 -82.78368)
		(end 116.082826 -82.78368)
		(stroke
			(width 0.06731)
			(type default)
		)
		(layer "F.Cu")
	)
	(gr_line
		(start 116.78031 -82.78368)
		(end 116.79301 -82.78368)
		(stroke
			(width 0.06731)
			(type default)
		)
		(layer "F.Cu")
	)
	(gr_line
		(start 116.781072 -86.79561)
		(end 117.0813 -86.495382)
		(stroke
			(width 0.06731)
			(type default)
		)
		(layer "F.Cu")
	)
	(gr_line
		(start 116.79301 -82.78368)
		(end 117.0813 -82.49539)
		(stroke
			(width 0.06731)
			(type default)
		)
		(layer "F.Cu")
	)
	(gr_line
		(start 117.536722 -88.77808)
		(end 117.560598 -88.77808)
		(stroke
			(width 0.06731)
			(type default)
		)
		(layer "F.Cu")
	)
	(gr_line
		(start 117.537992 -89.05367)
		(end 117.8433 -89.358978)
		(stroke
			(width 0.06731)
			(type default)
		)
		(layer "F.Cu")
	)
	(gr_line
		(start 117.560598 -88.77808)
		(end 117.8433 -88.495378)
		(stroke
			(width 0.06731)
			(type default)
		)
		(layer "F.Cu")
	)
	(gr_line
		(start 123.604782 -30.628336)
		(end 123.31065 -30.922468)
		(stroke
			(width 0.06731)
			(type default)
		)
		(layer "F.Cu")
	)
	(gr_line
		(start 125.45822 -28.829)
		(end 125.16485 -29.12237)
		(stroke
			(width 0.06731)
			(type default)
		)
		(layer "F.Cu")
	)
	(gr_line
		(start 125.46076 -28.829)
		(end 125.45822 -28.829)
		(stroke
			(width 0.06731)
			(type default)
		)
		(layer "F.Cu")
	)
	(gr_line
		(start 125.502162 -174.6885)
		(end 125.49251 -174.6885)
		(stroke
			(width 0.05715)
			(type default)
		)
		(layer "F.Cu")
	)
	(gr_line
		(start 125.821186 -177.039524)
		(end 125.492002 -176.71034)
		(stroke
			(width 0.05715)
			(type default)
		)
		(layer "F.Cu")
	)
	(gr_line
		(start 125.821186 -175.007524)
		(end 125.502162 -174.6885)
		(stroke
			(width 0.05715)
			(type default)
		)
		(layer "F.Cu")
	)
	(gr_line
		(start 125.821186 -173.991524)
		(end 125.49505 -174.31766)
		(stroke
			(width 0.05715)
			(type default)
		)
		(layer "F.Cu")
	)
	(gr_line
		(start 126.124716 -28.829)
		(end 126.119636 -28.829)
		(stroke
			(width 0.06731)
			(type default)
		)
		(layer "F.Cu")
	)
	(gr_line
		(start 126.28245 -30.790134)
		(end 126.120906 -30.62859)
		(stroke
			(width 0.06731)
			(type default)
		)
		(layer "F.Cu")
	)
	(gr_line
		(start 126.286006 -28.99029)
		(end 126.124716 -28.829)
		(stroke
			(width 0.06731)
			(type default)
		)
		(layer "F.Cu")
	)
	(gr_line
		(start 126.76505 -30.790134)
		(end 126.28245 -30.790134)
		(stroke
			(width 0.06731)
			(type default)
		)
		(layer "F.Cu")
	)
	(gr_line
		(start 126.76505 -28.99029)
		(end 126.286006 -28.99029)
		(stroke
			(width 0.06731)
			(type default)
		)
		(layer "F.Cu")
	)
	(gr_line
		(start 126.76505 -28.990036)
		(end 126.76505 -28.99029)
		(stroke
			(width 0.06731)
			(type default)
		)
		(layer "F.Cu")
	)
	(gr_line
		(start 126.938786 -174.690024)
		(end 126.621286 -175.007524)
		(stroke
			(width 0.05715)
			(type default)
		)
		(layer "F.Cu")
	)
	(gr_line
		(start 126.948946 -176.711864)
		(end 126.621286 -177.039524)
		(stroke
			(width 0.05715)
			(type default)
		)
		(layer "F.Cu")
	)
	(gr_line
		(start 126.948946 -174.319184)
		(end 126.621286 -173.991524)
		(stroke
			(width 0.05715)
			(type default)
		)
		(layer "F.Cu")
	)
	(gr_line
		(start 126.951486 -174.690024)
		(end 126.938786 -174.690024)
		(stroke
			(width 0.05715)
			(type default)
		)
		(layer "F.Cu")
	)
	(gr_line
		(start 127.99314 -195.445888)
		(end 128.24333 -195.696078)
		(stroke
			(width 0.05715)
			(type default)
		)
		(layer "F.Cu")
	)
	(gr_line
		(start 129.83845 -174.9552)
		(end 129.784856 -174.9552)
		(stroke
			(width 0.05715)
			(type default)
		)
		(layer "F.Cu")
	)
	(gr_line
		(start 129.854452 -176.3522)
		(end 129.769108 -176.3522)
		(stroke
			(width 0.05715)
			(type default)
		)
		(layer "F.Cu")
	)
	(gr_line
		(start 129.874518 -233.265472)
		(end 130.354324 -233.745024)
		(stroke
			(width 0.05715)
			(type default)
		)
		(layer "F.Cu")
	)
	(gr_line
		(start 129.971038 -176.40046)
		(end 129.854452 -176.3522)
		(stroke
			(width 0.05715)
			(type default)
		)
		(layer "F.Cu")
	)
	(gr_line
		(start 129.971038 -175.400462)
		(end 129.790952 -175.32604)
		(stroke
			(width 0.05715)
			(type default)
		)
		(layer "F.Cu")
	)
	(gr_line
		(start 129.971038 -174.900336)
		(end 129.83845 -174.9552)
		(stroke
			(width 0.05715)
			(type default)
		)
		(layer "F.Cu")
	)
	(gr_line
		(start 130.138678 -233.004868)
		(end 130.329178 -233.004868)
		(stroke
			(width 0.05715)
			(type default)
		)
		(layer "F.Cu")
	)
	(gr_line
		(start 130.329178 -233.004868)
		(end 130.614928 -233.290872)
		(stroke
			(width 0.05715)
			(type default)
		)
		(layer "F.Cu")
	)
	(gr_line
		(start 130.614928 -233.290872)
		(end 130.614928 -233.481118)
		(stroke
			(width 0.05715)
			(type default)
		)
		(layer "F.Cu")
	)
	(gr_line
		(start 130.63982 -234.03052)
		(end 131.11988 -234.51058)
		(stroke
			(width 0.05715)
			(type default)
		)
		(layer "F.Cu")
	)
	(gr_line
		(start 130.90398 -233.77017)
		(end 131.09448 -233.77017)
		(stroke
			(width 0.05715)
			(type default)
		)
		(layer "F.Cu")
	)
	(gr_line
		(start 131.09448 -233.77017)
		(end 131.38023 -234.05592)
		(stroke
			(width 0.05715)
			(type default)
		)
		(layer "F.Cu")
	)
	(gr_line
		(start 131.108196 -171.327572)
		(end 131.435856 -170.999912)
		(stroke
			(width 0.05715)
			(type default)
		)
		(layer "F.Cu")
	)
	(gr_line
		(start 131.38023 -234.05592)
		(end 131.38023 -234.24642)
		(stroke
			(width 0.05715)
			(type default)
		)
		(layer "F.Cu")
	)
	(gr_line
		(start 131.405122 -234.796076)
		(end 131.884928 -235.275628)
		(stroke
			(width 0.05715)
			(type default)
		)
		(layer "F.Cu")
	)
	(gr_line
		(start 131.435856 -170.199812)
		(end 131.10464 -169.868596)
		(stroke
			(width 0.05715)
			(type default)
		)
		(layer "F.Cu")
	)
	(gr_line
		(start 131.669282 -234.535472)
		(end 131.859528 -234.535472)
		(stroke
			(width 0.05715)
			(type default)
		)
		(layer "F.Cu")
	)
	(gr_line
		(start 131.859528 -234.535472)
		(end 132.145532 -234.821222)
		(stroke
			(width 0.05715)
			(type default)
		)
		(layer "F.Cu")
	)
	(gr_line
		(start 131.908042 -174.74819)
		(end 131.908042 -174.734728)
		(stroke
			(width 0.05715)
			(type default)
		)
		(layer "F.Cu")
	)
	(gr_line
		(start 131.971034 -174.900336)
		(end 131.908042 -174.74819)
		(stroke
			(width 0.05715)
			(type default)
		)
		(layer "F.Cu")
	)
	(gr_line
		(start 132.145532 -234.821222)
		(end 132.145532 -235.011722)
		(stroke
			(width 0.05715)
			(type default)
		)
		(layer "F.Cu")
	)
	(gr_line
		(start 133.38683 -236.221016)
		(end 134.06501 -236.221016)
		(stroke
			(width 0.05715)
			(type default)
		)
		(layer "F.Cu")
	)
	(gr_line
		(start 133.38937 -235.850176)
		(end 133.52399 -235.715556)
		(stroke
			(width 0.05715)
			(type default)
		)
		(layer "F.Cu")
	)
	(gr_line
		(start 133.52399 -235.715556)
		(end 133.92785 -235.715556)
		(stroke
			(width 0.05715)
			(type default)
		)
		(layer "F.Cu")
	)
	(gr_line
		(start 133.92785 -235.715556)
		(end 134.06247 -235.850176)
		(stroke
			(width 0.05715)
			(type default)
		)
		(layer "F.Cu")
	)
	(gr_line
		(start 134.46887 -236.221016)
		(end 135.14705 -236.221016)
		(stroke
			(width 0.05715)
			(type default)
		)
		(layer "F.Cu")
	)
	(gr_line
		(start 134.471156 -180.400452)
		(end 134.584948 -180.514244)
		(stroke
			(width 0.06731)
			(type default)
		)
		(layer "F.Cu")
	)
	(gr_line
		(start 134.47141 -235.850176)
		(end 134.60603 -235.715556)
		(stroke
			(width 0.05715)
			(type default)
		)
		(layer "F.Cu")
	)
	(gr_line
		(start 134.586218 -180.515514)
		(end 134.590282 -180.519578)
		(stroke
			(width 0.06731)
			(type default)
		)
		(layer "F.Cu")
	)
	(gr_line
		(start 134.590282 -180.519578)
		(end 134.598918 -180.528214)
		(stroke
			(width 0.06731)
			(type default)
		)
		(layer "F.Cu")
	)
	(gr_line
		(start 134.60603 -235.715556)
		(end 135.00989 -235.715556)
		(stroke
			(width 0.05715)
			(type default)
		)
		(layer "F.Cu")
	)
	(gr_line
		(start 134.860538 -180.519578)
		(end 134.869174 -180.528214)
		(stroke
			(width 0.06731)
			(type default)
		)
		(layer "F.Cu")
	)
	(gr_line
		(start 134.860538 -180.510942)
		(end 134.860538 -180.519578)
		(stroke
			(width 0.06731)
			(type default)
		)
		(layer "F.Cu")
	)
	(gr_line
		(start 134.869174 -180.528214)
		(end 134.873238 -180.532278)
		(stroke
			(width 0.06731)
			(type default)
		)
		(layer "F.Cu")
	)
	(gr_line
		(start 134.971028 -180.400452)
		(end 134.860538 -180.510942)
		(stroke
			(width 0.06731)
			(type default)
		)
		(layer "F.Cu")
	)
	(gr_line
		(start 135.00989 -235.715556)
		(end 135.14451 -235.850176)
		(stroke
			(width 0.05715)
			(type default)
		)
		(layer "F.Cu")
	)
	(gr_line
		(start 135.471154 -178.900328)
		(end 135.569706 -178.99888)
		(stroke
			(width 0.06731)
			(type default)
		)
		(layer "F.Cu")
	)
	(gr_line
		(start 135.55091 -236.221016)
		(end 136.22909 -236.221016)
		(stroke
			(width 0.05715)
			(type default)
		)
		(layer "F.Cu")
	)
	(gr_line
		(start 135.55345 -235.850176)
		(end 135.68807 -235.715556)
		(stroke
			(width 0.05715)
			(type default)
		)
		(layer "F.Cu")
	)
	(gr_line
		(start 135.569706 -178.99888)
		(end 135.598408 -178.99888)
		(stroke
			(width 0.06731)
			(type default)
		)
		(layer "F.Cu")
	)
	(gr_line
		(start 135.68807 -235.715556)
		(end 136.09193 -235.715556)
		(stroke
			(width 0.05715)
			(type default)
		)
		(layer "F.Cu")
	)
	(gr_line
		(start 135.96239 -185.057034)
		(end 136.32688 -185.421524)
		(stroke
			(width 0.06731)
			(type default)
		)
		(layer "F.Cu")
	)
	(gr_line
		(start 136.09193 -235.715556)
		(end 136.22655 -235.850176)
		(stroke
			(width 0.05715)
			(type default)
		)
		(layer "F.Cu")
	)
	(gr_line
		(start 136.32688 -186.806332)
		(end 136.03859 -187.094622)
		(stroke
			(width 0.06731)
			(type default)
		)
		(layer "F.Cu")
	)
	(gr_line
		(start 136.32688 -186.793632)
		(end 136.32688 -186.806332)
		(stroke
			(width 0.06731)
			(type default)
		)
		(layer "F.Cu")
	)
	(gr_line
		(start 136.32688 -185.421524)
		(end 136.32688 -185.434224)
		(stroke
			(width 0.06731)
			(type default)
		)
		(layer "F.Cu")
	)
	(gr_line
		(start 136.33831 -183.881014)
		(end 135.96239 -184.256934)
		(stroke
			(width 0.06731)
			(type default)
		)
		(layer "F.Cu")
	)
	(gr_line
		(start 136.60247 -186.794902)
		(end 136.90219 -187.094622)
		(stroke
			(width 0.06731)
			(type default)
		)
		(layer "F.Cu")
	)
	(gr_line
		(start 136.6139 -183.892444)
		(end 136.97839 -184.256934)
		(stroke
			(width 0.06731)
			(type default)
		)
		(layer "F.Cu")
	)
	(gr_line
		(start 136.6139 -183.879744)
		(end 136.6139 -183.892444)
		(stroke
			(width 0.06731)
			(type default)
		)
		(layer "F.Cu")
	)
	(gr_line
		(start 136.97839 -185.057034)
		(end 136.60247 -185.432954)
		(stroke
			(width 0.06731)
			(type default)
		)
		(layer "F.Cu")
	)
	(gr_line
		(start 138.625072 -198.5264)
		(end 138.909806 -198.811134)
		(stroke
			(width 0.06731)
			(type default)
		)
		(layer "F.Cu")
	)
	(gr_line
		(start 138.806682 -199.864726)
		(end 138.806682 -200.489058)
		(stroke
			(width 0.06731)
			(type default)
		)
		(layer "F.Cu")
	)
	(gr_line
		(start 138.909806 -199.761602)
		(end 138.806682 -199.864726)
		(stroke
			(width 0.06731)
			(type default)
		)
		(layer "F.Cu")
	)
	(gr_line
		(start 138.909806 -199.727058)
		(end 138.909806 -199.761602)
		(stroke
			(width 0.06731)
			(type default)
		)
		(layer "F.Cu")
	)
	(gr_line
		(start 138.909806 -198.843646)
		(end 138.909806 -199.727058)
		(stroke
			(width 0.06731)
			(type default)
		)
		(layer "F.Cu")
	)
	(gr_line
		(start 138.909806 -198.811134)
		(end 138.909806 -198.843646)
		(stroke
			(width 0.06731)
			(type default)
		)
		(layer "F.Cu")
	)
	(gr_line
		(start 139.171426 -199.727058)
		(end 139.184126 -199.739758)
		(stroke
			(width 0.06731)
			(type default)
		)
		(layer "F.Cu")
	)
	(gr_line
		(start 139.171426 -198.843646)
		(end 139.171426 -199.727058)
		(stroke
			(width 0.06731)
			(type default)
		)
		(layer "F.Cu")
	)
	(gr_line
		(start 139.184126 -198.830946)
		(end 139.171426 -198.843646)
		(stroke
			(width 0.06731)
			(type default)
		)
		(layer "F.Cu")
	)
	(gr_line
		(start 139.185396 -199.741028)
		(end 139.306808 -199.86244)
		(stroke
			(width 0.06731)
			(type default)
		)
		(layer "F.Cu")
	)
	(gr_line
		(start 139.296902 -180.325776)
		(end 139.309602 -180.325776)
		(stroke
			(width 0.06731)
			(type default)
		)
		(layer "F.Cu")
	)
	(gr_line
		(start 139.306808 -199.86244)
		(end 139.306808 -200.489058)
		(stroke
			(width 0.06731)
			(type default)
		)
		(layer "F.Cu")
	)
	(gr_line
		(start 139.309602 -180.325776)
		(end 139.674092 -179.961286)
		(stroke
			(width 0.06731)
			(type default)
		)
		(layer "F.Cu")
	)
	(gr_line
		(start 139.488672 -198.5264)
		(end 139.185396 -198.829676)
		(stroke
			(width 0.06731)
			(type default)
		)
		(layer "F.Cu")
	)
	(gr_line
		(start 140.474192 -179.961286)
		(end 140.832586 -180.31968)
		(stroke
			(width 0.06731)
			(type default)
		)
		(layer "F.Cu")
	)
	(gr_line
		(start 140.832586 -180.31968)
		(end 140.857478 -180.31968)
		(stroke
			(width 0.06731)
			(type default)
		)
		(layer "F.Cu")
	)
	(gr_line
		(start 141.42212 -167.81653)
		(end 141.70787 -168.10228)
		(stroke
			(width 0.05715)
			(type default)
		)
		(layer "F.Cu")
	)
	(gr_line
		(start 141.42212 -167.62603)
		(end 141.42212 -167.81653)
		(stroke
			(width 0.05715)
			(type default)
		)
		(layer "F.Cu")
	)
	(gr_line
		(start 141.70787 -168.10228)
		(end 141.89837 -168.10228)
		(stroke
			(width 0.05715)
			(type default)
		)
		(layer "F.Cu")
	)
	(gr_line
		(start 142.187422 -168.581578)
		(end 142.473172 -168.867582)
		(stroke
			(width 0.05715)
			(type default)
		)
		(layer "F.Cu")
	)
	(gr_line
		(start 142.187422 -168.391332)
		(end 142.187422 -168.581578)
		(stroke
			(width 0.05715)
			(type default)
		)
		(layer "F.Cu")
	)
	(gr_line
		(start 142.331694 -180.31968)
		(end 142.356586 -180.31968)
		(stroke
			(width 0.06731)
			(type default)
		)
		(layer "F.Cu")
	)
	(gr_line
		(start 142.356586 -180.31968)
		(end 142.63878 -180.037486)
		(stroke
			(width 0.06731)
			(type default)
		)
		(layer "F.Cu")
	)
	(gr_line
		(start 142.473172 -168.867582)
		(end 142.663672 -168.867582)
		(stroke
			(width 0.05715)
			(type default)
		)
		(layer "F.Cu")
	)
	(gr_line
		(start 142.952724 -169.34688)
		(end 143.238474 -169.632884)
		(stroke
			(width 0.05715)
			(type default)
		)
		(layer "F.Cu")
	)
	(gr_line
		(start 142.952724 -169.156634)
		(end 142.952724 -169.34688)
		(stroke
			(width 0.05715)
			(type default)
		)
		(layer "F.Cu")
	)
	(gr_line
		(start 143.238474 -169.632884)
		(end 143.428974 -169.632884)
		(stroke
			(width 0.05715)
			(type default)
		)
		(layer "F.Cu")
	)
	(gr_line
		(start 143.718026 -170.112182)
		(end 144.003776 -170.398186)
		(stroke
			(width 0.05715)
			(type default)
		)
		(layer "F.Cu")
	)
	(gr_line
		(start 143.718026 -169.921936)
		(end 143.718026 -170.112182)
		(stroke
			(width 0.05715)
			(type default)
		)
		(layer "F.Cu")
	)
	(gr_line
		(start 144.003776 -170.398186)
		(end 144.194276 -170.398186)
		(stroke
			(width 0.05715)
			(type default)
		)
		(layer "F.Cu")
	)
	(gr_line
		(start 144.483328 -170.877484)
		(end 144.769078 -171.163488)
		(stroke
			(width 0.05715)
			(type default)
		)
		(layer "F.Cu")
	)
	(gr_line
		(start 144.483328 -170.687238)
		(end 144.483328 -170.877484)
		(stroke
			(width 0.05715)
			(type default)
		)
		(layer "F.Cu")
	)
	(gr_line
		(start 144.769078 -171.163488)
		(end 144.959578 -171.163488)
		(stroke
			(width 0.05715)
			(type default)
		)
		(layer "F.Cu")
	)
	(gr_line
		(start 145.24863 -171.642786)
		(end 145.53438 -171.92879)
		(stroke
			(width 0.05715)
			(type default)
		)
		(layer "F.Cu")
	)
	(gr_line
		(start 145.24863 -171.45254)
		(end 145.24863 -171.642786)
		(stroke
			(width 0.05715)
			(type default)
		)
		(layer "F.Cu")
	)
	(gr_line
		(start 145.53438 -171.92879)
		(end 145.72488 -171.92879)
		(stroke
			(width 0.05715)
			(type default)
		)
		(layer "F.Cu")
	)
	(gr_line
		(start 146.013932 -172.408088)
		(end 146.299682 -172.694092)
		(stroke
			(width 0.05715)
			(type default)
		)
		(layer "F.Cu")
	)
	(gr_line
		(start 146.013932 -172.217842)
		(end 146.013932 -172.408088)
		(stroke
			(width 0.05715)
			(type default)
		)
		(layer "F.Cu")
	)
	(gr_line
		(start 146.299682 -172.694092)
		(end 146.490182 -172.694092)
		(stroke
			(width 0.05715)
			(type default)
		)
		(layer "F.Cu")
	)
	(gr_line
		(start 149.60473 -34.228278)
		(end 149.310598 -34.52241)
		(stroke
			(width 0.06731)
			(type default)
		)
		(layer "F.Cu")
	)
	(gr_line
		(start 151.225504 -120.087898)
		(end 151.520144 -119.793258)
		(stroke
			(width 0.06731)
			(type default)
		)
		(layer "F.Cu")
	)
	(gr_line
		(start 151.225504 -112.784382)
		(end 151.520144 -112.489742)
		(stroke
			(width 0.06731)
			(type default)
		)
		(layer "F.Cu")
	)
	(gr_line
		(start 151.225504 -111.920782)
		(end 151.520144 -112.215422)
		(stroke
			(width 0.06731)
			(type default)
		)
		(layer "F.Cu")
	)
	(gr_line
		(start 151.225504 -109.18444)
		(end 151.520144 -108.8898)
		(stroke
			(width 0.06731)
			(type default)
		)
		(layer "F.Cu")
	)
	(gr_line
		(start 151.225504 -108.32084)
		(end 151.520144 -108.61548)
		(stroke
			(width 0.06731)
			(type default)
		)
		(layer "F.Cu")
	)
	(gr_line
		(start 151.225504 -105.584498)
		(end 151.520144 -105.289858)
		(stroke
			(width 0.06731)
			(type default)
		)
		(layer "F.Cu")
	)
	(gr_line
		(start 151.225504 -104.720898)
		(end 151.520144 -105.015538)
		(stroke
			(width 0.06731)
			(type default)
		)
		(layer "F.Cu")
	)
	(gr_line
		(start 151.835104 -101.984302)
		(end 152.129744 -101.689662)
		(stroke
			(width 0.06731)
			(type default)
		)
		(layer "F.Cu")
	)
	(gr_line
		(start 151.835104 -101.120702)
		(end 152.129744 -101.415342)
		(stroke
			(width 0.06731)
			(type default)
		)
		(layer "F.Cu")
	)
	(gr_line
		(start 152.151588 -119.793258)
		(end 152.471628 -120.113298)
		(stroke
			(width 0.06731)
			(type default)
		)
		(layer "F.Cu")
	)
	(gr_line
		(start 152.151588 -112.489742)
		(end 152.471628 -112.809782)
		(stroke
			(width 0.06731)
			(type default)
		)
		(layer "F.Cu")
	)
	(gr_line
		(start 152.151588 -112.215422)
		(end 152.471628 -111.895382)
		(stroke
			(width 0.06731)
			(type default)
		)
		(layer "F.Cu")
	)
	(gr_line
		(start 152.151588 -108.8898)
		(end 152.471628 -109.20984)
		(stroke
			(width 0.06731)
			(type default)
		)
		(layer "F.Cu")
	)
	(gr_line
		(start 152.151588 -108.61548)
		(end 152.471628 -108.29544)
		(stroke
			(width 0.06731)
			(type default)
		)
		(layer "F.Cu")
	)
	(gr_line
		(start 152.151588 -105.289858)
		(end 152.471628 -105.609898)
		(stroke
			(width 0.06731)
			(type default)
		)
		(layer "F.Cu")
	)
	(gr_line
		(start 152.151588 -105.015538)
		(end 152.471628 -104.695498)
		(stroke
			(width 0.06731)
			(type default)
		)
		(layer "F.Cu")
	)
	(gr_line
		(start 152.282398 -34.390076)
		(end 152.120854 -34.228532)
		(stroke
			(width 0.06731)
			(type default)
		)
		(layer "F.Cu")
	)
	(gr_line
		(start 152.474676 -299.224954)
		(end 152.949656 -299.699934)
		(stroke
			(width 0.05715)
			(type default)
		)
		(layer "F.Cu")
	)
	(gr_line
		(start 152.474676 -297.32478)
		(end 152.949656 -297.79976)
		(stroke
			(width 0.05715)
			(type default)
		)
		(layer "F.Cu")
	)
	(gr_line
		(start 152.761188 -101.689662)
		(end 153.081228 -102.009702)
		(stroke
			(width 0.06731)
			(type default)
		)
		(layer "F.Cu")
	)
	(gr_line
		(start 152.761188 -101.415342)
		(end 153.081228 -101.095302)
		(stroke
			(width 0.06731)
			(type default)
		)
		(layer "F.Cu")
	)
	(gr_line
		(start 152.764998 -34.390076)
		(end 152.282398 -34.390076)
		(stroke
			(width 0.06731)
			(type default)
		)
		(layer "F.Cu")
	)
	(gr_line
		(start 152.94991 -299.699934)
		(end 152.949656 -299.699934)
		(stroke
			(width 0.05715)
			(type default)
		)
		(layer "F.Cu")
	)
	(gr_line
		(start 152.94991 -297.79976)
		(end 152.949656 -297.79976)
		(stroke
			(width 0.05715)
			(type default)
		)
		(layer "F.Cu")
	)
	(gr_line
		(start 153.005028 -120.113298)
		(end 153.324814 -119.793512)
		(stroke
			(width 0.06731)
			(type default)
		)
		(layer "F.Cu")
	)
	(gr_line
		(start 153.005028 -112.809782)
		(end 153.331418 -112.483392)
		(stroke
			(width 0.06731)
			(type default)
		)
		(layer "F.Cu")
	)
	(gr_line
		(start 153.005028 -111.895382)
		(end 153.317448 -112.207802)
		(stroke
			(width 0.06731)
			(type default)
		)
		(layer "F.Cu")
	)
	(gr_line
		(start 153.005028 -109.20984)
		(end 153.331418 -108.88345)
		(stroke
			(width 0.06731)
			(type default)
		)
		(layer "F.Cu")
	)
	(gr_line
		(start 153.005028 -108.29544)
		(end 153.317448 -108.60786)
		(stroke
			(width 0.06731)
			(type default)
		)
		(layer "F.Cu")
	)
	(gr_line
		(start 153.005028 -105.609898)
		(end 153.331418 -105.283508)
		(stroke
			(width 0.06731)
			(type default)
		)
		(layer "F.Cu")
	)
	(gr_line
		(start 153.005028 -104.695498)
		(end 153.317448 -105.007918)
		(stroke
			(width 0.06731)
			(type default)
		)
		(layer "F.Cu")
	)
	(gr_line
		(start 153.317448 -112.207802)
		(end 153.332688 -112.207802)
		(stroke
			(width 0.06731)
			(type default)
		)
		(layer "F.Cu")
	)
	(gr_line
		(start 153.317448 -108.60786)
		(end 153.332688 -108.60786)
		(stroke
			(width 0.06731)
			(type default)
		)
		(layer "F.Cu")
	)
	(gr_line
		(start 153.317448 -105.007918)
		(end 153.332688 -105.007918)
		(stroke
			(width 0.06731)
			(type default)
		)
		(layer "F.Cu")
	)
	(gr_line
		(start 153.424636 -299.224954)
		(end 153.899616 -299.699934)
		(stroke
			(width 0.05715)
			(type default)
		)
		(layer "F.Cu")
	)
	(gr_line
		(start 153.424636 -297.32478)
		(end 153.899616 -297.79976)
		(stroke
			(width 0.05715)
			(type default)
		)
		(layer "F.Cu")
	)
	(gr_line
		(start 153.614628 -102.009702)
		(end 153.941018 -101.683312)
		(stroke
			(width 0.06731)
			(type default)
		)
		(layer "F.Cu")
	)
	(gr_line
		(start 153.614628 -101.095302)
		(end 153.927048 -101.407722)
		(stroke
			(width 0.06731)
			(type default)
		)
		(layer "F.Cu")
	)
	(gr_line
		(start 153.867612 -136.704324)
		(end 154.162252 -136.409684)
		(stroke
			(width 0.06731)
			(type default)
		)
		(layer "F.Cu")
	)
	(gr_line
		(start 153.867612 -135.840724)
		(end 154.162252 -136.135364)
		(stroke
			(width 0.06731)
			(type default)
		)
		(layer "F.Cu")
	)
	(gr_line
		(start 153.867612 -133.104382)
		(end 154.162252 -132.809742)
		(stroke
			(width 0.06731)
			(type default)
		)
		(layer "F.Cu")
	)
	(gr_line
		(start 153.867612 -132.240782)
		(end 154.162252 -132.535422)
		(stroke
			(width 0.06731)
			(type default)
		)
		(layer "F.Cu")
	)
	(gr_line
		(start 153.867612 -125.494542)
		(end 154.162252 -125.199902)
		(stroke
			(width 0.06731)
			(type default)
		)
		(layer "F.Cu")
	)
	(gr_line
		(start 153.867612 -124.630942)
		(end 154.162252 -124.925582)
		(stroke
			(width 0.06731)
			(type default)
		)
		(layer "F.Cu")
	)
	(gr_line
		(start 153.867612 -121.894346)
		(end 154.162252 -121.599706)
		(stroke
			(width 0.06731)
			(type default)
		)
		(layer "F.Cu")
	)
	(gr_line
		(start 153.867612 -121.030746)
		(end 154.162252 -121.325386)
		(stroke
			(width 0.06731)
			(type default)
		)
		(layer "F.Cu")
	)
	(gr_line
		(start 153.89987 -299.699934)
		(end 153.899616 -299.699934)
		(stroke
			(width 0.05715)
			(type default)
		)
		(layer "F.Cu")
	)
	(gr_line
		(start 153.89987 -297.79976)
		(end 153.899616 -297.79976)
		(stroke
			(width 0.05715)
			(type default)
		)
		(layer "F.Cu")
	)
	(gr_line
		(start 153.927048 -101.407722)
		(end 153.942288 -101.407722)
		(stroke
			(width 0.06731)
			(type default)
		)
		(layer "F.Cu")
	)
	(gr_line
		(start 154.11196 -238.79302)
		(end 153.856182 -239.048798)
		(stroke
			(width 0.05715)
			(type default)
		)
		(layer "F.Cu")
	)
	(gr_line
		(start 154.4828 -238.811816)
		(end 154.719782 -239.048798)
		(stroke
			(width 0.05715)
			(type default)
		)
		(layer "F.Cu")
	)
	(gr_line
		(start 154.4828 -238.79048)
		(end 154.4828 -238.811816)
		(stroke
			(width 0.05715)
			(type default)
		)
		(layer "F.Cu")
	)
	(gr_line
		(start 154.793696 -136.409684)
		(end 155.113736 -136.729724)
		(stroke
			(width 0.06731)
			(type default)
		)
		(layer "F.Cu")
	)
	(gr_line
		(start 154.793696 -136.135364)
		(end 155.113736 -135.815324)
		(stroke
			(width 0.06731)
			(type default)
		)
		(layer "F.Cu")
	)
	(gr_line
		(start 154.793696 -132.809742)
		(end 155.113736 -133.129782)
		(stroke
			(width 0.06731)
			(type default)
		)
		(layer "F.Cu")
	)
	(gr_line
		(start 154.793696 -132.535422)
		(end 155.113736 -132.215382)
		(stroke
			(width 0.06731)
			(type default)
		)
		(layer "F.Cu")
	)
	(gr_line
		(start 154.793696 -125.199902)
		(end 155.113736 -125.519942)
		(stroke
			(width 0.06731)
			(type default)
		)
		(layer "F.Cu")
	)
	(gr_line
		(start 154.793696 -124.925582)
		(end 155.113736 -124.605542)
		(stroke
			(width 0.06731)
			(type default)
		)
		(layer "F.Cu")
	)
	(gr_line
		(start 154.793696 -121.599706)
		(end 155.113736 -121.919746)
		(stroke
			(width 0.06731)
			(type default)
		)
		(layer "F.Cu")
	)
	(gr_line
		(start 154.793696 -121.325386)
		(end 155.113736 -121.005346)
		(stroke
			(width 0.06731)
			(type default)
		)
		(layer "F.Cu")
	)
	(gr_line
		(start 155.647136 -136.729724)
		(end 155.973526 -136.403334)
		(stroke
			(width 0.06731)
			(type default)
		)
		(layer "F.Cu")
	)
	(gr_line
		(start 155.647136 -135.815324)
		(end 155.959556 -136.127744)
		(stroke
			(width 0.06731)
			(type default)
		)
		(layer "F.Cu")
	)
	(gr_line
		(start 155.647136 -133.129782)
		(end 155.973526 -132.803392)
		(stroke
			(width 0.06731)
			(type default)
		)
		(layer "F.Cu")
	)
	(gr_line
		(start 155.647136 -132.215382)
		(end 155.959556 -132.527802)
		(stroke
			(width 0.06731)
			(type default)
		)
		(layer "F.Cu")
	)
	(gr_line
		(start 155.647136 -125.519942)
		(end 155.973526 -125.193552)
		(stroke
			(width 0.06731)
			(type default)
		)
		(layer "F.Cu")
	)
	(gr_line
		(start 155.647136 -124.605542)
		(end 155.959556 -124.917962)
		(stroke
			(width 0.06731)
			(type default)
		)
		(layer "F.Cu")
	)
	(gr_line
		(start 155.647136 -121.919746)
		(end 155.973526 -121.593356)
		(stroke
			(width 0.06731)
			(type default)
		)
		(layer "F.Cu")
	)
	(gr_line
		(start 155.647136 -121.005346)
		(end 155.959556 -121.317766)
		(stroke
			(width 0.06731)
			(type default)
		)
		(layer "F.Cu")
	)
	(gr_line
		(start 155.959556 -136.127744)
		(end 155.974796 -136.127744)
		(stroke
			(width 0.06731)
			(type default)
		)
		(layer "F.Cu")
	)
	(gr_line
		(start 155.959556 -132.527802)
		(end 155.974796 -132.527802)
		(stroke
			(width 0.06731)
			(type default)
		)
		(layer "F.Cu")
	)
	(gr_line
		(start 155.959556 -124.917962)
		(end 155.974796 -124.917962)
		(stroke
			(width 0.06731)
			(type default)
		)
		(layer "F.Cu")
	)
	(gr_line
		(start 155.959556 -121.317766)
		(end 155.974796 -121.317766)
		(stroke
			(width 0.06731)
			(type default)
		)
		(layer "F.Cu")
	)
	(gr_line
		(start 157.86862 -27.189938)
		(end 157.364938 -27.189938)
		(stroke
			(width 0.06731)
			(type default)
		)
		(layer "F.Cu")
	)
	(gr_line
		(start 158.012638 -27.04592)
		(end 157.86862 -27.189938)
		(stroke
			(width 0.06731)
			(type default)
		)
		(layer "F.Cu")
	)
	(gr_line
		(start 158.036514 -27.04592)
		(end 158.012638 -27.04592)
		(stroke
			(width 0.06731)
			(type default)
		)
		(layer "F.Cu")
	)
	(gr_line
		(start 159.08147 -27.342846)
		(end 158.785814 -27.04719)
		(stroke
			(width 0.06731)
			(type default)
		)
		(layer "F.Cu")
	)
	(gr_line
		(start 161.491168 -136.402064)
		(end 161.654236 -136.565132)
		(stroke
			(width 0.06731)
			(type default)
		)
		(layer "F.Cu")
	)
	(gr_line
		(start 161.491168 -136.127744)
		(end 161.653982 -135.96493)
		(stroke
			(width 0.06731)
			(type default)
		)
		(layer "F.Cu")
	)
	(gr_line
		(start 161.491168 -101.682042)
		(end 161.654236 -101.84511)
		(stroke
			(width 0.06731)
			(type default)
		)
		(layer "F.Cu")
	)
	(gr_line
		(start 161.491168 -101.407722)
		(end 161.653982 -101.244908)
		(stroke
			(width 0.06731)
			(type default)
		)
		(layer "F.Cu")
	)
	(gr_line
		(start 161.491422 -132.802122)
		(end 161.654236 -132.964936)
		(stroke
			(width 0.06731)
			(type default)
		)
		(layer "F.Cu")
	)
	(gr_line
		(start 161.491422 -132.527802)
		(end 161.654236 -132.364988)
		(stroke
			(width 0.06731)
			(type default)
		)
		(layer "F.Cu")
	)
	(gr_line
		(start 161.491422 -125.192282)
		(end 161.654236 -125.355096)
		(stroke
			(width 0.06731)
			(type default)
		)
		(layer "F.Cu")
	)
	(gr_line
		(start 161.491422 -124.917962)
		(end 161.654236 -124.755148)
		(stroke
			(width 0.06731)
			(type default)
		)
		(layer "F.Cu")
	)
	(gr_line
		(start 161.491422 -121.592086)
		(end 161.654236 -121.7549)
		(stroke
			(width 0.06731)
			(type default)
		)
		(layer "F.Cu")
	)
	(gr_line
		(start 161.491422 -121.317766)
		(end 161.654236 -121.154952)
		(stroke
			(width 0.06731)
			(type default)
		)
		(layer "F.Cu")
	)
	(gr_line
		(start 161.491422 -119.792242)
		(end 161.654236 -119.955056)
		(stroke
			(width 0.06731)
			(type default)
		)
		(layer "F.Cu")
	)
	(gr_line
		(start 161.491422 -112.482122)
		(end 161.654236 -112.644936)
		(stroke
			(width 0.06731)
			(type default)
		)
		(layer "F.Cu")
	)
	(gr_line
		(start 161.491422 -112.207802)
		(end 161.654236 -112.044988)
		(stroke
			(width 0.06731)
			(type default)
		)
		(layer "F.Cu")
	)
	(gr_line
		(start 161.491422 -108.88218)
		(end 161.654236 -109.044994)
		(stroke
			(width 0.06731)
			(type default)
		)
		(layer "F.Cu")
	)
	(gr_line
		(start 161.491422 -108.60786)
		(end 161.654236 -108.445046)
		(stroke
			(width 0.06731)
			(type default)
		)
		(layer "F.Cu")
	)
	(gr_line
		(start 161.491422 -105.282238)
		(end 161.654236 -105.445052)
		(stroke
			(width 0.06731)
			(type default)
		)
		(layer "F.Cu")
	)
	(gr_line
		(start 161.491422 -105.007918)
		(end 161.654236 -104.845104)
		(stroke
			(width 0.06731)
			(type default)
		)
		(layer "F.Cu")
	)
	(gr_line
		(start 161.653982 -135.96493)
		(end 162.14217 -135.96493)
		(stroke
			(width 0.06731)
			(type default)
		)
		(layer "F.Cu")
	)
	(gr_line
		(start 161.653982 -101.244908)
		(end 162.14217 -101.244908)
		(stroke
			(width 0.06731)
			(type default)
		)
		(layer "F.Cu")
	)
	(gr_line
		(start 161.654236 -136.565132)
		(end 162.14217 -136.565132)
		(stroke
			(width 0.06731)
			(type default)
		)
		(layer "F.Cu")
	)
	(gr_line
		(start 161.654236 -132.964936)
		(end 162.14217 -132.964936)
		(stroke
			(width 0.06731)
			(type default)
		)
		(layer "F.Cu")
	)
	(gr_line
		(start 161.654236 -132.364988)
		(end 162.14217 -132.364988)
		(stroke
			(width 0.06731)
			(type default)
		)
		(layer "F.Cu")
	)
	(gr_line
		(start 161.654236 -125.355096)
		(end 162.14217 -125.355096)
		(stroke
			(width 0.06731)
			(type default)
		)
		(layer "F.Cu")
	)
	(gr_line
		(start 161.654236 -124.755148)
		(end 162.14217 -124.755148)
		(stroke
			(width 0.06731)
			(type default)
		)
		(layer "F.Cu")
	)
	(gr_line
		(start 161.654236 -121.7549)
		(end 162.14217 -121.7549)
		(stroke
			(width 0.06731)
			(type default)
		)
		(layer "F.Cu")
	)
	(gr_line
		(start 161.654236 -121.154952)
		(end 162.14217 -121.154952)
		(stroke
			(width 0.06731)
			(type default)
		)
		(layer "F.Cu")
	)
	(gr_line
		(start 161.654236 -119.955056)
		(end 162.14217 -119.955056)
		(stroke
			(width 0.06731)
			(type default)
		)
		(layer "F.Cu")
	)
	(gr_line
		(start 161.654236 -112.644936)
		(end 162.14217 -112.644936)
		(stroke
			(width 0.06731)
			(type default)
		)
		(layer "F.Cu")
	)
	(gr_line
		(start 161.654236 -112.044988)
		(end 162.14217 -112.044988)
		(stroke
			(width 0.06731)
			(type default)
		)
		(layer "F.Cu")
	)
	(gr_line
		(start 161.654236 -109.044994)
		(end 162.14217 -109.044994)
		(stroke
			(width 0.06731)
			(type default)
		)
		(layer "F.Cu")
	)
	(gr_line
		(start 161.654236 -108.445046)
		(end 162.14217 -108.445046)
		(stroke
			(width 0.06731)
			(type default)
		)
		(layer "F.Cu")
	)
	(gr_line
		(start 161.654236 -105.445052)
		(end 162.14217 -105.445052)
		(stroke
			(width 0.06731)
			(type default)
		)
		(layer "F.Cu")
	)
	(gr_line
		(start 161.654236 -104.845104)
		(end 162.14217 -104.845104)
		(stroke
			(width 0.06731)
			(type default)
		)
		(layer "F.Cu")
	)
	(gr_line
		(start 161.654236 -101.84511)
		(end 162.14217 -101.84511)
		(stroke
			(width 0.06731)
			(type default)
		)
		(layer "F.Cu")
	)
	(gr_line
		(start 167.230298 -134.765034)
		(end 166.742364 -134.765034)
		(stroke
			(width 0.06731)
			(type default)
		)
		(layer "F.Cu")
	)
	(gr_line
		(start 167.393112 -134.60222)
		(end 167.230298 -134.765034)
		(stroke
			(width 0.06731)
			(type default)
		)
		(layer "F.Cu")
	)
	(gr_line
		(start 169.902124 -134.601712)
		(end 169.901616 -134.60222)
		(stroke
			(width 0.06731)
			(type default)
		)
		(layer "F.Cu")
	)
	(gr_line
		(start 170.196764 -134.896352)
		(end 169.902124 -134.601712)
		(stroke
			(width 0.06731)
			(type default)
		)
		(layer "F.Cu")
	)
	(gr_line
		(start 175.604678 -30.628336)
		(end 175.310546 -30.922468)
		(stroke
			(width 0.06731)
			(type default)
		)
		(layer "F.Cu")
	)
	(gr_line
		(start 178.282346 -30.790134)
		(end 178.120802 -30.62859)
		(stroke
			(width 0.06731)
			(type default)
		)
		(layer "F.Cu")
	)
	(gr_line
		(start 178.764946 -30.790134)
		(end 178.282346 -30.790134)
		(stroke
			(width 0.06731)
			(type default)
		)
		(layer "F.Cu")
	)
	(gr_line
		(start 181.598062 -135.882126)
		(end 181.302914 -136.177274)
		(stroke
			(width 0.06731)
			(type default)
		)
		(layer "F.Cu")
	)
	(gr_line
		(start 181.598062 -121.072148)
		(end 181.302914 -121.367296)
		(stroke
			(width 0.06731)
			(type default)
		)
		(layer "F.Cu")
	)
	(gr_line
		(start 183.854852 -26.58999)
		(end 183.364886 -26.58999)
		(stroke
			(width 0.06731)
			(type default)
		)
		(layer "F.Cu")
	)
	(gr_line
		(start 183.868568 -27.189938)
		(end 183.364886 -27.189938)
		(stroke
			(width 0.06731)
			(type default)
		)
		(layer "F.Cu")
	)
	(gr_line
		(start 183.923432 -356.48773)
		(end 184.243472 -356.80777)
		(stroke
			(width 0.06731)
			(type default)
		)
		(layer "F.Cu")
	)
	(gr_line
		(start 183.948832 -354.708206)
		(end 184.243472 -355.002846)
		(stroke
			(width 0.06731)
			(type default)
		)
		(layer "F.Cu")
	)
	(gr_line
		(start 184.012586 -27.04592)
		(end 183.868568 -27.189938)
		(stroke
			(width 0.06731)
			(type default)
		)
		(layer "F.Cu")
	)
	(gr_line
		(start 184.035192 -26.77033)
		(end 183.854852 -26.58999)
		(stroke
			(width 0.06731)
			(type default)
		)
		(layer "F.Cu")
	)
	(gr_line
		(start 184.036462 -27.04592)
		(end 184.012586 -27.04592)
		(stroke
			(width 0.06731)
			(type default)
		)
		(layer "F.Cu")
	)
	(gr_line
		(start 184.243472 -357.439214)
		(end 183.948832 -357.733854)
		(stroke
			(width 0.06731)
			(type default)
		)
		(layer "F.Cu")
	)
	(gr_line
		(start 184.243472 -355.63429)
		(end 183.923432 -355.95433)
		(stroke
			(width 0.06731)
			(type default)
		)
		(layer "F.Cu")
	)
	(gr_line
		(start 184.26938 -136.04494)
		(end 184.106566 -135.882126)
		(stroke
			(width 0.06731)
			(type default)
		)
		(layer "F.Cu")
	)
	(gr_line
		(start 184.26938 -121.234962)
		(end 184.106566 -121.072148)
		(stroke
			(width 0.06731)
			(type default)
		)
		(layer "F.Cu")
	)
	(gr_line
		(start 184.517792 -357.439214)
		(end 184.812432 -357.733854)
		(stroke
			(width 0.06731)
			(type default)
		)
		(layer "F.Cu")
	)
	(gr_line
		(start 184.517792 -355.63429)
		(end 184.837832 -355.95433)
		(stroke
			(width 0.06731)
			(type default)
		)
		(layer "F.Cu")
	)
	(gr_line
		(start 184.757314 -136.04494)
		(end 184.26938 -136.04494)
		(stroke
			(width 0.06731)
			(type default)
		)
		(layer "F.Cu")
	)
	(gr_line
		(start 184.757314 -121.234962)
		(end 184.26938 -121.234962)
		(stroke
			(width 0.06731)
			(type default)
		)
		(layer "F.Cu")
	)
	(gr_line
		(start 184.789064 -26.7716)
		(end 184.784492 -26.7716)
		(stroke
			(width 0.06731)
			(type default)
		)
		(layer "F.Cu")
	)
	(gr_line
		(start 184.812432 -354.708206)
		(end 184.517792 -355.002846)
		(stroke
			(width 0.06731)
			(type default)
		)
		(layer "F.Cu")
	)
	(gr_line
		(start 184.837832 -356.48773)
		(end 184.517792 -356.80777)
		(stroke
			(width 0.06731)
			(type default)
		)
		(layer "F.Cu")
	)
	(gr_line
		(start 185.081418 -27.342846)
		(end 184.785762 -27.04719)
		(stroke
			(width 0.06731)
			(type default)
		)
		(layer "F.Cu")
	)
	(gr_line
		(start 185.081418 -26.479246)
		(end 184.789064 -26.7716)
		(stroke
			(width 0.06731)
			(type default)
		)
		(layer "F.Cu")
	)
	(gr_line
		(start 187.032392 -350.365314)
		(end 187.352432 -350.685354)
		(stroke
			(width 0.06731)
			(type default)
		)
		(layer "F.Cu")
	)
	(gr_line
		(start 187.057792 -348.58579)
		(end 187.352432 -348.88043)
		(stroke
			(width 0.06731)
			(type default)
		)
		(layer "F.Cu")
	)
	(gr_line
		(start 187.352432 -351.316798)
		(end 187.057792 -351.611438)
		(stroke
			(width 0.06731)
			(type default)
		)
		(layer "F.Cu")
	)
	(gr_line
		(start 187.352432 -349.511874)
		(end 187.032392 -349.831914)
		(stroke
			(width 0.06731)
			(type default)
		)
		(layer "F.Cu")
	)
	(gr_line
		(start 189.845696 -143.35506)
		(end 189.357508 -143.35506)
		(stroke
			(width 0.06731)
			(type default)
		)
		(layer "F.Cu")
	)
	(gr_line
		(start 190.00851 -143.192246)
		(end 189.845696 -143.35506)
		(stroke
			(width 0.06731)
			(type default)
		)
		(layer "F.Cu")
	)
	(gr_line
		(start 193.250312 -350.365314)
		(end 193.570352 -350.685354)
		(stroke
			(width 0.06731)
			(type default)
		)
		(layer "F.Cu")
	)
	(gr_line
		(start 193.275712 -348.58579)
		(end 193.570352 -348.88043)
		(stroke
			(width 0.06731)
			(type default)
		)
		(layer "F.Cu")
	)
	(gr_line
		(start 193.570352 -351.316798)
		(end 193.275712 -351.611438)
		(stroke
			(width 0.06731)
			(type default)
		)
		(layer "F.Cu")
	)
	(gr_line
		(start 193.570352 -349.511874)
		(end 193.250312 -349.831914)
		(stroke
			(width 0.06731)
			(type default)
		)
		(layer "F.Cu")
	)
	(gr_line
		(start 195.540122 -143.192246)
		(end 195.524882 -143.192246)
		(stroke
			(width 0.06731)
			(type default)
		)
		(layer "F.Cu")
	)
	(gr_line
		(start 195.852542 -143.504666)
		(end 195.540122 -143.192246)
		(stroke
			(width 0.06731)
			(type default)
		)
		(layer "F.Cu")
	)
	(gr_line
		(start 196.359272 -344.219022)
		(end 196.679312 -344.539062)
		(stroke
			(width 0.06731)
			(type default)
		)
		(layer "F.Cu")
	)
	(gr_line
		(start 196.384672 -342.439498)
		(end 196.679312 -342.734138)
		(stroke
			(width 0.06731)
			(type default)
		)
		(layer "F.Cu")
	)
	(gr_line
		(start 196.679312 -345.170506)
		(end 196.384672 -345.465146)
		(stroke
			(width 0.06731)
			(type default)
		)
		(layer "F.Cu")
	)
	(gr_line
		(start 196.679312 -343.365582)
		(end 196.359272 -343.685622)
		(stroke
			(width 0.06731)
			(type default)
		)
		(layer "F.Cu")
	)
	(gr_line
		(start 196.705982 -143.184626)
		(end 196.385942 -143.504666)
		(stroke
			(width 0.06731)
			(type default)
		)
		(layer "F.Cu")
	)
	(gr_line
		(start 197.632066 -143.479266)
		(end 197.337426 -143.184626)
		(stroke
			(width 0.06731)
			(type default)
		)
		(layer "F.Cu")
	)
	(gr_line
		(start 201.604626 -30.628336)
		(end 201.310494 -30.922468)
		(stroke
			(width 0.06731)
			(type default)
		)
		(layer "F.Cu")
	)
	(gr_line
		(start 201.604626 -30.353)
		(end 201.310494 -30.058868)
		(stroke
			(width 0.06731)
			(type default)
		)
		(layer "F.Cu")
	)
	(gr_line
		(start 201.605642 -30.353)
		(end 201.604626 -30.353)
		(stroke
			(width 0.06731)
			(type default)
		)
		(layer "F.Cu")
	)
	(gr_line
		(start 204.12456 -30.353)
		(end 204.11948 -30.353)
		(stroke
			(width 0.06731)
			(type default)
		)
		(layer "F.Cu")
	)
	(gr_line
		(start 204.282294 -30.790134)
		(end 204.12075 -30.62859)
		(stroke
			(width 0.06731)
			(type default)
		)
		(layer "F.Cu")
	)
	(gr_line
		(start 204.287374 -30.190186)
		(end 204.12456 -30.353)
		(stroke
			(width 0.06731)
			(type default)
		)
		(layer "F.Cu")
	)
	(gr_line
		(start 204.764894 -30.790134)
		(end 204.282294 -30.790134)
		(stroke
			(width 0.06731)
			(type default)
		)
		(layer "F.Cu")
	)
	(gr_line
		(start 204.764894 -30.190186)
		(end 204.287374 -30.190186)
		(stroke
			(width 0.06731)
			(type default)
		)
		(layer "F.Cu")
	)
	(gr_line
		(start 209.864452 -28.990036)
		(end 209.364834 -28.990036)
		(stroke
			(width 0.06731)
			(type default)
		)
		(layer "F.Cu")
	)
	(gr_line
		(start 209.868516 -27.189938)
		(end 209.364834 -27.189938)
		(stroke
			(width 0.06731)
			(type default)
		)
		(layer "F.Cu")
	)
	(gr_line
		(start 210.012534 -27.04592)
		(end 209.868516 -27.189938)
		(stroke
			(width 0.06731)
			(type default)
		)
		(layer "F.Cu")
	)
	(gr_line
		(start 210.025488 -28.829)
		(end 209.864452 -28.990036)
		(stroke
			(width 0.06731)
			(type default)
		)
		(layer "F.Cu")
	)
	(gr_line
		(start 210.0326 -28.829)
		(end 210.025488 -28.829)
		(stroke
			(width 0.06731)
			(type default)
		)
		(layer "F.Cu")
	)
	(gr_line
		(start 210.03641 -27.04592)
		(end 210.012534 -27.04592)
		(stroke
			(width 0.06731)
			(type default)
		)
		(layer "F.Cu")
	)
	(gr_line
		(start 211.081366 -27.342846)
		(end 210.78571 -27.04719)
		(stroke
			(width 0.06731)
			(type default)
		)
		(layer "F.Cu")
	)
	(gr_line
		(start 211.315046 -28.829)
		(end 211.29625 -28.829)
		(stroke
			(width 0.06731)
			(type default)
		)
		(layer "F.Cu")
	)
	(gr_line
		(start 211.625688 -29.139642)
		(end 211.315046 -28.829)
		(stroke
			(width 0.06731)
			(type default)
		)
		(layer "F.Cu")
	)
	(gr_line
		(start 212.46973 -28.829)
		(end 212.159088 -29.139642)
		(stroke
			(width 0.06731)
			(type default)
		)
		(layer "F.Cu")
	)
	(gr_line
		(start 212.488526 -28.829)
		(end 212.46973 -28.829)
		(stroke
			(width 0.06731)
			(type default)
		)
		(layer "F.Cu")
	)
	(gr_line
		(start 213.11997 -28.829)
		(end 213.101174 -28.829)
		(stroke
			(width 0.06731)
			(type default)
		)
		(layer "F.Cu")
	)
	(gr_line
		(start 213.405212 -29.114242)
		(end 213.11997 -28.829)
		(stroke
			(width 0.06731)
			(type default)
		)
		(layer "F.Cu")
	)
	(gr_line
		(start 227.188776 -59.837066)
		(end 226.894136 -60.131706)
		(stroke
			(width 0.06731)
			(type default)
		)
		(layer "F.Cu")
	)
	(gr_line
		(start 227.188776 -59.562746)
		(end 226.894136 -59.268106)
		(stroke
			(width 0.06731)
			(type default)
		)
		(layer "F.Cu")
	)
	(gr_line
		(start 228.695504 -156.340556)
		(end 229.0191 -156.664152)
		(stroke
			(width 0.05715)
			(type default)
		)
		(layer "F.Cu")
	)
	(gr_line
		(start 228.935534 -59.399932)
		(end 228.77272 -59.562746)
		(stroke
			(width 0.06731)
			(type default)
		)
		(layer "F.Cu")
	)
	(gr_line
		(start 228.935788 -60.000134)
		(end 228.77272 -59.837066)
		(stroke
			(width 0.06731)
			(type default)
		)
		(layer "F.Cu")
	)
	(gr_line
		(start 229.0191 -157.622748)
		(end 228.771704 -157.870144)
		(stroke
			(width 0.05715)
			(type default)
		)
		(layer "F.Cu")
	)
	(gr_line
		(start 229.0191 -157.62224)
		(end 229.0191 -157.622748)
		(stroke
			(width 0.05715)
			(type default)
		)
		(layer "F.Cu")
	)
	(gr_line
		(start 229.0191 -156.664152)
		(end 229.0191 -156.66466)
		(stroke
			(width 0.05715)
			(type default)
		)
		(layer "F.Cu")
	)
	(gr_line
		(start 229.019354 -155.216606)
		(end 228.695504 -155.540456)
		(stroke
			(width 0.05715)
			(type default)
		)
		(layer "F.Cu")
	)
	(gr_line
		(start 229.347014 -151.216614)
		(end 229.4128 -151.2824)
		(stroke
			(width 0.05715)
			(type default)
		)
		(layer "F.Cu")
	)
	(gr_line
		(start 229.347014 -151.015446)
		(end 229.347014 -151.216614)
		(stroke
			(width 0.05715)
			(type default)
		)
		(layer "F.Cu")
	)
	(gr_line
		(start 229.387654 -155.216606)
		(end 229.711504 -155.540456)
		(stroke
			(width 0.05715)
			(type default)
		)
		(layer "F.Cu")
	)
	(gr_line
		(start 229.387908 -157.622748)
		(end 229.635304 -157.870144)
		(stroke
			(width 0.05715)
			(type default)
		)
		(layer "F.Cu")
	)
	(gr_line
		(start 229.4128 -151.2824)
		(end 229.4128 -151.2951)
		(stroke
			(width 0.05715)
			(type default)
		)
		(layer "F.Cu")
	)
	(gr_line
		(start 229.437438 -60.000134)
		(end 228.935788 -60.000134)
		(stroke
			(width 0.06731)
			(type default)
		)
		(layer "F.Cu")
	)
	(gr_line
		(start 229.437438 -59.399932)
		(end 228.935534 -59.399932)
		(stroke
			(width 0.06731)
			(type default)
		)
		(layer "F.Cu")
	)
	(gr_line
		(start 229.711504 -156.340556)
		(end 229.387908 -156.664152)
		(stroke
			(width 0.05715)
			(type default)
		)
		(layer "F.Cu")
	)
	(gr_line
		(start 229.771956 -87.233506)
		(end 230.079296 -87.540846)
		(stroke
			(width 0.06731)
			(type default)
		)
		(layer "F.Cu")
	)
	(gr_line
		(start 229.846886 -151.229314)
		(end 229.78364 -151.29256)
		(stroke
			(width 0.05715)
			(type default)
		)
		(layer "F.Cu")
	)
	(gr_line
		(start 229.846886 -151.015446)
		(end 229.846886 -151.229314)
		(stroke
			(width 0.05715)
			(type default)
		)
		(layer "F.Cu")
	)
	(gr_line
		(start 230.08971 -86.115652)
		(end 229.771956 -86.433406)
		(stroke
			(width 0.06731)
			(type default)
		)
		(layer "F.Cu")
	)
	(gr_line
		(start 230.098092 -76.796138)
		(end 230.386382 -77.084428)
		(stroke
			(width 0.06731)
			(type default)
		)
		(layer "F.Cu")
	)
	(gr_line
		(start 230.329994 -79.829914)
		(end 230.397812 -79.897732)
		(stroke
			(width 0.06731)
			(type default)
		)
		(layer "F.Cu")
	)
	(gr_line
		(start 230.329994 -79.465678)
		(end 230.329994 -79.829914)
		(stroke
			(width 0.06731)
			(type default)
		)
		(layer "F.Cu")
	)
	(gr_line
		(start 230.329994 -78.182978)
		(end 230.329994 -78.54569)
		(stroke
			(width 0.06731)
			(type default)
		)
		(layer "F.Cu")
	)
	(gr_line
		(start 230.347012 -151.251158)
		(end 230.410258 -151.314404)
		(stroke
			(width 0.05715)
			(type default)
		)
		(layer "F.Cu")
	)
	(gr_line
		(start 230.347012 -151.015446)
		(end 230.347012 -151.251158)
		(stroke
			(width 0.05715)
			(type default)
		)
		(layer "F.Cu")
	)
	(gr_line
		(start 230.3653 -86.13775)
		(end 230.660956 -86.433406)
		(stroke
			(width 0.06731)
			(type default)
		)
		(layer "F.Cu")
	)
	(gr_line
		(start 230.3653 -86.114382)
		(end 230.3653 -86.13775)
		(stroke
			(width 0.06731)
			(type default)
		)
		(layer "F.Cu")
	)
	(gr_line
		(start 230.386382 -78.12659)
		(end 230.329994 -78.182978)
		(stroke
			(width 0.06731)
			(type default)
		)
		(layer "F.Cu")
	)
	(gr_line
		(start 230.386382 -78.113382)
		(end 230.386382 -78.12659)
		(stroke
			(width 0.06731)
			(type default)
		)
		(layer "F.Cu")
	)
	(gr_line
		(start 230.386382 -77.084428)
		(end 230.386382 -77.097128)
		(stroke
			(width 0.06731)
			(type default)
		)
		(layer "F.Cu")
	)
	(gr_line
		(start 230.660956 -87.233506)
		(end 230.353616 -87.540846)
		(stroke
			(width 0.06731)
			(type default)
		)
		(layer "F.Cu")
	)
	(gr_line
		(start 230.661972 -78.114652)
		(end 230.72979 -78.18247)
		(stroke
			(width 0.06731)
			(type default)
		)
		(layer "F.Cu")
	)
	(gr_line
		(start 230.673402 -79.887318)
		(end 230.673402 -79.899002)
		(stroke
			(width 0.06731)
			(type default)
		)
		(layer "F.Cu")
	)
	(gr_line
		(start 230.72979 -79.83093)
		(end 230.673402 -79.887318)
		(stroke
			(width 0.06731)
			(type default)
		)
		(layer "F.Cu")
	)
	(gr_line
		(start 230.72979 -79.465678)
		(end 230.72979 -79.83093)
		(stroke
			(width 0.06731)
			(type default)
		)
		(layer "F.Cu")
	)
	(gr_line
		(start 230.72979 -78.18247)
		(end 230.72979 -78.54569)
		(stroke
			(width 0.06731)
			(type default)
		)
		(layer "F.Cu")
	)
	(gr_line
		(start 230.781098 -151.310848)
		(end 230.781098 -151.316944)
		(stroke
			(width 0.05715)
			(type default)
		)
		(layer "F.Cu")
	)
	(gr_line
		(start 230.846884 -151.245062)
		(end 230.781098 -151.310848)
		(stroke
			(width 0.05715)
			(type default)
		)
		(layer "F.Cu")
	)
	(gr_line
		(start 230.846884 -151.015446)
		(end 230.846884 -151.245062)
		(stroke
			(width 0.05715)
			(type default)
		)
		(layer "F.Cu")
	)
	(gr_line
		(start 230.938832 -156.360876)
		(end 231.26446 -156.686504)
		(stroke
			(width 0.05715)
			(type default)
		)
		(layer "F.Cu")
	)
	(gr_line
		(start 230.961692 -76.796138)
		(end 230.661972 -77.095858)
		(stroke
			(width 0.06731)
			(type default)
		)
		(layer "F.Cu")
	)
	(gr_line
		(start 231.262682 -155.236926)
		(end 230.938832 -155.560776)
		(stroke
			(width 0.05715)
			(type default)
		)
		(layer "F.Cu")
	)
	(gr_line
		(start 231.26446 -157.641036)
		(end 231.015032 -157.890464)
		(stroke
			(width 0.05715)
			(type default)
		)
		(layer "F.Cu")
	)
	(gr_line
		(start 231.630982 -155.236926)
		(end 231.954832 -155.560776)
		(stroke
			(width 0.05715)
			(type default)
		)
		(layer "F.Cu")
	)
	(gr_line
		(start 231.6353 -157.647132)
		(end 231.878632 -157.890464)
		(stroke
			(width 0.05715)
			(type default)
		)
		(layer "F.Cu")
	)
	(gr_line
		(start 231.6353 -157.638496)
		(end 231.6353 -157.647132)
		(stroke
			(width 0.05715)
			(type default)
		)
		(layer "F.Cu")
	)
	(gr_line
		(start 231.6353 -156.680408)
		(end 231.6353 -156.689044)
		(stroke
			(width 0.05715)
			(type default)
		)
		(layer "F.Cu")
	)
	(gr_line
		(start 231.954832 -156.360876)
		(end 231.6353 -156.680408)
		(stroke
			(width 0.05715)
			(type default)
		)
		(layer "F.Cu")
	)
	(gr_line
		(start 232.46969 -84.216748)
		(end 233.009186 -84.756244)
		(stroke
			(width 0.06731)
			(type default)
		)
		(layer "F.Cu")
	)
	(gr_line
		(start 232.46969 -83.718908)
		(end 232.46969 -84.216748)
		(stroke
			(width 0.06731)
			(type default)
		)
		(layer "F.Cu")
	)
	(gr_line
		(start 232.46969 -82.918808)
		(end 232.693972 -82.918808)
		(stroke
			(width 0.06731)
			(type default)
		)
		(layer "F.Cu")
	)
	(gr_line
		(start 232.46969 -81.664048)
		(end 232.46969 -82.118708)
		(stroke
			(width 0.06731)
			(type default)
		)
		(layer "F.Cu")
	)
	(gr_line
		(start 232.471976 -148.890482)
		(end 232.794302 -148.890482)
		(stroke
			(width 0.05715)
			(type default)
		)
		(layer "F.Cu")
	)
	(gr_line
		(start 232.471976 -148.390356)
		(end 232.797096 -148.390356)
		(stroke
			(width 0.05715)
			(type default)
		)
		(layer "F.Cu")
	)
	(gr_line
		(start 232.520998 -89.523824)
		(end 232.520998 -89.854024)
		(stroke
			(width 0.06731)
			(type default)
		)
		(layer "F.Cu")
	)
	(gr_line
		(start 232.634028 -89.410794)
		(end 232.520998 -89.523824)
		(stroke
			(width 0.06731)
			(type default)
		)
		(layer "F.Cu")
	)
	(gr_line
		(start 232.652316 -87.4141)
		(end 232.974134 -87.735918)
		(stroke
			(width 0.06731)
			(type default)
		)
		(layer "F.Cu")
	)
	(gr_line
		(start 232.693972 -82.918808)
		(end 233.142028 -83.366864)
		(stroke
			(width 0.06731)
			(type default)
		)
		(layer "F.Cu")
	)
	(gr_line
		(start 232.794302 -148.890482)
		(end 232.860596 -148.824188)
		(stroke
			(width 0.05715)
			(type default)
		)
		(layer "F.Cu")
	)
	(gr_line
		(start 232.797096 -148.390356)
		(end 232.860088 -148.453348)
		(stroke
			(width 0.05715)
			(type default)
		)
		(layer "F.Cu")
	)
	(gr_line
		(start 232.860088 -148.453348)
		(end 232.867962 -148.453348)
		(stroke
			(width 0.05715)
			(type default)
		)
		(layer "F.Cu")
	)
	(gr_line
		(start 232.863136 -148.821648)
		(end 232.867962 -148.816822)
		(stroke
			(width 0.05715)
			(type default)
		)
		(layer "F.Cu")
	)
	(gr_line
		(start 232.867962 -148.816822)
		(end 232.875836 -148.808948)
		(stroke
			(width 0.05715)
			(type default)
		)
		(layer "F.Cu")
	)
	(gr_line
		(start 232.867962 -148.453348)
		(end 232.875836 -148.445474)
		(stroke
			(width 0.05715)
			(type default)
		)
		(layer "F.Cu")
	)
	(gr_line
		(start 232.875836 -148.445474)
		(end 232.880662 -148.440648)
		(stroke
			(width 0.05715)
			(type default)
		)
		(layer "F.Cu")
	)
	(gr_line
		(start 232.908348 -89.410794)
		(end 233.021124 -89.52357)
		(stroke
			(width 0.06731)
			(type default)
		)
		(layer "F.Cu")
	)
	(gr_line
		(start 233.010456 -85.140292)
		(end 232.722166 -85.428582)
		(stroke
			(width 0.06731)
			(type default)
		)
		(layer "F.Cu")
	)
	(gr_line
		(start 233.010456 -85.127592)
		(end 233.010456 -85.140292)
		(stroke
			(width 0.06731)
			(type default)
		)
		(layer "F.Cu")
	)
	(gr_line
		(start 233.014012 -81.119726)
		(end 232.46969 -81.664048)
		(stroke
			(width 0.06731)
			(type default)
		)
		(layer "F.Cu")
	)
	(gr_line
		(start 233.014012 -81.116932)
		(end 233.014012 -81.119726)
		(stroke
			(width 0.06731)
			(type default)
		)
		(layer "F.Cu")
	)
	(gr_line
		(start 233.021124 -89.52357)
		(end 233.021124 -89.854024)
		(stroke
			(width 0.06731)
			(type default)
		)
		(layer "F.Cu")
	)
	(gr_line
		(start 233.249724 -87.680292)
		(end 233.249724 -87.737188)
		(stroke
			(width 0.06731)
			(type default)
		)
		(layer "F.Cu")
	)
	(gr_line
		(start 233.284776 -84.748624)
		(end 233.284776 -84.757514)
		(stroke
			(width 0.06731)
			(type default)
		)
		(layer "F.Cu")
	)
	(gr_line
		(start 233.286046 -85.128862)
		(end 233.585766 -85.428582)
		(stroke
			(width 0.06731)
			(type default)
		)
		(layer "F.Cu")
	)
	(gr_line
		(start 233.289602 -81.118202)
		(end 233.871008 -81.699608)
		(stroke
			(width 0.06731)
			(type default)
		)
		(layer "F.Cu")
	)
	(gr_line
		(start 233.515916 -87.4141)
		(end 233.249724 -87.680292)
		(stroke
			(width 0.06731)
			(type default)
		)
		(layer "F.Cu")
	)
	(gr_line
		(start 233.520996 -89.85377)
		(end 233.52125 -89.854024)
		(stroke
			(width 0.06731)
			(type default)
		)
		(layer "F.Cu")
	)
	(gr_line
		(start 233.520996 -89.529666)
		(end 233.520996 -89.85377)
		(stroke
			(width 0.06731)
			(type default)
		)
		(layer "F.Cu")
	)
	(gr_line
		(start 233.557572 -82.918808)
		(end 233.142028 -82.503264)
		(stroke
			(width 0.06731)
			(type default)
		)
		(layer "F.Cu")
	)
	(gr_line
		(start 233.627422 -89.42324)
		(end 233.520996 -89.529666)
		(stroke
			(width 0.06731)
			(type default)
		)
		(layer "F.Cu")
	)
	(gr_line
		(start 233.627422 -89.408)
		(end 233.627422 -89.42324)
		(stroke
			(width 0.06731)
			(type default)
		)
		(layer "F.Cu")
	)
	(gr_line
		(start 233.871008 -84.162392)
		(end 233.284776 -84.748624)
		(stroke
			(width 0.06731)
			(type default)
		)
		(layer "F.Cu")
	)
	(gr_line
		(start 233.871008 -83.718908)
		(end 233.871008 -84.162392)
		(stroke
			(width 0.06731)
			(type default)
		)
		(layer "F.Cu")
	)
	(gr_line
		(start 233.871008 -82.918808)
		(end 233.557572 -82.918808)
		(stroke
			(width 0.06731)
			(type default)
		)
		(layer "F.Cu")
	)
	(gr_line
		(start 233.871008 -81.699608)
		(end 233.871008 -82.118708)
		(stroke
			(width 0.06731)
			(type default)
		)
		(layer "F.Cu")
	)
	(gr_line
		(start 233.903012 -89.40927)
		(end 234.021122 -89.52738)
		(stroke
			(width 0.06731)
			(type default)
		)
		(layer "F.Cu")
	)
	(gr_line
		(start 234.021122 -89.52738)
		(end 234.021122 -89.854024)
		(stroke
			(width 0.06731)
			(type default)
		)
		(layer "F.Cu")
	)
	(gr_line
		(start 234.21467 -80.024224)
		(end 234.07878 -79.888334)
		(stroke
			(width 0.06731)
			(type default)
		)
		(layer "F.Cu")
	)
	(gr_line
		(start 234.61853 -80.024224)
		(end 234.21467 -80.024224)
		(stroke
			(width 0.06731)
			(type default)
		)
		(layer "F.Cu")
	)
	(gr_line
		(start 234.75442 -79.888334)
		(end 234.61853 -80.024224)
		(stroke
			(width 0.06731)
			(type default)
		)
		(layer "F.Cu")
	)
	(gr_line
		(start 234.75569 -79.612744)
		(end 234.07751 -79.612744)
		(stroke
			(width 0.06731)
			(type default)
		)
		(layer "F.Cu")
	)
	(gr_line
		(start 234.88142 -149.046438)
		(end 234.909868 -149.046438)
		(stroke
			(width 0.05715)
			(type default)
		)
		(layer "F.Cu")
	)
	(gr_line
		(start 234.88396 -149.417278)
		(end 235.219494 -149.752812)
		(stroke
			(width 0.05715)
			(type default)
		)
		(layer "F.Cu")
	)
	(gr_line
		(start 234.909868 -149.046438)
		(end 235.219494 -148.736812)
		(stroke
			(width 0.05715)
			(type default)
		)
		(layer "F.Cu")
	)
	(gr_line
		(start 235.01858 -88.784938)
		(end 235.01858 -88.289638)
		(stroke
			(width 0.06731)
			(type default)
		)
		(layer "F.Cu")
	)
	(gr_line
		(start 235.01858 -88.289638)
		(end 235.13161 -88.176608)
		(stroke
			(width 0.06731)
			(type default)
		)
		(layer "F.Cu")
	)
	(gr_line
		(start 235.02112 -89.854024)
		(end 235.02112 -89.529666)
		(stroke
			(width 0.06731)
			(type default)
		)
		(layer "F.Cu")
	)
	(gr_line
		(start 235.02112 -89.529666)
		(end 235.13288 -89.417906)
		(stroke
			(width 0.06731)
			(type default)
		)
		(layer "F.Cu")
	)
	(gr_line
		(start 235.13161 -88.897968)
		(end 235.01858 -88.784938)
		(stroke
			(width 0.06731)
			(type default)
		)
		(layer "F.Cu")
	)
	(gr_line
		(start 235.13288 -89.417906)
		(end 235.13288 -89.413334)
		(stroke
			(width 0.06731)
			(type default)
		)
		(layer "F.Cu")
	)
	(gr_line
		(start 235.13288 -87.68207)
		(end 235.13288 -87.680038)
		(stroke
			(width 0.06731)
			(type default)
		)
		(layer "F.Cu")
	)
	(gr_line
		(start 235.13288 -87.680038)
		(end 234.839256 -87.386414)
		(stroke
			(width 0.06731)
			(type default)
		)
		(layer "F.Cu")
	)
	(gr_line
		(start 235.29671 -80.024224)
		(end 235.16082 -79.888334)
		(stroke
			(width 0.06731)
			(type default)
		)
		(layer "F.Cu")
	)
	(gr_line
		(start 235.4072 -88.899238)
		(end 235.4072 -88.175338)
		(stroke
			(width 0.06731)
			(type default)
		)
		(layer "F.Cu")
	)
	(gr_line
		(start 235.40847 -87.6808)
		(end 235.702856 -87.386414)
		(stroke
			(width 0.06731)
			(type default)
		)
		(layer "F.Cu")
	)
	(gr_line
		(start 235.521246 -89.854024)
		(end 235.521246 -89.52738)
		(stroke
			(width 0.06731)
			(type default)
		)
		(layer "F.Cu")
	)
	(gr_line
		(start 235.521246 -89.52738)
		(end 235.40847 -89.414604)
		(stroke
			(width 0.06731)
			(type default)
		)
		(layer "F.Cu")
	)
	(gr_line
		(start 235.70057 -80.024224)
		(end 235.29671 -80.024224)
		(stroke
			(width 0.06731)
			(type default)
		)
		(layer "F.Cu")
	)
	(gr_line
		(start 235.83646 -79.888334)
		(end 235.70057 -80.024224)
		(stroke
			(width 0.06731)
			(type default)
		)
		(layer "F.Cu")
	)
	(gr_line
		(start 235.83773 -79.612744)
		(end 235.15955 -79.612744)
		(stroke
			(width 0.06731)
			(type default)
		)
		(layer "F.Cu")
	)
	(gr_line
		(start 236.019594 -149.752812)
		(end 236.342682 -149.429724)
		(stroke
			(width 0.05715)
			(type default)
		)
		(layer "F.Cu")
	)
	(gr_line
		(start 236.019594 -148.736812)
		(end 236.342682 -149.0599)
		(stroke
			(width 0.05715)
			(type default)
		)
		(layer "F.Cu")
	)
	(gr_line
		(start 236.342682 -149.0599)
		(end 236.344206 -149.0599)
		(stroke
			(width 0.05715)
			(type default)
		)
		(layer "F.Cu")
	)
	(gr_line
		(start 236.37875 -80.024224)
		(end 236.24286 -79.888334)
		(stroke
			(width 0.06731)
			(type default)
		)
		(layer "F.Cu")
	)
	(gr_line
		(start 236.49432 -79.612744)
		(end 236.24159 -79.612744)
		(stroke
			(width 0.06731)
			(type default)
		)
		(layer "F.Cu")
	)
	(gr_line
		(start 236.78261 -80.024224)
		(end 236.37875 -80.024224)
		(stroke
			(width 0.06731)
			(type default)
		)
		(layer "F.Cu")
	)
	(gr_line
		(start 236.903006 -149.0599)
		(end 236.933994 -149.0599)
		(stroke
			(width 0.05715)
			(type default)
		)
		(layer "F.Cu")
	)
	(gr_line
		(start 236.905546 -149.43074)
		(end 237.16615 -149.691344)
		(stroke
			(width 0.05715)
			(type default)
		)
		(layer "F.Cu")
	)
	(gr_line
		(start 236.9185 -79.888334)
		(end 236.78261 -80.024224)
		(stroke
			(width 0.06731)
			(type default)
		)
		(layer "F.Cu")
	)
	(gr_line
		(start 236.91977 -79.612744)
		(end 236.49432 -79.612744)
		(stroke
			(width 0.06731)
			(type default)
		)
		(layer "F.Cu")
	)
	(gr_line
		(start 236.933994 -149.0599)
		(end 237.16615 -148.827744)
		(stroke
			(width 0.05715)
			(type default)
		)
		(layer "F.Cu")
	)
	(gr_line
		(start 237.705392 -79.612744)
		(end 237.701328 -79.612744)
		(stroke
			(width 0.06731)
			(type default)
		)
		(layer "F.Cu")
	)
	(gr_line
		(start 237.998 -80.183736)
		(end 237.702598 -79.888334)
		(stroke
			(width 0.06731)
			(type default)
		)
		(layer "F.Cu")
	)
	(gr_line
		(start 237.998 -79.320136)
		(end 237.705392 -79.612744)
		(stroke
			(width 0.06731)
			(type default)
		)
		(layer "F.Cu")
	)
	(gr_line
		(start 238.324898 -86.122256)
		(end 238.86668 -86.664038)
		(stroke
			(width 0.06731)
			(type default)
		)
		(layer "F.Cu")
	)
	(gr_line
		(start 238.324898 -85.551518)
		(end 238.324898 -86.122256)
		(stroke
			(width 0.06731)
			(type default)
		)
		(layer "F.Cu")
	)
	(gr_line
		(start 238.324898 -83.494626)
		(end 238.324898 -83.951318)
		(stroke
			(width 0.06731)
			(type default)
		)
		(layer "F.Cu")
	)
	(gr_line
		(start 238.590074 -82.307176)
		(end 238.88573 -82.602832)
		(stroke
			(width 0.06731)
			(type default)
		)
		(layer "F.Cu")
	)
	(gr_line
		(start 238.595408 -84.751418)
		(end 238.324898 -84.751418)
		(stroke
			(width 0.06731)
			(type default)
		)
		(layer "F.Cu")
	)
	(gr_line
		(start 238.86668 -87.691722)
		(end 238.5822 -87.976202)
		(stroke
			(width 0.06731)
			(type default)
		)
		(layer "F.Cu")
	)
	(gr_line
		(start 238.86668 -87.671402)
		(end 238.86668 -87.691722)
		(stroke
			(width 0.06731)
			(type default)
		)
		(layer "F.Cu")
	)
	(gr_line
		(start 238.86668 -86.664038)
		(end 238.86668 -86.68258)
		(stroke
			(width 0.06731)
			(type default)
		)
		(layer "F.Cu")
	)
	(gr_line
		(start 238.887 -82.932524)
		(end 238.324898 -83.494626)
		(stroke
			(width 0.06731)
			(type default)
		)
		(layer "F.Cu")
	)
	(gr_line
		(start 238.887 -82.92592)
		(end 238.887 -82.932524)
		(stroke
			(width 0.06731)
			(type default)
		)
		(layer "F.Cu")
	)
	(gr_line
		(start 239.013238 -85.169248)
		(end 238.595408 -84.751418)
		(stroke
			(width 0.06731)
			(type default)
		)
		(layer "F.Cu")
	)
	(gr_line
		(start 239.013238 -84.305648)
		(end 239.459008 -84.751418)
		(stroke
			(width 0.06731)
			(type default)
		)
		(layer "F.Cu")
	)
	(gr_line
		(start 239.14227 -87.672672)
		(end 239.4458 -87.976202)
		(stroke
			(width 0.06731)
			(type default)
		)
		(layer "F.Cu")
	)
	(gr_line
		(start 239.16132 -82.59953)
		(end 239.16132 -82.604102)
		(stroke
			(width 0.06731)
			(type default)
		)
		(layer "F.Cu")
	)
	(gr_line
		(start 239.16259 -82.92719)
		(end 239.721898 -83.486498)
		(stroke
			(width 0.06731)
			(type default)
		)
		(layer "F.Cu")
	)
	(gr_line
		(start 239.453674 -82.307176)
		(end 239.16132 -82.59953)
		(stroke
			(width 0.06731)
			(type default)
		)
		(layer "F.Cu")
	)
	(gr_line
		(start 239.459008 -84.751418)
		(end 239.721898 -84.751418)
		(stroke
			(width 0.06731)
			(type default)
		)
		(layer "F.Cu")
	)
	(gr_line
		(start 239.704626 -30.628336)
		(end 239.410494 -30.922468)
		(stroke
			(width 0.06731)
			(type default)
		)
		(layer "F.Cu")
	)
	(gr_line
		(start 239.721898 -86.101682)
		(end 239.14227 -86.68131)
		(stroke
			(width 0.06731)
			(type default)
		)
		(layer "F.Cu")
	)
	(gr_line
		(start 239.721898 -85.551518)
		(end 239.721898 -86.101682)
		(stroke
			(width 0.06731)
			(type default)
		)
		(layer "F.Cu")
	)
	(gr_line
		(start 239.721898 -83.486498)
		(end 239.721898 -83.951318)
		(stroke
			(width 0.06731)
			(type default)
		)
		(layer "F.Cu")
	)
	(gr_line
		(start 241.558064 -28.829)
		(end 241.264694 -29.12237)
		(stroke
			(width 0.06731)
			(type default)
		)
		(layer "F.Cu")
	)
	(gr_line
		(start 241.560604 -28.829)
		(end 241.558064 -28.829)
		(stroke
			(width 0.06731)
			(type default)
		)
		(layer "F.Cu")
	)
	(gr_line
		(start 242.22456 -28.829)
		(end 242.21948 -28.829)
		(stroke
			(width 0.06731)
			(type default)
		)
		(layer "F.Cu")
	)
	(gr_line
		(start 242.382294 -30.790134)
		(end 242.22075 -30.62859)
		(stroke
			(width 0.06731)
			(type default)
		)
		(layer "F.Cu")
	)
	(gr_line
		(start 242.38585 -28.99029)
		(end 242.22456 -28.829)
		(stroke
			(width 0.06731)
			(type default)
		)
		(layer "F.Cu")
	)
	(gr_line
		(start 242.864894 -30.790134)
		(end 242.382294 -30.790134)
		(stroke
			(width 0.06731)
			(type default)
		)
		(layer "F.Cu")
	)
	(gr_line
		(start 242.864894 -28.99029)
		(end 242.38585 -28.99029)
		(stroke
			(width 0.06731)
			(type default)
		)
		(layer "F.Cu")
	)
	(gr_line
		(start 242.864894 -28.990036)
		(end 242.864894 -28.99029)
		(stroke
			(width 0.06731)
			(type default)
		)
		(layer "F.Cu")
	)
	(gr_line
		(start 247.9548 -26.58999)
		(end 247.464834 -26.58999)
		(stroke
			(width 0.06731)
			(type default)
		)
		(layer "F.Cu")
	)
	(gr_line
		(start 247.968516 -27.189938)
		(end 247.464834 -27.189938)
		(stroke
			(width 0.06731)
			(type default)
		)
		(layer "F.Cu")
	)
	(gr_line
		(start 248.112534 -27.04592)
		(end 247.968516 -27.189938)
		(stroke
			(width 0.06731)
			(type default)
		)
		(layer "F.Cu")
	)
	(gr_line
		(start 248.13514 -26.77033)
		(end 247.9548 -26.58999)
		(stroke
			(width 0.06731)
			(type default)
		)
		(layer "F.Cu")
	)
	(gr_line
		(start 248.13641 -27.04592)
		(end 248.112534 -27.04592)
		(stroke
			(width 0.06731)
			(type default)
		)
		(layer "F.Cu")
	)
	(gr_line
		(start 248.889012 -26.7716)
		(end 248.88444 -26.7716)
		(stroke
			(width 0.06731)
			(type default)
		)
		(layer "F.Cu")
	)
	(gr_line
		(start 249.181366 -27.342846)
		(end 248.88571 -27.04719)
		(stroke
			(width 0.06731)
			(type default)
		)
		(layer "F.Cu")
	)
	(gr_line
		(start 249.181366 -26.479246)
		(end 248.889012 -26.7716)
		(stroke
			(width 0.06731)
			(type default)
		)
		(layer "F.Cu")
	)
	(gr_line
		(start 257.710686 -173.241716)
		(end 257.723386 -173.241716)
		(stroke
			(width 0.05715)
			(type default)
		)
		(layer "F.Cu")
	)
	(gr_line
		(start 257.723386 -173.241716)
		(end 257.977386 -173.495716)
		(stroke
			(width 0.05715)
			(type default)
		)
		(layer "F.Cu")
	)
	(gr_line
		(start 262.92683 -80.431386)
		(end 262.92683 -80.155288)
		(stroke
			(width 0.06731)
			(type default)
		)
		(layer "F.Cu")
	)
	(gr_line
		(start 262.92683 -80.155288)
		(end 262.808974 -80.037432)
		(stroke
			(width 0.06731)
			(type default)
		)
		(layer "F.Cu")
	)
	(gr_line
		(start 263.16559 -75.564492)
		(end 263.47166 -75.258422)
		(stroke
			(width 0.06731)
			(type default)
		)
		(layer "F.Cu")
	)
	(gr_line
		(start 263.170924 -78.004924)
		(end 263.496044 -77.679804)
		(stroke
			(width 0.06731)
			(type default)
		)
		(layer "F.Cu")
	)
	(gr_line
		(start 263.496044 -76.879704)
		(end 263.16559 -76.54925)
		(stroke
			(width 0.06731)
			(type default)
		)
		(layer "F.Cu")
	)
	(gr_line
		(start 265.704574 -34.228278)
		(end 265.410442 -34.52241)
		(stroke
			(width 0.06731)
			(type default)
		)
		(layer "F.Cu")
	)
	(gr_line
		(start 267.325602 -120.087898)
		(end 267.62583 -119.78767)
		(stroke
			(width 0.06731)
			(type default)
		)
		(layer "F.Cu")
	)
	(gr_line
		(start 267.325602 -112.784382)
		(end 267.613384 -112.4966)
		(stroke
			(width 0.06731)
			(type default)
		)
		(layer "F.Cu")
	)
	(gr_line
		(start 267.325602 -111.920782)
		(end 267.62583 -112.22101)
		(stroke
			(width 0.06731)
			(type default)
		)
		(layer "F.Cu")
	)
	(gr_line
		(start 267.325602 -109.18444)
		(end 267.620242 -108.8898)
		(stroke
			(width 0.06731)
			(type default)
		)
		(layer "F.Cu")
	)
	(gr_line
		(start 267.325602 -108.32084)
		(end 267.620242 -108.61548)
		(stroke
			(width 0.06731)
			(type default)
		)
		(layer "F.Cu")
	)
	(gr_line
		(start 267.325602 -105.584498)
		(end 267.62583 -105.28427)
		(stroke
			(width 0.06731)
			(type default)
		)
		(layer "F.Cu")
	)
	(gr_line
		(start 267.325602 -104.720898)
		(end 267.613384 -105.00868)
		(stroke
			(width 0.06731)
			(type default)
		)
		(layer "F.Cu")
	)
	(gr_line
		(start 267.613384 -112.4966)
		(end 267.6271 -112.4966)
		(stroke
			(width 0.06731)
			(type default)
		)
		(layer "F.Cu")
	)
	(gr_line
		(start 267.613384 -105.00868)
		(end 267.6271 -105.00868)
		(stroke
			(width 0.06731)
			(type default)
		)
		(layer "F.Cu")
	)
	(gr_line
		(start 267.935202 -101.984302)
		(end 268.242034 -101.67747)
		(stroke
			(width 0.06731)
			(type default)
		)
		(layer "F.Cu")
	)
	(gr_line
		(start 267.935202 -101.120702)
		(end 268.21638 -101.40188)
		(stroke
			(width 0.06731)
			(type default)
		)
		(layer "F.Cu")
	)
	(gr_line
		(start 268.21638 -101.40188)
		(end 268.243304 -101.40188)
		(stroke
			(width 0.06731)
			(type default)
		)
		(layer "F.Cu")
	)
	(gr_line
		(start 268.244828 -112.4966)
		(end 268.258544 -112.4966)
		(stroke
			(width 0.06731)
			(type default)
		)
		(layer "F.Cu")
	)
	(gr_line
		(start 268.244828 -105.00868)
		(end 268.258544 -105.00868)
		(stroke
			(width 0.06731)
			(type default)
		)
		(layer "F.Cu")
	)
	(gr_line
		(start 268.246098 -119.78767)
		(end 268.571726 -120.113298)
		(stroke
			(width 0.06731)
			(type default)
		)
		(layer "F.Cu")
	)
	(gr_line
		(start 268.246098 -112.22101)
		(end 268.571726 -111.895382)
		(stroke
			(width 0.06731)
			(type default)
		)
		(layer "F.Cu")
	)
	(gr_line
		(start 268.246098 -105.28427)
		(end 268.571726 -105.609898)
		(stroke
			(width 0.06731)
			(type default)
		)
		(layer "F.Cu")
	)
	(gr_line
		(start 268.251686 -108.8898)
		(end 268.571726 -109.20984)
		(stroke
			(width 0.06731)
			(type default)
		)
		(layer "F.Cu")
	)
	(gr_line
		(start 268.251686 -108.61548)
		(end 268.571726 -108.29544)
		(stroke
			(width 0.06731)
			(type default)
		)
		(layer "F.Cu")
	)
	(gr_line
		(start 268.258544 -112.4966)
		(end 268.571726 -112.809782)
		(stroke
			(width 0.06731)
			(type default)
		)
		(layer "F.Cu")
	)
	(gr_line
		(start 268.258544 -105.00868)
		(end 268.571726 -104.695498)
		(stroke
			(width 0.06731)
			(type default)
		)
		(layer "F.Cu")
	)
	(gr_line
		(start 268.382242 -34.390076)
		(end 268.220698 -34.228532)
		(stroke
			(width 0.06731)
			(type default)
		)
		(layer "F.Cu")
	)
	(gr_line
		(start 268.847824 -101.40188)
		(end 268.874748 -101.40188)
		(stroke
			(width 0.06731)
			(type default)
		)
		(layer "F.Cu")
	)
	(gr_line
		(start 268.849094 -101.67747)
		(end 269.181326 -102.009702)
		(stroke
			(width 0.06731)
			(type default)
		)
		(layer "F.Cu")
	)
	(gr_line
		(start 268.864842 -34.390076)
		(end 268.382242 -34.390076)
		(stroke
			(width 0.06731)
			(type default)
		)
		(layer "F.Cu")
	)
	(gr_line
		(start 268.874748 -101.40188)
		(end 269.181326 -101.095302)
		(stroke
			(width 0.06731)
			(type default)
		)
		(layer "F.Cu")
	)
	(gr_line
		(start 269.105126 -120.113298)
		(end 269.431262 -119.787162)
		(stroke
			(width 0.06731)
			(type default)
		)
		(layer "F.Cu")
	)
	(gr_line
		(start 269.105126 -112.809782)
		(end 269.442438 -112.47247)
		(stroke
			(width 0.06731)
			(type default)
		)
		(layer "F.Cu")
	)
	(gr_line
		(start 269.105126 -111.895382)
		(end 269.406624 -112.19688)
		(stroke
			(width 0.06731)
			(type default)
		)
		(layer "F.Cu")
	)
	(gr_line
		(start 269.105126 -109.20984)
		(end 269.425166 -108.8898)
		(stroke
			(width 0.06731)
			(type default)
		)
		(layer "F.Cu")
	)
	(gr_line
		(start 269.105126 -108.29544)
		(end 269.425166 -108.61548)
		(stroke
			(width 0.06731)
			(type default)
		)
		(layer "F.Cu")
	)
	(gr_line
		(start 269.105126 -105.609898)
		(end 269.430754 -105.28427)
		(stroke
			(width 0.06731)
			(type default)
		)
		(layer "F.Cu")
	)
	(gr_line
		(start 269.105126 -104.695498)
		(end 269.418308 -105.00868)
		(stroke
			(width 0.06731)
			(type default)
		)
		(layer "F.Cu")
	)
	(gr_line
		(start 269.406624 -112.19688)
		(end 269.443708 -112.19688)
		(stroke
			(width 0.06731)
			(type default)
		)
		(layer "F.Cu")
	)
	(gr_line
		(start 269.418308 -105.00868)
		(end 269.432024 -105.00868)
		(stroke
			(width 0.06731)
			(type default)
		)
		(layer "F.Cu")
	)
	(gr_line
		(start 269.714726 -102.009702)
		(end 270.034766 -101.689662)
		(stroke
			(width 0.06731)
			(type default)
		)
		(layer "F.Cu")
	)
	(gr_line
		(start 269.714726 -101.095302)
		(end 270.033496 -101.414072)
		(stroke
			(width 0.06731)
			(type default)
		)
		(layer "F.Cu")
	)
	(gr_line
		(start 269.96771 -136.704324)
		(end 270.277844 -136.39419)
		(stroke
			(width 0.06731)
			(type default)
		)
		(layer "F.Cu")
	)
	(gr_line
		(start 269.96771 -135.840724)
		(end 270.245586 -136.1186)
		(stroke
			(width 0.06731)
			(type default)
		)
		(layer "F.Cu")
	)
	(gr_line
		(start 269.96771 -133.104382)
		(end 270.260572 -132.81152)
		(stroke
			(width 0.06731)
			(type default)
		)
		(layer "F.Cu")
	)
	(gr_line
		(start 269.96771 -132.240782)
		(end 270.262858 -132.53593)
		(stroke
			(width 0.06731)
			(type default)
		)
		(layer "F.Cu")
	)
	(gr_line
		(start 269.96771 -125.494542)
		(end 270.264382 -125.19787)
		(stroke
			(width 0.06731)
			(type default)
		)
		(layer "F.Cu")
	)
	(gr_line
		(start 269.96771 -124.630942)
		(end 270.259048 -124.92228)
		(stroke
			(width 0.06731)
			(type default)
		)
		(layer "F.Cu")
	)
	(gr_line
		(start 269.96771 -121.894346)
		(end 270.270986 -121.59107)
		(stroke
			(width 0.06731)
			(type default)
		)
		(layer "F.Cu")
	)
	(gr_line
		(start 269.96771 -121.030746)
		(end 270.252444 -121.31548)
		(stroke
			(width 0.06731)
			(type default)
		)
		(layer "F.Cu")
	)
	(gr_line
		(start 269.96771 -100.177854)
		(end 270.271494 -99.87407)
		(stroke
			(width 0.06731)
			(type default)
		)
		(layer "F.Cu")
	)
	(gr_line
		(start 269.96771 -99.314254)
		(end 270.251936 -99.59848)
		(stroke
			(width 0.06731)
			(type default)
		)
		(layer "F.Cu")
	)
	(gr_line
		(start 270.033496 -101.414072)
		(end 270.036036 -101.414072)
		(stroke
			(width 0.06731)
			(type default)
		)
		(layer "F.Cu")
	)
	(gr_line
		(start 270.245586 -136.1186)
		(end 270.279114 -136.1186)
		(stroke
			(width 0.06731)
			(type default)
		)
		(layer "F.Cu")
	)
	(gr_line
		(start 270.251936 -99.59848)
		(end 270.272764 -99.59848)
		(stroke
			(width 0.06731)
			(type default)
		)
		(layer "F.Cu")
	)
	(gr_line
		(start 270.252444 -121.31548)
		(end 270.272256 -121.31548)
		(stroke
			(width 0.06731)
			(type default)
		)
		(layer "F.Cu")
	)
	(gr_line
		(start 270.259048 -124.92228)
		(end 270.265652 -124.92228)
		(stroke
			(width 0.06731)
			(type default)
		)
		(layer "F.Cu")
	)
	(gr_line
		(start 270.260572 -132.81152)
		(end 270.264128 -132.81152)
		(stroke
			(width 0.06731)
			(type default)
		)
		(layer "F.Cu")
	)
	(gr_line
		(start 270.87703 -136.1186)
		(end 270.910558 -136.1186)
		(stroke
			(width 0.06731)
			(type default)
		)
		(layer "F.Cu")
	)
	(gr_line
		(start 270.8783 -136.39419)
		(end 271.213834 -136.729724)
		(stroke
			(width 0.06731)
			(type default)
		)
		(layer "F.Cu")
	)
	(gr_line
		(start 270.88338 -99.59848)
		(end 270.904208 -99.59848)
		(stroke
			(width 0.06731)
			(type default)
		)
		(layer "F.Cu")
	)
	(gr_line
		(start 270.883888 -121.31548)
		(end 270.9037 -121.31548)
		(stroke
			(width 0.06731)
			(type default)
		)
		(layer "F.Cu")
	)
	(gr_line
		(start 270.88465 -99.87407)
		(end 271.213834 -100.203254)
		(stroke
			(width 0.06731)
			(type default)
		)
		(layer "F.Cu")
	)
	(gr_line
		(start 270.885158 -121.59107)
		(end 271.213834 -121.919746)
		(stroke
			(width 0.06731)
			(type default)
		)
		(layer "F.Cu")
	)
	(gr_line
		(start 270.890492 -124.92228)
		(end 270.897096 -124.92228)
		(stroke
			(width 0.06731)
			(type default)
		)
		(layer "F.Cu")
	)
	(gr_line
		(start 270.891762 -125.19787)
		(end 271.213834 -125.519942)
		(stroke
			(width 0.06731)
			(type default)
		)
		(layer "F.Cu")
	)
	(gr_line
		(start 270.892016 -132.81152)
		(end 270.895572 -132.81152)
		(stroke
			(width 0.06731)
			(type default)
		)
		(layer "F.Cu")
	)
	(gr_line
		(start 270.893286 -132.53593)
		(end 271.213834 -132.215382)
		(stroke
			(width 0.06731)
			(type default)
		)
		(layer "F.Cu")
	)
	(gr_line
		(start 270.895572 -132.81152)
		(end 271.213834 -133.129782)
		(stroke
			(width 0.06731)
			(type default)
		)
		(layer "F.Cu")
	)
	(gr_line
		(start 270.897096 -124.92228)
		(end 271.213834 -124.605542)
		(stroke
			(width 0.06731)
			(type default)
		)
		(layer "F.Cu")
	)
	(gr_line
		(start 270.9037 -121.31548)
		(end 271.213834 -121.005346)
		(stroke
			(width 0.06731)
			(type default)
		)
		(layer "F.Cu")
	)
	(gr_line
		(start 270.904208 -99.59848)
		(end 271.213834 -99.288854)
		(stroke
			(width 0.06731)
			(type default)
		)
		(layer "F.Cu")
	)
	(gr_line
		(start 270.910558 -136.1186)
		(end 271.213834 -135.815324)
		(stroke
			(width 0.06731)
			(type default)
		)
		(layer "F.Cu")
	)
	(gr_line
		(start 270.980662 -350.365314)
		(end 271.300702 -350.685354)
		(stroke
			(width 0.06731)
			(type default)
		)
		(layer "F.Cu")
	)
	(gr_line
		(start 271.006062 -348.58579)
		(end 271.300702 -348.88043)
		(stroke
			(width 0.06731)
			(type default)
		)
		(layer "F.Cu")
	)
	(gr_line
		(start 271.300702 -351.316798)
		(end 271.006062 -351.611438)
		(stroke
			(width 0.06731)
			(type default)
		)
		(layer "F.Cu")
	)
	(gr_line
		(start 271.300702 -349.511874)
		(end 270.980662 -349.831914)
		(stroke
			(width 0.06731)
			(type default)
		)
		(layer "F.Cu")
	)
	(gr_line
		(start 271.424908 -299.224954)
		(end 271.899888 -298.749974)
		(stroke
			(width 0.05715)
			(type default)
		)
		(layer "F.Cu")
	)
	(gr_line
		(start 271.575022 -351.316798)
		(end 271.869662 -351.611438)
		(stroke
			(width 0.06731)
			(type default)
		)
		(layer "F.Cu")
	)
	(gr_line
		(start 271.575022 -349.511874)
		(end 271.895062 -349.831914)
		(stroke
			(width 0.06731)
			(type default)
		)
		(layer "F.Cu")
	)
	(gr_line
		(start 271.747234 -136.729724)
		(end 272.058638 -136.41832)
		(stroke
			(width 0.06731)
			(type default)
		)
		(layer "F.Cu")
	)
	(gr_line
		(start 271.747234 -135.815324)
		(end 272.07464 -136.14273)
		(stroke
			(width 0.06731)
			(type default)
		)
		(layer "F.Cu")
	)
	(gr_line
		(start 271.747234 -133.129782)
		(end 272.065496 -132.81152)
		(stroke
			(width 0.06731)
			(type default)
		)
		(layer "F.Cu")
	)
	(gr_line
		(start 271.747234 -132.215382)
		(end 272.067782 -132.53593)
		(stroke
			(width 0.06731)
			(type default)
		)
		(layer "F.Cu")
	)
	(gr_line
		(start 271.747234 -125.519942)
		(end 272.069306 -125.19787)
		(stroke
			(width 0.06731)
			(type default)
		)
		(layer "F.Cu")
	)
	(gr_line
		(start 271.747234 -124.605542)
		(end 272.063972 -124.92228)
		(stroke
			(width 0.06731)
			(type default)
		)
		(layer "F.Cu")
	)
	(gr_line
		(start 271.747234 -121.919746)
		(end 272.07591 -121.59107)
		(stroke
			(width 0.06731)
			(type default)
		)
		(layer "F.Cu")
	)
	(gr_line
		(start 271.747234 -121.005346)
		(end 272.057368 -121.31548)
		(stroke
			(width 0.06731)
			(type default)
		)
		(layer "F.Cu")
	)
	(gr_line
		(start 271.747234 -100.203254)
		(end 272.076418 -99.87407)
		(stroke
			(width 0.06731)
			(type default)
		)
		(layer "F.Cu")
	)
	(gr_line
		(start 271.747234 -99.288854)
		(end 272.05686 -99.59848)
		(stroke
			(width 0.06731)
			(type default)
		)
		(layer "F.Cu")
	)
	(gr_line
		(start 271.869662 -348.58579)
		(end 271.575022 -348.88043)
		(stroke
			(width 0.06731)
			(type default)
		)
		(layer "F.Cu")
	)
	(gr_line
		(start 271.895062 -350.365314)
		(end 271.575022 -350.685354)
		(stroke
			(width 0.06731)
			(type default)
		)
		(layer "F.Cu")
	)
	(gr_line
		(start 271.899888 -298.74972)
		(end 271.899888 -298.749974)
		(stroke
			(width 0.05715)
			(type default)
		)
		(layer "F.Cu")
	)
	(gr_line
		(start 272.05686 -99.59848)
		(end 272.077688 -99.59848)
		(stroke
			(width 0.06731)
			(type default)
		)
		(layer "F.Cu")
	)
	(gr_line
		(start 272.057368 -121.31548)
		(end 272.07718 -121.31548)
		(stroke
			(width 0.06731)
			(type default)
		)
		(layer "F.Cu")
	)
	(gr_line
		(start 272.058638 -136.41832)
		(end 272.07591 -136.41832)
		(stroke
			(width 0.06731)
			(type default)
		)
		(layer "F.Cu")
	)
	(gr_line
		(start 272.063972 -124.92228)
		(end 272.070576 -124.92228)
		(stroke
			(width 0.06731)
			(type default)
		)
		(layer "F.Cu")
	)
	(gr_line
		(start 272.065496 -132.81152)
		(end 272.069052 -132.81152)
		(stroke
			(width 0.06731)
			(type default)
		)
		(layer "F.Cu")
	)
	(gr_line
		(start 273.954748 -26.58999)
		(end 273.464782 -26.58999)
		(stroke
			(width 0.06731)
			(type default)
		)
		(layer "F.Cu")
	)
	(gr_line
		(start 273.968464 -27.189938)
		(end 273.464782 -27.189938)
		(stroke
			(width 0.06731)
			(type default)
		)
		(layer "F.Cu")
	)
	(gr_line
		(start 274.112482 -27.04592)
		(end 273.968464 -27.189938)
		(stroke
			(width 0.06731)
			(type default)
		)
		(layer "F.Cu")
	)
	(gr_line
		(start 274.135088 -26.77033)
		(end 273.954748 -26.58999)
		(stroke
			(width 0.06731)
			(type default)
		)
		(layer "F.Cu")
	)
	(gr_line
		(start 274.136358 -27.04592)
		(end 274.112482 -27.04592)
		(stroke
			(width 0.06731)
			(type default)
		)
		(layer "F.Cu")
	)
	(gr_line
		(start 274.88896 -26.7716)
		(end 274.884388 -26.7716)
		(stroke
			(width 0.06731)
			(type default)
		)
		(layer "F.Cu")
	)
	(gr_line
		(start 275.181314 -27.342846)
		(end 274.885658 -27.04719)
		(stroke
			(width 0.06731)
			(type default)
		)
		(layer "F.Cu")
	)
	(gr_line
		(start 275.181314 -26.479246)
		(end 274.88896 -26.7716)
		(stroke
			(width 0.06731)
			(type default)
		)
		(layer "F.Cu")
	)
	(gr_line
		(start 277.563326 -99.59848)
		(end 277.586186 -99.59848)
		(stroke
			(width 0.06731)
			(type default)
		)
		(layer "F.Cu")
	)
	(gr_line
		(start 277.563834 -136.41832)
		(end 277.611078 -136.41832)
		(stroke
			(width 0.06731)
			(type default)
		)
		(layer "F.Cu")
	)
	(gr_line
		(start 277.564596 -99.87407)
		(end 277.735538 -100.045012)
		(stroke
			(width 0.06731)
			(type default)
		)
		(layer "F.Cu")
	)
	(gr_line
		(start 277.565104 -136.14273)
		(end 277.742904 -135.96493)
		(stroke
			(width 0.06731)
			(type default)
		)
		(layer "F.Cu")
	)
	(gr_line
		(start 277.565612 -112.19688)
		(end 277.591012 -112.19688)
		(stroke
			(width 0.06731)
			(type default)
		)
		(layer "F.Cu")
	)
	(gr_line
		(start 277.566882 -112.47247)
		(end 277.739348 -112.644936)
		(stroke
			(width 0.06731)
			(type default)
		)
		(layer "F.Cu")
	)
	(gr_line
		(start 277.567644 -119.787162)
		(end 277.735538 -119.955056)
		(stroke
			(width 0.06731)
			(type default)
		)
		(layer "F.Cu")
	)
	(gr_line
		(start 277.570692 -132.81152)
		(end 277.585932 -132.81152)
		(stroke
			(width 0.06731)
			(type default)
		)
		(layer "F.Cu")
	)
	(gr_line
		(start 277.571962 -132.53593)
		(end 277.742904 -132.364988)
		(stroke
			(width 0.06731)
			(type default)
		)
		(layer "F.Cu")
	)
	(gr_line
		(start 277.57247 -108.8898)
		(end 277.584154 -108.8898)
		(stroke
			(width 0.06731)
			(type default)
		)
		(layer "F.Cu")
	)
	(gr_line
		(start 277.57374 -108.61421)
		(end 277.742904 -108.445046)
		(stroke
			(width 0.06731)
			(type default)
		)
		(layer "F.Cu")
	)
	(gr_line
		(start 277.57374 -101.688392)
		(end 277.577804 -101.688392)
		(stroke
			(width 0.06731)
			(type default)
		)
		(layer "F.Cu")
	)
	(gr_line
		(start 277.574248 -121.31548)
		(end 277.582376 -121.31548)
		(stroke
			(width 0.06731)
			(type default)
		)
		(layer "F.Cu")
	)
	(gr_line
		(start 277.57501 -101.412802)
		(end 277.742904 -101.244908)
		(stroke
			(width 0.06731)
			(type default)
		)
		(layer "F.Cu")
	)
	(gr_line
		(start 277.575518 -121.59107)
		(end 277.739348 -121.7549)
		(stroke
			(width 0.06731)
			(type default)
		)
		(layer "F.Cu")
	)
	(gr_line
		(start 277.575772 -125.1966)
		(end 277.580852 -125.1966)
		(stroke
			(width 0.06731)
			(type default)
		)
		(layer "F.Cu")
	)
	(gr_line
		(start 277.577042 -124.92101)
		(end 277.742904 -124.755148)
		(stroke
			(width 0.06731)
			(type default)
		)
		(layer "F.Cu")
	)
	(gr_line
		(start 277.577296 -105.00868)
		(end 277.579328 -105.00868)
		(stroke
			(width 0.06731)
			(type default)
		)
		(layer "F.Cu")
	)
	(gr_line
		(start 277.577804 -101.688392)
		(end 277.734522 -101.84511)
		(stroke
			(width 0.06731)
			(type default)
		)
		(layer "F.Cu")
	)
	(gr_line
		(start 277.578566 -105.28427)
		(end 277.739348 -105.445052)
		(stroke
			(width 0.06731)
			(type default)
		)
		(layer "F.Cu")
	)
	(gr_line
		(start 277.579328 -105.00868)
		(end 277.742904 -104.845104)
		(stroke
			(width 0.06731)
			(type default)
		)
		(layer "F.Cu")
	)
	(gr_line
		(start 277.580852 -125.1966)
		(end 277.739348 -125.355096)
		(stroke
			(width 0.06731)
			(type default)
		)
		(layer "F.Cu")
	)
	(gr_line
		(start 277.582376 -121.31548)
		(end 277.742904 -121.154952)
		(stroke
			(width 0.06731)
			(type default)
		)
		(layer "F.Cu")
	)
	(gr_line
		(start 277.584154 -108.8898)
		(end 277.739348 -109.044994)
		(stroke
			(width 0.06731)
			(type default)
		)
		(layer "F.Cu")
	)
	(gr_line
		(start 277.585932 -132.81152)
		(end 277.739348 -132.964936)
		(stroke
			(width 0.06731)
			(type default)
		)
		(layer "F.Cu")
	)
	(gr_line
		(start 277.586186 -99.59848)
		(end 277.739602 -99.445064)
		(stroke
			(width 0.06731)
			(type default)
		)
		(layer "F.Cu")
	)
	(gr_line
		(start 277.591012 -112.19688)
		(end 277.742904 -112.044988)
		(stroke
			(width 0.06731)
			(type default)
		)
		(layer "F.Cu")
	)
	(gr_line
		(start 277.611078 -136.41832)
		(end 277.75789 -136.565132)
		(stroke
			(width 0.06731)
			(type default)
		)
		(layer "F.Cu")
	)
	(gr_line
		(start 277.734522 -101.84511)
		(end 278.242268 -101.84511)
		(stroke
			(width 0.06731)
			(type default)
		)
		(layer "F.Cu")
	)
	(gr_line
		(start 277.735538 -119.955056)
		(end 278.242268 -119.955056)
		(stroke
			(width 0.06731)
			(type default)
		)
		(layer "F.Cu")
	)
	(gr_line
		(start 277.735538 -100.045012)
		(end 278.242268 -100.045012)
		(stroke
			(width 0.06731)
			(type default)
		)
		(layer "F.Cu")
	)
	(gr_line
		(start 277.739348 -132.964936)
		(end 278.242268 -132.964936)
		(stroke
			(width 0.06731)
			(type default)
		)
		(layer "F.Cu")
	)
	(gr_line
		(start 277.739348 -125.355096)
		(end 278.242268 -125.355096)
		(stroke
			(width 0.06731)
			(type default)
		)
		(layer "F.Cu")
	)
	(gr_line
		(start 277.739348 -121.7549)
		(end 278.242268 -121.7549)
		(stroke
			(width 0.06731)
			(type default)
		)
		(layer "F.Cu")
	)
	(gr_line
		(start 277.739348 -112.644936)
		(end 278.242268 -112.644936)
		(stroke
			(width 0.06731)
			(type default)
		)
		(layer "F.Cu")
	)
	(gr_line
		(start 277.739348 -109.044994)
		(end 278.242268 -109.044994)
		(stroke
			(width 0.06731)
			(type default)
		)
		(layer "F.Cu")
	)
	(gr_line
		(start 277.739348 -105.445052)
		(end 278.242268 -105.445052)
		(stroke
			(width 0.06731)
			(type default)
		)
		(layer "F.Cu")
	)
	(gr_line
		(start 277.739602 -99.445064)
		(end 278.242268 -99.445064)
		(stroke
			(width 0.06731)
			(type default)
		)
		(layer "F.Cu")
	)
	(gr_line
		(start 277.742904 -135.96493)
		(end 278.242268 -135.96493)
		(stroke
			(width 0.06731)
			(type default)
		)
		(layer "F.Cu")
	)
	(gr_line
		(start 277.742904 -132.364988)
		(end 278.242268 -132.364988)
		(stroke
			(width 0.06731)
			(type default)
		)
		(layer "F.Cu")
	)
	(gr_line
		(start 277.742904 -124.755148)
		(end 278.242268 -124.755148)
		(stroke
			(width 0.06731)
			(type default)
		)
		(layer "F.Cu")
	)
	(gr_line
		(start 277.742904 -121.154952)
		(end 278.242268 -121.154952)
		(stroke
			(width 0.06731)
			(type default)
		)
		(layer "F.Cu")
	)
	(gr_line
		(start 277.742904 -112.044988)
		(end 278.242268 -112.044988)
		(stroke
			(width 0.06731)
			(type default)
		)
		(layer "F.Cu")
	)
	(gr_line
		(start 277.742904 -108.445046)
		(end 278.242268 -108.445046)
		(stroke
			(width 0.06731)
			(type default)
		)
		(layer "F.Cu")
	)
	(gr_line
		(start 277.742904 -104.845104)
		(end 278.242268 -104.845104)
		(stroke
			(width 0.06731)
			(type default)
		)
		(layer "F.Cu")
	)
	(gr_line
		(start 277.742904 -101.244908)
		(end 278.242268 -101.244908)
		(stroke
			(width 0.06731)
			(type default)
		)
		(layer "F.Cu")
	)
	(gr_line
		(start 277.75789 -136.565132)
		(end 278.242268 -136.565132)
		(stroke
			(width 0.06731)
			(type default)
		)
		(layer "F.Cu")
	)
	(gr_line
		(start 283.319982 -134.765034)
		(end 282.842462 -134.765034)
		(stroke
			(width 0.06731)
			(type default)
		)
		(layer "F.Cu")
	)
	(gr_line
		(start 283.470096 -134.61492)
		(end 283.319982 -134.765034)
		(stroke
			(width 0.06731)
			(type default)
		)
		(layer "F.Cu")
	)
	(gr_line
		(start 283.500576 -134.61492)
		(end 283.470096 -134.61492)
		(stroke
			(width 0.06731)
			(type default)
		)
		(layer "F.Cu")
	)
	(gr_line
		(start 286.01543 -134.61492)
		(end 285.989014 -134.61492)
		(stroke
			(width 0.06731)
			(type default)
		)
		(layer "F.Cu")
	)
	(gr_line
		(start 286.296862 -134.896352)
		(end 286.01543 -134.61492)
		(stroke
			(width 0.06731)
			(type default)
		)
		(layer "F.Cu")
	)
	(gr_line
		(start 289.634422 -350.365314)
		(end 289.954462 -350.685354)
		(stroke
			(width 0.06731)
			(type default)
		)
		(layer "F.Cu")
	)
	(gr_line
		(start 289.659822 -348.58579)
		(end 289.954462 -348.88043)
		(stroke
			(width 0.06731)
			(type default)
		)
		(layer "F.Cu")
	)
	(gr_line
		(start 289.954462 -351.316798)
		(end 289.659822 -351.611438)
		(stroke
			(width 0.06731)
			(type default)
		)
		(layer "F.Cu")
	)
	(gr_line
		(start 289.954462 -349.511874)
		(end 289.634422 -349.831914)
		(stroke
			(width 0.06731)
			(type default)
		)
		(layer "F.Cu")
	)
	(gr_line
		(start 292.743382 -356.511606)
		(end 293.063422 -356.831646)
		(stroke
			(width 0.06731)
			(type default)
		)
		(layer "F.Cu")
	)
	(gr_line
		(start 292.768782 -354.732082)
		(end 293.063422 -355.026722)
		(stroke
			(width 0.06731)
			(type default)
		)
		(layer "F.Cu")
	)
	(gr_line
		(start 293.063422 -357.46309)
		(end 292.768782 -357.75773)
		(stroke
			(width 0.06731)
			(type default)
		)
		(layer "F.Cu")
	)
	(gr_line
		(start 293.063422 -355.658166)
		(end 292.743382 -355.978206)
		(stroke
			(width 0.06731)
			(type default)
		)
		(layer "F.Cu")
	)
	(gr_line
		(start 297.699938 -121.07037)
		(end 297.403012 -121.367296)
		(stroke
			(width 0.06731)
			(type default)
		)
		(layer "F.Cu")
	)
	(gr_line
		(start 298.961302 -344.219022)
		(end 299.281342 -344.539062)
		(stroke
			(width 0.06731)
			(type default)
		)
		(layer "F.Cu")
	)
	(gr_line
		(start 298.986702 -342.439498)
		(end 299.281342 -342.734138)
		(stroke
			(width 0.06731)
			(type default)
		)
		(layer "F.Cu")
	)
	(gr_line
		(start 299.257212 -147.087336)
		(end 299.556678 -146.78787)
		(stroke
			(width 0.06731)
			(type default)
		)
		(layer "F.Cu")
	)
	(gr_line
		(start 299.281342 -345.170506)
		(end 298.986702 -345.465146)
		(stroke
			(width 0.06731)
			(type default)
		)
		(layer "F.Cu")
	)
	(gr_line
		(start 299.281342 -343.365582)
		(end 298.961302 -343.685622)
		(stroke
			(width 0.06731)
			(type default)
		)
		(layer "F.Cu")
	)
	(gr_line
		(start 299.545248 -119.279162)
		(end 299.257212 -119.567198)
		(stroke
			(width 0.06731)
			(type default)
		)
		(layer "F.Cu")
	)
	(gr_line
		(start 299.547026 -130.48742)
		(end 299.257212 -130.777234)
		(stroke
			(width 0.06731)
			(type default)
		)
		(layer "F.Cu")
	)
	(gr_line
		(start 299.556678 -130.48742)
		(end 299.547026 -130.48742)
		(stroke
			(width 0.06731)
			(type default)
		)
		(layer "F.Cu")
	)
	(gr_line
		(start 299.558456 -119.279162)
		(end 299.545248 -119.279162)
		(stroke
			(width 0.06731)
			(type default)
		)
		(layer "F.Cu")
	)
	(gr_line
		(start 300.20387 -146.78787)
		(end 300.371002 -146.955002)
		(stroke
			(width 0.06731)
			(type default)
		)
		(layer "F.Cu")
	)
	(gr_line
		(start 300.220634 -130.48742)
		(end 300.208442 -130.48742)
		(stroke
			(width 0.06731)
			(type default)
		)
		(layer "F.Cu")
	)
	(gr_line
		(start 300.222412 -119.279162)
		(end 300.206664 -119.279162)
		(stroke
			(width 0.06731)
			(type default)
		)
		(layer "F.Cu")
	)
	(gr_line
		(start 300.371002 -146.955002)
		(end 300.857412 -146.955002)
		(stroke
			(width 0.06731)
			(type default)
		)
		(layer "F.Cu")
	)
	(gr_line
		(start 300.374812 -121.234962)
		(end 300.21022 -121.07037)
		(stroke
			(width 0.06731)
			(type default)
		)
		(layer "F.Cu")
	)
	(gr_line
		(start 300.378114 -130.6449)
		(end 300.220634 -130.48742)
		(stroke
			(width 0.06731)
			(type default)
		)
		(layer "F.Cu")
	)
	(gr_line
		(start 300.378368 -119.435118)
		(end 300.222412 -119.279162)
		(stroke
			(width 0.06731)
			(type default)
		)
		(layer "F.Cu")
	)
	(gr_line
		(start 300.857412 -130.6449)
		(end 300.378114 -130.6449)
		(stroke
			(width 0.06731)
			(type default)
		)
		(layer "F.Cu")
	)
	(gr_line
		(start 300.857412 -121.234962)
		(end 300.374812 -121.234962)
		(stroke
			(width 0.06731)
			(type default)
		)
		(layer "F.Cu")
	)
	(gr_line
		(start 300.857412 -119.435118)
		(end 300.378368 -119.435118)
		(stroke
			(width 0.06731)
			(type default)
		)
		(layer "F.Cu")
	)
	(gr_line
		(start 305.94808 -117.63502)
		(end 305.457606 -117.63502)
		(stroke
			(width 0.06731)
			(type default)
		)
		(layer "F.Cu")
	)
	(gr_line
		(start 305.95697 -143.35506)
		(end 305.457606 -143.35506)
		(stroke
			(width 0.06731)
			(type default)
		)
		(layer "F.Cu")
	)
	(gr_line
		(start 306.09921 -117.48389)
		(end 305.94808 -117.63502)
		(stroke
			(width 0.06731)
			(type default)
		)
		(layer "F.Cu")
	)
	(gr_line
		(start 306.124864 -143.187166)
		(end 305.95697 -143.35506)
		(stroke
			(width 0.06731)
			(type default)
		)
		(layer "F.Cu")
	)
	(gr_line
		(start 306.856384 -117.48262)
		(end 306.819808 -117.48262)
		(stroke
			(width 0.06731)
			(type default)
		)
		(layer "F.Cu")
	)
	(gr_line
		(start 307.132736 -117.758972)
		(end 306.856384 -117.48262)
		(stroke
			(width 0.06731)
			(type default)
		)
		(layer "F.Cu")
	)
	(gr_line
		(start 311.63387 -143.185896)
		(end 311.63133 -143.185896)
		(stroke
			(width 0.06731)
			(type default)
		)
		(layer "F.Cu")
	)
	(gr_line
		(start 311.95264 -143.504666)
		(end 311.63387 -143.185896)
		(stroke
			(width 0.06731)
			(type default)
		)
		(layer "F.Cu")
	)
	(gr_line
		(start 312.809636 -143.18107)
		(end 312.48604 -143.504666)
		(stroke
			(width 0.06731)
			(type default)
		)
		(layer "F.Cu")
	)
	(gr_line
		(start 313.732164 -143.479266)
		(end 313.433968 -143.18107)
		(stroke
			(width 0.06731)
			(type default)
		)
		(layer "F.Cu")
	)
	(gr_line
		(start 317.70447 -30.628336)
		(end 317.410338 -30.922468)
		(stroke
			(width 0.06731)
			(type default)
		)
		(layer "F.Cu")
	)
	(gr_line
		(start 317.70447 -30.353)
		(end 317.410338 -30.058868)
		(stroke
			(width 0.06731)
			(type default)
		)
		(layer "F.Cu")
	)
	(gr_line
		(start 317.705486 -30.353)
		(end 317.70447 -30.353)
		(stroke
			(width 0.06731)
			(type default)
		)
		(layer "F.Cu")
	)
	(gr_line
		(start 320.224404 -30.353)
		(end 320.219324 -30.353)
		(stroke
			(width 0.06731)
			(type default)
		)
		(layer "F.Cu")
	)
	(gr_line
		(start 320.382138 -30.790134)
		(end 320.220594 -30.62859)
		(stroke
			(width 0.06731)
			(type default)
		)
		(layer "F.Cu")
	)
	(gr_line
		(start 320.387218 -30.190186)
		(end 320.224404 -30.353)
		(stroke
			(width 0.06731)
			(type default)
		)
		(layer "F.Cu")
	)
	(gr_line
		(start 320.864738 -30.790134)
		(end 320.382138 -30.790134)
		(stroke
			(width 0.06731)
			(type default)
		)
		(layer "F.Cu")
	)
	(gr_line
		(start 320.864738 -30.190186)
		(end 320.387218 -30.190186)
		(stroke
			(width 0.06731)
			(type default)
		)
		(layer "F.Cu")
	)
	(gr_line
		(start 325.954644 -26.58999)
		(end 325.464678 -26.58999)
		(stroke
			(width 0.06731)
			(type default)
		)
		(layer "F.Cu")
	)
	(gr_line
		(start 325.96836 -27.189938)
		(end 325.464678 -27.189938)
		(stroke
			(width 0.06731)
			(type default)
		)
		(layer "F.Cu")
	)
	(gr_line
		(start 326.112378 -27.04592)
		(end 325.96836 -27.189938)
		(stroke
			(width 0.06731)
			(type default)
		)
		(layer "F.Cu")
	)
	(gr_line
		(start 326.134984 -26.77033)
		(end 325.954644 -26.58999)
		(stroke
			(width 0.06731)
			(type default)
		)
		(layer "F.Cu")
	)
	(gr_line
		(start 326.136254 -27.04592)
		(end 326.112378 -27.04592)
		(stroke
			(width 0.06731)
			(type default)
		)
		(layer "F.Cu")
	)
	(gr_line
		(start 326.888856 -26.7716)
		(end 326.884284 -26.7716)
		(stroke
			(width 0.06731)
			(type default)
		)
		(layer "F.Cu")
	)
	(gr_line
		(start 327.18121 -27.342846)
		(end 326.885554 -27.04719)
		(stroke
			(width 0.06731)
			(type default)
		)
		(layer "F.Cu")
	)
	(gr_line
		(start 327.18121 -26.479246)
		(end 326.888856 -26.7716)
		(stroke
			(width 0.06731)
			(type default)
		)
		(layer "F.Cu")
	)
	(gr_line
		(start 330.935584 -87.324438)
		(end 331.223874 -87.036148)
		(stroke
			(width 0.06731)
			(type default)
		)
		(layer "F.Cu")
	)
	(gr_line
		(start 331.223874 -87.036148)
		(end 331.236574 -87.036148)
		(stroke
			(width 0.06731)
			(type default)
		)
		(layer "F.Cu")
	)
	(gr_line
		(start 334.64881 -87.707724)
		(end 334.662526 -87.707724)
		(stroke
			(width 0.06731)
			(type default)
		)
		(layer "F.Cu")
	)
	(gr_line
		(start 334.662526 -87.707724)
		(end 334.719168 -87.764366)
		(stroke
			(width 0.06731)
			(type default)
		)
		(layer "F.Cu")
	)
	(gr_line
		(start 334.719168 -87.764366)
		(end 335.145634 -87.764366)
		(stroke
			(width 0.06731)
			(type default)
		)
		(layer "F.Cu")
	)
	(gr_line
		(start 334.838548 -80.207612)
		(end 335.153 -79.89316)
		(stroke
			(width 0.06731)
			(type default)
		)
		(layer "F.Cu")
	)
	(gr_line
		(start 335.152238 -81.334102)
		(end 335.152238 -81.321402)
		(stroke
			(width 0.06731)
			(type default)
		)
		(layer "F.Cu")
	)
	(gr_line
		(start 335.152238 -81.321402)
		(end 334.838548 -81.007712)
		(stroke
			(width 0.06731)
			(type default)
		)
		(layer "F.Cu")
	)
	(gr_line
		(start 335.153 -79.89316)
		(end 335.153 -79.881984)
		(stroke
			(width 0.06731)
			(type default)
		)
		(layer "F.Cu")
	)
	(gr_line
		(start 335.153 -79.182976)
		(end 335.153 -79.1718)
		(stroke
			(width 0.06731)
			(type default)
		)
		(layer "F.Cu")
	)
	(gr_line
		(start 335.153 -79.1718)
		(end 334.863948 -78.882748)
		(stroke
			(width 0.06731)
			(type default)
		)
		(layer "F.Cu")
	)
	(gr_line
		(start 335.427828 -81.332832)
		(end 335.752948 -81.007712)
		(stroke
			(width 0.06731)
			(type default)
		)
		(layer "F.Cu")
	)
	(gr_line
		(start 335.42859 -79.181706)
		(end 335.727548 -78.882748)
		(stroke
			(width 0.06731)
			(type default)
		)
		(layer "F.Cu")
	)
	(gr_line
		(start 335.752948 -80.207612)
		(end 335.42859 -79.883254)
		(stroke
			(width 0.06731)
			(type default)
		)
		(layer "F.Cu")
	)
	(gr_line
		(start 335.895696 -83.814412)
		(end 335.895696 -83.387692)
		(stroke
			(width 0.06731)
			(type default)
		)
		(layer "F.Cu")
	)
	(gr_line
		(start 335.895696 -83.387692)
		(end 335.952084 -83.331304)
		(stroke
			(width 0.06731)
			(type default)
		)
		(layer "F.Cu")
	)
	(gr_line
		(start 335.952084 -83.331304)
		(end 335.952084 -83.317588)
		(stroke
			(width 0.06731)
			(type default)
		)
		(layer "F.Cu")
	)
	(gr_line
		(start 336.295492 -83.814412)
		(end 336.295492 -83.386676)
		(stroke
			(width 0.06731)
			(type default)
		)
		(layer "F.Cu")
	)
	(gr_line
		(start 336.295492 -83.386676)
		(end 336.227674 -83.318858)
		(stroke
			(width 0.06731)
			(type default)
		)
		(layer "F.Cu")
	)
	(gr_line
		(start 336.838544 -80.207612)
		(end 337.15833 -79.887826)
		(stroke
			(width 0.06731)
			(type default)
		)
		(layer "F.Cu")
	)
	(gr_line
		(start 337.095592 -83.814412)
		(end 337.095592 -83.387946)
		(stroke
			(width 0.06731)
			(type default)
		)
		(layer "F.Cu")
	)
	(gr_line
		(start 337.095592 -83.387946)
		(end 337.16341 -83.320128)
		(stroke
			(width 0.06731)
			(type default)
		)
		(layer "F.Cu")
	)
	(gr_line
		(start 337.15833 -78.415134)
		(end 336.863944 -78.120748)
		(stroke
			(width 0.06731)
			(type default)
		)
		(layer "F.Cu")
	)
	(gr_line
		(start 337.16341 -81.332578)
		(end 336.838544 -81.007712)
		(stroke
			(width 0.06731)
			(type default)
		)
		(layer "F.Cu")
	)
	(gr_line
		(start 337.43392 -79.888588)
		(end 337.43392 -79.886556)
		(stroke
			(width 0.06731)
			(type default)
		)
		(layer "F.Cu")
	)
	(gr_line
		(start 337.43392 -78.416404)
		(end 337.43392 -78.414372)
		(stroke
			(width 0.06731)
			(type default)
		)
		(layer "F.Cu")
	)
	(gr_line
		(start 337.43392 -78.414372)
		(end 337.727544 -78.120748)
		(stroke
			(width 0.06731)
			(type default)
		)
		(layer "F.Cu")
	)
	(gr_line
		(start 337.439 -83.330034)
		(end 337.439 -83.318858)
		(stroke
			(width 0.06731)
			(type default)
		)
		(layer "F.Cu")
	)
	(gr_line
		(start 337.439 -81.333848)
		(end 337.439 -81.321656)
		(stroke
			(width 0.06731)
			(type default)
		)
		(layer "F.Cu")
	)
	(gr_line
		(start 337.439 -81.321656)
		(end 337.752944 -81.007712)
		(stroke
			(width 0.06731)
			(type default)
		)
		(layer "F.Cu")
	)
	(gr_line
		(start 337.495642 -83.814412)
		(end 337.495642 -83.386676)
		(stroke
			(width 0.06731)
			(type default)
		)
		(layer "F.Cu")
	)
	(gr_line
		(start 337.495642 -83.386676)
		(end 337.439 -83.330034)
		(stroke
			(width 0.06731)
			(type default)
		)
		(layer "F.Cu")
	)
	(gr_line
		(start 337.752944 -80.207612)
		(end 337.43392 -79.888588)
		(stroke
			(width 0.06731)
			(type default)
		)
		(layer "F.Cu")
	)
	(gr_line
		(start 338.838286 -93.51899)
		(end 339.16493 -93.845634)
		(stroke
			(width 0.06731)
			(type default)
		)
		(layer "F.Cu")
	)
	(gr_line
		(start 339.095588 -90.14206)
		(end 339.16493 -90.211402)
		(stroke
			(width 0.06731)
			(type default)
		)
		(layer "F.Cu")
	)
	(gr_line
		(start 339.095588 -89.714324)
		(end 339.095588 -90.14206)
		(stroke
			(width 0.06731)
			(type default)
		)
		(layer "F.Cu")
	)
	(gr_line
		(start 339.16493 -94.54261)
		(end 338.863686 -94.843854)
		(stroke
			(width 0.06731)
			(type default)
		)
		(layer "F.Cu")
	)
	(gr_line
		(start 339.16493 -92.392246)
		(end 338.838286 -92.71889)
		(stroke
			(width 0.06731)
			(type default)
		)
		(layer "F.Cu")
	)
	(gr_line
		(start 339.44052 -94.557088)
		(end 339.727286 -94.843854)
		(stroke
			(width 0.06731)
			(type default)
		)
		(layer "F.Cu")
	)
	(gr_line
		(start 339.44052 -94.54134)
		(end 339.44052 -94.557088)
		(stroke
			(width 0.06731)
			(type default)
		)
		(layer "F.Cu")
	)
	(gr_line
		(start 339.44052 -93.831156)
		(end 339.44052 -93.846904)
		(stroke
			(width 0.06731)
			(type default)
		)
		(layer "F.Cu")
	)
	(gr_line
		(start 339.44052 -92.406724)
		(end 339.752686 -92.71889)
		(stroke
			(width 0.06731)
			(type default)
		)
		(layer "F.Cu")
	)
	(gr_line
		(start 339.44052 -92.390976)
		(end 339.44052 -92.406724)
		(stroke
			(width 0.06731)
			(type default)
		)
		(layer "F.Cu")
	)
	(gr_line
		(start 339.44052 -90.195908)
		(end 339.44052 -90.212672)
		(stroke
			(width 0.06731)
			(type default)
		)
		(layer "F.Cu")
	)
	(gr_line
		(start 339.495638 -90.14079)
		(end 339.44052 -90.195908)
		(stroke
			(width 0.06731)
			(type default)
		)
		(layer "F.Cu")
	)
	(gr_line
		(start 339.495638 -89.714324)
		(end 339.495638 -90.14079)
		(stroke
			(width 0.06731)
			(type default)
		)
		(layer "F.Cu")
	)
	(gr_line
		(start 339.752686 -93.51899)
		(end 339.44052 -93.831156)
		(stroke
			(width 0.06731)
			(type default)
		)
		(layer "F.Cu")
	)
	(gr_line
		(start 341.045546 -88.564466)
		(end 341.472266 -88.564466)
		(stroke
			(width 0.06731)
			(type default)
		)
		(layer "F.Cu")
	)
	(gr_line
		(start 341.045546 -87.364316)
		(end 341.472012 -87.364316)
		(stroke
			(width 0.06731)
			(type default)
		)
		(layer "F.Cu")
	)
	(gr_line
		(start 341.045546 -85.76437)
		(end 341.472012 -85.76437)
		(stroke
			(width 0.06731)
			(type default)
		)
		(layer "F.Cu")
	)
	(gr_line
		(start 341.045546 -84.96427)
		(end 341.473282 -84.96427)
		(stroke
			(width 0.06731)
			(type default)
		)
		(layer "F.Cu")
	)
	(gr_line
		(start 341.045546 -84.564474)
		(end 341.472266 -84.564474)
		(stroke
			(width 0.06731)
			(type default)
		)
		(layer "F.Cu")
	)
	(gr_line
		(start 341.472012 -87.364316)
		(end 341.540084 -87.432388)
		(stroke
			(width 0.06731)
			(type default)
		)
		(layer "F.Cu")
	)
	(gr_line
		(start 341.472012 -85.76437)
		(end 341.540084 -85.832442)
		(stroke
			(width 0.06731)
			(type default)
		)
		(layer "F.Cu")
	)
	(gr_line
		(start 341.472266 -88.564466)
		(end 341.540084 -88.632284)
		(stroke
			(width 0.06731)
			(type default)
		)
		(layer "F.Cu")
	)
	(gr_line
		(start 341.472266 -84.564474)
		(end 341.528654 -84.620862)
		(stroke
			(width 0.06731)
			(type default)
		)
		(layer "F.Cu")
	)
	(gr_line
		(start 341.473282 -84.96427)
		(end 341.5411 -84.896452)
		(stroke
			(width 0.06731)
			(type default)
		)
		(layer "F.Cu")
	)
	(gr_line
		(start 341.528654 -84.620862)
		(end 341.54237 -84.620862)
		(stroke
			(width 0.06731)
			(type default)
		)
		(layer "F.Cu")
	)
	(gr_line
		(start 343.886536 -83.569048)
		(end 343.899236 -83.569048)
		(stroke
			(width 0.06731)
			(type default)
		)
		(layer "F.Cu")
	)
	(gr_line
		(start 343.887806 -89.580466)
		(end 344.212926 -89.255346)
		(stroke
			(width 0.06731)
			(type default)
		)
		(layer "F.Cu")
	)
	(gr_line
		(start 343.887806 -85.580474)
		(end 344.212926 -85.255354)
		(stroke
			(width 0.06731)
			(type default)
		)
		(layer "F.Cu")
	)
	(gr_line
		(start 343.887806 -83.844638)
		(end 344.212926 -84.169758)
		(stroke
			(width 0.06731)
			(type default)
		)
		(layer "F.Cu")
	)
	(gr_line
		(start 343.892378 -87.575898)
		(end 344.212926 -87.25535)
		(stroke
			(width 0.06731)
			(type default)
		)
		(layer "F.Cu")
	)
	(gr_line
		(start 343.899236 -83.569048)
		(end 344.212926 -83.255358)
		(stroke
			(width 0.06731)
			(type default)
		)
		(layer "F.Cu")
	)
	(gr_line
		(start 345.013026 -89.255346)
		(end 345.34221 -89.58453)
		(stroke
			(width 0.06731)
			(type default)
		)
		(layer "F.Cu")
	)
	(gr_line
		(start 345.013026 -87.25535)
		(end 345.326716 -87.56904)
		(stroke
			(width 0.06731)
			(type default)
		)
		(layer "F.Cu")
	)
	(gr_line
		(start 345.013026 -85.255354)
		(end 345.334082 -85.57641)
		(stroke
			(width 0.06731)
			(type default)
		)
		(layer "F.Cu")
	)
	(gr_line
		(start 345.013026 -84.169758)
		(end 345.336114 -83.84667)
		(stroke
			(width 0.06731)
			(type default)
		)
		(layer "F.Cu")
	)
	(gr_line
		(start 345.013026 -83.255358)
		(end 345.328748 -83.57108)
		(stroke
			(width 0.06731)
			(type default)
		)
		(layer "F.Cu")
	)
	(gr_line
		(start 345.326716 -87.56904)
		(end 345.339416 -87.56904)
		(stroke
			(width 0.06731)
			(type default)
		)
		(layer "F.Cu")
	)
	(gr_line
		(start 345.328748 -83.57108)
		(end 345.337384 -83.57108)
		(stroke
			(width 0.06731)
			(type default)
		)
		(layer "F.Cu")
	)
	(gr_line
		(start 346.0369 -87.56904)
		(end 346.0496 -87.56904)
		(stroke
			(width 0.06731)
			(type default)
		)
		(layer "F.Cu")
	)
	(gr_line
		(start 346.038932 -83.57108)
		(end 346.047568 -83.57108)
		(stroke
			(width 0.06731)
			(type default)
		)
		(layer "F.Cu")
	)
	(gr_line
		(start 346.040202 -83.84667)
		(end 346.33789 -84.144358)
		(stroke
			(width 0.06731)
			(type default)
		)
		(layer "F.Cu")
	)
	(gr_line
		(start 346.047568 -83.57108)
		(end 346.33789 -83.280758)
		(stroke
			(width 0.06731)
			(type default)
		)
		(layer "F.Cu")
	)
	(gr_line
		(start 346.0496 -87.56904)
		(end 346.33789 -87.28075)
		(stroke
			(width 0.06731)
			(type default)
		)
		(layer "F.Cu")
	)
	(gr_line
		(start 346.796106 -89.58453)
		(end 347.09989 -89.280746)
		(stroke
			(width 0.06731)
			(type default)
		)
		(layer "F.Cu")
	)
	(gr_line
		(start 346.804234 -85.57641)
		(end 347.09989 -85.280754)
		(stroke
			(width 0.06731)
			(type default)
		)
		(layer "F.Cu")
	)
	(gr_line
		(start 355.804724 -30.628336)
		(end 355.510592 -30.922468)
		(stroke
			(width 0.06731)
			(type default)
		)
		(layer "F.Cu")
	)
	(gr_line
		(start 357.669592 -28.81757)
		(end 357.364792 -29.12237)
		(stroke
			(width 0.06731)
			(type default)
		)
		(layer "F.Cu")
	)
	(gr_line
		(start 358.482392 -30.790134)
		(end 358.320848 -30.62859)
		(stroke
			(width 0.06731)
			(type default)
		)
		(layer "F.Cu")
	)
	(gr_line
		(start 358.485948 -28.99029)
		(end 358.313228 -28.81757)
		(stroke
			(width 0.06731)
			(type default)
		)
		(layer "F.Cu")
	)
	(gr_line
		(start 358.964992 -30.790134)
		(end 358.482392 -30.790134)
		(stroke
			(width 0.06731)
			(type default)
		)
		(layer "F.Cu")
	)
	(gr_line
		(start 358.964992 -28.99029)
		(end 358.485948 -28.99029)
		(stroke
			(width 0.06731)
			(type default)
		)
		(layer "F.Cu")
	)
	(gr_line
		(start 358.964992 -28.990036)
		(end 358.964992 -28.99029)
		(stroke
			(width 0.06731)
			(type default)
		)
		(layer "F.Cu")
	)
	(gr_line
		(start 364.068614 -27.189938)
		(end 363.564932 -27.189938)
		(stroke
			(width 0.06731)
			(type default)
		)
		(layer "F.Cu")
	)
	(gr_line
		(start 364.231682 -27.02687)
		(end 364.068614 -27.189938)
		(stroke
			(width 0.06731)
			(type default)
		)
		(layer "F.Cu")
	)
	(gr_line
		(start 365.281464 -27.342846)
		(end 364.965488 -27.02687)
		(stroke
			(width 0.06731)
			(type default)
		)
		(layer "F.Cu")
	)
	(gr_line
		(start 381.81026 -34.22269)
		(end 381.51054 -34.52241)
		(stroke
			(width 0.06731)
			(type default)
		)
		(layer "F.Cu")
	)
	(gr_line
		(start 383.4257 -120.087898)
		(end 383.725928 -119.78767)
		(stroke
			(width 0.06731)
			(type default)
		)
		(layer "F.Cu")
	)
	(gr_line
		(start 383.4257 -112.784382)
		(end 383.713482 -112.4966)
		(stroke
			(width 0.06731)
			(type default)
		)
		(layer "F.Cu")
	)
	(gr_line
		(start 383.4257 -111.920782)
		(end 383.725928 -112.22101)
		(stroke
			(width 0.06731)
			(type default)
		)
		(layer "F.Cu")
	)
	(gr_line
		(start 383.4257 -109.18444)
		(end 383.72034 -108.8898)
		(stroke
			(width 0.06731)
			(type default)
		)
		(layer "F.Cu")
	)
	(gr_line
		(start 383.4257 -108.32084)
		(end 383.72034 -108.61548)
		(stroke
			(width 0.06731)
			(type default)
		)
		(layer "F.Cu")
	)
	(gr_line
		(start 383.4257 -105.584498)
		(end 383.725928 -105.28427)
		(stroke
			(width 0.06731)
			(type default)
		)
		(layer "F.Cu")
	)
	(gr_line
		(start 383.4257 -104.720898)
		(end 383.713482 -105.00868)
		(stroke
			(width 0.06731)
			(type default)
		)
		(layer "F.Cu")
	)
	(gr_line
		(start 383.673858 -230.873554)
		(end 383.968498 -231.168194)
		(stroke
			(width 0.06731)
			(type default)
		)
		(layer "F.Cu")
	)
	(gr_line
		(start 383.713482 -112.4966)
		(end 383.727198 -112.4966)
		(stroke
			(width 0.06731)
			(type default)
		)
		(layer "F.Cu")
	)
	(gr_line
		(start 383.713482 -105.00868)
		(end 383.727198 -105.00868)
		(stroke
			(width 0.06731)
			(type default)
		)
		(layer "F.Cu")
	)
	(gr_line
		(start 383.855468 -232.239058)
		(end 383.855468 -232.836212)
		(stroke
			(width 0.06731)
			(type default)
		)
		(layer "F.Cu")
	)
	(gr_line
		(start 383.968244 -232.126282)
		(end 383.855468 -232.239058)
		(stroke
			(width 0.06731)
			(type default)
		)
		(layer "F.Cu")
	)
	(gr_line
		(start 383.968498 -231.168194)
		(end 383.968244 -231.168448)
		(stroke
			(width 0.06731)
			(type default)
		)
		(layer "F.Cu")
	)
	(gr_line
		(start 384.0353 -101.984302)
		(end 384.342132 -101.67747)
		(stroke
			(width 0.06731)
			(type default)
		)
		(layer "F.Cu")
	)
	(gr_line
		(start 384.0353 -101.120702)
		(end 384.316478 -101.40188)
		(stroke
			(width 0.06731)
			(type default)
		)
		(layer "F.Cu")
	)
	(gr_line
		(start 384.242564 -232.126282)
		(end 384.355594 -232.239312)
		(stroke
			(width 0.06731)
			(type default)
		)
		(layer "F.Cu")
	)
	(gr_line
		(start 384.316478 -101.40188)
		(end 384.343402 -101.40188)
		(stroke
			(width 0.06731)
			(type default)
		)
		(layer "F.Cu")
	)
	(gr_line
		(start 384.344926 -112.4966)
		(end 384.358642 -112.4966)
		(stroke
			(width 0.06731)
			(type default)
		)
		(layer "F.Cu")
	)
	(gr_line
		(start 384.344926 -105.00868)
		(end 384.358642 -105.00868)
		(stroke
			(width 0.06731)
			(type default)
		)
		(layer "F.Cu")
	)
	(gr_line
		(start 384.346196 -119.78767)
		(end 384.671824 -120.113298)
		(stroke
			(width 0.06731)
			(type default)
		)
		(layer "F.Cu")
	)
	(gr_line
		(start 384.346196 -112.22101)
		(end 384.671824 -111.895382)
		(stroke
			(width 0.06731)
			(type default)
		)
		(layer "F.Cu")
	)
	(gr_line
		(start 384.346196 -105.28427)
		(end 384.671824 -105.609898)
		(stroke
			(width 0.06731)
			(type default)
		)
		(layer "F.Cu")
	)
	(gr_line
		(start 384.351784 -108.8898)
		(end 384.671824 -109.20984)
		(stroke
			(width 0.06731)
			(type default)
		)
		(layer "F.Cu")
	)
	(gr_line
		(start 384.351784 -108.61548)
		(end 384.671824 -108.29544)
		(stroke
			(width 0.06731)
			(type default)
		)
		(layer "F.Cu")
	)
	(gr_line
		(start 384.355594 -232.239312)
		(end 384.355594 -232.836212)
		(stroke
			(width 0.06731)
			(type default)
		)
		(layer "F.Cu")
	)
	(gr_line
		(start 384.358642 -112.4966)
		(end 384.671824 -112.809782)
		(stroke
			(width 0.06731)
			(type default)
		)
		(layer "F.Cu")
	)
	(gr_line
		(start 384.358642 -105.00868)
		(end 384.671824 -104.695498)
		(stroke
			(width 0.06731)
			(type default)
		)
		(layer "F.Cu")
	)
	(gr_line
		(start 384.48234 -34.390076)
		(end 384.314954 -34.22269)
		(stroke
			(width 0.06731)
			(type default)
		)
		(layer "F.Cu")
	)
	(gr_line
		(start 384.537458 -230.873554)
		(end 384.242564 -231.168448)
		(stroke
			(width 0.06731)
			(type default)
		)
		(layer "F.Cu")
	)
	(gr_line
		(start 384.674618 -299.224954)
		(end 385.149598 -299.699934)
		(stroke
			(width 0.05715)
			(type default)
		)
		(layer "F.Cu")
	)
	(gr_line
		(start 384.674618 -297.32478)
		(end 385.149598 -297.79976)
		(stroke
			(width 0.05715)
			(type default)
		)
		(layer "F.Cu")
	)
	(gr_line
		(start 384.947922 -101.40188)
		(end 384.974846 -101.40188)
		(stroke
			(width 0.06731)
			(type default)
		)
		(layer "F.Cu")
	)
	(gr_line
		(start 384.949192 -101.67747)
		(end 385.281424 -102.009702)
		(stroke
			(width 0.06731)
			(type default)
		)
		(layer "F.Cu")
	)
	(gr_line
		(start 384.96494 -34.390076)
		(end 384.48234 -34.390076)
		(stroke
			(width 0.06731)
			(type default)
		)
		(layer "F.Cu")
	)
	(gr_line
		(start 384.974846 -101.40188)
		(end 385.281424 -101.095302)
		(stroke
			(width 0.06731)
			(type default)
		)
		(layer "F.Cu")
	)
	(gr_line
		(start 385.149852 -299.699934)
		(end 385.149598 -299.699934)
		(stroke
			(width 0.05715)
			(type default)
		)
		(layer "F.Cu")
	)
	(gr_line
		(start 385.149852 -297.79976)
		(end 385.149598 -297.79976)
		(stroke
			(width 0.05715)
			(type default)
		)
		(layer "F.Cu")
	)
	(gr_line
		(start 385.205224 -120.113298)
		(end 385.530852 -119.78767)
		(stroke
			(width 0.06731)
			(type default)
		)
		(layer "F.Cu")
	)
	(gr_line
		(start 385.205224 -112.809782)
		(end 385.542536 -112.47247)
		(stroke
			(width 0.06731)
			(type default)
		)
		(layer "F.Cu")
	)
	(gr_line
		(start 385.205224 -111.895382)
		(end 385.506722 -112.19688)
		(stroke
			(width 0.06731)
			(type default)
		)
		(layer "F.Cu")
	)
	(gr_line
		(start 385.205224 -109.20984)
		(end 385.525264 -108.8898)
		(stroke
			(width 0.06731)
			(type default)
		)
		(layer "F.Cu")
	)
	(gr_line
		(start 385.205224 -108.29544)
		(end 385.525264 -108.61548)
		(stroke
			(width 0.06731)
			(type default)
		)
		(layer "F.Cu")
	)
	(gr_line
		(start 385.205224 -105.609898)
		(end 385.530852 -105.28427)
		(stroke
			(width 0.06731)
			(type default)
		)
		(layer "F.Cu")
	)
	(gr_line
		(start 385.205224 -104.695498)
		(end 385.518406 -105.00868)
		(stroke
			(width 0.06731)
			(type default)
		)
		(layer "F.Cu")
	)
	(gr_line
		(start 385.506722 -112.19688)
		(end 385.543806 -112.19688)
		(stroke
			(width 0.06731)
			(type default)
		)
		(layer "F.Cu")
	)
	(gr_line
		(start 385.518406 -105.00868)
		(end 385.532122 -105.00868)
		(stroke
			(width 0.06731)
			(type default)
		)
		(layer "F.Cu")
	)
	(gr_line
		(start 385.624578 -299.224954)
		(end 386.099558 -299.699934)
		(stroke
			(width 0.05715)
			(type default)
		)
		(layer "F.Cu")
	)
	(gr_line
		(start 385.814824 -102.009702)
		(end 386.147056 -101.67747)
		(stroke
			(width 0.06731)
			(type default)
		)
		(layer "F.Cu")
	)
	(gr_line
		(start 385.814824 -101.095302)
		(end 386.121402 -101.40188)
		(stroke
			(width 0.06731)
			(type default)
		)
		(layer "F.Cu")
	)
	(gr_line
		(start 386.067808 -136.704324)
		(end 386.348732 -136.4234)
		(stroke
			(width 0.06731)
			(type default)
		)
		(layer "F.Cu")
	)
	(gr_line
		(start 386.067808 -135.840724)
		(end 386.374894 -136.14781)
		(stroke
			(width 0.06731)
			(type default)
		)
		(layer "F.Cu")
	)
	(gr_line
		(start 386.067808 -133.104382)
		(end 386.35559 -132.8166)
		(stroke
			(width 0.06731)
			(type default)
		)
		(layer "F.Cu")
	)
	(gr_line
		(start 386.067808 -132.240782)
		(end 386.368036 -132.54101)
		(stroke
			(width 0.06731)
			(type default)
		)
		(layer "F.Cu")
	)
	(gr_line
		(start 386.067808 -125.494542)
		(end 386.36448 -125.19787)
		(stroke
			(width 0.06731)
			(type default)
		)
		(layer "F.Cu")
	)
	(gr_line
		(start 386.067808 -124.630942)
		(end 386.359146 -124.92228)
		(stroke
			(width 0.06731)
			(type default)
		)
		(layer "F.Cu")
	)
	(gr_line
		(start 386.067808 -121.894346)
		(end 386.371084 -121.59107)
		(stroke
			(width 0.06731)
			(type default)
		)
		(layer "F.Cu")
	)
	(gr_line
		(start 386.067808 -121.030746)
		(end 386.352542 -121.31548)
		(stroke
			(width 0.06731)
			(type default)
		)
		(layer "F.Cu")
	)
	(gr_line
		(start 386.067808 -110.977934)
		(end 386.352542 -110.6932)
		(stroke
			(width 0.06731)
			(type default)
		)
		(layer "F.Cu")
	)
	(gr_line
		(start 386.067808 -110.114334)
		(end 386.371084 -110.41761)
		(stroke
			(width 0.06731)
			(type default)
		)
		(layer "F.Cu")
	)
	(gr_line
		(start 386.067808 -100.177854)
		(end 386.371592 -99.87407)
		(stroke
			(width 0.06731)
			(type default)
		)
		(layer "F.Cu")
	)
	(gr_line
		(start 386.067808 -99.314254)
		(end 386.352034 -99.59848)
		(stroke
			(width 0.06731)
			(type default)
		)
		(layer "F.Cu")
	)
	(gr_line
		(start 386.099812 -299.699934)
		(end 386.099558 -299.699934)
		(stroke
			(width 0.05715)
			(type default)
		)
		(layer "F.Cu")
	)
	(gr_line
		(start 386.121402 -101.40188)
		(end 386.148326 -101.40188)
		(stroke
			(width 0.06731)
			(type default)
		)
		(layer "F.Cu")
	)
	(gr_line
		(start 386.348732 -136.4234)
		(end 386.376164 -136.4234)
		(stroke
			(width 0.06731)
			(type default)
		)
		(layer "F.Cu")
	)
	(gr_line
		(start 386.352034 -99.59848)
		(end 386.372862 -99.59848)
		(stroke
			(width 0.06731)
			(type default)
		)
		(layer "F.Cu")
	)
	(gr_line
		(start 386.352542 -121.31548)
		(end 386.372354 -121.31548)
		(stroke
			(width 0.06731)
			(type default)
		)
		(layer "F.Cu")
	)
	(gr_line
		(start 386.352542 -110.6932)
		(end 386.372354 -110.6932)
		(stroke
			(width 0.06731)
			(type default)
		)
		(layer "F.Cu")
	)
	(gr_line
		(start 386.35559 -132.8166)
		(end 386.369306 -132.8166)
		(stroke
			(width 0.06731)
			(type default)
		)
		(layer "F.Cu")
	)
	(gr_line
		(start 386.359146 -124.92228)
		(end 386.36575 -124.92228)
		(stroke
			(width 0.06731)
			(type default)
		)
		(layer "F.Cu")
	)
	(gr_line
		(start 386.980176 -136.4234)
		(end 387.007608 -136.4234)
		(stroke
			(width 0.06731)
			(type default)
		)
		(layer "F.Cu")
	)
	(gr_line
		(start 386.981446 -136.14781)
		(end 387.313932 -135.815324)
		(stroke
			(width 0.06731)
			(type default)
		)
		(layer "F.Cu")
	)
	(gr_line
		(start 386.983478 -99.59848)
		(end 387.004306 -99.59848)
		(stroke
			(width 0.06731)
			(type default)
		)
		(layer "F.Cu")
	)
	(gr_line
		(start 386.983986 -121.31548)
		(end 387.003798 -121.31548)
		(stroke
			(width 0.06731)
			(type default)
		)
		(layer "F.Cu")
	)
	(gr_line
		(start 386.983986 -110.6932)
		(end 387.003798 -110.6932)
		(stroke
			(width 0.06731)
			(type default)
		)
		(layer "F.Cu")
	)
	(gr_line
		(start 386.984748 -99.87407)
		(end 387.313932 -100.203254)
		(stroke
			(width 0.06731)
			(type default)
		)
		(layer "F.Cu")
	)
	(gr_line
		(start 386.985256 -121.59107)
		(end 387.313932 -121.919746)
		(stroke
			(width 0.06731)
			(type default)
		)
		(layer "F.Cu")
	)
	(gr_line
		(start 386.985256 -110.41761)
		(end 387.313932 -110.088934)
		(stroke
			(width 0.06731)
			(type default)
		)
		(layer "F.Cu")
	)
	(gr_line
		(start 386.987034 -132.8166)
		(end 387.00075 -132.8166)
		(stroke
			(width 0.06731)
			(type default)
		)
		(layer "F.Cu")
	)
	(gr_line
		(start 386.988304 -132.54101)
		(end 387.313932 -132.215382)
		(stroke
			(width 0.06731)
			(type default)
		)
		(layer "F.Cu")
	)
	(gr_line
		(start 386.99059 -124.92228)
		(end 386.997194 -124.92228)
		(stroke
			(width 0.06731)
			(type default)
		)
		(layer "F.Cu")
	)
	(gr_line
		(start 386.99186 -125.19787)
		(end 387.313932 -125.519942)
		(stroke
			(width 0.06731)
			(type default)
		)
		(layer "F.Cu")
	)
	(gr_line
		(start 386.997194 -124.92228)
		(end 387.313932 -124.605542)
		(stroke
			(width 0.06731)
			(type default)
		)
		(layer "F.Cu")
	)
	(gr_line
		(start 387.00075 -132.8166)
		(end 387.313932 -133.129782)
		(stroke
			(width 0.06731)
			(type default)
		)
		(layer "F.Cu")
	)
	(gr_line
		(start 387.003798 -121.31548)
		(end 387.313932 -121.005346)
		(stroke
			(width 0.06731)
			(type default)
		)
		(layer "F.Cu")
	)
	(gr_line
		(start 387.003798 -110.6932)
		(end 387.313932 -111.003334)
		(stroke
			(width 0.06731)
			(type default)
		)
		(layer "F.Cu")
	)
	(gr_line
		(start 387.004306 -99.59848)
		(end 387.313932 -99.288854)
		(stroke
			(width 0.06731)
			(type default)
		)
		(layer "F.Cu")
	)
	(gr_line
		(start 387.007608 -136.4234)
		(end 387.313932 -136.729724)
		(stroke
			(width 0.06731)
			(type default)
		)
		(layer "F.Cu")
	)
	(gr_line
		(start 387.847332 -136.729724)
		(end 388.182866 -136.39419)
		(stroke
			(width 0.06731)
			(type default)
		)
		(layer "F.Cu")
	)
	(gr_line
		(start 387.847332 -135.815324)
		(end 388.150608 -136.1186)
		(stroke
			(width 0.06731)
			(type default)
		)
		(layer "F.Cu")
	)
	(gr_line
		(start 387.847332 -133.129782)
		(end 388.184644 -132.79247)
		(stroke
			(width 0.06731)
			(type default)
		)
		(layer "F.Cu")
	)
	(gr_line
		(start 387.847332 -132.215382)
		(end 388.14883 -132.51688)
		(stroke
			(width 0.06731)
			(type default)
		)
		(layer "F.Cu")
	)
	(gr_line
		(start 387.847332 -125.519942)
		(end 388.169404 -125.19787)
		(stroke
			(width 0.06731)
			(type default)
		)
		(layer "F.Cu")
	)
	(gr_line
		(start 387.847332 -124.605542)
		(end 388.16407 -124.92228)
		(stroke
			(width 0.06731)
			(type default)
		)
		(layer "F.Cu")
	)
	(gr_line
		(start 387.847332 -121.919746)
		(end 388.176008 -121.59107)
		(stroke
			(width 0.06731)
			(type default)
		)
		(layer "F.Cu")
	)
	(gr_line
		(start 387.847332 -121.005346)
		(end 388.157466 -121.31548)
		(stroke
			(width 0.06731)
			(type default)
		)
		(layer "F.Cu")
	)
	(gr_line
		(start 387.847332 -111.003334)
		(end 388.162546 -110.68812)
		(stroke
			(width 0.06731)
			(type default)
		)
		(layer "F.Cu")
	)
	(gr_line
		(start 387.847332 -110.088934)
		(end 388.170928 -110.41253)
		(stroke
			(width 0.06731)
			(type default)
		)
		(layer "F.Cu")
	)
	(gr_line
		(start 387.847332 -100.203254)
		(end 388.176516 -99.87407)
		(stroke
			(width 0.06731)
			(type default)
		)
		(layer "F.Cu")
	)
	(gr_line
		(start 387.847332 -99.288854)
		(end 388.156958 -99.59848)
		(stroke
			(width 0.06731)
			(type default)
		)
		(layer "F.Cu")
	)
	(gr_line
		(start 388.14883 -132.51688)
		(end 388.185914 -132.51688)
		(stroke
			(width 0.06731)
			(type default)
		)
		(layer "F.Cu")
	)
	(gr_line
		(start 388.150608 -136.1186)
		(end 388.184136 -136.1186)
		(stroke
			(width 0.06731)
			(type default)
		)
		(layer "F.Cu")
	)
	(gr_line
		(start 388.156958 -99.59848)
		(end 388.177786 -99.59848)
		(stroke
			(width 0.06731)
			(type default)
		)
		(layer "F.Cu")
	)
	(gr_line
		(start 388.157466 -121.31548)
		(end 388.177278 -121.31548)
		(stroke
			(width 0.06731)
			(type default)
		)
		(layer "F.Cu")
	)
	(gr_line
		(start 388.162546 -110.68812)
		(end 388.172198 -110.68812)
		(stroke
			(width 0.06731)
			(type default)
		)
		(layer "F.Cu")
	)
	(gr_line
		(start 388.16407 -124.92228)
		(end 388.170674 -124.92228)
		(stroke
			(width 0.06731)
			(type default)
		)
		(layer "F.Cu")
	)
	(gr_line
		(start 390.068562 -27.189938)
		(end 389.56488 -27.189938)
		(stroke
			(width 0.06731)
			(type default)
		)
		(layer "F.Cu")
	)
	(gr_line
		(start 390.23163 -27.02687)
		(end 390.068562 -27.189938)
		(stroke
			(width 0.06731)
			(type default)
		)
		(layer "F.Cu")
	)
	(gr_line
		(start 391.281412 -27.342846)
		(end 390.965436 -27.02687)
		(stroke
			(width 0.06731)
			(type default)
		)
		(layer "F.Cu")
	)
	(gr_line
		(start 393.663424 -99.59848)
		(end 393.686284 -99.59848)
		(stroke
			(width 0.06731)
			(type default)
		)
		(layer "F.Cu")
	)
	(gr_line
		(start 393.664694 -99.87407)
		(end 393.835636 -100.045012)
		(stroke
			(width 0.06731)
			(type default)
		)
		(layer "F.Cu")
	)
	(gr_line
		(start 393.66571 -132.51688)
		(end 393.69111 -132.51688)
		(stroke
			(width 0.06731)
			(type default)
		)
		(layer "F.Cu")
	)
	(gr_line
		(start 393.66571 -112.19688)
		(end 393.69111 -112.19688)
		(stroke
			(width 0.06731)
			(type default)
		)
		(layer "F.Cu")
	)
	(gr_line
		(start 393.66571 -101.40188)
		(end 393.68603 -101.40188)
		(stroke
			(width 0.06731)
			(type default)
		)
		(layer "F.Cu")
	)
	(gr_line
		(start 393.66698 -132.79247)
		(end 393.839446 -132.964936)
		(stroke
			(width 0.06731)
			(type default)
		)
		(layer "F.Cu")
	)
	(gr_line
		(start 393.66698 -112.47247)
		(end 393.839446 -112.644936)
		(stroke
			(width 0.06731)
			(type default)
		)
		(layer "F.Cu")
	)
	(gr_line
		(start 393.66698 -101.67747)
		(end 393.83462 -101.84511)
		(stroke
			(width 0.06731)
			(type default)
		)
		(layer "F.Cu")
	)
	(gr_line
		(start 393.66825 -119.78767)
		(end 393.835636 -119.955056)
		(stroke
			(width 0.06731)
			(type default)
		)
		(layer "F.Cu")
	)
	(gr_line
		(start 393.671044 -110.68812)
		(end 393.678664 -110.68812)
		(stroke
			(width 0.06731)
			(type default)
		)
		(layer "F.Cu")
	)
	(gr_line
		(start 393.672314 -110.41253)
		(end 393.8397 -110.245144)
		(stroke
			(width 0.06731)
			(type default)
		)
		(layer "F.Cu")
	)
	(gr_line
		(start 393.672568 -108.8898)
		(end 393.684252 -108.8898)
		(stroke
			(width 0.06731)
			(type default)
		)
		(layer "F.Cu")
	)
	(gr_line
		(start 393.673838 -108.61421)
		(end 393.843002 -108.445046)
		(stroke
			(width 0.06731)
			(type default)
		)
		(layer "F.Cu")
	)
	(gr_line
		(start 393.674346 -121.31548)
		(end 393.682474 -121.31548)
		(stroke
			(width 0.06731)
			(type default)
		)
		(layer "F.Cu")
	)
	(gr_line
		(start 393.675616 -121.59107)
		(end 393.839446 -121.7549)
		(stroke
			(width 0.06731)
			(type default)
		)
		(layer "F.Cu")
	)
	(gr_line
		(start 393.67587 -125.1966)
		(end 393.68095 -125.1966)
		(stroke
			(width 0.06731)
			(type default)
		)
		(layer "F.Cu")
	)
	(gr_line
		(start 393.67714 -124.92101)
		(end 393.843002 -124.755148)
		(stroke
			(width 0.06731)
			(type default)
		)
		(layer "F.Cu")
	)
	(gr_line
		(start 393.677394 -105.00868)
		(end 393.679426 -105.00868)
		(stroke
			(width 0.06731)
			(type default)
		)
		(layer "F.Cu")
	)
	(gr_line
		(start 393.678664 -110.68812)
		(end 393.835636 -110.845092)
		(stroke
			(width 0.06731)
			(type default)
		)
		(layer "F.Cu")
	)
	(gr_line
		(start 393.678664 -105.28427)
		(end 393.839446 -105.445052)
		(stroke
			(width 0.06731)
			(type default)
		)
		(layer "F.Cu")
	)
	(gr_line
		(start 393.679426 -105.00868)
		(end 393.843002 -104.845104)
		(stroke
			(width 0.06731)
			(type default)
		)
		(layer "F.Cu")
	)
	(gr_line
		(start 393.68095 -125.1966)
		(end 393.839446 -125.355096)
		(stroke
			(width 0.06731)
			(type default)
		)
		(layer "F.Cu")
	)
	(gr_line
		(start 393.682474 -121.31548)
		(end 393.843002 -121.154952)
		(stroke
			(width 0.06731)
			(type default)
		)
		(layer "F.Cu")
	)
	(gr_line
		(start 393.684252 -108.8898)
		(end 393.839446 -109.044994)
		(stroke
			(width 0.06731)
			(type default)
		)
		(layer "F.Cu")
	)
	(gr_line
		(start 393.685776 -136.1186)
		(end 393.689332 -136.1186)
		(stroke
			(width 0.06731)
			(type default)
		)
		(layer "F.Cu")
	)
	(gr_line
		(start 393.68603 -101.40188)
		(end 393.843002 -101.244908)
		(stroke
			(width 0.06731)
			(type default)
		)
		(layer "F.Cu")
	)
	(gr_line
		(start 393.686284 -99.59848)
		(end 393.8397 -99.445064)
		(stroke
			(width 0.06731)
			(type default)
		)
		(layer "F.Cu")
	)
	(gr_line
		(start 393.687046 -136.39419)
		(end 393.857988 -136.565132)
		(stroke
			(width 0.06731)
			(type default)
		)
		(layer "F.Cu")
	)
	(gr_line
		(start 393.689332 -136.1186)
		(end 393.843002 -135.96493)
		(stroke
			(width 0.06731)
			(type default)
		)
		(layer "F.Cu")
	)
	(gr_line
		(start 393.69111 -132.51688)
		(end 393.843002 -132.364988)
		(stroke
			(width 0.06731)
			(type default)
		)
		(layer "F.Cu")
	)
	(gr_line
		(start 393.69111 -112.19688)
		(end 393.843002 -112.044988)
		(stroke
			(width 0.06731)
			(type default)
		)
		(layer "F.Cu")
	)
	(gr_line
		(start 393.83462 -101.84511)
		(end 394.342366 -101.84511)
		(stroke
			(width 0.06731)
			(type default)
		)
		(layer "F.Cu")
	)
	(gr_line
		(start 393.835636 -119.955056)
		(end 394.342366 -119.955056)
		(stroke
			(width 0.06731)
			(type default)
		)
		(layer "F.Cu")
	)
	(gr_line
		(start 393.835636 -110.845092)
		(end 394.342366 -110.845092)
		(stroke
			(width 0.06731)
			(type default)
		)
		(layer "F.Cu")
	)
	(gr_line
		(start 393.835636 -100.045012)
		(end 394.342366 -100.045012)
		(stroke
			(width 0.06731)
			(type default)
		)
		(layer "F.Cu")
	)
	(gr_line
		(start 393.839446 -132.964936)
		(end 394.342366 -132.964936)
		(stroke
			(width 0.06731)
			(type default)
		)
		(layer "F.Cu")
	)
	(gr_line
		(start 393.839446 -125.355096)
		(end 394.342366 -125.355096)
		(stroke
			(width 0.06731)
			(type default)
		)
		(layer "F.Cu")
	)
	(gr_line
		(start 393.839446 -121.7549)
		(end 394.342366 -121.7549)
		(stroke
			(width 0.06731)
			(type default)
		)
		(layer "F.Cu")
	)
	(gr_line
		(start 393.839446 -112.644936)
		(end 394.342366 -112.644936)
		(stroke
			(width 0.06731)
			(type default)
		)
		(layer "F.Cu")
	)
	(gr_line
		(start 393.839446 -109.044994)
		(end 394.342366 -109.044994)
		(stroke
			(width 0.06731)
			(type default)
		)
		(layer "F.Cu")
	)
	(gr_line
		(start 393.839446 -105.445052)
		(end 394.342366 -105.445052)
		(stroke
			(width 0.06731)
			(type default)
		)
		(layer "F.Cu")
	)
	(gr_line
		(start 393.8397 -110.245144)
		(end 394.342366 -110.245144)
		(stroke
			(width 0.06731)
			(type default)
		)
		(layer "F.Cu")
	)
	(gr_line
		(start 393.8397 -99.445064)
		(end 394.342366 -99.445064)
		(stroke
			(width 0.06731)
			(type default)
		)
		(layer "F.Cu")
	)
	(gr_line
		(start 393.843002 -135.96493)
		(end 394.342366 -135.96493)
		(stroke
			(width 0.06731)
			(type default)
		)
		(layer "F.Cu")
	)
	(gr_line
		(start 393.843002 -132.364988)
		(end 394.342366 -132.364988)
		(stroke
			(width 0.06731)
			(type default)
		)
		(layer "F.Cu")
	)
	(gr_line
		(start 393.843002 -124.755148)
		(end 394.342366 -124.755148)
		(stroke
			(width 0.06731)
			(type default)
		)
		(layer "F.Cu")
	)
	(gr_line
		(start 393.843002 -121.154952)
		(end 394.342366 -121.154952)
		(stroke
			(width 0.06731)
			(type default)
		)
		(layer "F.Cu")
	)
	(gr_line
		(start 393.843002 -112.044988)
		(end 394.342366 -112.044988)
		(stroke
			(width 0.06731)
			(type default)
		)
		(layer "F.Cu")
	)
	(gr_line
		(start 393.843002 -108.445046)
		(end 394.342366 -108.445046)
		(stroke
			(width 0.06731)
			(type default)
		)
		(layer "F.Cu")
	)
	(gr_line
		(start 393.843002 -104.845104)
		(end 394.342366 -104.845104)
		(stroke
			(width 0.06731)
			(type default)
		)
		(layer "F.Cu")
	)
	(gr_line
		(start 393.843002 -101.244908)
		(end 394.342366 -101.244908)
		(stroke
			(width 0.06731)
			(type default)
		)
		(layer "F.Cu")
	)
	(gr_line
		(start 393.857988 -136.565132)
		(end 394.342366 -136.565132)
		(stroke
			(width 0.06731)
			(type default)
		)
		(layer "F.Cu")
	)
	(gr_line
		(start 399.42008 -134.765034)
		(end 398.94256 -134.765034)
		(stroke
			(width 0.06731)
			(type default)
		)
		(layer "F.Cu")
	)
	(gr_line
		(start 399.577814 -134.6073)
		(end 399.42008 -134.765034)
		(stroke
			(width 0.06731)
			(type default)
		)
		(layer "F.Cu")
	)
	(gr_line
		(start 399.593054 -134.6073)
		(end 399.577814 -134.6073)
		(stroke
			(width 0.06731)
			(type default)
		)
		(layer "F.Cu")
	)
	(gr_line
		(start 402.107908 -134.6073)
		(end 402.096732 -134.6073)
		(stroke
			(width 0.06731)
			(type default)
		)
		(layer "F.Cu")
	)
	(gr_line
		(start 402.39696 -134.896352)
		(end 402.107908 -134.6073)
		(stroke
			(width 0.06731)
			(type default)
		)
		(layer "F.Cu")
	)
	(gr_line
		(start 407.800556 -30.6324)
		(end 407.510488 -30.922468)
		(stroke
			(width 0.06731)
			(type default)
		)
		(layer "F.Cu")
	)
	(gr_line
		(start 407.8097 -30.6324)
		(end 407.800556 -30.6324)
		(stroke
			(width 0.06731)
			(type default)
		)
		(layer "F.Cu")
	)
	(gr_line
		(start 410.324554 -30.6324)
		(end 410.319474 -30.6324)
		(stroke
			(width 0.06731)
			(type default)
		)
		(layer "F.Cu")
	)
	(gr_line
		(start 410.482288 -30.790134)
		(end 410.324554 -30.6324)
		(stroke
			(width 0.06731)
			(type default)
		)
		(layer "F.Cu")
	)
	(gr_line
		(start 410.964888 -30.790134)
		(end 410.482288 -30.790134)
		(stroke
			(width 0.06731)
			(type default)
		)
		(layer "F.Cu")
	)
	(gr_line
		(start 413.50311 -136.177274)
		(end 413.795464 -135.88492)
		(stroke
			(width 0.06731)
			(type default)
		)
		(layer "F.Cu")
	)
	(gr_line
		(start 413.50311 -135.313674)
		(end 413.798766 -135.60933)
		(stroke
			(width 0.06731)
			(type default)
		)
		(layer "F.Cu")
	)
	(gr_line
		(start 413.795464 -135.88492)
		(end 413.800036 -135.88492)
		(stroke
			(width 0.06731)
			(type default)
		)
		(layer "F.Cu")
	)
	(gr_line
		(start 413.797496 -121.07291)
		(end 413.50311 -121.367296)
		(stroke
			(width 0.06731)
			(type default)
		)
		(layer "F.Cu")
	)
	(gr_line
		(start 415.35731 -147.087336)
		(end 415.656776 -146.78787)
		(stroke
			(width 0.06731)
			(type default)
		)
		(layer "F.Cu")
	)
	(gr_line
		(start 416.06851 -27.189938)
		(end 415.564828 -27.189938)
		(stroke
			(width 0.06731)
			(type default)
		)
		(layer "F.Cu")
	)
	(gr_line
		(start 416.231578 -27.02687)
		(end 416.06851 -27.189938)
		(stroke
			(width 0.06731)
			(type default)
		)
		(layer "F.Cu")
	)
	(gr_line
		(start 416.31108 -146.78787)
		(end 416.478212 -146.955002)
		(stroke
			(width 0.06731)
			(type default)
		)
		(layer "F.Cu")
	)
	(gr_line
		(start 416.314382 -135.88492)
		(end 416.31489 -135.88492)
		(stroke
			(width 0.06731)
			(type default)
		)
		(layer "F.Cu")
	)
	(gr_line
		(start 416.31489 -135.88492)
		(end 416.47491 -136.04494)
		(stroke
			(width 0.06731)
			(type default)
		)
		(layer "F.Cu")
	)
	(gr_line
		(start 416.31489 -135.610092)
		(end 416.47999 -135.444992)
		(stroke
			(width 0.06731)
			(type default)
		)
		(layer "F.Cu")
	)
	(gr_line
		(start 416.47491 -136.04494)
		(end 416.95751 -136.04494)
		(stroke
			(width 0.06731)
			(type default)
		)
		(layer "F.Cu")
	)
	(gr_line
		(start 416.47491 -121.234962)
		(end 416.312858 -121.07291)
		(stroke
			(width 0.06731)
			(type default)
		)
		(layer "F.Cu")
	)
	(gr_line
		(start 416.478212 -146.955002)
		(end 416.95751 -146.955002)
		(stroke
			(width 0.06731)
			(type default)
		)
		(layer "F.Cu")
	)
	(gr_line
		(start 416.47999 -135.444992)
		(end 416.95751 -135.444992)
		(stroke
			(width 0.06731)
			(type default)
		)
		(layer "F.Cu")
	)
	(gr_line
		(start 416.95751 -121.234962)
		(end 416.47491 -121.234962)
		(stroke
			(width 0.06731)
			(type default)
		)
		(layer "F.Cu")
	)
	(gr_line
		(start 417.28136 -27.342846)
		(end 416.965384 -27.02687)
		(stroke
			(width 0.06731)
			(type default)
		)
		(layer "F.Cu")
	)
	(gr_line
		(start 422.020238 -117.035072)
		(end 421.557704 -117.035072)
		(stroke
			(width 0.06731)
			(type default)
		)
		(layer "F.Cu")
	)
	(gr_line
		(start 422.048178 -117.63502)
		(end 421.557704 -117.63502)
		(stroke
			(width 0.06731)
			(type default)
		)
		(layer "F.Cu")
	)
	(gr_line
		(start 422.057068 -143.35506)
		(end 421.557704 -143.35506)
		(stroke
			(width 0.06731)
			(type default)
		)
		(layer "F.Cu")
	)
	(gr_line
		(start 422.185846 -117.20068)
		(end 422.020238 -117.035072)
		(stroke
			(width 0.06731)
			(type default)
		)
		(layer "F.Cu")
	)
	(gr_line
		(start 422.206928 -117.47627)
		(end 422.048178 -117.63502)
		(stroke
			(width 0.06731)
			(type default)
		)
		(layer "F.Cu")
	)
	(gr_line
		(start 422.208198 -117.20068)
		(end 422.185846 -117.20068)
		(stroke
			(width 0.06731)
			(type default)
		)
		(layer "F.Cu")
	)
	(gr_line
		(start 422.231058 -143.18107)
		(end 422.057068 -143.35506)
		(stroke
			(width 0.06731)
			(type default)
		)
		(layer "F.Cu")
	)
	(gr_line
		(start 422.948862 -117.475)
		(end 422.927526 -117.475)
		(stroke
			(width 0.06731)
			(type default)
		)
		(layer "F.Cu")
	)
	(gr_line
		(start 423.232834 -117.758972)
		(end 422.948862 -117.475)
		(stroke
			(width 0.06731)
			(type default)
		)
		(layer "F.Cu")
	)
	(gr_line
		(start 423.232834 -116.895372)
		(end 422.928796 -117.19941)
		(stroke
			(width 0.06731)
			(type default)
		)
		(layer "F.Cu")
	)
	(gr_line
		(start 428.052738 -143.504666)
		(end 427.729142 -143.18107)
		(stroke
			(width 0.06731)
			(type default)
		)
		(layer "F.Cu")
	)
	(gr_line
		(start 428.909734 -143.18107)
		(end 428.586138 -143.504666)
		(stroke
			(width 0.06731)
			(type default)
		)
		(layer "F.Cu")
	)
	(gr_line
		(start 429.832262 -143.479266)
		(end 429.534066 -143.18107)
		(stroke
			(width 0.06731)
			(type default)
		)
		(layer "F.Cu")
	)
	(gr_line
		(start 433.804568 -30.628336)
		(end 433.510436 -30.922468)
		(stroke
			(width 0.06731)
			(type default)
		)
		(layer "F.Cu")
	)
	(gr_line
		(start 433.804568 -30.353)
		(end 433.510436 -30.058868)
		(stroke
			(width 0.06731)
			(type default)
		)
		(layer "F.Cu")
	)
	(gr_line
		(start 433.805584 -30.353)
		(end 433.804568 -30.353)
		(stroke
			(width 0.06731)
			(type default)
		)
		(layer "F.Cu")
	)
	(gr_line
		(start 436.324502 -30.353)
		(end 436.319422 -30.353)
		(stroke
			(width 0.06731)
			(type default)
		)
		(layer "F.Cu")
	)
	(gr_line
		(start 436.482236 -30.790134)
		(end 436.320692 -30.62859)
		(stroke
			(width 0.06731)
			(type default)
		)
		(layer "F.Cu")
	)
	(gr_line
		(start 436.487316 -30.190186)
		(end 436.324502 -30.353)
		(stroke
			(width 0.06731)
			(type default)
		)
		(layer "F.Cu")
	)
	(gr_line
		(start 436.964836 -30.790134)
		(end 436.482236 -30.790134)
		(stroke
			(width 0.06731)
			(type default)
		)
		(layer "F.Cu")
	)
	(gr_line
		(start 436.964836 -30.190186)
		(end 436.487316 -30.190186)
		(stroke
			(width 0.06731)
			(type default)
		)
		(layer "F.Cu")
	)
	(gr_line
		(start 442.054742 -26.58999)
		(end 441.564776 -26.58999)
		(stroke
			(width 0.06731)
			(type default)
		)
		(layer "F.Cu")
	)
	(gr_line
		(start 442.068458 -27.189938)
		(end 441.564776 -27.189938)
		(stroke
			(width 0.06731)
			(type default)
		)
		(layer "F.Cu")
	)
	(gr_line
		(start 442.216032 -26.75128)
		(end 442.054742 -26.58999)
		(stroke
			(width 0.06731)
			(type default)
		)
		(layer "F.Cu")
	)
	(gr_line
		(start 442.231526 -27.02687)
		(end 442.068458 -27.189938)
		(stroke
			(width 0.06731)
			(type default)
		)
		(layer "F.Cu")
	)
	(gr_line
		(start 442.232796 -26.75128)
		(end 442.216032 -26.75128)
		(stroke
			(width 0.06731)
			(type default)
		)
		(layer "F.Cu")
	)
	(gr_line
		(start 443.009274 -26.75128)
		(end 442.964062 -26.75128)
		(stroke
			(width 0.06731)
			(type default)
		)
		(layer "F.Cu")
	)
	(gr_line
		(start 443.281308 -27.342846)
		(end 442.965332 -27.02687)
		(stroke
			(width 0.06731)
			(type default)
		)
		(layer "F.Cu")
	)
	(gr_line
		(start 443.281308 -26.479246)
		(end 443.009274 -26.75128)
		(stroke
			(width 0.06731)
			(type default)
		)
		(layer "F.Cu")
	)
	(gr_line
		(start 448.773296 -234.331256)
		(end 448.478656 -234.625896)
		(stroke
			(width 0.06731)
			(type default)
		)
		(layer "F.Cu")
	)
	(gr_line
		(start 449.047616 -234.331256)
		(end 449.342256 -234.625896)
		(stroke
			(width 0.06731)
			(type default)
		)
		(layer "F.Cu")
	)
	(gr_line
		(start 449.12407 -232.224834)
		(end 449.236846 -232.33761)
		(stroke
			(width 0.06731)
			(type default)
		)
		(layer "F.Cu")
	)
	(gr_line
		(start 449.12407 -231.88168)
		(end 449.12407 -232.224834)
		(stroke
			(width 0.06731)
			(type default)
		)
		(layer "F.Cu")
	)
	(gr_line
		(start 449.623942 -232.224834)
		(end 449.511166 -232.33761)
		(stroke
			(width 0.06731)
			(type default)
		)
		(layer "F.Cu")
	)
	(gr_line
		(start 449.623942 -231.88168)
		(end 449.623942 -232.224834)
		(stroke
			(width 0.06731)
			(type default)
		)
		(layer "F.Cu")
	)
	(gr_poly
		(pts
			(xy 72.838564 -298.554902) (xy 72.838564 -293.183564) (xy 72.779636 -293.124636) (xy 72.052434 -293.124636)
			(xy 72.002396 -293.174674) (xy 72.002396 -298.527216) (xy 72.074786 -298.599606) (xy 72.79386 -298.599606)
		)
		(stroke
			(width 0)
			(type solid)
		)
		(fill yes)
		(layer "B.Cu")
		(net "P1V25_SERDES_VDDPLL_PEX0")
	)
	(gr_poly
		(pts
			(xy 105.275126 -81.406492) (xy 105.275126 -79.59852) (xy 105.177082 -79.500476) (xy 103.824024 -79.500476)
			(xy 103.703628 -79.620872) (xy 103.703628 -81.458816) (xy 103.741474 -81.496916) (xy 105.184702 -81.496916)
		)
		(stroke
			(width 0)
			(type solid)
		)
		(fill yes)
		(layer "B.Cu")
		(net "GND")
	)
	(gr_poly
		(pts
			(xy 108.232956 -238.798354) (xy 108.232956 -237.655354) (xy 108.105956 -237.528354) (xy 99.088956 -237.528354)
			(xy 98.961956 -237.655354) (xy 98.961956 -238.925354) (xy 99.088956 -239.052354) (xy 107.978956 -239.052354)
		)
		(stroke
			(width 0)
			(type solid)
		)
		(fill yes)
		(layer "B.Cu")
		(net "GND")
	)
	(gr_poly
		(pts
			(xy 111.133382 -397.222218) (xy 111.133382 -394.684758) (xy 110.883192 -394.434568) (xy 107.92587 -394.434568)
			(xy 107.69346 -394.666978) (xy 107.69346 -397.231108) (xy 107.890056 -397.427704) (xy 110.927896 -397.427704)
		)
		(stroke
			(width 0)
			(type solid)
		)
		(fill yes)
		(layer "B.Cu")
		(net "GND")
	)
	(gr_poly
		(pts
			(xy 137.729214 -204.507846) (xy 137.729214 -199.935846) (xy 137.602214 -199.808846) (xy 136.459214 -199.808846)
			(xy 136.205214 -200.062846) (xy 136.205214 -204.634846) (xy 136.332214 -204.761846) (xy 137.475214 -204.761846)
		)
		(stroke
			(width 0)
			(type solid)
		)
		(fill yes)
		(layer "B.Cu")
		(net "P3V3_CLI_VPHY")
	)
	(gr_poly
		(pts
			(xy 139.76985 -195.612512) (xy 139.76985 -192.564512) (xy 139.64285 -192.437512) (xy 135.95985 -192.437512)
			(xy 135.70585 -192.691512) (xy 135.70585 -195.485512) (xy 135.95985 -195.739512) (xy 139.64285 -195.739512)
		)
		(stroke
			(width 0)
			(type solid)
		)
		(fill yes)
		(layer "B.Cu")
		(net "GND")
	)
	(gr_poly
		(pts
			(xy 151.395684 -51.477926) (xy 151.395684 -49.78273) (xy 151.000968 -49.388014) (xy 148.170138 -49.388014)
			(xy 147.98929 -49.568862) (xy 147.98929 -51.41214) (xy 148.301964 -51.724814) (xy 151.148796 -51.724814)
		)
		(stroke
			(width 0)
			(type solid)
		)
		(fill yes)
		(layer "B.Cu")
		(net "P3V3_SSD5")
	)
	(gr_poly
		(pts
			(xy 177.395632 -51.477926) (xy 177.395632 -49.78273) (xy 177.000916 -49.388014) (xy 174.170086 -49.388014)
			(xy 173.989238 -49.568862) (xy 173.989238 -51.41214) (xy 174.301912 -51.724814) (xy 177.148744 -51.724814)
		)
		(stroke
			(width 0)
			(type solid)
		)
		(fill yes)
		(layer "B.Cu")
		(net "P3V3_SSD6")
	)
	(gr_poly
		(pts
			(xy 203.39558 -51.477926) (xy 203.39558 -49.78273) (xy 203.000864 -49.388014) (xy 200.170034 -49.388014)
			(xy 199.989186 -49.568862) (xy 199.989186 -51.41214) (xy 200.30186 -51.724814) (xy 203.148692 -51.724814)
		)
		(stroke
			(width 0)
			(type solid)
		)
		(fill yes)
		(layer "B.Cu")
		(net "P3V3_SSD7")
	)
	(gr_poly
		(pts
			(xy 241.664744 -47.71136) (xy 241.664744 -46.016164) (xy 241.270028 -45.621448) (xy 238.439198 -45.621448)
			(xy 238.25835 -45.802296) (xy 238.25835 -47.645574) (xy 238.571024 -47.958248) (xy 241.417856 -47.958248)
		)
		(stroke
			(width 0)
			(type solid)
		)
		(fill yes)
		(layer "B.Cu")
		(net "P3V3_SSD8")
	)
	(gr_poly
		(pts
			(xy 267.495528 -51.477926) (xy 267.495528 -49.78273) (xy 267.100812 -49.388014) (xy 264.269982 -49.388014)
			(xy 264.089134 -49.568862) (xy 264.089134 -51.41214) (xy 264.401808 -51.724814) (xy 267.24864 -51.724814)
		)
		(stroke
			(width 0)
			(type solid)
		)
		(fill yes)
		(layer "B.Cu")
		(net "P3V3_SSD9")
	)
	(gr_poly
		(pts
			(xy 293.495476 -51.477926) (xy 293.495476 -49.78273) (xy 293.10076 -49.388014) (xy 290.26993 -49.388014)
			(xy 290.089082 -49.568862) (xy 290.089082 -51.41214) (xy 290.401756 -51.724814) (xy 293.248588 -51.724814)
		)
		(stroke
			(width 0)
			(type solid)
		)
		(fill yes)
		(layer "B.Cu")
		(net "P3V3_SSD10")
	)
	(gr_poly
		(pts
			(xy 319.495424 -51.477926) (xy 319.495424 -49.78273) (xy 319.100708 -49.388014) (xy 316.269878 -49.388014)
			(xy 316.08903 -49.568862) (xy 316.08903 -51.41214) (xy 316.401704 -51.724814) (xy 319.248536 -51.724814)
		)
		(stroke
			(width 0)
			(type solid)
		)
		(fill yes)
		(layer "B.Cu")
		(net "P3V3_SSD11")
	)
	(gr_poly
		(pts
			(xy 357.595678 -51.477926) (xy 357.595678 -49.78273) (xy 357.200962 -49.388014) (xy 354.370132 -49.388014)
			(xy 354.189284 -49.568862) (xy 354.189284 -51.41214) (xy 354.501958 -51.724814) (xy 357.34879 -51.724814)
		)
		(stroke
			(width 0)
			(type solid)
		)
		(fill yes)
		(layer "B.Cu")
		(net "P3V3_SSD12")
	)
	(gr_poly
		(pts
			(xy 374.685306 -223.582992) (xy 374.685306 -221.229936) (xy 374.528334 -221.072964) (xy 373.165878 -221.072964)
			(xy 373.124476 -221.114366) (xy 373.124476 -223.609408) (xy 373.28856 -223.773492) (xy 374.494806 -223.773492)
		)
		(stroke
			(width 0)
			(type solid)
		)
		(fill yes)
		(layer "B.Cu")
		(net "P1V8_PEX")
	)
	(gr_poly
		(pts
			(xy 383.595626 -51.477926) (xy 383.595626 -50.306986) (xy 383.389886 -50.101246) (xy 380.460758 -50.101246)
			(xy 380.189232 -50.372772) (xy 380.189232 -51.41214) (xy 380.501906 -51.724814) (xy 383.348738 -51.724814)
		)
		(stroke
			(width 0)
			(type solid)
		)
		(fill yes)
		(layer "B.Cu")
		(net "P3V3_SSD13")
	)
	(gr_poly
		(pts
			(xy 409.595574 -51.477926) (xy 409.595574 -49.78273) (xy 409.200858 -49.388014) (xy 406.370028 -49.388014)
			(xy 406.18918 -49.568862) (xy 406.18918 -51.41214) (xy 406.501854 -51.724814) (xy 409.348686 -51.724814)
		)
		(stroke
			(width 0)
			(type solid)
		)
		(fill yes)
		(layer "B.Cu")
		(net "P3V3_SSD14")
	)
	(gr_poly
		(pts
			(xy 435.595522 -51.477926) (xy 435.595522 -49.78273) (xy 435.200806 -49.388014) (xy 432.369976 -49.388014)
			(xy 432.189128 -49.568862) (xy 432.189128 -51.41214) (xy 432.501802 -51.724814) (xy 435.348634 -51.724814)
		)
		(stroke
			(width 0)
			(type solid)
		)
		(fill yes)
		(layer "B.Cu")
		(net "P3V3_SSD15")
	)
	(gr_poly
		(pts
			(xy 24.5745 -223.67494) (xy 24.5745 -222.059246) (xy 24.432514 -221.91726) (xy 23.022814 -221.91726)
			(xy 22.8473 -222.092774) (xy 22.8473 -223.519238) (xy 23.052278 -223.724216) (xy 23.29434 -223.724216)
			(xy 24.525224 -223.724216)
		)
		(stroke
			(width 0)
			(type solid)
		)
		(fill yes)
		(layer "B.Cu")
		(net "GND")
	)
	(gr_poly
		(pts
			(xy 140.63726 -223.67494) (xy 140.63726 -222.059246) (xy 140.495274 -221.91726) (xy 139.085574 -221.91726)
			(xy 138.91006 -222.092774) (xy 138.91006 -223.519238) (xy 139.115038 -223.724216) (xy 139.3571 -223.724216)
			(xy 140.587984 -223.724216)
		)
		(stroke
			(width 0)
			(type solid)
		)
		(fill yes)
		(layer "B.Cu")
		(net "GND")
	)
	(gr_poly
		(pts
			(xy 256.737104 -223.67494) (xy 256.737104 -222.059246) (xy 256.595118 -221.91726) (xy 255.185418 -221.91726)
			(xy 255.009904 -222.092774) (xy 255.009904 -223.519238) (xy 255.214882 -223.724216) (xy 255.456944 -223.724216)
			(xy 256.687828 -223.724216)
		)
		(stroke
			(width 0)
			(type solid)
		)
		(fill yes)
		(layer "B.Cu")
		(net "GND")
	)
	(gr_poly
		(pts
			(xy 372.837202 -223.67494) (xy 372.837202 -222.059246) (xy 372.695216 -221.91726) (xy 371.285516 -221.91726)
			(xy 371.110002 -222.092774) (xy 371.110002 -223.519238) (xy 371.31498 -223.724216) (xy 371.557042 -223.724216)
			(xy 372.787926 -223.724216)
		)
		(stroke
			(width 0)
			(type solid)
		)
		(fill yes)
		(layer "B.Cu")
		(net "GND")
	)
	(gr_poly
		(pts
			(xy 3.603752 -382.481836) (xy 3.603752 -381.393954) (xy 3.60172 -381.391922) (xy 3.60172 -381.18415)
			(xy 3.477006 -381.059436) (xy 1.573276 -381.059436) (xy 1.368806 -381.263906) (xy 1.368806 -382.382268)
			(xy 1.519174 -382.532636) (xy 3.552952 -382.532636)
		)
		(stroke
			(width 0)
			(type solid)
		)
		(fill yes)
		(layer "B.Cu")
		(net "P3V3_USB_HUB")
	)
	(gr_poly
		(pts
			(xy 5.501386 -388.984236) (xy 6.626606 -388.984236) (xy 6.80466 -388.806182) (xy 6.80466 -387.82244)
			(xy 6.586982 -387.604762) (xy 5.03428 -387.604762) (xy 4.763008 -387.876034) (xy 4.763008 -388.896098)
			(xy 4.983226 -389.116316) (xy 5.369306 -389.116316)
		)
		(stroke
			(width 0)
			(type solid)
		)
		(fill yes)
		(layer "B.Cu")
		(net "P3V3_USB_8042")
	)
	(gr_poly
		(pts
			(xy 26.47823 -223.527366) (xy 26.47823 -221.607126) (xy 26.47823 -221.285562) (xy 26.265632 -221.072964)
			(xy 24.903176 -221.072964) (xy 24.861774 -221.114366) (xy 24.861774 -221.516448) (xy 24.861774 -223.609408)
			(xy 25.025858 -223.773492) (xy 26.232104 -223.773492)
		)
		(stroke
			(width 0)
			(type solid)
		)
		(fill yes)
		(layer "B.Cu")
		(net "P1V8_PEX")
	)
	(gr_poly
		(pts
			(xy 103.407972 -81.338928) (xy 103.407972 -79.714598) (xy 103.363014 -79.66964) (xy 102.068884 -79.66964)
			(xy 101.540056 -79.66964) (xy 101.149658 -80.060038) (xy 101.149658 -81.426304) (xy 101.246686 -81.523332)
			(xy 102.117652 -81.523332) (xy 103.223568 -81.523332)
		)
		(stroke
			(width 0)
			(type solid)
		)
		(fill yes)
		(layer "B.Cu")
		(net "P3V3")
	)
	(gr_poly
		(pts
			(xy 106.591354 -271.715992) (xy 106.591354 -269.187168) (xy 106.591354 -268.795246) (xy 106.29773 -268.501622)
			(xy 102.350316 -268.501622) (xy 102.032816 -268.819122) (xy 102.032816 -269.023084) (xy 102.032816 -271.692116)
			(xy 102.302818 -271.962118) (xy 106.345228 -271.962118)
		)
		(stroke
			(width 0)
			(type solid)
		)
		(fill yes)
		(layer "B.Cu")
		(net "P12V_AUX")
	)
	(gr_poly
		(pts
			(xy 119.584216 -137.25906) (xy 119.584216 -133.70306) (xy 119.475504 -133.594348) (xy 104.629458 -133.594348)
			(xy 104.222296 -134.00151) (xy 104.222296 -137.149332) (xy 104.302052 -137.229088) (xy 104.484424 -137.41146)
			(xy 119.381016 -137.41146) (xy 119.431816 -137.41146)
		)
		(stroke
			(width 0)
			(type solid)
		)
		(fill yes)
		(layer "B.Cu")
		(net "GND")
	)
	(gr_poly
		(pts
			(xy 139.549886 -173.425866) (xy 139.549886 -171.985686) (xy 139.549886 -171.276264) (xy 139.385802 -171.11218)
			(xy 138.655298 -171.11218) (xy 138.554968 -171.21251) (xy 138.554968 -171.926758) (xy 138.554968 -173.501304)
			(xy 138.58875 -173.535086) (xy 139.440666 -173.535086)
		)
		(stroke
			(width 0)
			(type solid)
		)
		(fill yes)
		(layer "B.Cu")
		(net "P3V3")
	)
	(gr_poly
		(pts
			(xy 142.54099 -223.527366) (xy 142.54099 -221.607126) (xy 142.54099 -221.543118) (xy 142.070836 -221.072964)
			(xy 140.965936 -221.072964) (xy 140.924534 -221.114366) (xy 140.924534 -221.516448) (xy 140.924534 -223.609408)
			(xy 141.088618 -223.773492) (xy 142.294864 -223.773492)
		)
		(stroke
			(width 0)
			(type solid)
		)
		(fill yes)
		(layer "B.Cu")
		(net "P1V8_PEX")
	)
	(gr_poly
		(pts
			(xy 258.640834 -223.527366) (xy 258.640834 -221.607126) (xy 258.640834 -221.285562) (xy 258.428236 -221.072964)
			(xy 257.06578 -221.072964) (xy 257.024378 -221.114366) (xy 257.024378 -221.516448) (xy 257.024378 -223.609408)
			(xy 257.188462 -223.773492) (xy 258.394708 -223.773492)
		)
		(stroke
			(width 0)
			(type solid)
		)
		(fill yes)
		(layer "B.Cu")
		(net "P1V8_PEX")
	)
	(gr_poly
		(pts
			(xy 338.79155 -271.715992) (xy 338.79155 -269.187168) (xy 338.79155 -268.77137) (xy 338.521802 -268.501622)
			(xy 334.754474 -268.501622) (xy 334.370934 -268.885162) (xy 334.233012 -269.023084) (xy 334.233012 -271.692116)
			(xy 334.503014 -271.962118) (xy 338.545424 -271.962118)
		)
		(stroke
			(width 0)
			(type solid)
		)
		(fill yes)
		(layer "B.Cu")
		(net "P12V_AUX")
	)
	(gr_poly
		(pts
			(xy 19.662648 -211.82457) (xy 19.799046 -211.688172) (xy 19.799046 -208.386172) (xy 19.621246 -208.208372)
			(xy 19.214846 -208.208372) (xy 17.157446 -208.208372) (xy 17.005046 -208.360772) (xy 17.005046 -211.631784)
			(xy 17.005046 -211.815172) (xy 17.081246 -211.891372) (xy 19.595846 -211.891372)
		)
		(stroke
			(width 0)
			(type solid)
		)
		(fill yes)
		(layer "B.Cu")
		(net "P1V8_PLL0_PEX0")
	)
	(gr_poly
		(pts
			(xy 151.130762 -240.666778) (xy 151.130762 -237.364778) (xy 150.952962 -237.186978) (xy 150.546562 -237.186978)
			(xy 148.489162 -237.186978) (xy 148.336762 -237.339378) (xy 148.336762 -240.793778) (xy 148.412962 -240.869978)
			(xy 149.657562 -240.869978) (xy 150.444962 -240.869978) (xy 150.927562 -240.869978)
		)
		(stroke
			(width 0)
			(type solid)
		)
		(fill yes)
		(layer "B.Cu")
		(net "P1V8_PLL0_PEX1")
	)
	(gr_poly
		(pts
			(xy 189.1665 -115.887754) (xy 189.1665 -113.277396) (xy 189.413896 -113.03) (xy 189.413896 -109.032802)
			(xy 188.449966 -109.032802) (xy 188.083952 -109.032802) (xy 187.769246 -109.032802) (xy 187.55106 -109.250988)
			(xy 187.55106 -115.866926) (xy 187.680346 -115.996212) (xy 189.058042 -115.996212)
		)
		(stroke
			(width 0)
			(type solid)
		)
		(fill yes)
		(layer "B.Cu")
		(net "GND")
	)
	(gr_poly
		(pts
			(xy 263.301226 -239.908588) (xy 263.301226 -236.606588) (xy 263.123426 -236.428788) (xy 262.717026 -236.428788)
			(xy 260.659626 -236.428788) (xy 260.507226 -236.581188) (xy 260.507226 -240.035588) (xy 260.583426 -240.111788)
			(xy 261.828026 -240.111788) (xy 262.615426 -240.111788) (xy 263.098026 -240.111788)
		)
		(stroke
			(width 0)
			(type solid)
		)
		(fill yes)
		(layer "B.Cu")
		(net "P1V8_PLL0_PEX2")
	)
	(gr_poly
		(pts
			(xy 305.266598 -115.887754) (xy 305.266598 -113.277396) (xy 305.513994 -113.03) (xy 305.513994 -109.032802)
			(xy 304.550064 -109.032802) (xy 304.18405 -109.032802) (xy 303.869344 -109.032802) (xy 303.651158 -109.250988)
			(xy 303.651158 -115.866926) (xy 303.780444 -115.996212) (xy 305.15814 -115.996212)
		)
		(stroke
			(width 0)
			(type solid)
		)
		(fill yes)
		(layer "B.Cu")
		(net "GND")
	)
	(gr_poly
		(pts
			(xy 361.17657 -271.715992) (xy 361.17657 -269.187168) (xy 361.173014 -269.183612) (xy 361.173014 -268.830298)
			(xy 360.834686 -268.49197) (xy 356.843838 -268.49197) (xy 356.618032 -268.717776) (xy 356.618032 -269.023084)
			(xy 356.618032 -271.692116) (xy 356.888034 -271.962118) (xy 360.930444 -271.962118)
		)
		(stroke
			(width 0)
			(type solid)
		)
		(fill yes)
		(layer "B.Cu")
		(net "P12V_AUX")
	)
	(gr_poly
		(pts
			(xy 421.366696 -115.887754) (xy 421.366696 -113.277396) (xy 421.614092 -113.03) (xy 421.614092 -109.032802)
			(xy 420.650162 -109.032802) (xy 420.284148 -109.032802) (xy 419.969442 -109.032802) (xy 419.751256 -109.250988)
			(xy 419.751256 -115.866926) (xy 419.880542 -115.996212) (xy 421.258238 -115.996212)
		)
		(stroke
			(width 0)
			(type solid)
		)
		(fill yes)
		(layer "B.Cu")
		(net "GND")
	)
	(gr_poly
		(pts
			(xy 460.060802 -247.74144) (xy 460.060802 -244.43944) (xy 459.883002 -244.26164) (xy 459.476602 -244.26164)
			(xy 457.419202 -244.26164) (xy 457.266802 -244.41404) (xy 457.266802 -247.86844) (xy 457.343002 -247.94464)
			(xy 458.587602 -247.94464) (xy 459.375002 -247.94464) (xy 459.857602 -247.94464)
		)
		(stroke
			(width 0)
			(type solid)
		)
		(fill yes)
		(layer "B.Cu")
		(net "P1V8_PLL0_PEX3")
	)
	(gr_poly
		(pts
			(xy 12.824968 -177.851562) (xy 12.824968 -173.290992) (xy 12.824968 -168.33723) (xy 12.486894 -167.999156)
			(xy 9.281922 -167.999156) (xy 8.795766 -167.999156) (xy 8.472678 -168.322244) (xy 8.472678 -173.49851)
			(xy 7.926578 -174.04461) (xy 7.926578 -177.549048) (xy 8.39216 -178.01463) (xy 12.6619 -178.01463)
		)
		(stroke
			(width 0)
			(type solid)
		)
		(fill yes)
		(layer "B.Cu")
		(net "P5V_AUX")
	)
	(gr_poly
		(pts
			(xy 13.499846 -213.008972) (xy 13.499846 -212.627972) (xy 13.753846 -212.373972) (xy 14.693646 -212.373972)
			(xy 14.769846 -212.297772) (xy 14.769846 -211.230972) (xy 14.719046 -211.180172) (xy 11.518646 -211.180172)
			(xy 11.442446 -211.256372) (xy 11.442446 -213.135972) (xy 11.569446 -213.262972) (xy 13.245846 -213.262972)
		)
		(stroke
			(width 0)
			(type solid)
		)
		(fill yes)
		(layer "B.Cu")
		(net "P3V3_AUX")
	)
	(gr_poly
		(pts
			(xy 47.848774 -146.14906) (xy 47.848774 -139.573) (xy 47.721774 -139.446) (xy 46.360334 -139.446)
			(xy 46.233334 -139.573) (xy 46.233334 -142.122652) (xy 45.974254 -142.381732) (xy 45.974254 -146.3548)
			(xy 45.9867 -146.367246) (xy 46.949868 -146.367246) (xy 47.315882 -146.367246) (xy 47.630588 -146.367246)
		)
		(stroke
			(width 0)
			(type solid)
		)
		(fill yes)
		(layer "B.Cu")
		(net "GND")
	)
	(gr_poly
		(pts
			(xy 144.831562 -241.987578) (xy 144.831562 -241.606578) (xy 145.085562 -241.352578) (xy 146.025362 -241.352578)
			(xy 146.101562 -241.276378) (xy 146.101562 -240.209578) (xy 146.050762 -240.158778) (xy 142.850362 -240.158778)
			(xy 142.774162 -240.234978) (xy 142.774162 -242.114578) (xy 142.901162 -242.241578) (xy 144.577562 -242.241578)
		)
		(stroke
			(width 0)
			(type solid)
		)
		(fill yes)
		(layer "B.Cu")
		(net "P3V3_AUX")
	)
	(gr_poly
		(pts
			(xy 163.948618 -146.14906) (xy 163.948618 -139.573) (xy 163.821618 -139.446) (xy 162.460178 -139.446)
			(xy 162.333178 -139.573) (xy 162.333178 -142.122652) (xy 162.080956 -142.374874) (xy 162.080956 -146.356832)
			(xy 162.09137 -146.367246) (xy 163.049712 -146.367246) (xy 163.415726 -146.367246) (xy 163.730432 -146.367246)
		)
		(stroke
			(width 0)
			(type solid)
		)
		(fill yes)
		(layer "B.Cu")
		(net "GND")
	)
	(gr_poly
		(pts
			(xy 257.002026 -241.229388) (xy 257.002026 -240.848388) (xy 257.256026 -240.594388) (xy 258.195826 -240.594388)
			(xy 258.272026 -240.518188) (xy 258.272026 -239.451388) (xy 258.221226 -239.400588) (xy 255.020826 -239.400588)
			(xy 254.944626 -239.476788) (xy 254.944626 -241.356388) (xy 255.071626 -241.483388) (xy 256.748026 -241.483388)
		)
		(stroke
			(width 0)
			(type solid)
		)
		(fill yes)
		(layer "B.Cu")
		(net "P3V3_AUX")
	)
	(gr_poly
		(pts
			(xy 280.048716 -146.14906) (xy 280.048716 -139.573) (xy 279.921716 -139.446) (xy 278.560276 -139.446)
			(xy 278.433276 -139.573) (xy 278.433276 -142.122652) (xy 278.181054 -142.374874) (xy 278.181054 -146.349212)
			(xy 278.199088 -146.367246) (xy 279.14981 -146.367246) (xy 279.515824 -146.367246) (xy 279.83053 -146.367246)
		)
		(stroke
			(width 0)
			(type solid)
		)
		(fill yes)
		(layer "B.Cu")
		(net "GND")
	)
	(gr_poly
		(pts
			(xy 396.148814 -146.14906) (xy 396.148814 -139.573) (xy 396.021814 -139.446) (xy 394.660374 -139.446)
			(xy 394.533374 -139.573) (xy 394.533374 -142.122652) (xy 394.279882 -142.376144) (xy 394.279882 -146.352006)
			(xy 394.295122 -146.367246) (xy 395.249908 -146.367246) (xy 395.615922 -146.367246) (xy 395.930628 -146.367246)
		)
		(stroke
			(width 0)
			(type solid)
		)
		(fill yes)
		(layer "B.Cu")
		(net "GND")
	)
	(gr_poly
		(pts
			(xy 453.761602 -248.9962) (xy 453.761602 -248.68124) (xy 454.015602 -248.42724) (xy 454.955402 -248.42724)
			(xy 455.031602 -248.35104) (xy 455.031602 -247.28424) (xy 454.980802 -247.23344) (xy 451.780402 -247.23344)
			(xy 451.704202 -247.30964) (xy 451.704202 -248.957338) (xy 451.845426 -249.098562) (xy 453.65924 -249.098562)
		)
		(stroke
			(width 0)
			(type solid)
		)
		(fill yes)
		(layer "B.Cu")
		(net "P3V3_AUX")
	)
	(gr_poly
		(pts
			(xy 7.61746 -173.5328) (xy 7.928356 -173.5328) (xy 7.982204 -173.478952) (xy 8.15086 -173.310296)
			(xy 8.15086 -168.507664) (xy 8.15086 -168.270682) (xy 7.852664 -167.972486) (xy 5.96265 -167.972486)
			(xy 5.624576 -168.31056) (xy 5.624576 -173.304708) (xy 5.856986 -173.537118) (xy 6.205474 -173.537118)
			(xy 7.613396 -173.537118)
		)
		(stroke
			(width 0)
			(type solid)
		)
		(fill yes)
		(layer "B.Cu")
		(net "GND")
	)
	(gr_poly
		(pts
			(xy 128.976374 -271.715992) (xy 128.976374 -269.187168) (xy 128.976374 -269.00759) (xy 128.975866 -269.007082)
			(xy 128.975866 -268.728952) (xy 128.732026 -268.485112) (xy 124.978668 -268.485112) (xy 124.788422 -268.675358)
			(xy 124.578618 -268.885162) (xy 124.417836 -269.045944) (xy 124.417836 -271.692116) (xy 124.687838 -271.962118)
			(xy 128.730248 -271.962118)
		)
		(stroke
			(width 0)
			(type solid)
		)
		(fill yes)
		(layer "B.Cu")
		(net "P12V_AUX")
	)
	(gr_poly
		(pts
			(xy 71.716138 -299.332142) (xy 71.72325 -299.32503) (xy 71.72325 -298.965112) (xy 71.72325 -292.487858)
			(xy 71.701152 -292.46576) (xy 71.589138 -292.353746) (xy 71.310246 -292.353746) (xy 71.162672 -292.50132)
			(xy 71.162672 -292.737286) (xy 71.162672 -298.804838) (xy 71.16318 -298.8056) (xy 71.16318 -299.163994)
			(xy 71.388224 -299.389038) (xy 71.659242 -299.389038)
		)
		(stroke
			(width 0)
			(type solid)
		)
		(fill yes)
		(layer "B.Cu")
		(net "GND")
	)
	(gr_poly
		(pts
			(xy 73.066656 -115.887754) (xy 73.066656 -113.277396) (xy 73.314052 -113.03) (xy 73.314052 -109.032802)
			(xy 72.350122 -109.032802) (xy 71.984108 -109.032802) (xy 71.669402 -109.032802) (xy 71.451216 -109.250988)
			(xy 71.451216 -113.44275) (xy 71.606664 -113.598198) (xy 71.606664 -114.251994) (xy 71.451216 -114.407442)
			(xy 71.451216 -115.866926) (xy 71.580502 -115.996212) (xy 72.958198 -115.996212)
		)
		(stroke
			(width 0)
			(type solid)
		)
		(fill yes)
		(layer "B.Cu")
		(net "GND")
	)
	(gr_poly
		(pts
			(xy 119.586248 -146.197828) (xy 119.586248 -145.791428) (xy 119.586248 -143.124428) (xy 119.586248 -142.109698)
			(xy 119.586248 -141.722348) (xy 119.586248 -138.448796) (xy 119.586248 -137.817098) (xy 119.440198 -137.671048)
			(xy 109.953298 -137.671048) (xy 109.164628 -137.671048) (xy 104.518714 -137.671048) (xy 104.244902 -137.94486)
			(xy 104.244902 -146.132042) (xy 104.54132 -146.42846) (xy 119.355616 -146.42846)
		)
		(stroke
			(width 0)
			(type solid)
		)
		(fill yes)
		(layer "B.Cu")
		(net "P3V3_AUX")
	)
	(gr_poly
		(pts
			(xy 128.152398 -179.319428) (xy 128.152398 -178.709828) (xy 128.311402 -178.550824) (xy 128.311402 -177.862992)
			(xy 128.311402 -176.826672) (xy 128.096772 -176.612042) (xy 128.096772 -175.709072) (xy 128.014476 -175.626776)
			(xy 127.304292 -175.626776) (xy 126.765558 -175.626776) (xy 126.4158 -175.976534) (xy 126.4158 -179.250848)
			(xy 126.556262 -179.39131) (xy 126.98349 -179.39131) (xy 128.080516 -179.39131)
		)
		(stroke
			(width 0)
			(type solid)
		)
		(fill yes)
		(layer "B.Cu")
		(net "GND")
	)
	(gr_poly
		(pts
			(xy 140.650214 -205.269846) (xy 140.650214 -203.071222) (xy 140.51153 -202.932538) (xy 140.51153 -202.819254)
			(xy 140.503656 -202.81138) (xy 140.503656 -201.636884) (xy 140.650214 -201.490326) (xy 140.650214 -201.078846)
			(xy 140.650214 -200.443846) (xy 140.269214 -200.062846) (xy 139.634214 -200.062846) (xy 139.380214 -200.316846)
			(xy 139.380214 -201.078846) (xy 139.380214 -205.015846) (xy 139.761214 -205.396846) (xy 140.523214 -205.396846)
		)
		(stroke
			(width 0)
			(type solid)
		)
		(fill yes)
		(layer "B.Cu")
		(net "P3V3_CLI_VPLL")
	)
	(gr_poly
		(pts
			(xy 392.609832 -300.255432) (xy 392.609832 -297.55211) (xy 392.609832 -297.25493) (xy 392.472926 -297.118024)
			(xy 392.465814 -297.110658) (xy 392.447018 -297.103038)
			(arc
				(start 391.971022 -297.103038)
				(mid 391.951499 -297.106939)
				(end 391.934954 -297.118024)
			)
			(xy 391.837926 -297.215052) (xy 391.83056 -297.222164) (xy 391.82294 -297.24096) (xy 391.82294 -300.20133)
			(xy 391.99947 -300.37786) (xy 392.487404 -300.37786)
		)
		(stroke
			(width 0)
			(type solid)
		)
		(fill yes)
		(layer "B.Cu")
		(net "GND")
	)
	(gr_poly
		(pts
			(xy 5.853684 -384.245358) (xy 5.853684 -383.831338) (xy 5.857748 -383.82702) (xy 5.857748 -383.11582)
			(xy 5.37337 -382.631442) (xy 5.37337 -381.336296) (xy 5.251958 -381.214884) (xy 4.024884 -381.214884)
			(xy 3.899916 -381.339852) (xy 3.899916 -382.117092) (xy 3.899916 -382.897126) (xy 3.809238 -382.987804)
			(xy 2.130552 -382.987804) (xy 2.067052 -383.051304) (xy 2.067052 -384.327654) (xy 2.166874 -384.427476)
			(xy 5.671566 -384.427476)
		)
		(stroke
			(width 0)
			(type solid)
		)
		(fill yes)
		(layer "B.Cu")
		(net "P3V3_USB_8042")
	)
	(gr_poly
		(pts
			(arc
				(start 225.517964 -144.364202)
				(mid 225.537487 -144.360301)
				(end 225.554032 -144.349216)
			)
			(xy 225.679 -144.224248) (xy 225.679 -143.907764) (xy 225.119438 -143.348202) (xy 222.645732 -143.348202)
			(xy 222.144082 -142.846552) (xy 222.144082 -141.68755) (xy 221.905576 -141.449044) (xy 220.910658 -141.449044)
			(xy 220.75648 -141.603222) (xy 220.75648 -144.184116) (xy 220.936566 -144.364202) (xy 221.283276 -144.364202)
			(xy 222.512128 -144.364202)
		)
		(stroke
			(width 0)
			(type solid)
		)
		(fill yes)
		(layer "B.Cu")
		(net "P3V3_CLK_GEN_VDDA25M_CK440_PEX")
	)
	(gr_poly
		(pts
			(xy 110.81893 -88.906096) (xy 110.81893 -88.4047) (xy 110.997492 -88.226138) (xy 110.997492 -87.118444)
			(xy 110.997492 -84.074762) (xy 110.748826 -83.826096) (xy 106.748326 -83.826096) (xy 106.582464 -83.991958)
			(xy 106.582464 -88.414352) (xy 106.770678 -88.602566) (xy 108.201968 -88.602566) (xy 108.458254 -88.34628)
			(xy 109.075982 -88.34628) (xy 109.249718 -88.520016) (xy 109.249718 -89.056464) (xy 109.330998 -89.137744)
			(xy 110.085886 -89.137744) (xy 110.587282 -89.137744)
		)
		(stroke
			(width 0)
			(type solid)
		)
		(fill yes)
		(layer "B.Cu")
		(net "GND")
	)
	(gr_poly
		(pts
			(xy 139.486894 -176.124108) (xy 139.486894 -175.839882) (xy 139.486894 -174.126906) (xy 139.392914 -174.032926)
			(xy 138.813286 -174.032926) (xy 138.15441 -174.032926) (xy 137.710164 -174.032926) (xy 136.900412 -174.032926)
			(xy 136.560052 -174.373286) (xy 136.121394 -174.373286) (xy 134.695438 -174.373286) (xy 134.266178 -174.802546)
			(xy 134.266178 -175.35017) (xy 134.266178 -175.956976) (xy 134.429246 -176.120044) (xy 134.789418 -176.120044)
			(xy 134.906004 -176.23663) (xy 139.374372 -176.23663)
		)
		(stroke
			(width 0)
			(type solid)
		)
		(fill yes)
		(layer "B.Cu")
		(net "P3V3_DB2000QL_VDD")
	)
	(gr_poly
		(pts
			(xy 16.725646 -213.948772) (xy 16.725646 -213.186772) (xy 16.725646 -208.386172) (xy 16.547846 -208.208372)
			(xy 11.544046 -208.208372) (xy 11.417046 -208.335372) (xy 11.417046 -210.468972) (xy 11.467846 -210.519772)
			(xy 13.245846 -210.519772) (xy 13.398246 -210.367372) (xy 13.398246 -209.884772) (xy 13.614146 -209.668872)
			(xy 14.807946 -209.668872) (xy 15.049246 -209.910172) (xy 15.049246 -213.212172) (xy 15.049246 -213.897972)
			(xy 15.100046 -213.948772) (xy 15.201646 -214.050372) (xy 16.624046 -214.050372)
		)
		(stroke
			(width 0)
			(type solid)
		)
		(fill yes)
		(layer "B.Cu")
		(net "GND")
	)
	(gr_poly
		(pts
			(xy 109.187996 -338.828634) (xy 109.187996 -337.65617) (xy 108.627164 -337.095338) (xy 108.627164 -337.030568)
			(xy 108.627164 -336.498438) (xy 108.30814 -336.179414) (xy 108.30814 -335.345786) (xy 108.19511 -335.232756)
			(xy 108.086906 -335.232756) (xy 108.071412 -335.24825) (xy 107.624118 -335.24825) (xy 107.510834 -335.134966)
			(xy 106.800904 -335.134966) (xy 106.610658 -335.325212) (xy 106.610658 -336.323432) (xy 106.939842 -336.652616)
			(xy 106.939842 -338.68995) (xy 107.186476 -338.936584) (xy 109.080046 -338.936584)
		)
		(stroke
			(width 0)
			(type solid)
		)
		(fill yes)
		(layer "B.Cu")
		(net "P3V3_CLK_BUFFER_9ZXL0451E_VZX3P3A")
	)
	(gr_poly
		(pts
			(xy 148.057362 -242.927378) (xy 148.057362 -242.165378) (xy 148.057362 -237.364778) (xy 147.879562 -237.186978)
			(xy 142.875762 -237.186978) (xy 142.748762 -237.313978) (xy 142.748762 -239.447578) (xy 142.799562 -239.498378)
			(xy 144.577562 -239.498378) (xy 144.729962 -239.345978) (xy 144.729962 -238.863378) (xy 144.945862 -238.647478)
			(xy 146.139662 -238.647478) (xy 146.380962 -238.888778) (xy 146.380962 -242.190778) (xy 146.380962 -242.876578)
			(xy 146.431762 -242.927378) (xy 146.533362 -243.028978) (xy 147.955762 -243.028978)
		)
		(stroke
			(width 0)
			(type solid)
		)
		(fill yes)
		(layer "B.Cu")
		(net "GND")
	)
	(gr_poly
		(pts
			(xy 260.227826 -242.169188) (xy 260.227826 -241.407188) (xy 260.227826 -236.606588) (xy 260.050026 -236.428788)
			(xy 255.046226 -236.428788) (xy 254.919226 -236.555788) (xy 254.919226 -238.689388) (xy 254.970026 -238.740188)
			(xy 256.748026 -238.740188) (xy 256.900426 -238.587788) (xy 256.900426 -238.105188) (xy 257.116326 -237.889288)
			(xy 258.310126 -237.889288) (xy 258.551426 -238.130588) (xy 258.551426 -241.432588) (xy 258.551426 -242.118388)
			(xy 258.602226 -242.169188) (xy 258.703826 -242.270788) (xy 260.126226 -242.270788)
		)
		(stroke
			(width 0)
			(type solid)
		)
		(fill yes)
		(layer "B.Cu")
		(net "GND")
	)
	(gr_poly
		(pts
			(arc
				(start 67.784218 -291.972238)
				(mid 67.803741 -291.968337)
				(end 67.820286 -291.957252)
			)
			(arc
				(start 67.917314 -291.860224)
				(mid 67.928425 -291.84369)
				(end 67.9323 -291.824156)
			)
			(arc
				(start 67.9323 -291.56152)
				(mid 67.928399 -291.541997)
				(end 67.917314 -291.525452)
			)
			(arc
				(start 67.769486 -291.377624)
				(mid 67.752952 -291.366513)
				(end 67.733418 -291.362638)
			)
			(xy 51.054762 -291.362638) (xy 50.927 -291.4904) (xy 50.927 -291.9222) (xy 50.977038 -291.972238)
		)
		(stroke
			(width 0)
			(type solid)
		)
		(fill yes)
		(layer "B.Cu")
		(net "GND")
	)
	(gr_poly
		(pts
			(arc
				(start 105.571544 -280.227024)
				(mid 105.588078 -280.215913)
				(end 105.607612 -280.212038)
			)
			(xy 106.151426 -280.212038) (xy 106.600752 -280.212038) (xy 106.89971 -279.91308) (xy 107.461304 -279.351486)
			(xy 107.945936 -279.351486) (xy 108.083096 -279.351486) (xy 108.219748 -279.214834) (xy 108.219748 -278.772874)
			(xy 108.17987 -278.732996) (xy 106.79176 -278.732996) (xy 106.075226 -278.732996) (xy 104.470454 -278.732996)
			(xy 103.712772 -279.490678) (xy 103.712772 -280.635964) (xy 103.753412 -280.676604) (xy 105.121964 -280.676604)
		)
		(stroke
			(width 0)
			(type solid)
		)
		(fill yes)
		(layer "B.Cu")
		(net "GND")
	)
	(gr_poly
		(pts
			(arc
				(start 122.281442 -280.227024)
				(mid 122.297976 -280.215913)
				(end 122.31751 -280.212038)
			)
			(xy 122.861324 -280.212038) (xy 123.31065 -280.212038) (xy 123.609608 -279.91308) (xy 124.171202 -279.351486)
			(xy 124.655834 -279.351486) (xy 124.792994 -279.351486) (xy 124.929646 -279.214834) (xy 124.929646 -278.772874)
			(xy 124.889768 -278.732996) (xy 123.501658 -278.732996) (xy 122.785124 -278.732996) (xy 121.180352 -278.732996)
			(xy 120.42267 -279.490678) (xy 120.42267 -280.635964) (xy 120.46331 -280.676604) (xy 121.831862 -280.676604)
		)
		(stroke
			(width 0)
			(type solid)
		)
		(fill yes)
		(layer "B.Cu")
		(net "GND")
	)
	(gr_poly
		(pts
			(xy 123.240546 -260.298946) (xy 123.240546 -255.62052) (xy 123.13539 -255.515364) (xy 123.062746 -255.44272)
			(xy 122.037348 -255.44272) (xy 121.84253 -255.637538) (xy 121.028968 -255.637538) (xy 120.83415 -255.44272)
			(xy 117.294914 -255.44272) (xy 117.23243 -255.505204) (xy 117.23243 -257.00736) (xy 117.385846 -257.160776)
			(xy 118.326662 -257.160776) (xy 118.46179 -257.295904) (xy 118.549166 -257.38328) (xy 118.549166 -259.594096)
			(xy 119.35079 -260.39572) (xy 121.12879 -260.39572) (xy 122.604276 -260.39572) (xy 123.143772 -260.39572)
		)
		(stroke
			(width 0)
			(type solid)
		)
		(fill yes)
		(layer "B.Cu")
		(net "GND")
	)
	(gr_poly
		(pts
			(arc
				(start 183.934608 -300.39691)
				(mid 183.954131 -300.393009)
				(end 183.970676 -300.381924)
			)
			(arc
				(start 184.017412 -300.335188)
				(mid 184.028523 -300.318654)
				(end 184.032398 -300.29912)
			)
			(xy 184.032398 -300.123352) (xy 183.727852 -299.818806) (xy 166.802054 -299.818806) (xy 166.543482 -300.077378)
			(arc
				(start 166.543482 -300.290738)
				(mid 166.547383 -300.310261)
				(end 166.558468 -300.326806)
			)
			(arc
				(start 166.613586 -300.381924)
				(mid 166.63012 -300.393035)
				(end 166.649654 -300.39691)
			)
		)
		(stroke
			(width 0)
			(type solid)
		)
		(fill yes)
		(layer "B.Cu")
		(net "GND")
	)
	(gr_poly
		(pts
			(xy 245.129304 -208.27365)
			(arc
				(start 245.129304 -204.595476)
				(mid 245.125403 -204.575953)
				(end 245.114318 -204.559408)
			)
			(arc
				(start 244.889274 -204.334364)
				(mid 244.87274 -204.323253)
				(end 244.853206 -204.319378)
			)
			(arc
				(start 244.020086 -204.319378)
				(mid 244.000563 -204.323279)
				(end 243.984018 -204.334364)
			)
			(arc
				(start 243.623084 -204.695298)
				(mid 243.611973 -204.711832)
				(end 243.608098 -204.731366)
			)
			(xy 243.608098 -208.27365) (xy 243.739162 -208.404714) (xy 244.99824 -208.404714)
		)
		(stroke
			(width 0)
			(type solid)
		)
		(fill yes)
		(layer "B.Cu")
		(net "GND")
	)
	(gr_poly
		(pts
			(arc
				(start 337.77174 -280.227024)
				(mid 337.788274 -280.215913)
				(end 337.807808 -280.212038)
			)
			(xy 338.351622 -280.212038) (xy 338.800948 -280.212038) (xy 339.099906 -279.91308) (xy 339.6615 -279.351486)
			(xy 340.146132 -279.351486) (xy 340.283292 -279.351486) (xy 340.419944 -279.214834) (xy 340.419944 -278.772874)
			(xy 340.380066 -278.732996) (xy 338.991956 -278.732996) (xy 338.275422 -278.732996) (xy 336.67065 -278.732996)
			(xy 335.912968 -279.490678) (xy 335.912968 -280.635964) (xy 335.953608 -280.676604) (xy 337.32216 -280.676604)
		)
		(stroke
			(width 0)
			(type solid)
		)
		(fill yes)
		(layer "B.Cu")
		(net "GND")
	)
	(gr_poly
		(pts
			(arc
				(start 354.481638 -280.227024)
				(mid 354.498172 -280.215913)
				(end 354.517706 -280.212038)
			)
			(xy 355.06152 -280.212038) (xy 355.510846 -280.212038) (xy 355.809804 -279.91308) (xy 356.371398 -279.351486)
			(xy 356.85603 -279.351486) (xy 356.99319 -279.351486) (xy 357.129842 -279.214834) (xy 357.129842 -278.772874)
			(xy 357.089964 -278.732996) (xy 355.701854 -278.732996) (xy 354.98532 -278.732996) (xy 353.380548 -278.732996)
			(xy 352.622866 -279.490678) (xy 352.622866 -280.635964) (xy 352.663506 -280.676604) (xy 354.032058 -280.676604)
		)
		(stroke
			(width 0)
			(type solid)
		)
		(fill yes)
		(layer "B.Cu")
		(net "GND")
	)
	(gr_poly
		(pts
			(xy 355.440742 -260.298946) (xy 355.440742 -255.62052) (xy 355.335586 -255.515364) (xy 355.262942 -255.44272)
			(xy 354.237544 -255.44272) (xy 354.042726 -255.637538) (xy 353.229164 -255.637538) (xy 353.034346 -255.44272)
			(xy 349.49511 -255.44272) (xy 349.432626 -255.505204) (xy 349.432626 -257.00736) (xy 349.586042 -257.160776)
			(xy 350.526858 -257.160776) (xy 350.661986 -257.295904) (xy 350.749362 -257.38328) (xy 350.749362 -259.594096)
			(xy 351.550986 -260.39572) (xy 353.328986 -260.39572) (xy 354.804472 -260.39572) (xy 355.343968 -260.39572)
		)
		(stroke
			(width 0)
			(type solid)
		)
		(fill yes)
		(layer "B.Cu")
		(net "GND")
	)
	(gr_poly
		(pts
			(arc
				(start 416.084258 -291.972238)
				(mid 416.103781 -291.968337)
				(end 416.120326 -291.957252)
			)
			(arc
				(start 416.217354 -291.860224)
				(mid 416.228465 -291.84369)
				(end 416.23234 -291.824156)
			)
			(arc
				(start 416.23234 -291.56152)
				(mid 416.228439 -291.541997)
				(end 416.217354 -291.525452)
			)
			(arc
				(start 416.069526 -291.377624)
				(mid 416.052992 -291.366513)
				(end 416.033458 -291.362638)
			)
			(xy 399.354802 -291.362638) (xy 399.22704 -291.4904) (xy 399.22704 -291.9222) (xy 399.277078 -291.972238)
		)
		(stroke
			(width 0)
			(type solid)
		)
		(fill yes)
		(layer "B.Cu")
		(net "GND")
	)
	(gr_poly
		(pts
			(xy 135.835136 -321.413886) (xy 135.835136 -319.269872) (xy 135.676132 -319.110868) (xy 134.723124 -319.110868)
			(xy 123.380754 -319.110868) (xy 123.178062 -318.908176) (xy 123.178062 -308.800754) (xy 123.070874 -308.693566)
			(xy 122.106182 -308.693566) (xy 118.873016 -308.693566) (xy 118.19128 -308.693566) (xy 118.059962 -308.824884)
			(xy 118.059962 -314.904374) (xy 118.567454 -315.411866) (xy 118.608602 -315.453014) (xy 118.608602 -319.04813)
			(xy 118.567454 -319.089278) (xy 118.059962 -319.59677) (xy 118.059962 -321.208908) (xy 118.155974 -321.30492)
			(xy 124.899166 -321.30492) (xy 125.3109 -321.716654) (xy 135.532368 -321.716654)
		)
		(stroke
			(width 0)
			(type solid)
		)
		(fill yes)
		(layer "B.Cu")
		(net "P0V8_SERDES_VDDA_PEX1")
	)
	(gr_poly
		(pts
			(arc
				(start 220.896688 -212.010244)
				(mid 220.916211 -212.006343)
				(end 220.932756 -211.995258)
			)
			(arc
				(start 220.970856 -211.957158)
				(mid 220.981967 -211.940624)
				(end 220.985842 -211.92109)
			)
			(arc
				(start 220.985842 -208.30921)
				(mid 220.981941 -208.289687)
				(end 220.970856 -208.273142)
			)
			(arc
				(start 220.87332 -208.175606)
				(mid 220.856786 -208.164495)
				(end 220.837252 -208.16062)
			)
			(xy 219.70238 -208.16062) (xy 219.329 -208.534) (xy 219.329 -211.201) (xy 219.366084 -211.238084)
			(arc
				(start 220.123512 -211.995258)
				(mid 220.140046 -212.006369)
				(end 220.15958 -212.010244)
			)
		)
		(stroke
			(width 0)
			(type solid)
		)
		(fill yes)
		(layer "B.Cu")
		(net "GND")
	)
	(gr_poly
		(pts
			(arc
				(start 268.182598 -79.617316)
				(mid 268.202121 -79.613415)
				(end 268.218666 -79.60233)
			)
			(arc
				(start 268.315694 -79.505302)
				(mid 268.326805 -79.488768)
				(end 268.33068 -79.469234)
			)
			(xy 268.33068 -77.098398) (xy 268.496796 -76.932282) (xy 268.496796 -76.480162) (xy 268.307312 -76.290678)
			(xy 266.45743 -76.290678) (xy 266.329414 -76.418694) (xy 266.329414 -77.482954) (xy 266.93368 -78.08722)
			(arc
				(start 266.93368 -79.469234)
				(mid 266.937581 -79.488757)
				(end 266.948666 -79.505302)
			)
			(arc
				(start 267.045694 -79.60233)
				(mid 267.062228 -79.613441)
				(end 267.081762 -79.617316)
			)
		)
		(stroke
			(width 0)
			(type solid)
		)
		(fill yes)
		(layer "B.Cu")
		(net "P3V3")
	)
	(gr_poly
		(pts
			(xy 109.38002 -350.474788) (xy 109.38002 -349.406464) (xy 109.76991 -349.016574) (xy 110.679738 -349.016574)
			(xy 110.838488 -348.857824) (xy 110.838488 -345.753436) (xy 110.838488 -344.58402) (xy 110.57128 -344.316812)
			(xy 108.189014 -344.316812) (xy 107.98683 -344.518996) (xy 107.98683 -345.738958) (xy 108.773722 -346.52585)
			(xy 108.773722 -347.11767) (xy 109.365796 -347.709744) (xy 109.365796 -348.453202) (xy 107.842304 -349.976694)
			(xy 107.315508 -349.976694) (xy 106.918506 -350.373696) (xy 105.81386 -350.373696) (xy 105.770426 -350.41713)
			(xy 105.770426 -350.590104) (xy 105.828338 -350.648016) (xy 107.02671 -350.648016) (xy 107.18546 -350.806766)
			(xy 109.048042 -350.806766)
		)
		(stroke
			(width 0)
			(type solid)
		)
		(fill yes)
		(layer "B.Cu")
		(net "P3V3_CLK_BUFFER_9ZXL0451E_S3_VZX3P3A")
	)
	(gr_poly
		(pts
			(xy 131.109466 -177.54346) (xy 131.109466 -177.482246) (xy 131.144264 -177.447448) (xy 131.144264 -177.325782)
			(xy 131.144264 -176.545748) (xy 131.004818 -176.406556) (xy 130.912616 -176.406556) (xy 130.828796 -176.406556)
			(xy 130.415538 -175.993298) (xy 130.291586 -175.993298) (xy 129.99593 -175.697642) (xy 129.99593 -175.541686)
			(xy 129.270252 -174.816008) (xy 129.270252 -174.406814) (xy 129.182622 -174.319184) (xy 128.419352 -174.319184)
			(xy 128.419352 -175.873156) (xy 128.528064 -175.981868) (xy 128.528064 -175.98898) (xy 128.586738 -176.047654)
			(xy 128.586738 -177.461926) (xy 128.730248 -177.605436) (xy 129.603246 -177.605436) (xy 129.67208 -177.67427)
			(xy 130.978656 -177.67427)
		)
		(stroke
			(width 0)
			(type solid)
		)
		(fill yes)
		(layer "B.Cu")
		(net "P3V3_DB2000QL_VDDR")
	)
	(gr_poly
		(pts
			(arc
				(start 259.742432 -80.867504)
				(mid 259.761819 -80.863554)
				(end 259.778246 -80.852518)
			)
			(arc
				(start 259.93344 -80.697324)
				(mid 259.944366 -80.680878)
				(end 259.948172 -80.66151)
			)
			(xy 259.948172 -78.62189) (xy 259.948172 -77.577696) (xy 259.751576 -77.3811) (xy 257.567938 -77.3811)
			(xy 257.436874 -77.512164)
			(arc
				(start 257.436874 -78.700122)
				(mid 257.425763 -78.716656)
				(end 257.421888 -78.73619)
			)
			(arc
				(start 257.421888 -80.558894)
				(mid 257.425789 -80.578417)
				(end 257.436874 -80.594962)
			)
			(arc
				(start 257.69443 -80.852518)
				(mid 257.710847 -80.86358)
				(end 257.730244 -80.867504)
			)
		)
		(stroke
			(width 0)
			(type solid)
		)
		(fill yes)
		(layer "B.Cu")
		(net "P3V3_CLK_GEN_VDDA100M_CK440")
	)
	(gr_poly
		(pts
			(arc
				(start 18.888202 -351.611438)
				(mid 18.638774 -351.611438)
				(end 18.888202 -351.611438)
			)
		)
		(stroke
			(width 0)
			(type solid)
		)
		(fill yes)
		(layer "B.Cu")
		(net "GND")
	)
	(gr_poly
		(pts
			(arc
				(start 18.888202 -348.58579)
				(mid 18.638774 -348.58579)
				(end 18.888202 -348.58579)
			)
		)
		(stroke
			(width 0)
			(type solid)
		)
		(fill yes)
		(layer "B.Cu")
		(net "GND")
	)
	(gr_poly
		(pts
			(arc
				(start 18.888202 -345.465146)
				(mid 18.638774 -345.465146)
				(end 18.888202 -345.465146)
			)
		)
		(stroke
			(width 0)
			(type solid)
		)
		(fill yes)
		(layer "B.Cu")
		(net "GND")
	)
	(gr_poly
		(pts
			(arc
				(start 18.888202 -342.439498)
				(mid 18.638774 -342.439498)
				(end 18.888202 -342.439498)
			)
		)
		(stroke
			(width 0)
			(type solid)
		)
		(fill yes)
		(layer "B.Cu")
		(net "GND")
	)
	(gr_poly
		(pts
			(arc
				(start 20.889722 -351.611438)
				(mid 20.640294 -351.611438)
				(end 20.889722 -351.611438)
			)
		)
		(stroke
			(width 0)
			(type solid)
		)
		(fill yes)
		(layer "B.Cu")
		(net "GND")
	)
	(gr_poly
		(pts
			(arc
				(start 20.889722 -348.58579)
				(mid 20.640294 -348.58579)
				(end 20.889722 -348.58579)
			)
		)
		(stroke
			(width 0)
			(type solid)
		)
		(fill yes)
		(layer "B.Cu")
		(net "GND")
	)
	(gr_poly
		(pts
			(arc
				(start 20.889722 -345.465146)
				(mid 20.640294 -345.465146)
				(end 20.889722 -345.465146)
			)
		)
		(stroke
			(width 0)
			(type solid)
		)
		(fill yes)
		(layer "B.Cu")
		(net "GND")
	)
	(gr_poly
		(pts
			(arc
				(start 20.889722 -342.439498)
				(mid 20.640294 -342.439498)
				(end 20.889722 -342.439498)
			)
		)
		(stroke
			(width 0)
			(type solid)
		)
		(fill yes)
		(layer "B.Cu")
		(net "GND")
	)
	(gr_poly
		(pts
			(arc
				(start 21.997162 -357.75773)
				(mid 21.747734 -357.75773)
				(end 21.997162 -357.75773)
			)
		)
		(stroke
			(width 0)
			(type solid)
		)
		(fill yes)
		(layer "B.Cu")
		(net "GND")
	)
	(gr_poly
		(pts
			(arc
				(start 21.997162 -354.732082)
				(mid 21.747734 -354.732082)
				(end 21.997162 -354.732082)
			)
		)
		(stroke
			(width 0)
			(type solid)
		)
		(fill yes)
		(layer "B.Cu")
		(net "GND")
	)
	(gr_poly
		(pts
			(arc
				(start 21.997162 -351.611438)
				(mid 21.747734 -351.611438)
				(end 21.997162 -351.611438)
			)
		)
		(stroke
			(width 0)
			(type solid)
		)
		(fill yes)
		(layer "B.Cu")
		(net "GND")
	)
	(gr_poly
		(pts
			(arc
				(start 21.997162 -348.58579)
				(mid 21.747734 -348.58579)
				(end 21.997162 -348.58579)
			)
		)
		(stroke
			(width 0)
			(type solid)
		)
		(fill yes)
		(layer "B.Cu")
		(net "GND")
	)
	(gr_poly
		(pts
			(arc
				(start 21.997162 -345.465146)
				(mid 21.747734 -345.465146)
				(end 21.997162 -345.465146)
			)
		)
		(stroke
			(width 0)
			(type solid)
		)
		(fill yes)
		(layer "B.Cu")
		(net "GND")
	)
	(gr_poly
		(pts
			(arc
				(start 21.997162 -342.439498)
				(mid 21.747734 -342.439498)
				(end 21.997162 -342.439498)
			)
		)
		(stroke
			(width 0)
			(type solid)
		)
		(fill yes)
		(layer "B.Cu")
		(net "GND")
	)
	(gr_poly
		(pts
			(arc
				(start 23.998682 -357.75773)
				(mid 23.749254 -357.75773)
				(end 23.998682 -357.75773)
			)
		)
		(stroke
			(width 0)
			(type solid)
		)
		(fill yes)
		(layer "B.Cu")
		(net "GND")
	)
	(gr_poly
		(pts
			(arc
				(start 23.998682 -354.732082)
				(mid 23.749254 -354.732082)
				(end 23.998682 -354.732082)
			)
		)
		(stroke
			(width 0)
			(type solid)
		)
		(fill yes)
		(layer "B.Cu")
		(net "GND")
	)
	(gr_poly
		(pts
			(arc
				(start 23.998682 -351.611438)
				(mid 23.749254 -351.611438)
				(end 23.998682 -351.611438)
			)
		)
		(stroke
			(width 0)
			(type solid)
		)
		(fill yes)
		(layer "B.Cu")
		(net "GND")
	)
	(gr_poly
		(pts
			(arc
				(start 23.998682 -348.58579)
				(mid 23.749254 -348.58579)
				(end 23.998682 -348.58579)
			)
		)
		(stroke
			(width 0)
			(type solid)
		)
		(fill yes)
		(layer "B.Cu")
		(net "GND")
	)
	(gr_poly
		(pts
			(arc
				(start 23.998682 -345.465146)
				(mid 23.749254 -345.465146)
				(end 23.998682 -345.465146)
			)
		)
		(stroke
			(width 0)
			(type solid)
		)
		(fill yes)
		(layer "B.Cu")
		(net "GND")
	)
	(gr_poly
		(pts
			(arc
				(start 23.998682 -342.439498)
				(mid 23.749254 -342.439498)
				(end 23.998682 -342.439498)
			)
		)
		(stroke
			(width 0)
			(type solid)
		)
		(fill yes)
		(layer "B.Cu")
		(net "GND")
	)
	(gr_poly
		(pts
			(arc
				(start 25.106122 -357.75773)
				(mid 24.856694 -357.75773)
				(end 25.106122 -357.75773)
			)
		)
		(stroke
			(width 0)
			(type solid)
		)
		(fill yes)
		(layer "B.Cu")
		(net "GND")
	)
	(gr_poly
		(pts
			(arc
				(start 25.106122 -354.732082)
				(mid 24.856694 -354.732082)
				(end 25.106122 -354.732082)
			)
		)
		(stroke
			(width 0)
			(type solid)
		)
		(fill yes)
		(layer "B.Cu")
		(net "GND")
	)
	(gr_poly
		(pts
			(arc
				(start 25.106122 -351.611438)
				(mid 24.856694 -351.611438)
				(end 25.106122 -351.611438)
			)
		)
		(stroke
			(width 0)
			(type solid)
		)
		(fill yes)
		(layer "B.Cu")
		(net "GND")
	)
	(gr_poly
		(pts
			(arc
				(start 25.106122 -348.58579)
				(mid 24.856694 -348.58579)
				(end 25.106122 -348.58579)
			)
		)
		(stroke
			(width 0)
			(type solid)
		)
		(fill yes)
		(layer "B.Cu")
		(net "GND")
	)
	(gr_poly
		(pts
			(arc
				(start 25.106122 -345.465146)
				(mid 24.856694 -345.465146)
				(end 25.106122 -345.465146)
			)
		)
		(stroke
			(width 0)
			(type solid)
		)
		(fill yes)
		(layer "B.Cu")
		(net "GND")
	)
	(gr_poly
		(pts
			(arc
				(start 25.106122 -342.439498)
				(mid 24.856694 -342.439498)
				(end 25.106122 -342.439498)
			)
		)
		(stroke
			(width 0)
			(type solid)
		)
		(fill yes)
		(layer "B.Cu")
		(net "GND")
	)
	(gr_poly
		(pts
			(arc
				(start 27.107642 -357.75773)
				(mid 26.858214 -357.75773)
				(end 27.107642 -357.75773)
			)
		)
		(stroke
			(width 0)
			(type solid)
		)
		(fill yes)
		(layer "B.Cu")
		(net "GND")
	)
	(gr_poly
		(pts
			(arc
				(start 27.107642 -354.732082)
				(mid 26.858214 -354.732082)
				(end 27.107642 -354.732082)
			)
		)
		(stroke
			(width 0)
			(type solid)
		)
		(fill yes)
		(layer "B.Cu")
		(net "GND")
	)
	(gr_poly
		(pts
			(arc
				(start 27.107642 -351.611438)
				(mid 26.858214 -351.611438)
				(end 27.107642 -351.611438)
			)
		)
		(stroke
			(width 0)
			(type solid)
		)
		(fill yes)
		(layer "B.Cu")
		(net "GND")
	)
	(gr_poly
		(pts
			(arc
				(start 27.107642 -348.58579)
				(mid 26.858214 -348.58579)
				(end 27.107642 -348.58579)
			)
		)
		(stroke
			(width 0)
			(type solid)
		)
		(fill yes)
		(layer "B.Cu")
		(net "GND")
	)
	(gr_poly
		(pts
			(arc
				(start 27.107642 -345.465146)
				(mid 26.858214 -345.465146)
				(end 27.107642 -345.465146)
			)
		)
		(stroke
			(width 0)
			(type solid)
		)
		(fill yes)
		(layer "B.Cu")
		(net "GND")
	)
	(gr_poly
		(pts
			(arc
				(start 27.107642 -342.439498)
				(mid 26.858214 -342.439498)
				(end 27.107642 -342.439498)
			)
		)
		(stroke
			(width 0)
			(type solid)
		)
		(fill yes)
		(layer "B.Cu")
		(net "GND")
	)
	(gr_poly
		(pts
			(arc
				(start 27.47264 -410.041852)
				(mid 27.223212 -410.041852)
				(end 27.47264 -410.041852)
			)
		)
		(stroke
			(width 0)
			(type solid)
		)
		(fill yes)
		(layer "B.Cu")
		(net "GND")
	)
	(gr_poly
		(pts
			(arc
				(start 27.47264 -408.840178)
				(mid 27.223212 -408.840178)
				(end 27.47264 -408.840178)
			)
		)
		(stroke
			(width 0)
			(type solid)
		)
		(fill yes)
		(layer "B.Cu")
		(net "GND")
	)
	(gr_poly
		(pts
			(arc
				(start 27.47264 -407.638504)
				(mid 27.223212 -407.638504)
				(end 27.47264 -407.638504)
			)
		)
		(stroke
			(width 0)
			(type solid)
		)
		(fill yes)
		(layer "B.Cu")
		(net "GND")
	)
	(gr_poly
		(pts
			(arc
				(start 27.47264 -406.141936)
				(mid 27.223212 -406.141936)
				(end 27.47264 -406.141936)
			)
		)
		(stroke
			(width 0)
			(type solid)
		)
		(fill yes)
		(layer "B.Cu")
		(net "GND")
	)
	(gr_poly
		(pts
			(arc
				(start 27.47264 -404.940262)
				(mid 27.223212 -404.940262)
				(end 27.47264 -404.940262)
			)
		)
		(stroke
			(width 0)
			(type solid)
		)
		(fill yes)
		(layer "B.Cu")
		(net "GND")
	)
	(gr_poly
		(pts
			(arc
				(start 27.47264 -403.738588)
				(mid 27.223212 -403.738588)
				(end 27.47264 -403.738588)
			)
		)
		(stroke
			(width 0)
			(type solid)
		)
		(fill yes)
		(layer "B.Cu")
		(net "GND")
	)
	(gr_poly
		(pts
			(arc
				(start 27.47264 -402.241766)
				(mid 27.223212 -402.241766)
				(end 27.47264 -402.241766)
			)
		)
		(stroke
			(width 0)
			(type solid)
		)
		(fill yes)
		(layer "B.Cu")
		(net "GND")
	)
	(gr_poly
		(pts
			(arc
				(start 27.47264 -401.040092)
				(mid 27.223212 -401.040092)
				(end 27.47264 -401.040092)
			)
		)
		(stroke
			(width 0)
			(type solid)
		)
		(fill yes)
		(layer "B.Cu")
		(net "GND")
	)
	(gr_poly
		(pts
			(arc
				(start 27.47264 -399.838418)
				(mid 27.223212 -399.838418)
				(end 27.47264 -399.838418)
			)
		)
		(stroke
			(width 0)
			(type solid)
		)
		(fill yes)
		(layer "B.Cu")
		(net "GND")
	)
	(gr_poly
		(pts
			(arc
				(start 27.47264 -398.34185)
				(mid 27.223212 -398.34185)
				(end 27.47264 -398.34185)
			)
		)
		(stroke
			(width 0)
			(type solid)
		)
		(fill yes)
		(layer "B.Cu")
		(net "GND")
	)
	(gr_poly
		(pts
			(arc
				(start 27.47264 -397.140176)
				(mid 27.223212 -397.140176)
				(end 27.47264 -397.140176)
			)
		)
		(stroke
			(width 0)
			(type solid)
		)
		(fill yes)
		(layer "B.Cu")
		(net "GND")
	)
	(gr_poly
		(pts
			(arc
				(start 27.47264 -395.938502)
				(mid 27.223212 -395.938502)
				(end 27.47264 -395.938502)
			)
		)
		(stroke
			(width 0)
			(type solid)
		)
		(fill yes)
		(layer "B.Cu")
		(net "GND")
	)
	(gr_poly
		(pts
			(arc
				(start 27.47264 -384.041904)
				(mid 27.223212 -384.041904)
				(end 27.47264 -384.041904)
			)
		)
		(stroke
			(width 0)
			(type solid)
		)
		(fill yes)
		(layer "B.Cu")
		(net "GND")
	)
	(gr_poly
		(pts
			(arc
				(start 27.47264 -382.84023)
				(mid 27.223212 -382.84023)
				(end 27.47264 -382.84023)
			)
		)
		(stroke
			(width 0)
			(type solid)
		)
		(fill yes)
		(layer "B.Cu")
		(net "GND")
	)
	(gr_poly
		(pts
			(arc
				(start 27.47264 -381.638556)
				(mid 27.223212 -381.638556)
				(end 27.47264 -381.638556)
			)
		)
		(stroke
			(width 0)
			(type solid)
		)
		(fill yes)
		(layer "B.Cu")
		(net "GND")
	)
	(gr_poly
		(pts
			(arc
				(start 27.47264 -380.141988)
				(mid 27.223212 -380.141988)
				(end 27.47264 -380.141988)
			)
		)
		(stroke
			(width 0)
			(type solid)
		)
		(fill yes)
		(layer "B.Cu")
		(net "GND")
	)
	(gr_poly
		(pts
			(arc
				(start 27.47264 -378.940314)
				(mid 27.223212 -378.940314)
				(end 27.47264 -378.940314)
			)
		)
		(stroke
			(width 0)
			(type solid)
		)
		(fill yes)
		(layer "B.Cu")
		(net "GND")
	)
	(gr_poly
		(pts
			(arc
				(start 27.47264 -377.73864)
				(mid 27.223212 -377.73864)
				(end 27.47264 -377.73864)
			)
		)
		(stroke
			(width 0)
			(type solid)
		)
		(fill yes)
		(layer "B.Cu")
		(net "GND")
	)
	(gr_poly
		(pts
			(arc
				(start 27.47264 -376.241818)
				(mid 27.223212 -376.241818)
				(end 27.47264 -376.241818)
			)
		)
		(stroke
			(width 0)
			(type solid)
		)
		(fill yes)
		(layer "B.Cu")
		(net "GND")
	)
	(gr_poly
		(pts
			(arc
				(start 27.47264 -375.040144)
				(mid 27.223212 -375.040144)
				(end 27.47264 -375.040144)
			)
		)
		(stroke
			(width 0)
			(type solid)
		)
		(fill yes)
		(layer "B.Cu")
		(net "GND")
	)
	(gr_poly
		(pts
			(arc
				(start 27.47264 -373.83847)
				(mid 27.223212 -373.83847)
				(end 27.47264 -373.83847)
			)
		)
		(stroke
			(width 0)
			(type solid)
		)
		(fill yes)
		(layer "B.Cu")
		(net "GND")
	)
	(gr_poly
		(pts
			(arc
				(start 27.47264 -372.341902)
				(mid 27.223212 -372.341902)
				(end 27.47264 -372.341902)
			)
		)
		(stroke
			(width 0)
			(type solid)
		)
		(fill yes)
		(layer "B.Cu")
		(net "GND")
	)
	(gr_poly
		(pts
			(arc
				(start 27.47264 -371.140228)
				(mid 27.223212 -371.140228)
				(end 27.47264 -371.140228)
			)
		)
		(stroke
			(width 0)
			(type solid)
		)
		(fill yes)
		(layer "B.Cu")
		(net "GND")
	)
	(gr_poly
		(pts
			(arc
				(start 27.47264 -369.938554)
				(mid 27.223212 -369.938554)
				(end 27.47264 -369.938554)
			)
		)
		(stroke
			(width 0)
			(type solid)
		)
		(fill yes)
		(layer "B.Cu")
		(net "GND")
	)
	(gr_poly
		(pts
			(arc
				(start 28.215082 -357.75773)
				(mid 27.965654 -357.75773)
				(end 28.215082 -357.75773)
			)
		)
		(stroke
			(width 0)
			(type solid)
		)
		(fill yes)
		(layer "B.Cu")
		(net "GND")
	)
	(gr_poly
		(pts
			(arc
				(start 28.215082 -354.732082)
				(mid 27.965654 -354.732082)
				(end 28.215082 -354.732082)
			)
		)
		(stroke
			(width 0)
			(type solid)
		)
		(fill yes)
		(layer "B.Cu")
		(net "GND")
	)
	(gr_poly
		(pts
			(arc
				(start 28.215082 -351.611438)
				(mid 27.965654 -351.611438)
				(end 28.215082 -351.611438)
			)
		)
		(stroke
			(width 0)
			(type solid)
		)
		(fill yes)
		(layer "B.Cu")
		(net "GND")
	)
	(gr_poly
		(pts
			(arc
				(start 28.215082 -348.58579)
				(mid 27.965654 -348.58579)
				(end 28.215082 -348.58579)
			)
		)
		(stroke
			(width 0)
			(type solid)
		)
		(fill yes)
		(layer "B.Cu")
		(net "GND")
	)
	(gr_poly
		(pts
			(arc
				(start 28.215082 -345.465146)
				(mid 27.965654 -345.465146)
				(end 28.215082 -345.465146)
			)
		)
		(stroke
			(width 0)
			(type solid)
		)
		(fill yes)
		(layer "B.Cu")
		(net "GND")
	)
	(gr_poly
		(pts
			(arc
				(start 28.215082 -342.439498)
				(mid 27.965654 -342.439498)
				(end 28.215082 -342.439498)
			)
		)
		(stroke
			(width 0)
			(type solid)
		)
		(fill yes)
		(layer "B.Cu")
		(net "GND")
	)
	(gr_poly
		(pts
			(arc
				(start 29.672534 -411.141926)
				(mid 29.423106 -411.141926)
				(end 29.672534 -411.141926)
			)
		)
		(stroke
			(width 0)
			(type solid)
		)
		(fill yes)
		(layer "B.Cu")
		(net "GND")
	)
	(gr_poly
		(pts
			(arc
				(start 29.672534 -409.940252)
				(mid 29.423106 -409.940252)
				(end 29.672534 -409.940252)
			)
		)
		(stroke
			(width 0)
			(type solid)
		)
		(fill yes)
		(layer "B.Cu")
		(net "GND")
	)
	(gr_poly
		(pts
			(arc
				(start 29.672534 -408.738578)
				(mid 29.423106 -408.738578)
				(end 29.672534 -408.738578)
			)
		)
		(stroke
			(width 0)
			(type solid)
		)
		(fill yes)
		(layer "B.Cu")
		(net "GND")
	)
	(gr_poly
		(pts
			(arc
				(start 29.672534 -407.24201)
				(mid 29.423106 -407.24201)
				(end 29.672534 -407.24201)
			)
		)
		(stroke
			(width 0)
			(type solid)
		)
		(fill yes)
		(layer "B.Cu")
		(net "GND")
	)
	(gr_poly
		(pts
			(arc
				(start 29.672534 -406.040336)
				(mid 29.423106 -406.040336)
				(end 29.672534 -406.040336)
			)
		)
		(stroke
			(width 0)
			(type solid)
		)
		(fill yes)
		(layer "B.Cu")
		(net "GND")
	)
	(gr_poly
		(pts
			(arc
				(start 29.672534 -404.838662)
				(mid 29.423106 -404.838662)
				(end 29.672534 -404.838662)
			)
		)
		(stroke
			(width 0)
			(type solid)
		)
		(fill yes)
		(layer "B.Cu")
		(net "GND")
	)
	(gr_poly
		(pts
			(arc
				(start 29.672534 -403.34184)
				(mid 29.423106 -403.34184)
				(end 29.672534 -403.34184)
			)
		)
		(stroke
			(width 0)
			(type solid)
		)
		(fill yes)
		(layer "B.Cu")
		(net "GND")
	)
	(gr_poly
		(pts
			(arc
				(start 29.672534 -402.140166)
				(mid 29.423106 -402.140166)
				(end 29.672534 -402.140166)
			)
		)
		(stroke
			(width 0)
			(type solid)
		)
		(fill yes)
		(layer "B.Cu")
		(net "GND")
	)
	(gr_poly
		(pts
			(arc
				(start 29.672534 -400.938492)
				(mid 29.423106 -400.938492)
				(end 29.672534 -400.938492)
			)
		)
		(stroke
			(width 0)
			(type solid)
		)
		(fill yes)
		(layer "B.Cu")
		(net "GND")
	)
	(gr_poly
		(pts
			(arc
				(start 29.672534 -399.441924)
				(mid 29.423106 -399.441924)
				(end 29.672534 -399.441924)
			)
		)
		(stroke
			(width 0)
			(type solid)
		)
		(fill yes)
		(layer "B.Cu")
		(net "GND")
	)
	(gr_poly
		(pts
			(arc
				(start 29.672534 -398.24025)
				(mid 29.423106 -398.24025)
				(end 29.672534 -398.24025)
			)
		)
		(stroke
			(width 0)
			(type solid)
		)
		(fill yes)
		(layer "B.Cu")
		(net "GND")
	)
	(gr_poly
		(pts
			(arc
				(start 29.672534 -397.038576)
				(mid 29.423106 -397.038576)
				(end 29.672534 -397.038576)
			)
		)
		(stroke
			(width 0)
			(type solid)
		)
		(fill yes)
		(layer "B.Cu")
		(net "GND")
	)
	(gr_poly
		(pts
			(arc
				(start 29.672534 -385.141978)
				(mid 29.423106 -385.141978)
				(end 29.672534 -385.141978)
			)
		)
		(stroke
			(width 0)
			(type solid)
		)
		(fill yes)
		(layer "B.Cu")
		(net "GND")
	)
	(gr_poly
		(pts
			(arc
				(start 29.672534 -383.940304)
				(mid 29.423106 -383.940304)
				(end 29.672534 -383.940304)
			)
		)
		(stroke
			(width 0)
			(type solid)
		)
		(fill yes)
		(layer "B.Cu")
		(net "GND")
	)
	(gr_poly
		(pts
			(arc
				(start 29.672534 -382.73863)
				(mid 29.423106 -382.73863)
				(end 29.672534 -382.73863)
			)
		)
		(stroke
			(width 0)
			(type solid)
		)
		(fill yes)
		(layer "B.Cu")
		(net "GND")
	)
	(gr_poly
		(pts
			(arc
				(start 29.672534 -381.242062)
				(mid 29.423106 -381.242062)
				(end 29.672534 -381.242062)
			)
		)
		(stroke
			(width 0)
			(type solid)
		)
		(fill yes)
		(layer "B.Cu")
		(net "GND")
	)
	(gr_poly
		(pts
			(arc
				(start 29.672534 -380.040388)
				(mid 29.423106 -380.040388)
				(end 29.672534 -380.040388)
			)
		)
		(stroke
			(width 0)
			(type solid)
		)
		(fill yes)
		(layer "B.Cu")
		(net "GND")
	)
	(gr_poly
		(pts
			(arc
				(start 29.672534 -378.838714)
				(mid 29.423106 -378.838714)
				(end 29.672534 -378.838714)
			)
		)
		(stroke
			(width 0)
			(type solid)
		)
		(fill yes)
		(layer "B.Cu")
		(net "GND")
	)
	(gr_poly
		(pts
			(arc
				(start 29.672534 -377.341892)
				(mid 29.423106 -377.341892)
				(end 29.672534 -377.341892)
			)
		)
		(stroke
			(width 0)
			(type solid)
		)
		(fill yes)
		(layer "B.Cu")
		(net "GND")
	)
	(gr_poly
		(pts
			(arc
				(start 29.672534 -376.140218)
				(mid 29.423106 -376.140218)
				(end 29.672534 -376.140218)
			)
		)
		(stroke
			(width 0)
			(type solid)
		)
		(fill yes)
		(layer "B.Cu")
		(net "GND")
	)
	(gr_poly
		(pts
			(arc
				(start 29.672534 -374.938544)
				(mid 29.423106 -374.938544)
				(end 29.672534 -374.938544)
			)
		)
		(stroke
			(width 0)
			(type solid)
		)
		(fill yes)
		(layer "B.Cu")
		(net "GND")
	)
	(gr_poly
		(pts
			(arc
				(start 29.672534 -373.441976)
				(mid 29.423106 -373.441976)
				(end 29.672534 -373.441976)
			)
		)
		(stroke
			(width 0)
			(type solid)
		)
		(fill yes)
		(layer "B.Cu")
		(net "GND")
	)
	(gr_poly
		(pts
			(arc
				(start 29.672534 -372.240302)
				(mid 29.423106 -372.240302)
				(end 29.672534 -372.240302)
			)
		)
		(stroke
			(width 0)
			(type solid)
		)
		(fill yes)
		(layer "B.Cu")
		(net "GND")
	)
	(gr_poly
		(pts
			(arc
				(start 29.672534 -371.038628)
				(mid 29.423106 -371.038628)
				(end 29.672534 -371.038628)
			)
		)
		(stroke
			(width 0)
			(type solid)
		)
		(fill yes)
		(layer "B.Cu")
		(net "GND")
	)
	(gr_poly
		(pts
			(arc
				(start 30.216602 -357.75773)
				(mid 29.967174 -357.75773)
				(end 30.216602 -357.75773)
			)
		)
		(stroke
			(width 0)
			(type solid)
		)
		(fill yes)
		(layer "B.Cu")
		(net "GND")
	)
	(gr_poly
		(pts
			(arc
				(start 30.216602 -354.732082)
				(mid 29.967174 -354.732082)
				(end 30.216602 -354.732082)
			)
		)
		(stroke
			(width 0)
			(type solid)
		)
		(fill yes)
		(layer "B.Cu")
		(net "GND")
	)
	(gr_poly
		(pts
			(arc
				(start 30.216602 -351.611438)
				(mid 29.967174 -351.611438)
				(end 30.216602 -351.611438)
			)
		)
		(stroke
			(width 0)
			(type solid)
		)
		(fill yes)
		(layer "B.Cu")
		(net "GND")
	)
	(gr_poly
		(pts
			(arc
				(start 30.216602 -348.58579)
				(mid 29.967174 -348.58579)
				(end 30.216602 -348.58579)
			)
		)
		(stroke
			(width 0)
			(type solid)
		)
		(fill yes)
		(layer "B.Cu")
		(net "GND")
	)
	(gr_poly
		(pts
			(arc
				(start 30.216602 -345.465146)
				(mid 29.967174 -345.465146)
				(end 30.216602 -345.465146)
			)
		)
		(stroke
			(width 0)
			(type solid)
		)
		(fill yes)
		(layer "B.Cu")
		(net "GND")
	)
	(gr_poly
		(pts
			(arc
				(start 30.216602 -342.439498)
				(mid 29.967174 -342.439498)
				(end 30.216602 -342.439498)
			)
		)
		(stroke
			(width 0)
			(type solid)
		)
		(fill yes)
		(layer "B.Cu")
		(net "GND")
	)
	(gr_poly
		(pts
			(arc
				(start 31.324042 -357.75773)
				(mid 31.074614 -357.75773)
				(end 31.324042 -357.75773)
			)
		)
		(stroke
			(width 0)
			(type solid)
		)
		(fill yes)
		(layer "B.Cu")
		(net "GND")
	)
	(gr_poly
		(pts
			(arc
				(start 31.324042 -354.732082)
				(mid 31.074614 -354.732082)
				(end 31.324042 -354.732082)
			)
		)
		(stroke
			(width 0)
			(type solid)
		)
		(fill yes)
		(layer "B.Cu")
		(net "GND")
	)
	(gr_poly
		(pts
			(arc
				(start 31.324042 -351.611438)
				(mid 31.074614 -351.611438)
				(end 31.324042 -351.611438)
			)
		)
		(stroke
			(width 0)
			(type solid)
		)
		(fill yes)
		(layer "B.Cu")
		(net "GND")
	)
	(gr_poly
		(pts
			(arc
				(start 31.324042 -348.58579)
				(mid 31.074614 -348.58579)
				(end 31.324042 -348.58579)
			)
		)
		(stroke
			(width 0)
			(type solid)
		)
		(fill yes)
		(layer "B.Cu")
		(net "GND")
	)
	(gr_poly
		(pts
			(arc
				(start 31.324042 -345.465146)
				(mid 31.074614 -345.465146)
				(end 31.324042 -345.465146)
			)
		)
		(stroke
			(width 0)
			(type solid)
		)
		(fill yes)
		(layer "B.Cu")
		(net "GND")
	)
	(gr_poly
		(pts
			(arc
				(start 31.324042 -342.439498)
				(mid 31.074614 -342.439498)
				(end 31.324042 -342.439498)
			)
		)
		(stroke
			(width 0)
			(type solid)
		)
		(fill yes)
		(layer "B.Cu")
		(net "GND")
	)
	(gr_poly
		(pts
			(arc
				(start 31.872682 -410.041852)
				(mid 31.623254 -410.041852)
				(end 31.872682 -410.041852)
			)
		)
		(stroke
			(width 0)
			(type solid)
		)
		(fill yes)
		(layer "B.Cu")
		(net "GND")
	)
	(gr_poly
		(pts
			(arc
				(start 31.872682 -408.840178)
				(mid 31.623254 -408.840178)
				(end 31.872682 -408.840178)
			)
		)
		(stroke
			(width 0)
			(type solid)
		)
		(fill yes)
		(layer "B.Cu")
		(net "GND")
	)
	(gr_poly
		(pts
			(arc
				(start 31.872682 -407.638504)
				(mid 31.623254 -407.638504)
				(end 31.872682 -407.638504)
			)
		)
		(stroke
			(width 0)
			(type solid)
		)
		(fill yes)
		(layer "B.Cu")
		(net "GND")
	)
	(gr_poly
		(pts
			(arc
				(start 31.872682 -406.141936)
				(mid 31.623254 -406.141936)
				(end 31.872682 -406.141936)
			)
		)
		(stroke
			(width 0)
			(type solid)
		)
		(fill yes)
		(layer "B.Cu")
		(net "GND")
	)
	(gr_poly
		(pts
			(arc
				(start 31.872682 -404.940262)
				(mid 31.623254 -404.940262)
				(end 31.872682 -404.940262)
			)
		)
		(stroke
			(width 0)
			(type solid)
		)
		(fill yes)
		(layer "B.Cu")
		(net "GND")
	)
	(gr_poly
		(pts
			(arc
				(start 31.872682 -403.738588)
				(mid 31.623254 -403.738588)
				(end 31.872682 -403.738588)
			)
		)
		(stroke
			(width 0)
			(type solid)
		)
		(fill yes)
		(layer "B.Cu")
		(net "GND")
	)
	(gr_poly
		(pts
			(arc
				(start 31.872682 -402.241766)
				(mid 31.623254 -402.241766)
				(end 31.872682 -402.241766)
			)
		)
		(stroke
			(width 0)
			(type solid)
		)
		(fill yes)
		(layer "B.Cu")
		(net "GND")
	)
	(gr_poly
		(pts
			(arc
				(start 31.872682 -401.040092)
				(mid 31.623254 -401.040092)
				(end 31.872682 -401.040092)
			)
		)
		(stroke
			(width 0)
			(type solid)
		)
		(fill yes)
		(layer "B.Cu")
		(net "GND")
	)
	(gr_poly
		(pts
			(arc
				(start 31.872682 -399.838418)
				(mid 31.623254 -399.838418)
				(end 31.872682 -399.838418)
			)
		)
		(stroke
			(width 0)
			(type solid)
		)
		(fill yes)
		(layer "B.Cu")
		(net "GND")
	)
	(gr_poly
		(pts
			(arc
				(start 31.872682 -398.34185)
				(mid 31.623254 -398.34185)
				(end 31.872682 -398.34185)
			)
		)
		(stroke
			(width 0)
			(type solid)
		)
		(fill yes)
		(layer "B.Cu")
		(net "GND")
	)
	(gr_poly
		(pts
			(arc
				(start 31.872682 -397.140176)
				(mid 31.623254 -397.140176)
				(end 31.872682 -397.140176)
			)
		)
		(stroke
			(width 0)
			(type solid)
		)
		(fill yes)
		(layer "B.Cu")
		(net "GND")
	)
	(gr_poly
		(pts
			(arc
				(start 31.872682 -395.938502)
				(mid 31.623254 -395.938502)
				(end 31.872682 -395.938502)
			)
		)
		(stroke
			(width 0)
			(type solid)
		)
		(fill yes)
		(layer "B.Cu")
		(net "GND")
	)
	(gr_poly
		(pts
			(arc
				(start 31.872682 -384.041904)
				(mid 31.623254 -384.041904)
				(end 31.872682 -384.041904)
			)
		)
		(stroke
			(width 0)
			(type solid)
		)
		(fill yes)
		(layer "B.Cu")
		(net "GND")
	)
	(gr_poly
		(pts
			(arc
				(start 31.872682 -382.84023)
				(mid 31.623254 -382.84023)
				(end 31.872682 -382.84023)
			)
		)
		(stroke
			(width 0)
			(type solid)
		)
		(fill yes)
		(layer "B.Cu")
		(net "GND")
	)
	(gr_poly
		(pts
			(arc
				(start 31.872682 -381.638556)
				(mid 31.623254 -381.638556)
				(end 31.872682 -381.638556)
			)
		)
		(stroke
			(width 0)
			(type solid)
		)
		(fill yes)
		(layer "B.Cu")
		(net "GND")
	)
	(gr_poly
		(pts
			(arc
				(start 31.872682 -380.141988)
				(mid 31.623254 -380.141988)
				(end 31.872682 -380.141988)
			)
		)
		(stroke
			(width 0)
			(type solid)
		)
		(fill yes)
		(layer "B.Cu")
		(net "GND")
	)
	(gr_poly
		(pts
			(arc
				(start 31.872682 -378.940314)
				(mid 31.623254 -378.940314)
				(end 31.872682 -378.940314)
			)
		)
		(stroke
			(width 0)
			(type solid)
		)
		(fill yes)
		(layer "B.Cu")
		(net "GND")
	)
	(gr_poly
		(pts
			(arc
				(start 31.872682 -377.73864)
				(mid 31.623254 -377.73864)
				(end 31.872682 -377.73864)
			)
		)
		(stroke
			(width 0)
			(type solid)
		)
		(fill yes)
		(layer "B.Cu")
		(net "GND")
	)
	(gr_poly
		(pts
			(arc
				(start 31.872682 -376.241818)
				(mid 31.623254 -376.241818)
				(end 31.872682 -376.241818)
			)
		)
		(stroke
			(width 0)
			(type solid)
		)
		(fill yes)
		(layer "B.Cu")
		(net "GND")
	)
	(gr_poly
		(pts
			(arc
				(start 31.872682 -375.040144)
				(mid 31.623254 -375.040144)
				(end 31.872682 -375.040144)
			)
		)
		(stroke
			(width 0)
			(type solid)
		)
		(fill yes)
		(layer "B.Cu")
		(net "GND")
	)
	(gr_poly
		(pts
			(arc
				(start 31.872682 -373.83847)
				(mid 31.623254 -373.83847)
				(end 31.872682 -373.83847)
			)
		)
		(stroke
			(width 0)
			(type solid)
		)
		(fill yes)
		(layer "B.Cu")
		(net "GND")
	)
	(gr_poly
		(pts
			(arc
				(start 31.872682 -372.341902)
				(mid 31.623254 -372.341902)
				(end 31.872682 -372.341902)
			)
		)
		(stroke
			(width 0)
			(type solid)
		)
		(fill yes)
		(layer "B.Cu")
		(net "GND")
	)
	(gr_poly
		(pts
			(arc
				(start 31.872682 -371.140228)
				(mid 31.623254 -371.140228)
				(end 31.872682 -371.140228)
			)
		)
		(stroke
			(width 0)
			(type solid)
		)
		(fill yes)
		(layer "B.Cu")
		(net "GND")
	)
	(gr_poly
		(pts
			(arc
				(start 31.872682 -369.938554)
				(mid 31.623254 -369.938554)
				(end 31.872682 -369.938554)
			)
		)
		(stroke
			(width 0)
			(type solid)
		)
		(fill yes)
		(layer "B.Cu")
		(net "GND")
	)
	(gr_poly
		(pts
			(arc
				(start 33.325562 -357.75773)
				(mid 33.076134 -357.75773)
				(end 33.325562 -357.75773)
			)
		)
		(stroke
			(width 0)
			(type solid)
		)
		(fill yes)
		(layer "B.Cu")
		(net "GND")
	)
	(gr_poly
		(pts
			(arc
				(start 33.325562 -354.732082)
				(mid 33.076134 -354.732082)
				(end 33.325562 -354.732082)
			)
		)
		(stroke
			(width 0)
			(type solid)
		)
		(fill yes)
		(layer "B.Cu")
		(net "GND")
	)
	(gr_poly
		(pts
			(arc
				(start 33.325562 -351.611438)
				(mid 33.076134 -351.611438)
				(end 33.325562 -351.611438)
			)
		)
		(stroke
			(width 0)
			(type solid)
		)
		(fill yes)
		(layer "B.Cu")
		(net "GND")
	)
	(gr_poly
		(pts
			(arc
				(start 33.325562 -348.58579)
				(mid 33.076134 -348.58579)
				(end 33.325562 -348.58579)
			)
		)
		(stroke
			(width 0)
			(type solid)
		)
		(fill yes)
		(layer "B.Cu")
		(net "GND")
	)
	(gr_poly
		(pts
			(arc
				(start 33.325562 -345.465146)
				(mid 33.076134 -345.465146)
				(end 33.325562 -345.465146)
			)
		)
		(stroke
			(width 0)
			(type solid)
		)
		(fill yes)
		(layer "B.Cu")
		(net "GND")
	)
	(gr_poly
		(pts
			(arc
				(start 33.325562 -342.439498)
				(mid 33.076134 -342.439498)
				(end 33.325562 -342.439498)
			)
		)
		(stroke
			(width 0)
			(type solid)
		)
		(fill yes)
		(layer "B.Cu")
		(net "GND")
	)
	(gr_poly
		(pts
			(arc
				(start 34.072576 -411.141926)
				(mid 33.823148 -411.141926)
				(end 34.072576 -411.141926)
			)
		)
		(stroke
			(width 0)
			(type solid)
		)
		(fill yes)
		(layer "B.Cu")
		(net "GND")
	)
	(gr_poly
		(pts
			(arc
				(start 34.072576 -409.940252)
				(mid 33.823148 -409.940252)
				(end 34.072576 -409.940252)
			)
		)
		(stroke
			(width 0)
			(type solid)
		)
		(fill yes)
		(layer "B.Cu")
		(net "GND")
	)
	(gr_poly
		(pts
			(arc
				(start 34.072576 -408.738578)
				(mid 33.823148 -408.738578)
				(end 34.072576 -408.738578)
			)
		)
		(stroke
			(width 0)
			(type solid)
		)
		(fill yes)
		(layer "B.Cu")
		(net "GND")
	)
	(gr_poly
		(pts
			(arc
				(start 34.072576 -407.24201)
				(mid 33.823148 -407.24201)
				(end 34.072576 -407.24201)
			)
		)
		(stroke
			(width 0)
			(type solid)
		)
		(fill yes)
		(layer "B.Cu")
		(net "GND")
	)
	(gr_poly
		(pts
			(arc
				(start 34.072576 -406.040336)
				(mid 33.823148 -406.040336)
				(end 34.072576 -406.040336)
			)
		)
		(stroke
			(width 0)
			(type solid)
		)
		(fill yes)
		(layer "B.Cu")
		(net "GND")
	)
	(gr_poly
		(pts
			(arc
				(start 34.072576 -404.838662)
				(mid 33.823148 -404.838662)
				(end 34.072576 -404.838662)
			)
		)
		(stroke
			(width 0)
			(type solid)
		)
		(fill yes)
		(layer "B.Cu")
		(net "GND")
	)
	(gr_poly
		(pts
			(arc
				(start 34.072576 -403.34184)
				(mid 33.823148 -403.34184)
				(end 34.072576 -403.34184)
			)
		)
		(stroke
			(width 0)
			(type solid)
		)
		(fill yes)
		(layer "B.Cu")
		(net "GND")
	)
	(gr_poly
		(pts
			(arc
				(start 34.072576 -402.140166)
				(mid 33.823148 -402.140166)
				(end 34.072576 -402.140166)
			)
		)
		(stroke
			(width 0)
			(type solid)
		)
		(fill yes)
		(layer "B.Cu")
		(net "GND")
	)
	(gr_poly
		(pts
			(arc
				(start 34.072576 -400.938492)
				(mid 33.823148 -400.938492)
				(end 34.072576 -400.938492)
			)
		)
		(stroke
			(width 0)
			(type solid)
		)
		(fill yes)
		(layer "B.Cu")
		(net "GND")
	)
	(gr_poly
		(pts
			(arc
				(start 34.072576 -399.441924)
				(mid 33.823148 -399.441924)
				(end 34.072576 -399.441924)
			)
		)
		(stroke
			(width 0)
			(type solid)
		)
		(fill yes)
		(layer "B.Cu")
		(net "GND")
	)
	(gr_poly
		(pts
			(arc
				(start 34.072576 -398.24025)
				(mid 33.823148 -398.24025)
				(end 34.072576 -398.24025)
			)
		)
		(stroke
			(width 0)
			(type solid)
		)
		(fill yes)
		(layer "B.Cu")
		(net "GND")
	)
	(gr_poly
		(pts
			(arc
				(start 34.072576 -397.038576)
				(mid 33.823148 -397.038576)
				(end 34.072576 -397.038576)
			)
		)
		(stroke
			(width 0)
			(type solid)
		)
		(fill yes)
		(layer "B.Cu")
		(net "GND")
	)
	(gr_poly
		(pts
			(arc
				(start 34.072576 -385.141978)
				(mid 33.823148 -385.141978)
				(end 34.072576 -385.141978)
			)
		)
		(stroke
			(width 0)
			(type solid)
		)
		(fill yes)
		(layer "B.Cu")
		(net "GND")
	)
	(gr_poly
		(pts
			(arc
				(start 34.072576 -383.940304)
				(mid 33.823148 -383.940304)
				(end 34.072576 -383.940304)
			)
		)
		(stroke
			(width 0)
			(type solid)
		)
		(fill yes)
		(layer "B.Cu")
		(net "GND")
	)
	(gr_poly
		(pts
			(arc
				(start 34.072576 -382.73863)
				(mid 33.823148 -382.73863)
				(end 34.072576 -382.73863)
			)
		)
		(stroke
			(width 0)
			(type solid)
		)
		(fill yes)
		(layer "B.Cu")
		(net "GND")
	)
	(gr_poly
		(pts
			(arc
				(start 34.072576 -381.242062)
				(mid 33.823148 -381.242062)
				(end 34.072576 -381.242062)
			)
		)
		(stroke
			(width 0)
			(type solid)
		)
		(fill yes)
		(layer "B.Cu")
		(net "GND")
	)
	(gr_poly
		(pts
			(arc
				(start 34.072576 -380.040388)
				(mid 33.823148 -380.040388)
				(end 34.072576 -380.040388)
			)
		)
		(stroke
			(width 0)
			(type solid)
		)
		(fill yes)
		(layer "B.Cu")
		(net "GND")
	)
	(gr_poly
		(pts
			(arc
				(start 34.072576 -378.838714)
				(mid 33.823148 -378.838714)
				(end 34.072576 -378.838714)
			)
		)
		(stroke
			(width 0)
			(type solid)
		)
		(fill yes)
		(layer "B.Cu")
		(net "GND")
	)
	(gr_poly
		(pts
			(arc
				(start 34.072576 -377.341892)
				(mid 33.823148 -377.341892)
				(end 34.072576 -377.341892)
			)
		)
		(stroke
			(width 0)
			(type solid)
		)
		(fill yes)
		(layer "B.Cu")
		(net "GND")
	)
	(gr_poly
		(pts
			(arc
				(start 34.072576 -376.140218)
				(mid 33.823148 -376.140218)
				(end 34.072576 -376.140218)
			)
		)
		(stroke
			(width 0)
			(type solid)
		)
		(fill yes)
		(layer "B.Cu")
		(net "GND")
	)
	(gr_poly
		(pts
			(arc
				(start 34.072576 -374.938544)
				(mid 33.823148 -374.938544)
				(end 34.072576 -374.938544)
			)
		)
		(stroke
			(width 0)
			(type solid)
		)
		(fill yes)
		(layer "B.Cu")
		(net "GND")
	)
	(gr_poly
		(pts
			(arc
				(start 34.072576 -373.441976)
				(mid 33.823148 -373.441976)
				(end 34.072576 -373.441976)
			)
		)
		(stroke
			(width 0)
			(type solid)
		)
		(fill yes)
		(layer "B.Cu")
		(net "GND")
	)
	(gr_poly
		(pts
			(arc
				(start 34.072576 -372.240302)
				(mid 33.823148 -372.240302)
				(end 34.072576 -372.240302)
			)
		)
		(stroke
			(width 0)
			(type solid)
		)
		(fill yes)
		(layer "B.Cu")
		(net "GND")
	)
	(gr_poly
		(pts
			(arc
				(start 34.072576 -371.038628)
				(mid 33.823148 -371.038628)
				(end 34.072576 -371.038628)
			)
		)
		(stroke
			(width 0)
			(type solid)
		)
		(fill yes)
		(layer "B.Cu")
		(net "GND")
	)
	(gr_poly
		(pts
			(arc
				(start 34.433002 -357.75773)
				(mid 34.183574 -357.75773)
				(end 34.433002 -357.75773)
			)
		)
		(stroke
			(width 0)
			(type solid)
		)
		(fill yes)
		(layer "B.Cu")
		(net "GND")
	)
	(gr_poly
		(pts
			(arc
				(start 34.433002 -354.732082)
				(mid 34.183574 -354.732082)
				(end 34.433002 -354.732082)
			)
		)
		(stroke
			(width 0)
			(type solid)
		)
		(fill yes)
		(layer "B.Cu")
		(net "GND")
	)
	(gr_poly
		(pts
			(arc
				(start 34.433002 -351.611438)
				(mid 34.183574 -351.611438)
				(end 34.433002 -351.611438)
			)
		)
		(stroke
			(width 0)
			(type solid)
		)
		(fill yes)
		(layer "B.Cu")
		(net "GND")
	)
	(gr_poly
		(pts
			(arc
				(start 34.433002 -348.58579)
				(mid 34.183574 -348.58579)
				(end 34.433002 -348.58579)
			)
		)
		(stroke
			(width 0)
			(type solid)
		)
		(fill yes)
		(layer "B.Cu")
		(net "GND")
	)
	(gr_poly
		(pts
			(arc
				(start 34.433002 -345.465146)
				(mid 34.183574 -345.465146)
				(end 34.433002 -345.465146)
			)
		)
		(stroke
			(width 0)
			(type solid)
		)
		(fill yes)
		(layer "B.Cu")
		(net "GND")
	)
	(gr_poly
		(pts
			(arc
				(start 34.433002 -342.439498)
				(mid 34.183574 -342.439498)
				(end 34.433002 -342.439498)
			)
		)
		(stroke
			(width 0)
			(type solid)
		)
		(fill yes)
		(layer "B.Cu")
		(net "GND")
	)
	(gr_poly
		(pts
			(arc
				(start 36.272724 -410.041852)
				(mid 36.023296 -410.041852)
				(end 36.272724 -410.041852)
			)
		)
		(stroke
			(width 0)
			(type solid)
		)
		(fill yes)
		(layer "B.Cu")
		(net "GND")
	)
	(gr_poly
		(pts
			(arc
				(start 36.272724 -408.840178)
				(mid 36.023296 -408.840178)
				(end 36.272724 -408.840178)
			)
		)
		(stroke
			(width 0)
			(type solid)
		)
		(fill yes)
		(layer "B.Cu")
		(net "GND")
	)
	(gr_poly
		(pts
			(arc
				(start 36.272724 -407.638504)
				(mid 36.023296 -407.638504)
				(end 36.272724 -407.638504)
			)
		)
		(stroke
			(width 0)
			(type solid)
		)
		(fill yes)
		(layer "B.Cu")
		(net "GND")
	)
	(gr_poly
		(pts
			(arc
				(start 36.272724 -406.141936)
				(mid 36.023296 -406.141936)
				(end 36.272724 -406.141936)
			)
		)
		(stroke
			(width 0)
			(type solid)
		)
		(fill yes)
		(layer "B.Cu")
		(net "GND")
	)
	(gr_poly
		(pts
			(arc
				(start 36.272724 -404.940262)
				(mid 36.023296 -404.940262)
				(end 36.272724 -404.940262)
			)
		)
		(stroke
			(width 0)
			(type solid)
		)
		(fill yes)
		(layer "B.Cu")
		(net "GND")
	)
	(gr_poly
		(pts
			(arc
				(start 36.272724 -403.738588)
				(mid 36.023296 -403.738588)
				(end 36.272724 -403.738588)
			)
		)
		(stroke
			(width 0)
			(type solid)
		)
		(fill yes)
		(layer "B.Cu")
		(net "GND")
	)
	(gr_poly
		(pts
			(arc
				(start 36.272724 -402.241766)
				(mid 36.023296 -402.241766)
				(end 36.272724 -402.241766)
			)
		)
		(stroke
			(width 0)
			(type solid)
		)
		(fill yes)
		(layer "B.Cu")
		(net "GND")
	)
	(gr_poly
		(pts
			(arc
				(start 36.272724 -401.040092)
				(mid 36.023296 -401.040092)
				(end 36.272724 -401.040092)
			)
		)
		(stroke
			(width 0)
			(type solid)
		)
		(fill yes)
		(layer "B.Cu")
		(net "GND")
	)
	(gr_poly
		(pts
			(arc
				(start 36.272724 -399.838418)
				(mid 36.023296 -399.838418)
				(end 36.272724 -399.838418)
			)
		)
		(stroke
			(width 0)
			(type solid)
		)
		(fill yes)
		(layer "B.Cu")
		(net "GND")
	)
	(gr_poly
		(pts
			(arc
				(start 36.272724 -398.34185)
				(mid 36.023296 -398.34185)
				(end 36.272724 -398.34185)
			)
		)
		(stroke
			(width 0)
			(type solid)
		)
		(fill yes)
		(layer "B.Cu")
		(net "GND")
	)
	(gr_poly
		(pts
			(arc
				(start 36.272724 -397.140176)
				(mid 36.023296 -397.140176)
				(end 36.272724 -397.140176)
			)
		)
		(stroke
			(width 0)
			(type solid)
		)
		(fill yes)
		(layer "B.Cu")
		(net "GND")
	)
	(gr_poly
		(pts
			(arc
				(start 36.272724 -395.938502)
				(mid 36.023296 -395.938502)
				(end 36.272724 -395.938502)
			)
		)
		(stroke
			(width 0)
			(type solid)
		)
		(fill yes)
		(layer "B.Cu")
		(net "GND")
	)
	(gr_poly
		(pts
			(arc
				(start 36.272724 -384.041904)
				(mid 36.023296 -384.041904)
				(end 36.272724 -384.041904)
			)
		)
		(stroke
			(width 0)
			(type solid)
		)
		(fill yes)
		(layer "B.Cu")
		(net "GND")
	)
	(gr_poly
		(pts
			(arc
				(start 36.272724 -382.84023)
				(mid 36.023296 -382.84023)
				(end 36.272724 -382.84023)
			)
		)
		(stroke
			(width 0)
			(type solid)
		)
		(fill yes)
		(layer "B.Cu")
		(net "GND")
	)
	(gr_poly
		(pts
			(arc
				(start 36.272724 -381.638556)
				(mid 36.023296 -381.638556)
				(end 36.272724 -381.638556)
			)
		)
		(stroke
			(width 0)
			(type solid)
		)
		(fill yes)
		(layer "B.Cu")
		(net "GND")
	)
	(gr_poly
		(pts
			(arc
				(start 36.272724 -380.141988)
				(mid 36.023296 -380.141988)
				(end 36.272724 -380.141988)
			)
		)
		(stroke
			(width 0)
			(type solid)
		)
		(fill yes)
		(layer "B.Cu")
		(net "GND")
	)
	(gr_poly
		(pts
			(arc
				(start 36.272724 -378.940314)
				(mid 36.023296 -378.940314)
				(end 36.272724 -378.940314)
			)
		)
		(stroke
			(width 0)
			(type solid)
		)
		(fill yes)
		(layer "B.Cu")
		(net "GND")
	)
	(gr_poly
		(pts
			(arc
				(start 36.272724 -377.73864)
				(mid 36.023296 -377.73864)
				(end 36.272724 -377.73864)
			)
		)
		(stroke
			(width 0)
			(type solid)
		)
		(fill yes)
		(layer "B.Cu")
		(net "GND")
	)
	(gr_poly
		(pts
			(arc
				(start 36.272724 -376.241818)
				(mid 36.023296 -376.241818)
				(end 36.272724 -376.241818)
			)
		)
		(stroke
			(width 0)
			(type solid)
		)
		(fill yes)
		(layer "B.Cu")
		(net "GND")
	)
	(gr_poly
		(pts
			(arc
				(start 36.272724 -375.040144)
				(mid 36.023296 -375.040144)
				(end 36.272724 -375.040144)
			)
		)
		(stroke
			(width 0)
			(type solid)
		)
		(fill yes)
		(layer "B.Cu")
		(net "GND")
	)
	(gr_poly
		(pts
			(arc
				(start 36.272724 -373.83847)
				(mid 36.023296 -373.83847)
				(end 36.272724 -373.83847)
			)
		)
		(stroke
			(width 0)
			(type solid)
		)
		(fill yes)
		(layer "B.Cu")
		(net "GND")
	)
	(gr_poly
		(pts
			(arc
				(start 36.272724 -372.341902)
				(mid 36.023296 -372.341902)
				(end 36.272724 -372.341902)
			)
		)
		(stroke
			(width 0)
			(type solid)
		)
		(fill yes)
		(layer "B.Cu")
		(net "GND")
	)
	(gr_poly
		(pts
			(arc
				(start 36.272724 -371.140228)
				(mid 36.023296 -371.140228)
				(end 36.272724 -371.140228)
			)
		)
		(stroke
			(width 0)
			(type solid)
		)
		(fill yes)
		(layer "B.Cu")
		(net "GND")
	)
	(gr_poly
		(pts
			(arc
				(start 36.272724 -369.938554)
				(mid 36.023296 -369.938554)
				(end 36.272724 -369.938554)
			)
		)
		(stroke
			(width 0)
			(type solid)
		)
		(fill yes)
		(layer "B.Cu")
		(net "GND")
	)
	(gr_poly
		(pts
			(arc
				(start 36.434522 -357.75773)
				(mid 36.185094 -357.75773)
				(end 36.434522 -357.75773)
			)
		)
		(stroke
			(width 0)
			(type solid)
		)
		(fill yes)
		(layer "B.Cu")
		(net "GND")
	)
	(gr_poly
		(pts
			(arc
				(start 36.434522 -354.732082)
				(mid 36.185094 -354.732082)
				(end 36.434522 -354.732082)
			)
		)
		(stroke
			(width 0)
			(type solid)
		)
		(fill yes)
		(layer "B.Cu")
		(net "GND")
	)
	(gr_poly
		(pts
			(arc
				(start 36.434522 -351.611438)
				(mid 36.185094 -351.611438)
				(end 36.434522 -351.611438)
			)
		)
		(stroke
			(width 0)
			(type solid)
		)
		(fill yes)
		(layer "B.Cu")
		(net "GND")
	)
	(gr_poly
		(pts
			(arc
				(start 36.434522 -348.58579)
				(mid 36.185094 -348.58579)
				(end 36.434522 -348.58579)
			)
		)
		(stroke
			(width 0)
			(type solid)
		)
		(fill yes)
		(layer "B.Cu")
		(net "GND")
	)
	(gr_poly
		(pts
			(arc
				(start 36.434522 -345.465146)
				(mid 36.185094 -345.465146)
				(end 36.434522 -345.465146)
			)
		)
		(stroke
			(width 0)
			(type solid)
		)
		(fill yes)
		(layer "B.Cu")
		(net "GND")
	)
	(gr_poly
		(pts
			(arc
				(start 36.434522 -342.439498)
				(mid 36.185094 -342.439498)
				(end 36.434522 -342.439498)
			)
		)
		(stroke
			(width 0)
			(type solid)
		)
		(fill yes)
		(layer "B.Cu")
		(net "GND")
	)
	(gr_poly
		(pts
			(arc
				(start 37.541962 -357.75773)
				(mid 37.292534 -357.75773)
				(end 37.541962 -357.75773)
			)
		)
		(stroke
			(width 0)
			(type solid)
		)
		(fill yes)
		(layer "B.Cu")
		(net "GND")
	)
	(gr_poly
		(pts
			(arc
				(start 37.541962 -354.732082)
				(mid 37.292534 -354.732082)
				(end 37.541962 -354.732082)
			)
		)
		(stroke
			(width 0)
			(type solid)
		)
		(fill yes)
		(layer "B.Cu")
		(net "GND")
	)
	(gr_poly
		(pts
			(arc
				(start 37.541962 -351.611438)
				(mid 37.292534 -351.611438)
				(end 37.541962 -351.611438)
			)
		)
		(stroke
			(width 0)
			(type solid)
		)
		(fill yes)
		(layer "B.Cu")
		(net "GND")
	)
	(gr_poly
		(pts
			(arc
				(start 37.541962 -348.58579)
				(mid 37.292534 -348.58579)
				(end 37.541962 -348.58579)
			)
		)
		(stroke
			(width 0)
			(type solid)
		)
		(fill yes)
		(layer "B.Cu")
		(net "GND")
	)
	(gr_poly
		(pts
			(arc
				(start 37.541962 -345.465146)
				(mid 37.292534 -345.465146)
				(end 37.541962 -345.465146)
			)
		)
		(stroke
			(width 0)
			(type solid)
		)
		(fill yes)
		(layer "B.Cu")
		(net "GND")
	)
	(gr_poly
		(pts
			(arc
				(start 37.541962 -342.439498)
				(mid 37.292534 -342.439498)
				(end 37.541962 -342.439498)
			)
		)
		(stroke
			(width 0)
			(type solid)
		)
		(fill yes)
		(layer "B.Cu")
		(net "GND")
	)
	(gr_poly
		(pts
			(arc
				(start 38.472618 -411.141926)
				(mid 38.22319 -411.141926)
				(end 38.472618 -411.141926)
			)
		)
		(stroke
			(width 0)
			(type solid)
		)
		(fill yes)
		(layer "B.Cu")
		(net "GND")
	)
	(gr_poly
		(pts
			(arc
				(start 38.472618 -409.940252)
				(mid 38.22319 -409.940252)
				(end 38.472618 -409.940252)
			)
		)
		(stroke
			(width 0)
			(type solid)
		)
		(fill yes)
		(layer "B.Cu")
		(net "GND")
	)
	(gr_poly
		(pts
			(arc
				(start 38.472618 -408.738578)
				(mid 38.22319 -408.738578)
				(end 38.472618 -408.738578)
			)
		)
		(stroke
			(width 0)
			(type solid)
		)
		(fill yes)
		(layer "B.Cu")
		(net "GND")
	)
	(gr_poly
		(pts
			(arc
				(start 38.472618 -407.24201)
				(mid 38.22319 -407.24201)
				(end 38.472618 -407.24201)
			)
		)
		(stroke
			(width 0)
			(type solid)
		)
		(fill yes)
		(layer "B.Cu")
		(net "GND")
	)
	(gr_poly
		(pts
			(arc
				(start 38.472618 -406.040336)
				(mid 38.22319 -406.040336)
				(end 38.472618 -406.040336)
			)
		)
		(stroke
			(width 0)
			(type solid)
		)
		(fill yes)
		(layer "B.Cu")
		(net "GND")
	)
	(gr_poly
		(pts
			(arc
				(start 38.472618 -404.838662)
				(mid 38.22319 -404.838662)
				(end 38.472618 -404.838662)
			)
		)
		(stroke
			(width 0)
			(type solid)
		)
		(fill yes)
		(layer "B.Cu")
		(net "GND")
	)
	(gr_poly
		(pts
			(arc
				(start 38.472618 -403.34184)
				(mid 38.22319 -403.34184)
				(end 38.472618 -403.34184)
			)
		)
		(stroke
			(width 0)
			(type solid)
		)
		(fill yes)
		(layer "B.Cu")
		(net "GND")
	)
	(gr_poly
		(pts
			(arc
				(start 38.472618 -402.140166)
				(mid 38.22319 -402.140166)
				(end 38.472618 -402.140166)
			)
		)
		(stroke
			(width 0)
			(type solid)
		)
		(fill yes)
		(layer "B.Cu")
		(net "GND")
	)
	(gr_poly
		(pts
			(arc
				(start 38.472618 -400.938492)
				(mid 38.22319 -400.938492)
				(end 38.472618 -400.938492)
			)
		)
		(stroke
			(width 0)
			(type solid)
		)
		(fill yes)
		(layer "B.Cu")
		(net "GND")
	)
	(gr_poly
		(pts
			(arc
				(start 38.472618 -399.441924)
				(mid 38.22319 -399.441924)
				(end 38.472618 -399.441924)
			)
		)
		(stroke
			(width 0)
			(type solid)
		)
		(fill yes)
		(layer "B.Cu")
		(net "GND")
	)
	(gr_poly
		(pts
			(arc
				(start 38.472618 -398.24025)
				(mid 38.22319 -398.24025)
				(end 38.472618 -398.24025)
			)
		)
		(stroke
			(width 0)
			(type solid)
		)
		(fill yes)
		(layer "B.Cu")
		(net "GND")
	)
	(gr_poly
		(pts
			(arc
				(start 38.472618 -397.038576)
				(mid 38.22319 -397.038576)
				(end 38.472618 -397.038576)
			)
		)
		(stroke
			(width 0)
			(type solid)
		)
		(fill yes)
		(layer "B.Cu")
		(net "GND")
	)
	(gr_poly
		(pts
			(arc
				(start 38.472618 -385.141978)
				(mid 38.22319 -385.141978)
				(end 38.472618 -385.141978)
			)
		)
		(stroke
			(width 0)
			(type solid)
		)
		(fill yes)
		(layer "B.Cu")
		(net "GND")
	)
	(gr_poly
		(pts
			(arc
				(start 38.472618 -383.940304)
				(mid 38.22319 -383.940304)
				(end 38.472618 -383.940304)
			)
		)
		(stroke
			(width 0)
			(type solid)
		)
		(fill yes)
		(layer "B.Cu")
		(net "GND")
	)
	(gr_poly
		(pts
			(arc
				(start 38.472618 -382.73863)
				(mid 38.22319 -382.73863)
				(end 38.472618 -382.73863)
			)
		)
		(stroke
			(width 0)
			(type solid)
		)
		(fill yes)
		(layer "B.Cu")
		(net "GND")
	)
	(gr_poly
		(pts
			(arc
				(start 38.472618 -381.242062)
				(mid 38.22319 -381.242062)
				(end 38.472618 -381.242062)
			)
		)
		(stroke
			(width 0)
			(type solid)
		)
		(fill yes)
		(layer "B.Cu")
		(net "GND")
	)
	(gr_poly
		(pts
			(arc
				(start 38.472618 -380.040388)
				(mid 38.22319 -380.040388)
				(end 38.472618 -380.040388)
			)
		)
		(stroke
			(width 0)
			(type solid)
		)
		(fill yes)
		(layer "B.Cu")
		(net "GND")
	)
	(gr_poly
		(pts
			(arc
				(start 38.472618 -378.838714)
				(mid 38.22319 -378.838714)
				(end 38.472618 -378.838714)
			)
		)
		(stroke
			(width 0)
			(type solid)
		)
		(fill yes)
		(layer "B.Cu")
		(net "GND")
	)
	(gr_poly
		(pts
			(arc
				(start 38.472618 -377.341892)
				(mid 38.22319 -377.341892)
				(end 38.472618 -377.341892)
			)
		)
		(stroke
			(width 0)
			(type solid)
		)
		(fill yes)
		(layer "B.Cu")
		(net "GND")
	)
	(gr_poly
		(pts
			(arc
				(start 38.472618 -376.140218)
				(mid 38.22319 -376.140218)
				(end 38.472618 -376.140218)
			)
		)
		(stroke
			(width 0)
			(type solid)
		)
		(fill yes)
		(layer "B.Cu")
		(net "GND")
	)
	(gr_poly
		(pts
			(arc
				(start 38.472618 -374.938544)
				(mid 38.22319 -374.938544)
				(end 38.472618 -374.938544)
			)
		)
		(stroke
			(width 0)
			(type solid)
		)
		(fill yes)
		(layer "B.Cu")
		(net "GND")
	)
	(gr_poly
		(pts
			(arc
				(start 38.472618 -373.441976)
				(mid 38.22319 -373.441976)
				(end 38.472618 -373.441976)
			)
		)
		(stroke
			(width 0)
			(type solid)
		)
		(fill yes)
		(layer "B.Cu")
		(net "GND")
	)
	(gr_poly
		(pts
			(arc
				(start 38.472618 -372.240302)
				(mid 38.22319 -372.240302)
				(end 38.472618 -372.240302)
			)
		)
		(stroke
			(width 0)
			(type solid)
		)
		(fill yes)
		(layer "B.Cu")
		(net "GND")
	)
	(gr_poly
		(pts
			(arc
				(start 38.472618 -371.038628)
				(mid 38.22319 -371.038628)
				(end 38.472618 -371.038628)
			)
		)
		(stroke
			(width 0)
			(type solid)
		)
		(fill yes)
		(layer "B.Cu")
		(net "GND")
	)
	(gr_poly
		(pts
			(arc
				(start 39.543482 -357.75773)
				(mid 39.294054 -357.75773)
				(end 39.543482 -357.75773)
			)
		)
		(stroke
			(width 0)
			(type solid)
		)
		(fill yes)
		(layer "B.Cu")
		(net "GND")
	)
	(gr_poly
		(pts
			(arc
				(start 39.543482 -354.732082)
				(mid 39.294054 -354.732082)
				(end 39.543482 -354.732082)
			)
		)
		(stroke
			(width 0)
			(type solid)
		)
		(fill yes)
		(layer "B.Cu")
		(net "GND")
	)
	(gr_poly
		(pts
			(arc
				(start 39.543482 -351.611438)
				(mid 39.294054 -351.611438)
				(end 39.543482 -351.611438)
			)
		)
		(stroke
			(width 0)
			(type solid)
		)
		(fill yes)
		(layer "B.Cu")
		(net "GND")
	)
	(gr_poly
		(pts
			(arc
				(start 39.543482 -348.58579)
				(mid 39.294054 -348.58579)
				(end 39.543482 -348.58579)
			)
		)
		(stroke
			(width 0)
			(type solid)
		)
		(fill yes)
		(layer "B.Cu")
		(net "GND")
	)
	(gr_poly
		(pts
			(arc
				(start 39.543482 -345.465146)
				(mid 39.294054 -345.465146)
				(end 39.543482 -345.465146)
			)
		)
		(stroke
			(width 0)
			(type solid)
		)
		(fill yes)
		(layer "B.Cu")
		(net "GND")
	)
	(gr_poly
		(pts
			(arc
				(start 39.543482 -342.439498)
				(mid 39.294054 -342.439498)
				(end 39.543482 -342.439498)
			)
		)
		(stroke
			(width 0)
			(type solid)
		)
		(fill yes)
		(layer "B.Cu")
		(net "GND")
	)
	(gr_poly
		(pts
			(arc
				(start 40.650922 -357.75773)
				(mid 40.401494 -357.75773)
				(end 40.650922 -357.75773)
			)
		)
		(stroke
			(width 0)
			(type solid)
		)
		(fill yes)
		(layer "B.Cu")
		(net "GND")
	)
	(gr_poly
		(pts
			(arc
				(start 40.650922 -354.732082)
				(mid 40.401494 -354.732082)
				(end 40.650922 -354.732082)
			)
		)
		(stroke
			(width 0)
			(type solid)
		)
		(fill yes)
		(layer "B.Cu")
		(net "GND")
	)
	(gr_poly
		(pts
			(arc
				(start 40.650922 -351.611438)
				(mid 40.401494 -351.611438)
				(end 40.650922 -351.611438)
			)
		)
		(stroke
			(width 0)
			(type solid)
		)
		(fill yes)
		(layer "B.Cu")
		(net "GND")
	)
	(gr_poly
		(pts
			(arc
				(start 40.650922 -348.58579)
				(mid 40.401494 -348.58579)
				(end 40.650922 -348.58579)
			)
		)
		(stroke
			(width 0)
			(type solid)
		)
		(fill yes)
		(layer "B.Cu")
		(net "GND")
	)
	(gr_poly
		(pts
			(arc
				(start 40.650922 -345.465146)
				(mid 40.401494 -345.465146)
				(end 40.650922 -345.465146)
			)
		)
		(stroke
			(width 0)
			(type solid)
		)
		(fill yes)
		(layer "B.Cu")
		(net "GND")
	)
	(gr_poly
		(pts
			(arc
				(start 40.650922 -342.439498)
				(mid 40.401494 -342.439498)
				(end 40.650922 -342.439498)
			)
		)
		(stroke
			(width 0)
			(type solid)
		)
		(fill yes)
		(layer "B.Cu")
		(net "GND")
	)
	(gr_poly
		(pts
			(arc
				(start 40.672512 -410.041852)
				(mid 40.423084 -410.041852)
				(end 40.672512 -410.041852)
			)
		)
		(stroke
			(width 0)
			(type solid)
		)
		(fill yes)
		(layer "B.Cu")
		(net "GND")
	)
	(gr_poly
		(pts
			(arc
				(start 40.672512 -408.840178)
				(mid 40.423084 -408.840178)
				(end 40.672512 -408.840178)
			)
		)
		(stroke
			(width 0)
			(type solid)
		)
		(fill yes)
		(layer "B.Cu")
		(net "GND")
	)
	(gr_poly
		(pts
			(arc
				(start 40.672512 -407.638504)
				(mid 40.423084 -407.638504)
				(end 40.672512 -407.638504)
			)
		)
		(stroke
			(width 0)
			(type solid)
		)
		(fill yes)
		(layer "B.Cu")
		(net "GND")
	)
	(gr_poly
		(pts
			(arc
				(start 40.672512 -406.141936)
				(mid 40.423084 -406.141936)
				(end 40.672512 -406.141936)
			)
		)
		(stroke
			(width 0)
			(type solid)
		)
		(fill yes)
		(layer "B.Cu")
		(net "GND")
	)
	(gr_poly
		(pts
			(arc
				(start 40.672512 -404.940262)
				(mid 40.423084 -404.940262)
				(end 40.672512 -404.940262)
			)
		)
		(stroke
			(width 0)
			(type solid)
		)
		(fill yes)
		(layer "B.Cu")
		(net "GND")
	)
	(gr_poly
		(pts
			(arc
				(start 40.672512 -403.738588)
				(mid 40.423084 -403.738588)
				(end 40.672512 -403.738588)
			)
		)
		(stroke
			(width 0)
			(type solid)
		)
		(fill yes)
		(layer "B.Cu")
		(net "GND")
	)
	(gr_poly
		(pts
			(arc
				(start 40.672512 -402.241766)
				(mid 40.423084 -402.241766)
				(end 40.672512 -402.241766)
			)
		)
		(stroke
			(width 0)
			(type solid)
		)
		(fill yes)
		(layer "B.Cu")
		(net "GND")
	)
	(gr_poly
		(pts
			(arc
				(start 40.672512 -401.040092)
				(mid 40.423084 -401.040092)
				(end 40.672512 -401.040092)
			)
		)
		(stroke
			(width 0)
			(type solid)
		)
		(fill yes)
		(layer "B.Cu")
		(net "GND")
	)
	(gr_poly
		(pts
			(arc
				(start 40.672512 -399.838418)
				(mid 40.423084 -399.838418)
				(end 40.672512 -399.838418)
			)
		)
		(stroke
			(width 0)
			(type solid)
		)
		(fill yes)
		(layer "B.Cu")
		(net "GND")
	)
	(gr_poly
		(pts
			(arc
				(start 40.672512 -398.34185)
				(mid 40.423084 -398.34185)
				(end 40.672512 -398.34185)
			)
		)
		(stroke
			(width 0)
			(type solid)
		)
		(fill yes)
		(layer "B.Cu")
		(net "GND")
	)
	(gr_poly
		(pts
			(arc
				(start 40.672512 -397.140176)
				(mid 40.423084 -397.140176)
				(end 40.672512 -397.140176)
			)
		)
		(stroke
			(width 0)
			(type solid)
		)
		(fill yes)
		(layer "B.Cu")
		(net "GND")
	)
	(gr_poly
		(pts
			(arc
				(start 40.672512 -395.938502)
				(mid 40.423084 -395.938502)
				(end 40.672512 -395.938502)
			)
		)
		(stroke
			(width 0)
			(type solid)
		)
		(fill yes)
		(layer "B.Cu")
		(net "GND")
	)
	(gr_poly
		(pts
			(arc
				(start 40.672512 -384.041904)
				(mid 40.423084 -384.041904)
				(end 40.672512 -384.041904)
			)
		)
		(stroke
			(width 0)
			(type solid)
		)
		(fill yes)
		(layer "B.Cu")
		(net "GND")
	)
	(gr_poly
		(pts
			(arc
				(start 40.672512 -382.84023)
				(mid 40.423084 -382.84023)
				(end 40.672512 -382.84023)
			)
		)
		(stroke
			(width 0)
			(type solid)
		)
		(fill yes)
		(layer "B.Cu")
		(net "GND")
	)
	(gr_poly
		(pts
			(arc
				(start 40.672512 -381.638556)
				(mid 40.423084 -381.638556)
				(end 40.672512 -381.638556)
			)
		)
		(stroke
			(width 0)
			(type solid)
		)
		(fill yes)
		(layer "B.Cu")
		(net "GND")
	)
	(gr_poly
		(pts
			(arc
				(start 40.672512 -380.141988)
				(mid 40.423084 -380.141988)
				(end 40.672512 -380.141988)
			)
		)
		(stroke
			(width 0)
			(type solid)
		)
		(fill yes)
		(layer "B.Cu")
		(net "GND")
	)
	(gr_poly
		(pts
			(arc
				(start 40.672512 -378.940314)
				(mid 40.423084 -378.940314)
				(end 40.672512 -378.940314)
			)
		)
		(stroke
			(width 0)
			(type solid)
		)
		(fill yes)
		(layer "B.Cu")
		(net "GND")
	)
	(gr_poly
		(pts
			(arc
				(start 40.672512 -377.73864)
				(mid 40.423084 -377.73864)
				(end 40.672512 -377.73864)
			)
		)
		(stroke
			(width 0)
			(type solid)
		)
		(fill yes)
		(layer "B.Cu")
		(net "GND")
	)
	(gr_poly
		(pts
			(arc
				(start 40.672512 -376.241818)
				(mid 40.423084 -376.241818)
				(end 40.672512 -376.241818)
			)
		)
		(stroke
			(width 0)
			(type solid)
		)
		(fill yes)
		(layer "B.Cu")
		(net "GND")
	)
	(gr_poly
		(pts
			(arc
				(start 40.672512 -375.040144)
				(mid 40.423084 -375.040144)
				(end 40.672512 -375.040144)
			)
		)
		(stroke
			(width 0)
			(type solid)
		)
		(fill yes)
		(layer "B.Cu")
		(net "GND")
	)
	(gr_poly
		(pts
			(arc
				(start 40.672512 -373.83847)
				(mid 40.423084 -373.83847)
				(end 40.672512 -373.83847)
			)
		)
		(stroke
			(width 0)
			(type solid)
		)
		(fill yes)
		(layer "B.Cu")
		(net "GND")
	)
	(gr_poly
		(pts
			(arc
				(start 40.672512 -372.341902)
				(mid 40.423084 -372.341902)
				(end 40.672512 -372.341902)
			)
		)
		(stroke
			(width 0)
			(type solid)
		)
		(fill yes)
		(layer "B.Cu")
		(net "GND")
	)
	(gr_poly
		(pts
			(arc
				(start 40.672512 -371.140228)
				(mid 40.423084 -371.140228)
				(end 40.672512 -371.140228)
			)
		)
		(stroke
			(width 0)
			(type solid)
		)
		(fill yes)
		(layer "B.Cu")
		(net "GND")
	)
	(gr_poly
		(pts
			(arc
				(start 40.672512 -369.938554)
				(mid 40.423084 -369.938554)
				(end 40.672512 -369.938554)
			)
		)
		(stroke
			(width 0)
			(type solid)
		)
		(fill yes)
		(layer "B.Cu")
		(net "GND")
	)
	(gr_poly
		(pts
			(arc
				(start 42.652442 -357.75773)
				(mid 42.403014 -357.75773)
				(end 42.652442 -357.75773)
			)
		)
		(stroke
			(width 0)
			(type solid)
		)
		(fill yes)
		(layer "B.Cu")
		(net "GND")
	)
	(gr_poly
		(pts
			(arc
				(start 42.652442 -354.732082)
				(mid 42.403014 -354.732082)
				(end 42.652442 -354.732082)
			)
		)
		(stroke
			(width 0)
			(type solid)
		)
		(fill yes)
		(layer "B.Cu")
		(net "GND")
	)
	(gr_poly
		(pts
			(arc
				(start 42.652442 -351.611438)
				(mid 42.403014 -351.611438)
				(end 42.652442 -351.611438)
			)
		)
		(stroke
			(width 0)
			(type solid)
		)
		(fill yes)
		(layer "B.Cu")
		(net "GND")
	)
	(gr_poly
		(pts
			(arc
				(start 42.652442 -348.58579)
				(mid 42.403014 -348.58579)
				(end 42.652442 -348.58579)
			)
		)
		(stroke
			(width 0)
			(type solid)
		)
		(fill yes)
		(layer "B.Cu")
		(net "GND")
	)
	(gr_poly
		(pts
			(arc
				(start 42.652442 -345.465146)
				(mid 42.403014 -345.465146)
				(end 42.652442 -345.465146)
			)
		)
		(stroke
			(width 0)
			(type solid)
		)
		(fill yes)
		(layer "B.Cu")
		(net "GND")
	)
	(gr_poly
		(pts
			(arc
				(start 42.652442 -342.439498)
				(mid 42.403014 -342.439498)
				(end 42.652442 -342.439498)
			)
		)
		(stroke
			(width 0)
			(type solid)
		)
		(fill yes)
		(layer "B.Cu")
		(net "GND")
	)
	(gr_poly
		(pts
			(arc
				(start 42.87266 -411.141926)
				(mid 42.623232 -411.141926)
				(end 42.87266 -411.141926)
			)
		)
		(stroke
			(width 0)
			(type solid)
		)
		(fill yes)
		(layer "B.Cu")
		(net "GND")
	)
	(gr_poly
		(pts
			(arc
				(start 42.87266 -409.940252)
				(mid 42.623232 -409.940252)
				(end 42.87266 -409.940252)
			)
		)
		(stroke
			(width 0)
			(type solid)
		)
		(fill yes)
		(layer "B.Cu")
		(net "GND")
	)
	(gr_poly
		(pts
			(arc
				(start 42.87266 -408.738578)
				(mid 42.623232 -408.738578)
				(end 42.87266 -408.738578)
			)
		)
		(stroke
			(width 0)
			(type solid)
		)
		(fill yes)
		(layer "B.Cu")
		(net "GND")
	)
	(gr_poly
		(pts
			(arc
				(start 42.87266 -407.24201)
				(mid 42.623232 -407.24201)
				(end 42.87266 -407.24201)
			)
		)
		(stroke
			(width 0)
			(type solid)
		)
		(fill yes)
		(layer "B.Cu")
		(net "GND")
	)
	(gr_poly
		(pts
			(arc
				(start 42.87266 -406.040336)
				(mid 42.623232 -406.040336)
				(end 42.87266 -406.040336)
			)
		)
		(stroke
			(width 0)
			(type solid)
		)
		(fill yes)
		(layer "B.Cu")
		(net "GND")
	)
	(gr_poly
		(pts
			(arc
				(start 42.87266 -404.838662)
				(mid 42.623232 -404.838662)
				(end 42.87266 -404.838662)
			)
		)
		(stroke
			(width 0)
			(type solid)
		)
		(fill yes)
		(layer "B.Cu")
		(net "GND")
	)
	(gr_poly
		(pts
			(arc
				(start 42.87266 -403.34184)
				(mid 42.623232 -403.34184)
				(end 42.87266 -403.34184)
			)
		)
		(stroke
			(width 0)
			(type solid)
		)
		(fill yes)
		(layer "B.Cu")
		(net "GND")
	)
	(gr_poly
		(pts
			(arc
				(start 42.87266 -402.140166)
				(mid 42.623232 -402.140166)
				(end 42.87266 -402.140166)
			)
		)
		(stroke
			(width 0)
			(type solid)
		)
		(fill yes)
		(layer "B.Cu")
		(net "GND")
	)
	(gr_poly
		(pts
			(arc
				(start 42.87266 -400.938492)
				(mid 42.623232 -400.938492)
				(end 42.87266 -400.938492)
			)
		)
		(stroke
			(width 0)
			(type solid)
		)
		(fill yes)
		(layer "B.Cu")
		(net "GND")
	)
	(gr_poly
		(pts
			(arc
				(start 42.87266 -399.441924)
				(mid 42.623232 -399.441924)
				(end 42.87266 -399.441924)
			)
		)
		(stroke
			(width 0)
			(type solid)
		)
		(fill yes)
		(layer "B.Cu")
		(net "GND")
	)
	(gr_poly
		(pts
			(arc
				(start 42.87266 -398.24025)
				(mid 42.623232 -398.24025)
				(end 42.87266 -398.24025)
			)
		)
		(stroke
			(width 0)
			(type solid)
		)
		(fill yes)
		(layer "B.Cu")
		(net "GND")
	)
	(gr_poly
		(pts
			(arc
				(start 42.87266 -397.038576)
				(mid 42.623232 -397.038576)
				(end 42.87266 -397.038576)
			)
		)
		(stroke
			(width 0)
			(type solid)
		)
		(fill yes)
		(layer "B.Cu")
		(net "GND")
	)
	(gr_poly
		(pts
			(arc
				(start 42.87266 -385.141978)
				(mid 42.623232 -385.141978)
				(end 42.87266 -385.141978)
			)
		)
		(stroke
			(width 0)
			(type solid)
		)
		(fill yes)
		(layer "B.Cu")
		(net "GND")
	)
	(gr_poly
		(pts
			(arc
				(start 42.87266 -383.940304)
				(mid 42.623232 -383.940304)
				(end 42.87266 -383.940304)
			)
		)
		(stroke
			(width 0)
			(type solid)
		)
		(fill yes)
		(layer "B.Cu")
		(net "GND")
	)
	(gr_poly
		(pts
			(arc
				(start 42.87266 -382.73863)
				(mid 42.623232 -382.73863)
				(end 42.87266 -382.73863)
			)
		)
		(stroke
			(width 0)
			(type solid)
		)
		(fill yes)
		(layer "B.Cu")
		(net "GND")
	)
	(gr_poly
		(pts
			(arc
				(start 42.87266 -381.242062)
				(mid 42.623232 -381.242062)
				(end 42.87266 -381.242062)
			)
		)
		(stroke
			(width 0)
			(type solid)
		)
		(fill yes)
		(layer "B.Cu")
		(net "GND")
	)
	(gr_poly
		(pts
			(arc
				(start 42.87266 -380.040388)
				(mid 42.623232 -380.040388)
				(end 42.87266 -380.040388)
			)
		)
		(stroke
			(width 0)
			(type solid)
		)
		(fill yes)
		(layer "B.Cu")
		(net "GND")
	)
	(gr_poly
		(pts
			(arc
				(start 42.87266 -378.838714)
				(mid 42.623232 -378.838714)
				(end 42.87266 -378.838714)
			)
		)
		(stroke
			(width 0)
			(type solid)
		)
		(fill yes)
		(layer "B.Cu")
		(net "GND")
	)
	(gr_poly
		(pts
			(arc
				(start 42.87266 -377.341892)
				(mid 42.623232 -377.341892)
				(end 42.87266 -377.341892)
			)
		)
		(stroke
			(width 0)
			(type solid)
		)
		(fill yes)
		(layer "B.Cu")
		(net "GND")
	)
	(gr_poly
		(pts
			(arc
				(start 42.87266 -376.140218)
				(mid 42.623232 -376.140218)
				(end 42.87266 -376.140218)
			)
		)
		(stroke
			(width 0)
			(type solid)
		)
		(fill yes)
		(layer "B.Cu")
		(net "GND")
	)
	(gr_poly
		(pts
			(arc
				(start 42.87266 -374.938544)
				(mid 42.623232 -374.938544)
				(end 42.87266 -374.938544)
			)
		)
		(stroke
			(width 0)
			(type solid)
		)
		(fill yes)
		(layer "B.Cu")
		(net "GND")
	)
	(gr_poly
		(pts
			(arc
				(start 42.87266 -373.441976)
				(mid 42.623232 -373.441976)
				(end 42.87266 -373.441976)
			)
		)
		(stroke
			(width 0)
			(type solid)
		)
		(fill yes)
		(layer "B.Cu")
		(net "GND")
	)
	(gr_poly
		(pts
			(arc
				(start 42.87266 -372.240302)
				(mid 42.623232 -372.240302)
				(end 42.87266 -372.240302)
			)
		)
		(stroke
			(width 0)
			(type solid)
		)
		(fill yes)
		(layer "B.Cu")
		(net "GND")
	)
	(gr_poly
		(pts
			(arc
				(start 42.87266 -371.038628)
				(mid 42.623232 -371.038628)
				(end 42.87266 -371.038628)
			)
		)
		(stroke
			(width 0)
			(type solid)
		)
		(fill yes)
		(layer "B.Cu")
		(net "GND")
	)
	(gr_poly
		(pts
			(arc
				(start 43.759882 -357.75773)
				(mid 43.510454 -357.75773)
				(end 43.759882 -357.75773)
			)
		)
		(stroke
			(width 0)
			(type solid)
		)
		(fill yes)
		(layer "B.Cu")
		(net "GND")
	)
	(gr_poly
		(pts
			(arc
				(start 43.759882 -354.732082)
				(mid 43.510454 -354.732082)
				(end 43.759882 -354.732082)
			)
		)
		(stroke
			(width 0)
			(type solid)
		)
		(fill yes)
		(layer "B.Cu")
		(net "GND")
	)
	(gr_poly
		(pts
			(arc
				(start 43.759882 -351.611438)
				(mid 43.510454 -351.611438)
				(end 43.759882 -351.611438)
			)
		)
		(stroke
			(width 0)
			(type solid)
		)
		(fill yes)
		(layer "B.Cu")
		(net "GND")
	)
	(gr_poly
		(pts
			(arc
				(start 43.759882 -348.58579)
				(mid 43.510454 -348.58579)
				(end 43.759882 -348.58579)
			)
		)
		(stroke
			(width 0)
			(type solid)
		)
		(fill yes)
		(layer "B.Cu")
		(net "GND")
	)
	(gr_poly
		(pts
			(arc
				(start 43.759882 -345.465146)
				(mid 43.510454 -345.465146)
				(end 43.759882 -345.465146)
			)
		)
		(stroke
			(width 0)
			(type solid)
		)
		(fill yes)
		(layer "B.Cu")
		(net "GND")
	)
	(gr_poly
		(pts
			(arc
				(start 43.759882 -342.439498)
				(mid 43.510454 -342.439498)
				(end 43.759882 -342.439498)
			)
		)
		(stroke
			(width 0)
			(type solid)
		)
		(fill yes)
		(layer "B.Cu")
		(net "GND")
	)
	(gr_poly
		(pts
			(arc
				(start 45.072554 -410.041852)
				(mid 44.823126 -410.041852)
				(end 45.072554 -410.041852)
			)
		)
		(stroke
			(width 0)
			(type solid)
		)
		(fill yes)
		(layer "B.Cu")
		(net "GND")
	)
	(gr_poly
		(pts
			(arc
				(start 45.072554 -408.840178)
				(mid 44.823126 -408.840178)
				(end 45.072554 -408.840178)
			)
		)
		(stroke
			(width 0)
			(type solid)
		)
		(fill yes)
		(layer "B.Cu")
		(net "GND")
	)
	(gr_poly
		(pts
			(arc
				(start 45.072554 -407.638504)
				(mid 44.823126 -407.638504)
				(end 45.072554 -407.638504)
			)
		)
		(stroke
			(width 0)
			(type solid)
		)
		(fill yes)
		(layer "B.Cu")
		(net "GND")
	)
	(gr_poly
		(pts
			(arc
				(start 45.072554 -406.141936)
				(mid 44.823126 -406.141936)
				(end 45.072554 -406.141936)
			)
		)
		(stroke
			(width 0)
			(type solid)
		)
		(fill yes)
		(layer "B.Cu")
		(net "GND")
	)
	(gr_poly
		(pts
			(arc
				(start 45.072554 -404.940262)
				(mid 44.823126 -404.940262)
				(end 45.072554 -404.940262)
			)
		)
		(stroke
			(width 0)
			(type solid)
		)
		(fill yes)
		(layer "B.Cu")
		(net "GND")
	)
	(gr_poly
		(pts
			(arc
				(start 45.072554 -403.738588)
				(mid 44.823126 -403.738588)
				(end 45.072554 -403.738588)
			)
		)
		(stroke
			(width 0)
			(type solid)
		)
		(fill yes)
		(layer "B.Cu")
		(net "GND")
	)
	(gr_poly
		(pts
			(arc
				(start 45.072554 -402.241766)
				(mid 44.823126 -402.241766)
				(end 45.072554 -402.241766)
			)
		)
		(stroke
			(width 0)
			(type solid)
		)
		(fill yes)
		(layer "B.Cu")
		(net "GND")
	)
	(gr_poly
		(pts
			(arc
				(start 45.072554 -398.34185)
				(mid 44.823126 -398.34185)
				(end 45.072554 -398.34185)
			)
		)
		(stroke
			(width 0)
			(type solid)
		)
		(fill yes)
		(layer "B.Cu")
		(net "GND")
	)
	(gr_poly
		(pts
			(arc
				(start 45.072554 -397.140176)
				(mid 44.823126 -397.140176)
				(end 45.072554 -397.140176)
			)
		)
		(stroke
			(width 0)
			(type solid)
		)
		(fill yes)
		(layer "B.Cu")
		(net "GND")
	)
	(gr_poly
		(pts
			(arc
				(start 45.072554 -395.938502)
				(mid 44.823126 -395.938502)
				(end 45.072554 -395.938502)
			)
		)
		(stroke
			(width 0)
			(type solid)
		)
		(fill yes)
		(layer "B.Cu")
		(net "GND")
	)
	(gr_poly
		(pts
			(arc
				(start 45.072554 -382.840484)
				(mid 44.823126 -382.840484)
				(end 45.072554 -382.840484)
			)
		)
		(stroke
			(width 0)
			(type solid)
		)
		(fill yes)
		(layer "B.Cu")
		(net "GND")
	)
	(gr_poly
		(pts
			(arc
				(start 45.072554 -381.63881)
				(mid 44.823126 -381.63881)
				(end 45.072554 -381.63881)
			)
		)
		(stroke
			(width 0)
			(type solid)
		)
		(fill yes)
		(layer "B.Cu")
		(net "GND")
	)
	(gr_poly
		(pts
			(arc
				(start 45.072554 -380.141988)
				(mid 44.823126 -380.141988)
				(end 45.072554 -380.141988)
			)
		)
		(stroke
			(width 0)
			(type solid)
		)
		(fill yes)
		(layer "B.Cu")
		(net "GND")
	)
	(gr_poly
		(pts
			(arc
				(start 45.072554 -378.940314)
				(mid 44.823126 -378.940314)
				(end 45.072554 -378.940314)
			)
		)
		(stroke
			(width 0)
			(type solid)
		)
		(fill yes)
		(layer "B.Cu")
		(net "GND")
	)
	(gr_poly
		(pts
			(arc
				(start 45.072554 -377.73864)
				(mid 44.823126 -377.73864)
				(end 45.072554 -377.73864)
			)
		)
		(stroke
			(width 0)
			(type solid)
		)
		(fill yes)
		(layer "B.Cu")
		(net "GND")
	)
	(gr_poly
		(pts
			(arc
				(start 45.072554 -376.242072)
				(mid 44.823126 -376.242072)
				(end 45.072554 -376.242072)
			)
		)
		(stroke
			(width 0)
			(type solid)
		)
		(fill yes)
		(layer "B.Cu")
		(net "GND")
	)
	(gr_poly
		(pts
			(arc
				(start 45.072554 -375.040398)
				(mid 44.823126 -375.040398)
				(end 45.072554 -375.040398)
			)
		)
		(stroke
			(width 0)
			(type solid)
		)
		(fill yes)
		(layer "B.Cu")
		(net "GND")
	)
	(gr_poly
		(pts
			(arc
				(start 45.072554 -373.838724)
				(mid 44.823126 -373.838724)
				(end 45.072554 -373.838724)
			)
		)
		(stroke
			(width 0)
			(type solid)
		)
		(fill yes)
		(layer "B.Cu")
		(net "GND")
	)
	(gr_poly
		(pts
			(arc
				(start 45.072554 -372.342156)
				(mid 44.823126 -372.342156)
				(end 45.072554 -372.342156)
			)
		)
		(stroke
			(width 0)
			(type solid)
		)
		(fill yes)
		(layer "B.Cu")
		(net "GND")
	)
	(gr_poly
		(pts
			(arc
				(start 45.072554 -371.140482)
				(mid 44.823126 -371.140482)
				(end 45.072554 -371.140482)
			)
		)
		(stroke
			(width 0)
			(type solid)
		)
		(fill yes)
		(layer "B.Cu")
		(net "GND")
	)
	(gr_poly
		(pts
			(arc
				(start 45.072554 -369.938808)
				(mid 44.823126 -369.938808)
				(end 45.072554 -369.938808)
			)
		)
		(stroke
			(width 0)
			(type solid)
		)
		(fill yes)
		(layer "B.Cu")
		(net "GND")
	)
	(gr_poly
		(pts
			(arc
				(start 45.761402 -357.75773)
				(mid 45.511974 -357.75773)
				(end 45.761402 -357.75773)
			)
		)
		(stroke
			(width 0)
			(type solid)
		)
		(fill yes)
		(layer "B.Cu")
		(net "GND")
	)
	(gr_poly
		(pts
			(arc
				(start 45.761402 -354.732082)
				(mid 45.511974 -354.732082)
				(end 45.761402 -354.732082)
			)
		)
		(stroke
			(width 0)
			(type solid)
		)
		(fill yes)
		(layer "B.Cu")
		(net "GND")
	)
	(gr_poly
		(pts
			(arc
				(start 45.761402 -351.611438)
				(mid 45.511974 -351.611438)
				(end 45.761402 -351.611438)
			)
		)
		(stroke
			(width 0)
			(type solid)
		)
		(fill yes)
		(layer "B.Cu")
		(net "GND")
	)
	(gr_poly
		(pts
			(arc
				(start 45.761402 -348.58579)
				(mid 45.511974 -348.58579)
				(end 45.761402 -348.58579)
			)
		)
		(stroke
			(width 0)
			(type solid)
		)
		(fill yes)
		(layer "B.Cu")
		(net "GND")
	)
	(gr_poly
		(pts
			(arc
				(start 45.761402 -345.465146)
				(mid 45.511974 -345.465146)
				(end 45.761402 -345.465146)
			)
		)
		(stroke
			(width 0)
			(type solid)
		)
		(fill yes)
		(layer "B.Cu")
		(net "GND")
	)
	(gr_poly
		(pts
			(arc
				(start 45.761402 -342.439498)
				(mid 45.511974 -342.439498)
				(end 45.761402 -342.439498)
			)
		)
		(stroke
			(width 0)
			(type solid)
		)
		(fill yes)
		(layer "B.Cu")
		(net "GND")
	)
	(gr_poly
		(pts
			(arc
				(start 46.868842 -357.75773)
				(mid 46.619414 -357.75773)
				(end 46.868842 -357.75773)
			)
		)
		(stroke
			(width 0)
			(type solid)
		)
		(fill yes)
		(layer "B.Cu")
		(net "GND")
	)
	(gr_poly
		(pts
			(arc
				(start 46.868842 -354.732082)
				(mid 46.619414 -354.732082)
				(end 46.868842 -354.732082)
			)
		)
		(stroke
			(width 0)
			(type solid)
		)
		(fill yes)
		(layer "B.Cu")
		(net "GND")
	)
	(gr_poly
		(pts
			(arc
				(start 46.868842 -351.611438)
				(mid 46.619414 -351.611438)
				(end 46.868842 -351.611438)
			)
		)
		(stroke
			(width 0)
			(type solid)
		)
		(fill yes)
		(layer "B.Cu")
		(net "GND")
	)
	(gr_poly
		(pts
			(arc
				(start 46.868842 -348.58579)
				(mid 46.619414 -348.58579)
				(end 46.868842 -348.58579)
			)
		)
		(stroke
			(width 0)
			(type solid)
		)
		(fill yes)
		(layer "B.Cu")
		(net "GND")
	)
	(gr_poly
		(pts
			(arc
				(start 46.868842 -345.465146)
				(mid 46.619414 -345.465146)
				(end 46.868842 -345.465146)
			)
		)
		(stroke
			(width 0)
			(type solid)
		)
		(fill yes)
		(layer "B.Cu")
		(net "GND")
	)
	(gr_poly
		(pts
			(arc
				(start 46.868842 -342.439498)
				(mid 46.619414 -342.439498)
				(end 46.868842 -342.439498)
			)
		)
		(stroke
			(width 0)
			(type solid)
		)
		(fill yes)
		(layer "B.Cu")
		(net "GND")
	)
	(gr_poly
		(pts
			(arc
				(start 47.272702 -377.342146)
				(mid 47.023274 -377.342146)
				(end 47.272702 -377.342146)
			)
		)
		(stroke
			(width 0)
			(type solid)
		)
		(fill yes)
		(layer "B.Cu")
		(net "GND")
	)
	(gr_poly
		(pts
			(arc
				(start 47.272702 -376.140472)
				(mid 47.023274 -376.140472)
				(end 47.272702 -376.140472)
			)
		)
		(stroke
			(width 0)
			(type solid)
		)
		(fill yes)
		(layer "B.Cu")
		(net "GND")
	)
	(gr_poly
		(pts
			(arc
				(start 47.272702 -374.938798)
				(mid 47.023274 -374.938798)
				(end 47.272702 -374.938798)
			)
		)
		(stroke
			(width 0)
			(type solid)
		)
		(fill yes)
		(layer "B.Cu")
		(net "GND")
	)
	(gr_poly
		(pts
			(arc
				(start 47.272702 -373.441976)
				(mid 47.023274 -373.441976)
				(end 47.272702 -373.441976)
			)
		)
		(stroke
			(width 0)
			(type solid)
		)
		(fill yes)
		(layer "B.Cu")
		(net "GND")
	)
	(gr_poly
		(pts
			(arc
				(start 47.272702 -372.240302)
				(mid 47.023274 -372.240302)
				(end 47.272702 -372.240302)
			)
		)
		(stroke
			(width 0)
			(type solid)
		)
		(fill yes)
		(layer "B.Cu")
		(net "GND")
	)
	(gr_poly
		(pts
			(arc
				(start 47.272702 -371.038628)
				(mid 47.023274 -371.038628)
				(end 47.272702 -371.038628)
			)
		)
		(stroke
			(width 0)
			(type solid)
		)
		(fill yes)
		(layer "B.Cu")
		(net "GND")
	)
	(gr_poly
		(pts
			(arc
				(start 48.870362 -357.75773)
				(mid 48.620934 -357.75773)
				(end 48.870362 -357.75773)
			)
		)
		(stroke
			(width 0)
			(type solid)
		)
		(fill yes)
		(layer "B.Cu")
		(net "GND")
	)
	(gr_poly
		(pts
			(arc
				(start 48.870362 -354.732082)
				(mid 48.620934 -354.732082)
				(end 48.870362 -354.732082)
			)
		)
		(stroke
			(width 0)
			(type solid)
		)
		(fill yes)
		(layer "B.Cu")
		(net "GND")
	)
	(gr_poly
		(pts
			(arc
				(start 48.870362 -351.611438)
				(mid 48.620934 -351.611438)
				(end 48.870362 -351.611438)
			)
		)
		(stroke
			(width 0)
			(type solid)
		)
		(fill yes)
		(layer "B.Cu")
		(net "GND")
	)
	(gr_poly
		(pts
			(arc
				(start 48.870362 -348.58579)
				(mid 48.620934 -348.58579)
				(end 48.870362 -348.58579)
			)
		)
		(stroke
			(width 0)
			(type solid)
		)
		(fill yes)
		(layer "B.Cu")
		(net "GND")
	)
	(gr_poly
		(pts
			(arc
				(start 48.870362 -345.465146)
				(mid 48.620934 -345.465146)
				(end 48.870362 -345.465146)
			)
		)
		(stroke
			(width 0)
			(type solid)
		)
		(fill yes)
		(layer "B.Cu")
		(net "GND")
	)
	(gr_poly
		(pts
			(arc
				(start 48.870362 -342.439498)
				(mid 48.620934 -342.439498)
				(end 48.870362 -342.439498)
			)
		)
		(stroke
			(width 0)
			(type solid)
		)
		(fill yes)
		(layer "B.Cu")
		(net "GND")
	)
	(gr_poly
		(pts
			(arc
				(start 49.977802 -357.75773)
				(mid 49.728374 -357.75773)
				(end 49.977802 -357.75773)
			)
		)
		(stroke
			(width 0)
			(type solid)
		)
		(fill yes)
		(layer "B.Cu")
		(net "GND")
	)
	(gr_poly
		(pts
			(arc
				(start 49.977802 -354.732082)
				(mid 49.728374 -354.732082)
				(end 49.977802 -354.732082)
			)
		)
		(stroke
			(width 0)
			(type solid)
		)
		(fill yes)
		(layer "B.Cu")
		(net "GND")
	)
	(gr_poly
		(pts
			(arc
				(start 49.977802 -351.611438)
				(mid 49.728374 -351.611438)
				(end 49.977802 -351.611438)
			)
		)
		(stroke
			(width 0)
			(type solid)
		)
		(fill yes)
		(layer "B.Cu")
		(net "GND")
	)
	(gr_poly
		(pts
			(arc
				(start 49.977802 -348.58579)
				(mid 49.728374 -348.58579)
				(end 49.977802 -348.58579)
			)
		)
		(stroke
			(width 0)
			(type solid)
		)
		(fill yes)
		(layer "B.Cu")
		(net "GND")
	)
	(gr_poly
		(pts
			(arc
				(start 49.977802 -345.465146)
				(mid 49.728374 -345.465146)
				(end 49.977802 -345.465146)
			)
		)
		(stroke
			(width 0)
			(type solid)
		)
		(fill yes)
		(layer "B.Cu")
		(net "GND")
	)
	(gr_poly
		(pts
			(arc
				(start 49.977802 -342.439498)
				(mid 49.728374 -342.439498)
				(end 49.977802 -342.439498)
			)
		)
		(stroke
			(width 0)
			(type solid)
		)
		(fill yes)
		(layer "B.Cu")
		(net "GND")
	)
	(gr_poly
		(pts
			(arc
				(start 51.979322 -357.75773)
				(mid 51.729894 -357.75773)
				(end 51.979322 -357.75773)
			)
		)
		(stroke
			(width 0)
			(type solid)
		)
		(fill yes)
		(layer "B.Cu")
		(net "GND")
	)
	(gr_poly
		(pts
			(arc
				(start 51.979322 -354.732082)
				(mid 51.729894 -354.732082)
				(end 51.979322 -354.732082)
			)
		)
		(stroke
			(width 0)
			(type solid)
		)
		(fill yes)
		(layer "B.Cu")
		(net "GND")
	)
	(gr_poly
		(pts
			(arc
				(start 51.979322 -351.611438)
				(mid 51.729894 -351.611438)
				(end 51.979322 -351.611438)
			)
		)
		(stroke
			(width 0)
			(type solid)
		)
		(fill yes)
		(layer "B.Cu")
		(net "GND")
	)
	(gr_poly
		(pts
			(arc
				(start 51.979322 -348.58579)
				(mid 51.729894 -348.58579)
				(end 51.979322 -348.58579)
			)
		)
		(stroke
			(width 0)
			(type solid)
		)
		(fill yes)
		(layer "B.Cu")
		(net "GND")
	)
	(gr_poly
		(pts
			(arc
				(start 51.979322 -345.465146)
				(mid 51.729894 -345.465146)
				(end 51.979322 -345.465146)
			)
		)
		(stroke
			(width 0)
			(type solid)
		)
		(fill yes)
		(layer "B.Cu")
		(net "GND")
	)
	(gr_poly
		(pts
			(arc
				(start 51.979322 -342.439498)
				(mid 51.729894 -342.439498)
				(end 51.979322 -342.439498)
			)
		)
		(stroke
			(width 0)
			(type solid)
		)
		(fill yes)
		(layer "B.Cu")
		(net "GND")
	)
	(gr_poly
		(pts
			(arc
				(start 53.838856 -371.508274)
				(mid 53.589428 -371.508274)
				(end 53.838856 -371.508274)
			)
		)
		(stroke
			(width 0)
			(type solid)
		)
		(fill yes)
		(layer "B.Cu")
		(net "GND")
	)
	(gr_poly
		(pts
			(arc
				(start 53.838856 -370.24945)
				(mid 53.589428 -370.24945)
				(end 53.838856 -370.24945)
			)
		)
		(stroke
			(width 0)
			(type solid)
		)
		(fill yes)
		(layer "B.Cu")
		(net "GND")
	)
	(gr_poly
		(pts
			(arc
				(start 53.838856 -368.714274)
				(mid 53.589428 -368.714274)
				(end 53.838856 -368.714274)
			)
		)
		(stroke
			(width 0)
			(type solid)
		)
		(fill yes)
		(layer "B.Cu")
		(net "GND")
	)
	(gr_poly
		(pts
			(arc
				(start 53.838856 -367.45545)
				(mid 53.589428 -367.45545)
				(end 53.838856 -367.45545)
			)
		)
		(stroke
			(width 0)
			(type solid)
		)
		(fill yes)
		(layer "B.Cu")
		(net "GND")
	)
	(gr_poly
		(pts
			(arc
				(start 54.47284 -371.930422)
				(mid 54.223412 -371.930422)
				(end 54.47284 -371.930422)
			)
		)
		(stroke
			(width 0)
			(type solid)
		)
		(fill yes)
		(layer "B.Cu")
		(net "GND")
	)
	(gr_poly
		(pts
			(arc
				(start 54.47284 -369.827302)
				(mid 54.223412 -369.827302)
				(end 54.47284 -369.827302)
			)
		)
		(stroke
			(width 0)
			(type solid)
		)
		(fill yes)
		(layer "B.Cu")
		(net "GND")
	)
	(gr_poly
		(pts
			(arc
				(start 54.47284 -369.136422)
				(mid 54.223412 -369.136422)
				(end 54.47284 -369.136422)
			)
		)
		(stroke
			(width 0)
			(type solid)
		)
		(fill yes)
		(layer "B.Cu")
		(net "GND")
	)
	(gr_poly
		(pts
			(arc
				(start 54.47284 -367.033302)
				(mid 54.223412 -367.033302)
				(end 54.47284 -367.033302)
			)
		)
		(stroke
			(width 0)
			(type solid)
		)
		(fill yes)
		(layer "B.Cu")
		(net "GND")
	)
	(gr_poly
		(pts
			(arc
				(start 55.106824 -371.508274)
				(mid 54.857396 -371.508274)
				(end 55.106824 -371.508274)
			)
		)
		(stroke
			(width 0)
			(type solid)
		)
		(fill yes)
		(layer "B.Cu")
		(net "GND")
	)
	(gr_poly
		(pts
			(arc
				(start 55.106824 -370.24945)
				(mid 54.857396 -370.24945)
				(end 55.106824 -370.24945)
			)
		)
		(stroke
			(width 0)
			(type solid)
		)
		(fill yes)
		(layer "B.Cu")
		(net "GND")
	)
	(gr_poly
		(pts
			(arc
				(start 55.106824 -368.714274)
				(mid 54.857396 -368.714274)
				(end 55.106824 -368.714274)
			)
		)
		(stroke
			(width 0)
			(type solid)
		)
		(fill yes)
		(layer "B.Cu")
		(net "GND")
	)
	(gr_poly
		(pts
			(arc
				(start 55.106824 -367.45545)
				(mid 54.857396 -367.45545)
				(end 55.106824 -367.45545)
			)
		)
		(stroke
			(width 0)
			(type solid)
		)
		(fill yes)
		(layer "B.Cu")
		(net "GND")
	)
	(gr_poly
		(pts
			(arc
				(start 57.211976 -371.508274)
				(mid 56.962548 -371.508274)
				(end 57.211976 -371.508274)
			)
		)
		(stroke
			(width 0)
			(type solid)
		)
		(fill yes)
		(layer "B.Cu")
		(net "GND")
	)
	(gr_poly
		(pts
			(arc
				(start 57.211976 -370.24945)
				(mid 56.962548 -370.24945)
				(end 57.211976 -370.24945)
			)
		)
		(stroke
			(width 0)
			(type solid)
		)
		(fill yes)
		(layer "B.Cu")
		(net "GND")
	)
	(gr_poly
		(pts
			(arc
				(start 57.211976 -368.714274)
				(mid 56.962548 -368.714274)
				(end 57.211976 -368.714274)
			)
		)
		(stroke
			(width 0)
			(type solid)
		)
		(fill yes)
		(layer "B.Cu")
		(net "GND")
	)
	(gr_poly
		(pts
			(arc
				(start 57.211976 -367.45545)
				(mid 56.962548 -367.45545)
				(end 57.211976 -367.45545)
			)
		)
		(stroke
			(width 0)
			(type solid)
		)
		(fill yes)
		(layer "B.Cu")
		(net "GND")
	)
	(gr_poly
		(pts
			(arc
				(start 57.84596 -371.930422)
				(mid 57.596532 -371.930422)
				(end 57.84596 -371.930422)
			)
		)
		(stroke
			(width 0)
			(type solid)
		)
		(fill yes)
		(layer "B.Cu")
		(net "GND")
	)
	(gr_poly
		(pts
			(arc
				(start 57.84596 -369.827302)
				(mid 57.596532 -369.827302)
				(end 57.84596 -369.827302)
			)
		)
		(stroke
			(width 0)
			(type solid)
		)
		(fill yes)
		(layer "B.Cu")
		(net "GND")
	)
	(gr_poly
		(pts
			(arc
				(start 57.84596 -369.136422)
				(mid 57.596532 -369.136422)
				(end 57.84596 -369.136422)
			)
		)
		(stroke
			(width 0)
			(type solid)
		)
		(fill yes)
		(layer "B.Cu")
		(net "GND")
	)
	(gr_poly
		(pts
			(arc
				(start 57.84596 -367.033302)
				(mid 57.596532 -367.033302)
				(end 57.84596 -367.033302)
			)
		)
		(stroke
			(width 0)
			(type solid)
		)
		(fill yes)
		(layer "B.Cu")
		(net "GND")
	)
	(gr_poly
		(pts
			(arc
				(start 58.479944 -371.508274)
				(mid 58.230516 -371.508274)
				(end 58.479944 -371.508274)
			)
		)
		(stroke
			(width 0)
			(type solid)
		)
		(fill yes)
		(layer "B.Cu")
		(net "GND")
	)
	(gr_poly
		(pts
			(arc
				(start 58.479944 -370.24945)
				(mid 58.230516 -370.24945)
				(end 58.479944 -370.24945)
			)
		)
		(stroke
			(width 0)
			(type solid)
		)
		(fill yes)
		(layer "B.Cu")
		(net "GND")
	)
	(gr_poly
		(pts
			(arc
				(start 58.479944 -368.714274)
				(mid 58.230516 -368.714274)
				(end 58.479944 -368.714274)
			)
		)
		(stroke
			(width 0)
			(type solid)
		)
		(fill yes)
		(layer "B.Cu")
		(net "GND")
	)
	(gr_poly
		(pts
			(arc
				(start 58.479944 -367.45545)
				(mid 58.230516 -367.45545)
				(end 58.479944 -367.45545)
			)
		)
		(stroke
			(width 0)
			(type solid)
		)
		(fill yes)
		(layer "B.Cu")
		(net "GND")
	)
	(gr_poly
		(pts
			(arc
				(start 60.927996 -351.611438)
				(mid 60.678568 -351.611438)
				(end 60.927996 -351.611438)
			)
		)
		(stroke
			(width 0)
			(type solid)
		)
		(fill yes)
		(layer "B.Cu")
		(net "GND")
	)
	(gr_poly
		(pts
			(arc
				(start 60.927996 -348.58579)
				(mid 60.678568 -348.58579)
				(end 60.927996 -348.58579)
			)
		)
		(stroke
			(width 0)
			(type solid)
		)
		(fill yes)
		(layer "B.Cu")
		(net "GND")
	)
	(gr_poly
		(pts
			(arc
				(start 60.927996 -345.465146)
				(mid 60.678568 -345.465146)
				(end 60.927996 -345.465146)
			)
		)
		(stroke
			(width 0)
			(type solid)
		)
		(fill yes)
		(layer "B.Cu")
		(net "GND")
	)
	(gr_poly
		(pts
			(arc
				(start 60.927996 -342.439498)
				(mid 60.678568 -342.439498)
				(end 60.927996 -342.439498)
			)
		)
		(stroke
			(width 0)
			(type solid)
		)
		(fill yes)
		(layer "B.Cu")
		(net "GND")
	)
	(gr_poly
		(pts
			(arc
				(start 62.929516 -351.611438)
				(mid 62.680088 -351.611438)
				(end 62.929516 -351.611438)
			)
		)
		(stroke
			(width 0)
			(type solid)
		)
		(fill yes)
		(layer "B.Cu")
		(net "GND")
	)
	(gr_poly
		(pts
			(arc
				(start 62.929516 -348.58579)
				(mid 62.680088 -348.58579)
				(end 62.929516 -348.58579)
			)
		)
		(stroke
			(width 0)
			(type solid)
		)
		(fill yes)
		(layer "B.Cu")
		(net "GND")
	)
	(gr_poly
		(pts
			(arc
				(start 62.929516 -345.465146)
				(mid 62.680088 -345.465146)
				(end 62.929516 -345.465146)
			)
		)
		(stroke
			(width 0)
			(type solid)
		)
		(fill yes)
		(layer "B.Cu")
		(net "GND")
	)
	(gr_poly
		(pts
			(arc
				(start 62.929516 -342.439498)
				(mid 62.680088 -342.439498)
				(end 62.929516 -342.439498)
			)
		)
		(stroke
			(width 0)
			(type solid)
		)
		(fill yes)
		(layer "B.Cu")
		(net "GND")
	)
	(gr_poly
		(pts
			(arc
				(start 64.036956 -357.75773)
				(mid 63.787528 -357.75773)
				(end 64.036956 -357.75773)
			)
		)
		(stroke
			(width 0)
			(type solid)
		)
		(fill yes)
		(layer "B.Cu")
		(net "GND")
	)
	(gr_poly
		(pts
			(arc
				(start 64.036956 -354.732082)
				(mid 63.787528 -354.732082)
				(end 64.036956 -354.732082)
			)
		)
		(stroke
			(width 0)
			(type solid)
		)
		(fill yes)
		(layer "B.Cu")
		(net "GND")
	)
	(gr_poly
		(pts
			(arc
				(start 64.036956 -351.611438)
				(mid 63.787528 -351.611438)
				(end 64.036956 -351.611438)
			)
		)
		(stroke
			(width 0)
			(type solid)
		)
		(fill yes)
		(layer "B.Cu")
		(net "GND")
	)
	(gr_poly
		(pts
			(arc
				(start 64.036956 -348.58579)
				(mid 63.787528 -348.58579)
				(end 64.036956 -348.58579)
			)
		)
		(stroke
			(width 0)
			(type solid)
		)
		(fill yes)
		(layer "B.Cu")
		(net "GND")
	)
	(gr_poly
		(pts
			(arc
				(start 64.036956 -345.465146)
				(mid 63.787528 -345.465146)
				(end 64.036956 -345.465146)
			)
		)
		(stroke
			(width 0)
			(type solid)
		)
		(fill yes)
		(layer "B.Cu")
		(net "GND")
	)
	(gr_poly
		(pts
			(arc
				(start 64.036956 -342.439498)
				(mid 63.787528 -342.439498)
				(end 64.036956 -342.439498)
			)
		)
		(stroke
			(width 0)
			(type solid)
		)
		(fill yes)
		(layer "B.Cu")
		(net "GND")
	)
	(gr_poly
		(pts
			(arc
				(start 66.038476 -357.75773)
				(mid 65.789048 -357.75773)
				(end 66.038476 -357.75773)
			)
		)
		(stroke
			(width 0)
			(type solid)
		)
		(fill yes)
		(layer "B.Cu")
		(net "GND")
	)
	(gr_poly
		(pts
			(arc
				(start 66.038476 -354.732082)
				(mid 65.789048 -354.732082)
				(end 66.038476 -354.732082)
			)
		)
		(stroke
			(width 0)
			(type solid)
		)
		(fill yes)
		(layer "B.Cu")
		(net "GND")
	)
	(gr_poly
		(pts
			(arc
				(start 66.038476 -351.611438)
				(mid 65.789048 -351.611438)
				(end 66.038476 -351.611438)
			)
		)
		(stroke
			(width 0)
			(type solid)
		)
		(fill yes)
		(layer "B.Cu")
		(net "GND")
	)
	(gr_poly
		(pts
			(arc
				(start 66.038476 -348.58579)
				(mid 65.789048 -348.58579)
				(end 66.038476 -348.58579)
			)
		)
		(stroke
			(width 0)
			(type solid)
		)
		(fill yes)
		(layer "B.Cu")
		(net "GND")
	)
	(gr_poly
		(pts
			(arc
				(start 66.038476 -345.465146)
				(mid 65.789048 -345.465146)
				(end 66.038476 -345.465146)
			)
		)
		(stroke
			(width 0)
			(type solid)
		)
		(fill yes)
		(layer "B.Cu")
		(net "GND")
	)
	(gr_poly
		(pts
			(arc
				(start 66.038476 -342.439498)
				(mid 65.789048 -342.439498)
				(end 66.038476 -342.439498)
			)
		)
		(stroke
			(width 0)
			(type solid)
		)
		(fill yes)
		(layer "B.Cu")
		(net "GND")
	)
	(gr_poly
		(pts
			(arc
				(start 67.145916 -357.75773)
				(mid 66.896488 -357.75773)
				(end 67.145916 -357.75773)
			)
		)
		(stroke
			(width 0)
			(type solid)
		)
		(fill yes)
		(layer "B.Cu")
		(net "GND")
	)
	(gr_poly
		(pts
			(arc
				(start 67.145916 -354.732082)
				(mid 66.896488 -354.732082)
				(end 67.145916 -354.732082)
			)
		)
		(stroke
			(width 0)
			(type solid)
		)
		(fill yes)
		(layer "B.Cu")
		(net "GND")
	)
	(gr_poly
		(pts
			(arc
				(start 67.145916 -351.611438)
				(mid 66.896488 -351.611438)
				(end 67.145916 -351.611438)
			)
		)
		(stroke
			(width 0)
			(type solid)
		)
		(fill yes)
		(layer "B.Cu")
		(net "GND")
	)
	(gr_poly
		(pts
			(arc
				(start 67.145916 -348.58579)
				(mid 66.896488 -348.58579)
				(end 67.145916 -348.58579)
			)
		)
		(stroke
			(width 0)
			(type solid)
		)
		(fill yes)
		(layer "B.Cu")
		(net "GND")
	)
	(gr_poly
		(pts
			(arc
				(start 67.145916 -345.465146)
				(mid 66.896488 -345.465146)
				(end 67.145916 -345.465146)
			)
		)
		(stroke
			(width 0)
			(type solid)
		)
		(fill yes)
		(layer "B.Cu")
		(net "GND")
	)
	(gr_poly
		(pts
			(arc
				(start 67.145916 -342.439498)
				(mid 66.896488 -342.439498)
				(end 67.145916 -342.439498)
			)
		)
		(stroke
			(width 0)
			(type solid)
		)
		(fill yes)
		(layer "B.Cu")
		(net "GND")
	)
	(gr_poly
		(pts
			(arc
				(start 67.962526 -290.066984)
				(mid 67.981913 -290.063034)
				(end 67.99834 -290.051998)
			)
			(xy 68.00088 -290.049458) (xy 68.0085 -290.030916)
			(arc
				(start 68.0085 -289.559492)
				(mid 67.993621 -289.523571)
				(end 67.9577 -289.508692)
			)
			(arc
				(start 50.528474 -289.508692)
				(mid 50.509087 -289.512642)
				(end 50.49266 -289.523678)
			)
			(arc
				(start 50.421286 -289.595052)
				(mid 50.410175 -289.611586)
				(end 50.4063 -289.63112)
			)
			(xy 50.4063 -290.030916) (xy 50.41392 -290.049458)
			(arc
				(start 50.41646 -290.051998)
				(mid 50.432877 -290.06306)
				(end 50.452274 -290.066984)
			)
		)
		(stroke
			(width 0)
			(type solid)
		)
		(fill yes)
		(layer "B.Cu")
		(net "GND")
	)
	(gr_poly
		(pts
			(arc
				(start 69.147436 -357.75773)
				(mid 68.898008 -357.75773)
				(end 69.147436 -357.75773)
			)
		)
		(stroke
			(width 0)
			(type solid)
		)
		(fill yes)
		(layer "B.Cu")
		(net "GND")
	)
	(gr_poly
		(pts
			(arc
				(start 69.147436 -354.732082)
				(mid 68.898008 -354.732082)
				(end 69.147436 -354.732082)
			)
		)
		(stroke
			(width 0)
			(type solid)
		)
		(fill yes)
		(layer "B.Cu")
		(net "GND")
	)
	(gr_poly
		(pts
			(arc
				(start 69.147436 -351.611438)
				(mid 68.898008 -351.611438)
				(end 69.147436 -351.611438)
			)
		)
		(stroke
			(width 0)
			(type solid)
		)
		(fill yes)
		(layer "B.Cu")
		(net "GND")
	)
	(gr_poly
		(pts
			(arc
				(start 69.147436 -348.58579)
				(mid 68.898008 -348.58579)
				(end 69.147436 -348.58579)
			)
		)
		(stroke
			(width 0)
			(type solid)
		)
		(fill yes)
		(layer "B.Cu")
		(net "GND")
	)
	(gr_poly
		(pts
			(arc
				(start 69.147436 -345.465146)
				(mid 68.898008 -345.465146)
				(end 69.147436 -345.465146)
			)
		)
		(stroke
			(width 0)
			(type solid)
		)
		(fill yes)
		(layer "B.Cu")
		(net "GND")
	)
	(gr_poly
		(pts
			(arc
				(start 69.147436 -342.439498)
				(mid 68.898008 -342.439498)
				(end 69.147436 -342.439498)
			)
		)
		(stroke
			(width 0)
			(type solid)
		)
		(fill yes)
		(layer "B.Cu")
		(net "GND")
	)
	(gr_poly
		(pts
			(arc
				(start 70.254876 -357.75773)
				(mid 70.005448 -357.75773)
				(end 70.254876 -357.75773)
			)
		)
		(stroke
			(width 0)
			(type solid)
		)
		(fill yes)
		(layer "B.Cu")
		(net "GND")
	)
	(gr_poly
		(pts
			(arc
				(start 70.254876 -354.732082)
				(mid 70.005448 -354.732082)
				(end 70.254876 -354.732082)
			)
		)
		(stroke
			(width 0)
			(type solid)
		)
		(fill yes)
		(layer "B.Cu")
		(net "GND")
	)
	(gr_poly
		(pts
			(arc
				(start 70.254876 -351.611438)
				(mid 70.005448 -351.611438)
				(end 70.254876 -351.611438)
			)
		)
		(stroke
			(width 0)
			(type solid)
		)
		(fill yes)
		(layer "B.Cu")
		(net "GND")
	)
	(gr_poly
		(pts
			(arc
				(start 70.254876 -348.58579)
				(mid 70.005448 -348.58579)
				(end 70.254876 -348.58579)
			)
		)
		(stroke
			(width 0)
			(type solid)
		)
		(fill yes)
		(layer "B.Cu")
		(net "GND")
	)
	(gr_poly
		(pts
			(arc
				(start 70.254876 -345.465146)
				(mid 70.005448 -345.465146)
				(end 70.254876 -345.465146)
			)
		)
		(stroke
			(width 0)
			(type solid)
		)
		(fill yes)
		(layer "B.Cu")
		(net "GND")
	)
	(gr_poly
		(pts
			(arc
				(start 70.254876 -342.439498)
				(mid 70.005448 -342.439498)
				(end 70.254876 -342.439498)
			)
		)
		(stroke
			(width 0)
			(type solid)
		)
		(fill yes)
		(layer "B.Cu")
		(net "GND")
	)
	(gr_poly
		(pts
			(arc
				(start 71.472552 -410.041852)
				(mid 71.223124 -410.041852)
				(end 71.472552 -410.041852)
			)
		)
		(stroke
			(width 0)
			(type solid)
		)
		(fill yes)
		(layer "B.Cu")
		(net "GND")
	)
	(gr_poly
		(pts
			(arc
				(start 71.472552 -408.840178)
				(mid 71.223124 -408.840178)
				(end 71.472552 -408.840178)
			)
		)
		(stroke
			(width 0)
			(type solid)
		)
		(fill yes)
		(layer "B.Cu")
		(net "GND")
	)
	(gr_poly
		(pts
			(arc
				(start 71.472552 -407.638504)
				(mid 71.223124 -407.638504)
				(end 71.472552 -407.638504)
			)
		)
		(stroke
			(width 0)
			(type solid)
		)
		(fill yes)
		(layer "B.Cu")
		(net "GND")
	)
	(gr_poly
		(pts
			(arc
				(start 71.472552 -406.141936)
				(mid 71.223124 -406.141936)
				(end 71.472552 -406.141936)
			)
		)
		(stroke
			(width 0)
			(type solid)
		)
		(fill yes)
		(layer "B.Cu")
		(net "GND")
	)
	(gr_poly
		(pts
			(arc
				(start 71.472552 -404.940262)
				(mid 71.223124 -404.940262)
				(end 71.472552 -404.940262)
			)
		)
		(stroke
			(width 0)
			(type solid)
		)
		(fill yes)
		(layer "B.Cu")
		(net "GND")
	)
	(gr_poly
		(pts
			(arc
				(start 71.472552 -403.738588)
				(mid 71.223124 -403.738588)
				(end 71.472552 -403.738588)
			)
		)
		(stroke
			(width 0)
			(type solid)
		)
		(fill yes)
		(layer "B.Cu")
		(net "GND")
	)
	(gr_poly
		(pts
			(arc
				(start 71.472552 -402.241766)
				(mid 71.223124 -402.241766)
				(end 71.472552 -402.241766)
			)
		)
		(stroke
			(width 0)
			(type solid)
		)
		(fill yes)
		(layer "B.Cu")
		(net "GND")
	)
	(gr_poly
		(pts
			(arc
				(start 71.472552 -401.040092)
				(mid 71.223124 -401.040092)
				(end 71.472552 -401.040092)
			)
		)
		(stroke
			(width 0)
			(type solid)
		)
		(fill yes)
		(layer "B.Cu")
		(net "GND")
	)
	(gr_poly
		(pts
			(arc
				(start 71.472552 -399.838418)
				(mid 71.223124 -399.838418)
				(end 71.472552 -399.838418)
			)
		)
		(stroke
			(width 0)
			(type solid)
		)
		(fill yes)
		(layer "B.Cu")
		(net "GND")
	)
	(gr_poly
		(pts
			(arc
				(start 71.472552 -398.34185)
				(mid 71.223124 -398.34185)
				(end 71.472552 -398.34185)
			)
		)
		(stroke
			(width 0)
			(type solid)
		)
		(fill yes)
		(layer "B.Cu")
		(net "GND")
	)
	(gr_poly
		(pts
			(arc
				(start 71.472552 -397.140176)
				(mid 71.223124 -397.140176)
				(end 71.472552 -397.140176)
			)
		)
		(stroke
			(width 0)
			(type solid)
		)
		(fill yes)
		(layer "B.Cu")
		(net "GND")
	)
	(gr_poly
		(pts
			(arc
				(start 71.472552 -395.938502)
				(mid 71.223124 -395.938502)
				(end 71.472552 -395.938502)
			)
		)
		(stroke
			(width 0)
			(type solid)
		)
		(fill yes)
		(layer "B.Cu")
		(net "GND")
	)
	(gr_poly
		(pts
			(arc
				(start 71.472552 -384.041904)
				(mid 71.223124 -384.041904)
				(end 71.472552 -384.041904)
			)
		)
		(stroke
			(width 0)
			(type solid)
		)
		(fill yes)
		(layer "B.Cu")
		(net "GND")
	)
	(gr_poly
		(pts
			(arc
				(start 71.472552 -382.84023)
				(mid 71.223124 -382.84023)
				(end 71.472552 -382.84023)
			)
		)
		(stroke
			(width 0)
			(type solid)
		)
		(fill yes)
		(layer "B.Cu")
		(net "GND")
	)
	(gr_poly
		(pts
			(arc
				(start 71.472552 -381.638556)
				(mid 71.223124 -381.638556)
				(end 71.472552 -381.638556)
			)
		)
		(stroke
			(width 0)
			(type solid)
		)
		(fill yes)
		(layer "B.Cu")
		(net "GND")
	)
	(gr_poly
		(pts
			(arc
				(start 71.472552 -380.141988)
				(mid 71.223124 -380.141988)
				(end 71.472552 -380.141988)
			)
		)
		(stroke
			(width 0)
			(type solid)
		)
		(fill yes)
		(layer "B.Cu")
		(net "GND")
	)
	(gr_poly
		(pts
			(arc
				(start 71.472552 -378.940314)
				(mid 71.223124 -378.940314)
				(end 71.472552 -378.940314)
			)
		)
		(stroke
			(width 0)
			(type solid)
		)
		(fill yes)
		(layer "B.Cu")
		(net "GND")
	)
	(gr_poly
		(pts
			(arc
				(start 71.472552 -377.73864)
				(mid 71.223124 -377.73864)
				(end 71.472552 -377.73864)
			)
		)
		(stroke
			(width 0)
			(type solid)
		)
		(fill yes)
		(layer "B.Cu")
		(net "GND")
	)
	(gr_poly
		(pts
			(arc
				(start 71.472552 -376.241818)
				(mid 71.223124 -376.241818)
				(end 71.472552 -376.241818)
			)
		)
		(stroke
			(width 0)
			(type solid)
		)
		(fill yes)
		(layer "B.Cu")
		(net "GND")
	)
	(gr_poly
		(pts
			(arc
				(start 71.472552 -375.040144)
				(mid 71.223124 -375.040144)
				(end 71.472552 -375.040144)
			)
		)
		(stroke
			(width 0)
			(type solid)
		)
		(fill yes)
		(layer "B.Cu")
		(net "GND")
	)
	(gr_poly
		(pts
			(arc
				(start 71.472552 -373.83847)
				(mid 71.223124 -373.83847)
				(end 71.472552 -373.83847)
			)
		)
		(stroke
			(width 0)
			(type solid)
		)
		(fill yes)
		(layer "B.Cu")
		(net "GND")
	)
	(gr_poly
		(pts
			(arc
				(start 71.472552 -372.341902)
				(mid 71.223124 -372.341902)
				(end 71.472552 -372.341902)
			)
		)
		(stroke
			(width 0)
			(type solid)
		)
		(fill yes)
		(layer "B.Cu")
		(net "GND")
	)
	(gr_poly
		(pts
			(arc
				(start 71.472552 -371.140228)
				(mid 71.223124 -371.140228)
				(end 71.472552 -371.140228)
			)
		)
		(stroke
			(width 0)
			(type solid)
		)
		(fill yes)
		(layer "B.Cu")
		(net "GND")
	)
	(gr_poly
		(pts
			(arc
				(start 71.472552 -369.938554)
				(mid 71.223124 -369.938554)
				(end 71.472552 -369.938554)
			)
		)
		(stroke
			(width 0)
			(type solid)
		)
		(fill yes)
		(layer "B.Cu")
		(net "GND")
	)
	(gr_poly
		(pts
			(arc
				(start 72.256396 -357.75773)
				(mid 72.006968 -357.75773)
				(end 72.256396 -357.75773)
			)
		)
		(stroke
			(width 0)
			(type solid)
		)
		(fill yes)
		(layer "B.Cu")
		(net "GND")
	)
	(gr_poly
		(pts
			(arc
				(start 72.256396 -354.732082)
				(mid 72.006968 -354.732082)
				(end 72.256396 -354.732082)
			)
		)
		(stroke
			(width 0)
			(type solid)
		)
		(fill yes)
		(layer "B.Cu")
		(net "GND")
	)
	(gr_poly
		(pts
			(arc
				(start 72.256396 -351.611438)
				(mid 72.006968 -351.611438)
				(end 72.256396 -351.611438)
			)
		)
		(stroke
			(width 0)
			(type solid)
		)
		(fill yes)
		(layer "B.Cu")
		(net "GND")
	)
	(gr_poly
		(pts
			(arc
				(start 72.256396 -348.58579)
				(mid 72.006968 -348.58579)
				(end 72.256396 -348.58579)
			)
		)
		(stroke
			(width 0)
			(type solid)
		)
		(fill yes)
		(layer "B.Cu")
		(net "GND")
	)
	(gr_poly
		(pts
			(arc
				(start 72.256396 -345.465146)
				(mid 72.006968 -345.465146)
				(end 72.256396 -345.465146)
			)
		)
		(stroke
			(width 0)
			(type solid)
		)
		(fill yes)
		(layer "B.Cu")
		(net "GND")
	)
	(gr_poly
		(pts
			(arc
				(start 72.256396 -342.439498)
				(mid 72.006968 -342.439498)
				(end 72.256396 -342.439498)
			)
		)
		(stroke
			(width 0)
			(type solid)
		)
		(fill yes)
		(layer "B.Cu")
		(net "GND")
	)
	(gr_poly
		(pts
			(arc
				(start 73.363836 -357.75773)
				(mid 73.114408 -357.75773)
				(end 73.363836 -357.75773)
			)
		)
		(stroke
			(width 0)
			(type solid)
		)
		(fill yes)
		(layer "B.Cu")
		(net "GND")
	)
	(gr_poly
		(pts
			(arc
				(start 73.363836 -354.732082)
				(mid 73.114408 -354.732082)
				(end 73.363836 -354.732082)
			)
		)
		(stroke
			(width 0)
			(type solid)
		)
		(fill yes)
		(layer "B.Cu")
		(net "GND")
	)
	(gr_poly
		(pts
			(arc
				(start 73.363836 -351.611438)
				(mid 73.114408 -351.611438)
				(end 73.363836 -351.611438)
			)
		)
		(stroke
			(width 0)
			(type solid)
		)
		(fill yes)
		(layer "B.Cu")
		(net "GND")
	)
	(gr_poly
		(pts
			(arc
				(start 73.363836 -348.58579)
				(mid 73.114408 -348.58579)
				(end 73.363836 -348.58579)
			)
		)
		(stroke
			(width 0)
			(type solid)
		)
		(fill yes)
		(layer "B.Cu")
		(net "GND")
	)
	(gr_poly
		(pts
			(arc
				(start 73.363836 -345.465146)
				(mid 73.114408 -345.465146)
				(end 73.363836 -345.465146)
			)
		)
		(stroke
			(width 0)
			(type solid)
		)
		(fill yes)
		(layer "B.Cu")
		(net "GND")
	)
	(gr_poly
		(pts
			(arc
				(start 73.363836 -342.439498)
				(mid 73.114408 -342.439498)
				(end 73.363836 -342.439498)
			)
		)
		(stroke
			(width 0)
			(type solid)
		)
		(fill yes)
		(layer "B.Cu")
		(net "GND")
	)
	(gr_poly
		(pts
			(arc
				(start 73.672446 -411.141926)
				(mid 73.423018 -411.141926)
				(end 73.672446 -411.141926)
			)
		)
		(stroke
			(width 0)
			(type solid)
		)
		(fill yes)
		(layer "B.Cu")
		(net "GND")
	)
	(gr_poly
		(pts
			(arc
				(start 73.672446 -409.940252)
				(mid 73.423018 -409.940252)
				(end 73.672446 -409.940252)
			)
		)
		(stroke
			(width 0)
			(type solid)
		)
		(fill yes)
		(layer "B.Cu")
		(net "GND")
	)
	(gr_poly
		(pts
			(arc
				(start 73.672446 -408.738578)
				(mid 73.423018 -408.738578)
				(end 73.672446 -408.738578)
			)
		)
		(stroke
			(width 0)
			(type solid)
		)
		(fill yes)
		(layer "B.Cu")
		(net "GND")
	)
	(gr_poly
		(pts
			(arc
				(start 73.672446 -407.24201)
				(mid 73.423018 -407.24201)
				(end 73.672446 -407.24201)
			)
		)
		(stroke
			(width 0)
			(type solid)
		)
		(fill yes)
		(layer "B.Cu")
		(net "GND")
	)
	(gr_poly
		(pts
			(arc
				(start 73.672446 -406.040336)
				(mid 73.423018 -406.040336)
				(end 73.672446 -406.040336)
			)
		)
		(stroke
			(width 0)
			(type solid)
		)
		(fill yes)
		(layer "B.Cu")
		(net "GND")
	)
	(gr_poly
		(pts
			(arc
				(start 73.672446 -404.838662)
				(mid 73.423018 -404.838662)
				(end 73.672446 -404.838662)
			)
		)
		(stroke
			(width 0)
			(type solid)
		)
		(fill yes)
		(layer "B.Cu")
		(net "GND")
	)
	(gr_poly
		(pts
			(arc
				(start 73.672446 -403.34184)
				(mid 73.423018 -403.34184)
				(end 73.672446 -403.34184)
			)
		)
		(stroke
			(width 0)
			(type solid)
		)
		(fill yes)
		(layer "B.Cu")
		(net "GND")
	)
	(gr_poly
		(pts
			(arc
				(start 73.672446 -402.140166)
				(mid 73.423018 -402.140166)
				(end 73.672446 -402.140166)
			)
		)
		(stroke
			(width 0)
			(type solid)
		)
		(fill yes)
		(layer "B.Cu")
		(net "GND")
	)
	(gr_poly
		(pts
			(arc
				(start 73.672446 -400.938492)
				(mid 73.423018 -400.938492)
				(end 73.672446 -400.938492)
			)
		)
		(stroke
			(width 0)
			(type solid)
		)
		(fill yes)
		(layer "B.Cu")
		(net "GND")
	)
	(gr_poly
		(pts
			(arc
				(start 73.672446 -399.441924)
				(mid 73.423018 -399.441924)
				(end 73.672446 -399.441924)
			)
		)
		(stroke
			(width 0)
			(type solid)
		)
		(fill yes)
		(layer "B.Cu")
		(net "GND")
	)
	(gr_poly
		(pts
			(arc
				(start 73.672446 -398.24025)
				(mid 73.423018 -398.24025)
				(end 73.672446 -398.24025)
			)
		)
		(stroke
			(width 0)
			(type solid)
		)
		(fill yes)
		(layer "B.Cu")
		(net "GND")
	)
	(gr_poly
		(pts
			(arc
				(start 73.672446 -397.038576)
				(mid 73.423018 -397.038576)
				(end 73.672446 -397.038576)
			)
		)
		(stroke
			(width 0)
			(type solid)
		)
		(fill yes)
		(layer "B.Cu")
		(net "GND")
	)
	(gr_poly
		(pts
			(arc
				(start 73.672446 -385.141978)
				(mid 73.423018 -385.141978)
				(end 73.672446 -385.141978)
			)
		)
		(stroke
			(width 0)
			(type solid)
		)
		(fill yes)
		(layer "B.Cu")
		(net "GND")
	)
	(gr_poly
		(pts
			(arc
				(start 73.672446 -383.940304)
				(mid 73.423018 -383.940304)
				(end 73.672446 -383.940304)
			)
		)
		(stroke
			(width 0)
			(type solid)
		)
		(fill yes)
		(layer "B.Cu")
		(net "GND")
	)
	(gr_poly
		(pts
			(arc
				(start 73.672446 -382.73863)
				(mid 73.423018 -382.73863)
				(end 73.672446 -382.73863)
			)
		)
		(stroke
			(width 0)
			(type solid)
		)
		(fill yes)
		(layer "B.Cu")
		(net "GND")
	)
	(gr_poly
		(pts
			(arc
				(start 73.672446 -381.242062)
				(mid 73.423018 -381.242062)
				(end 73.672446 -381.242062)
			)
		)
		(stroke
			(width 0)
			(type solid)
		)
		(fill yes)
		(layer "B.Cu")
		(net "GND")
	)
	(gr_poly
		(pts
			(arc
				(start 73.672446 -380.040388)
				(mid 73.423018 -380.040388)
				(end 73.672446 -380.040388)
			)
		)
		(stroke
			(width 0)
			(type solid)
		)
		(fill yes)
		(layer "B.Cu")
		(net "GND")
	)
	(gr_poly
		(pts
			(arc
				(start 73.672446 -378.838714)
				(mid 73.423018 -378.838714)
				(end 73.672446 -378.838714)
			)
		)
		(stroke
			(width 0)
			(type solid)
		)
		(fill yes)
		(layer "B.Cu")
		(net "GND")
	)
	(gr_poly
		(pts
			(arc
				(start 73.672446 -377.341892)
				(mid 73.423018 -377.341892)
				(end 73.672446 -377.341892)
			)
		)
		(stroke
			(width 0)
			(type solid)
		)
		(fill yes)
		(layer "B.Cu")
		(net "GND")
	)
	(gr_poly
		(pts
			(arc
				(start 73.672446 -376.140218)
				(mid 73.423018 -376.140218)
				(end 73.672446 -376.140218)
			)
		)
		(stroke
			(width 0)
			(type solid)
		)
		(fill yes)
		(layer "B.Cu")
		(net "GND")
	)
	(gr_poly
		(pts
			(arc
				(start 73.672446 -374.938544)
				(mid 73.423018 -374.938544)
				(end 73.672446 -374.938544)
			)
		)
		(stroke
			(width 0)
			(type solid)
		)
		(fill yes)
		(layer "B.Cu")
		(net "GND")
	)
	(gr_poly
		(pts
			(arc
				(start 73.672446 -373.441976)
				(mid 73.423018 -373.441976)
				(end 73.672446 -373.441976)
			)
		)
		(stroke
			(width 0)
			(type solid)
		)
		(fill yes)
		(layer "B.Cu")
		(net "GND")
	)
	(gr_poly
		(pts
			(arc
				(start 73.672446 -372.240302)
				(mid 73.423018 -372.240302)
				(end 73.672446 -372.240302)
			)
		)
		(stroke
			(width 0)
			(type solid)
		)
		(fill yes)
		(layer "B.Cu")
		(net "GND")
	)
	(gr_poly
		(pts
			(arc
				(start 73.672446 -371.038628)
				(mid 73.423018 -371.038628)
				(end 73.672446 -371.038628)
			)
		)
		(stroke
			(width 0)
			(type solid)
		)
		(fill yes)
		(layer "B.Cu")
		(net "GND")
	)
	(gr_poly
		(pts
			(arc
				(start 75.365356 -357.75773)
				(mid 75.115928 -357.75773)
				(end 75.365356 -357.75773)
			)
		)
		(stroke
			(width 0)
			(type solid)
		)
		(fill yes)
		(layer "B.Cu")
		(net "GND")
	)
	(gr_poly
		(pts
			(arc
				(start 75.365356 -354.732082)
				(mid 75.115928 -354.732082)
				(end 75.365356 -354.732082)
			)
		)
		(stroke
			(width 0)
			(type solid)
		)
		(fill yes)
		(layer "B.Cu")
		(net "GND")
	)
	(gr_poly
		(pts
			(arc
				(start 75.365356 -351.611438)
				(mid 75.115928 -351.611438)
				(end 75.365356 -351.611438)
			)
		)
		(stroke
			(width 0)
			(type solid)
		)
		(fill yes)
		(layer "B.Cu")
		(net "GND")
	)
	(gr_poly
		(pts
			(arc
				(start 75.365356 -348.58579)
				(mid 75.115928 -348.58579)
				(end 75.365356 -348.58579)
			)
		)
		(stroke
			(width 0)
			(type solid)
		)
		(fill yes)
		(layer "B.Cu")
		(net "GND")
	)
	(gr_poly
		(pts
			(arc
				(start 75.365356 -345.465146)
				(mid 75.115928 -345.465146)
				(end 75.365356 -345.465146)
			)
		)
		(stroke
			(width 0)
			(type solid)
		)
		(fill yes)
		(layer "B.Cu")
		(net "GND")
	)
	(gr_poly
		(pts
			(arc
				(start 75.365356 -342.439498)
				(mid 75.115928 -342.439498)
				(end 75.365356 -342.439498)
			)
		)
		(stroke
			(width 0)
			(type solid)
		)
		(fill yes)
		(layer "B.Cu")
		(net "GND")
	)
	(gr_poly
		(pts
			(arc
				(start 75.872594 -410.041852)
				(mid 75.623166 -410.041852)
				(end 75.872594 -410.041852)
			)
		)
		(stroke
			(width 0)
			(type solid)
		)
		(fill yes)
		(layer "B.Cu")
		(net "GND")
	)
	(gr_poly
		(pts
			(arc
				(start 75.872594 -408.840178)
				(mid 75.623166 -408.840178)
				(end 75.872594 -408.840178)
			)
		)
		(stroke
			(width 0)
			(type solid)
		)
		(fill yes)
		(layer "B.Cu")
		(net "GND")
	)
	(gr_poly
		(pts
			(arc
				(start 75.872594 -407.638504)
				(mid 75.623166 -407.638504)
				(end 75.872594 -407.638504)
			)
		)
		(stroke
			(width 0)
			(type solid)
		)
		(fill yes)
		(layer "B.Cu")
		(net "GND")
	)
	(gr_poly
		(pts
			(arc
				(start 75.872594 -406.141936)
				(mid 75.623166 -406.141936)
				(end 75.872594 -406.141936)
			)
		)
		(stroke
			(width 0)
			(type solid)
		)
		(fill yes)
		(layer "B.Cu")
		(net "GND")
	)
	(gr_poly
		(pts
			(arc
				(start 75.872594 -404.940262)
				(mid 75.623166 -404.940262)
				(end 75.872594 -404.940262)
			)
		)
		(stroke
			(width 0)
			(type solid)
		)
		(fill yes)
		(layer "B.Cu")
		(net "GND")
	)
	(gr_poly
		(pts
			(arc
				(start 75.872594 -403.738588)
				(mid 75.623166 -403.738588)
				(end 75.872594 -403.738588)
			)
		)
		(stroke
			(width 0)
			(type solid)
		)
		(fill yes)
		(layer "B.Cu")
		(net "GND")
	)
	(gr_poly
		(pts
			(arc
				(start 75.872594 -402.241766)
				(mid 75.623166 -402.241766)
				(end 75.872594 -402.241766)
			)
		)
		(stroke
			(width 0)
			(type solid)
		)
		(fill yes)
		(layer "B.Cu")
		(net "GND")
	)
	(gr_poly
		(pts
			(arc
				(start 75.872594 -401.040092)
				(mid 75.623166 -401.040092)
				(end 75.872594 -401.040092)
			)
		)
		(stroke
			(width 0)
			(type solid)
		)
		(fill yes)
		(layer "B.Cu")
		(net "GND")
	)
	(gr_poly
		(pts
			(arc
				(start 75.872594 -399.838418)
				(mid 75.623166 -399.838418)
				(end 75.872594 -399.838418)
			)
		)
		(stroke
			(width 0)
			(type solid)
		)
		(fill yes)
		(layer "B.Cu")
		(net "GND")
	)
	(gr_poly
		(pts
			(arc
				(start 75.872594 -398.34185)
				(mid 75.623166 -398.34185)
				(end 75.872594 -398.34185)
			)
		)
		(stroke
			(width 0)
			(type solid)
		)
		(fill yes)
		(layer "B.Cu")
		(net "GND")
	)
	(gr_poly
		(pts
			(arc
				(start 75.872594 -397.140176)
				(mid 75.623166 -397.140176)
				(end 75.872594 -397.140176)
			)
		)
		(stroke
			(width 0)
			(type solid)
		)
		(fill yes)
		(layer "B.Cu")
		(net "GND")
	)
	(gr_poly
		(pts
			(arc
				(start 75.872594 -395.938502)
				(mid 75.623166 -395.938502)
				(end 75.872594 -395.938502)
			)
		)
		(stroke
			(width 0)
			(type solid)
		)
		(fill yes)
		(layer "B.Cu")
		(net "GND")
	)
	(gr_poly
		(pts
			(arc
				(start 75.872594 -384.041904)
				(mid 75.623166 -384.041904)
				(end 75.872594 -384.041904)
			)
		)
		(stroke
			(width 0)
			(type solid)
		)
		(fill yes)
		(layer "B.Cu")
		(net "GND")
	)
	(gr_poly
		(pts
			(arc
				(start 75.872594 -382.84023)
				(mid 75.623166 -382.84023)
				(end 75.872594 -382.84023)
			)
		)
		(stroke
			(width 0)
			(type solid)
		)
		(fill yes)
		(layer "B.Cu")
		(net "GND")
	)
	(gr_poly
		(pts
			(arc
				(start 75.872594 -381.638556)
				(mid 75.623166 -381.638556)
				(end 75.872594 -381.638556)
			)
		)
		(stroke
			(width 0)
			(type solid)
		)
		(fill yes)
		(layer "B.Cu")
		(net "GND")
	)
	(gr_poly
		(pts
			(arc
				(start 75.872594 -380.141988)
				(mid 75.623166 -380.141988)
				(end 75.872594 -380.141988)
			)
		)
		(stroke
			(width 0)
			(type solid)
		)
		(fill yes)
		(layer "B.Cu")
		(net "GND")
	)
	(gr_poly
		(pts
			(arc
				(start 75.872594 -378.940314)
				(mid 75.623166 -378.940314)
				(end 75.872594 -378.940314)
			)
		)
		(stroke
			(width 0)
			(type solid)
		)
		(fill yes)
		(layer "B.Cu")
		(net "GND")
	)
	(gr_poly
		(pts
			(arc
				(start 75.872594 -377.73864)
				(mid 75.623166 -377.73864)
				(end 75.872594 -377.73864)
			)
		)
		(stroke
			(width 0)
			(type solid)
		)
		(fill yes)
		(layer "B.Cu")
		(net "GND")
	)
	(gr_poly
		(pts
			(arc
				(start 75.872594 -376.241818)
				(mid 75.623166 -376.241818)
				(end 75.872594 -376.241818)
			)
		)
		(stroke
			(width 0)
			(type solid)
		)
		(fill yes)
		(layer "B.Cu")
		(net "GND")
	)
	(gr_poly
		(pts
			(arc
				(start 75.872594 -375.040144)
				(mid 75.623166 -375.040144)
				(end 75.872594 -375.040144)
			)
		)
		(stroke
			(width 0)
			(type solid)
		)
		(fill yes)
		(layer "B.Cu")
		(net "GND")
	)
	(gr_poly
		(pts
			(arc
				(start 75.872594 -373.83847)
				(mid 75.623166 -373.83847)
				(end 75.872594 -373.83847)
			)
		)
		(stroke
			(width 0)
			(type solid)
		)
		(fill yes)
		(layer "B.Cu")
		(net "GND")
	)
	(gr_poly
		(pts
			(arc
				(start 75.872594 -372.341902)
				(mid 75.623166 -372.341902)
				(end 75.872594 -372.341902)
			)
		)
		(stroke
			(width 0)
			(type solid)
		)
		(fill yes)
		(layer "B.Cu")
		(net "GND")
	)
	(gr_poly
		(pts
			(arc
				(start 75.872594 -371.140228)
				(mid 75.623166 -371.140228)
				(end 75.872594 -371.140228)
			)
		)
		(stroke
			(width 0)
			(type solid)
		)
		(fill yes)
		(layer "B.Cu")
		(net "GND")
	)
	(gr_poly
		(pts
			(arc
				(start 75.872594 -369.938554)
				(mid 75.623166 -369.938554)
				(end 75.872594 -369.938554)
			)
		)
		(stroke
			(width 0)
			(type solid)
		)
		(fill yes)
		(layer "B.Cu")
		(net "GND")
	)
	(gr_poly
		(pts
			(arc
				(start 76.472796 -357.75773)
				(mid 76.223368 -357.75773)
				(end 76.472796 -357.75773)
			)
		)
		(stroke
			(width 0)
			(type solid)
		)
		(fill yes)
		(layer "B.Cu")
		(net "GND")
	)
	(gr_poly
		(pts
			(arc
				(start 76.472796 -354.732082)
				(mid 76.223368 -354.732082)
				(end 76.472796 -354.732082)
			)
		)
		(stroke
			(width 0)
			(type solid)
		)
		(fill yes)
		(layer "B.Cu")
		(net "GND")
	)
	(gr_poly
		(pts
			(arc
				(start 76.472796 -351.611438)
				(mid 76.223368 -351.611438)
				(end 76.472796 -351.611438)
			)
		)
		(stroke
			(width 0)
			(type solid)
		)
		(fill yes)
		(layer "B.Cu")
		(net "GND")
	)
	(gr_poly
		(pts
			(arc
				(start 76.472796 -348.58579)
				(mid 76.223368 -348.58579)
				(end 76.472796 -348.58579)
			)
		)
		(stroke
			(width 0)
			(type solid)
		)
		(fill yes)
		(layer "B.Cu")
		(net "GND")
	)
	(gr_poly
		(pts
			(arc
				(start 76.472796 -345.465146)
				(mid 76.223368 -345.465146)
				(end 76.472796 -345.465146)
			)
		)
		(stroke
			(width 0)
			(type solid)
		)
		(fill yes)
		(layer "B.Cu")
		(net "GND")
	)
	(gr_poly
		(pts
			(arc
				(start 76.472796 -342.439498)
				(mid 76.223368 -342.439498)
				(end 76.472796 -342.439498)
			)
		)
		(stroke
			(width 0)
			(type solid)
		)
		(fill yes)
		(layer "B.Cu")
		(net "GND")
	)
	(gr_poly
		(pts
			(arc
				(start 78.072488 -411.141926)
				(mid 77.82306 -411.141926)
				(end 78.072488 -411.141926)
			)
		)
		(stroke
			(width 0)
			(type solid)
		)
		(fill yes)
		(layer "B.Cu")
		(net "GND")
	)
	(gr_poly
		(pts
			(arc
				(start 78.072488 -409.940252)
				(mid 77.82306 -409.940252)
				(end 78.072488 -409.940252)
			)
		)
		(stroke
			(width 0)
			(type solid)
		)
		(fill yes)
		(layer "B.Cu")
		(net "GND")
	)
	(gr_poly
		(pts
			(arc
				(start 78.072488 -408.738578)
				(mid 77.82306 -408.738578)
				(end 78.072488 -408.738578)
			)
		)
		(stroke
			(width 0)
			(type solid)
		)
		(fill yes)
		(layer "B.Cu")
		(net "GND")
	)
	(gr_poly
		(pts
			(arc
				(start 78.072488 -407.24201)
				(mid 77.82306 -407.24201)
				(end 78.072488 -407.24201)
			)
		)
		(stroke
			(width 0)
			(type solid)
		)
		(fill yes)
		(layer "B.Cu")
		(net "GND")
	)
	(gr_poly
		(pts
			(arc
				(start 78.072488 -406.040336)
				(mid 77.82306 -406.040336)
				(end 78.072488 -406.040336)
			)
		)
		(stroke
			(width 0)
			(type solid)
		)
		(fill yes)
		(layer "B.Cu")
		(net "GND")
	)
	(gr_poly
		(pts
			(arc
				(start 78.072488 -404.838662)
				(mid 77.82306 -404.838662)
				(end 78.072488 -404.838662)
			)
		)
		(stroke
			(width 0)
			(type solid)
		)
		(fill yes)
		(layer "B.Cu")
		(net "GND")
	)
	(gr_poly
		(pts
			(arc
				(start 78.072488 -403.34184)
				(mid 77.82306 -403.34184)
				(end 78.072488 -403.34184)
			)
		)
		(stroke
			(width 0)
			(type solid)
		)
		(fill yes)
		(layer "B.Cu")
		(net "GND")
	)
	(gr_poly
		(pts
			(arc
				(start 78.072488 -402.140166)
				(mid 77.82306 -402.140166)
				(end 78.072488 -402.140166)
			)
		)
		(stroke
			(width 0)
			(type solid)
		)
		(fill yes)
		(layer "B.Cu")
		(net "GND")
	)
	(gr_poly
		(pts
			(arc
				(start 78.072488 -400.938492)
				(mid 77.82306 -400.938492)
				(end 78.072488 -400.938492)
			)
		)
		(stroke
			(width 0)
			(type solid)
		)
		(fill yes)
		(layer "B.Cu")
		(net "GND")
	)
	(gr_poly
		(pts
			(arc
				(start 78.072488 -399.441924)
				(mid 77.82306 -399.441924)
				(end 78.072488 -399.441924)
			)
		)
		(stroke
			(width 0)
			(type solid)
		)
		(fill yes)
		(layer "B.Cu")
		(net "GND")
	)
	(gr_poly
		(pts
			(arc
				(start 78.072488 -398.24025)
				(mid 77.82306 -398.24025)
				(end 78.072488 -398.24025)
			)
		)
		(stroke
			(width 0)
			(type solid)
		)
		(fill yes)
		(layer "B.Cu")
		(net "GND")
	)
	(gr_poly
		(pts
			(arc
				(start 78.072488 -397.038576)
				(mid 77.82306 -397.038576)
				(end 78.072488 -397.038576)
			)
		)
		(stroke
			(width 0)
			(type solid)
		)
		(fill yes)
		(layer "B.Cu")
		(net "GND")
	)
	(gr_poly
		(pts
			(arc
				(start 78.072488 -385.141978)
				(mid 77.82306 -385.141978)
				(end 78.072488 -385.141978)
			)
		)
		(stroke
			(width 0)
			(type solid)
		)
		(fill yes)
		(layer "B.Cu")
		(net "GND")
	)
	(gr_poly
		(pts
			(arc
				(start 78.072488 -383.940304)
				(mid 77.82306 -383.940304)
				(end 78.072488 -383.940304)
			)
		)
		(stroke
			(width 0)
			(type solid)
		)
		(fill yes)
		(layer "B.Cu")
		(net "GND")
	)
	(gr_poly
		(pts
			(arc
				(start 78.072488 -382.73863)
				(mid 77.82306 -382.73863)
				(end 78.072488 -382.73863)
			)
		)
		(stroke
			(width 0)
			(type solid)
		)
		(fill yes)
		(layer "B.Cu")
		(net "GND")
	)
	(gr_poly
		(pts
			(arc
				(start 78.072488 -381.242062)
				(mid 77.82306 -381.242062)
				(end 78.072488 -381.242062)
			)
		)
		(stroke
			(width 0)
			(type solid)
		)
		(fill yes)
		(layer "B.Cu")
		(net "GND")
	)
	(gr_poly
		(pts
			(arc
				(start 78.072488 -380.040388)
				(mid 77.82306 -380.040388)
				(end 78.072488 -380.040388)
			)
		)
		(stroke
			(width 0)
			(type solid)
		)
		(fill yes)
		(layer "B.Cu")
		(net "GND")
	)
	(gr_poly
		(pts
			(arc
				(start 78.072488 -378.838714)
				(mid 77.82306 -378.838714)
				(end 78.072488 -378.838714)
			)
		)
		(stroke
			(width 0)
			(type solid)
		)
		(fill yes)
		(layer "B.Cu")
		(net "GND")
	)
	(gr_poly
		(pts
			(arc
				(start 78.072488 -377.341892)
				(mid 77.82306 -377.341892)
				(end 78.072488 -377.341892)
			)
		)
		(stroke
			(width 0)
			(type solid)
		)
		(fill yes)
		(layer "B.Cu")
		(net "GND")
	)
	(gr_poly
		(pts
			(arc
				(start 78.072488 -376.140218)
				(mid 77.82306 -376.140218)
				(end 78.072488 -376.140218)
			)
		)
		(stroke
			(width 0)
			(type solid)
		)
		(fill yes)
		(layer "B.Cu")
		(net "GND")
	)
	(gr_poly
		(pts
			(arc
				(start 78.072488 -374.938544)
				(mid 77.82306 -374.938544)
				(end 78.072488 -374.938544)
			)
		)
		(stroke
			(width 0)
			(type solid)
		)
		(fill yes)
		(layer "B.Cu")
		(net "GND")
	)
	(gr_poly
		(pts
			(arc
				(start 78.072488 -373.441976)
				(mid 77.82306 -373.441976)
				(end 78.072488 -373.441976)
			)
		)
		(stroke
			(width 0)
			(type solid)
		)
		(fill yes)
		(layer "B.Cu")
		(net "GND")
	)
	(gr_poly
		(pts
			(arc
				(start 78.072488 -372.240302)
				(mid 77.82306 -372.240302)
				(end 78.072488 -372.240302)
			)
		)
		(stroke
			(width 0)
			(type solid)
		)
		(fill yes)
		(layer "B.Cu")
		(net "GND")
	)
	(gr_poly
		(pts
			(arc
				(start 78.072488 -371.038628)
				(mid 77.82306 -371.038628)
				(end 78.072488 -371.038628)
			)
		)
		(stroke
			(width 0)
			(type solid)
		)
		(fill yes)
		(layer "B.Cu")
		(net "GND")
	)
	(gr_poly
		(pts
			(arc
				(start 78.474316 -357.75773)
				(mid 78.224888 -357.75773)
				(end 78.474316 -357.75773)
			)
		)
		(stroke
			(width 0)
			(type solid)
		)
		(fill yes)
		(layer "B.Cu")
		(net "GND")
	)
	(gr_poly
		(pts
			(arc
				(start 78.474316 -354.732082)
				(mid 78.224888 -354.732082)
				(end 78.474316 -354.732082)
			)
		)
		(stroke
			(width 0)
			(type solid)
		)
		(fill yes)
		(layer "B.Cu")
		(net "GND")
	)
	(gr_poly
		(pts
			(arc
				(start 78.474316 -351.611438)
				(mid 78.224888 -351.611438)
				(end 78.474316 -351.611438)
			)
		)
		(stroke
			(width 0)
			(type solid)
		)
		(fill yes)
		(layer "B.Cu")
		(net "GND")
	)
	(gr_poly
		(pts
			(arc
				(start 78.474316 -348.58579)
				(mid 78.224888 -348.58579)
				(end 78.474316 -348.58579)
			)
		)
		(stroke
			(width 0)
			(type solid)
		)
		(fill yes)
		(layer "B.Cu")
		(net "GND")
	)
	(gr_poly
		(pts
			(arc
				(start 78.474316 -345.465146)
				(mid 78.224888 -345.465146)
				(end 78.474316 -345.465146)
			)
		)
		(stroke
			(width 0)
			(type solid)
		)
		(fill yes)
		(layer "B.Cu")
		(net "GND")
	)
	(gr_poly
		(pts
			(arc
				(start 78.474316 -342.439498)
				(mid 78.224888 -342.439498)
				(end 78.474316 -342.439498)
			)
		)
		(stroke
			(width 0)
			(type solid)
		)
		(fill yes)
		(layer "B.Cu")
		(net "GND")
	)
	(gr_poly
		(pts
			(arc
				(start 79.581756 -357.75773)
				(mid 79.332328 -357.75773)
				(end 79.581756 -357.75773)
			)
		)
		(stroke
			(width 0)
			(type solid)
		)
		(fill yes)
		(layer "B.Cu")
		(net "GND")
	)
	(gr_poly
		(pts
			(arc
				(start 79.581756 -354.732082)
				(mid 79.332328 -354.732082)
				(end 79.581756 -354.732082)
			)
		)
		(stroke
			(width 0)
			(type solid)
		)
		(fill yes)
		(layer "B.Cu")
		(net "GND")
	)
	(gr_poly
		(pts
			(arc
				(start 79.581756 -351.611438)
				(mid 79.332328 -351.611438)
				(end 79.581756 -351.611438)
			)
		)
		(stroke
			(width 0)
			(type solid)
		)
		(fill yes)
		(layer "B.Cu")
		(net "GND")
	)
	(gr_poly
		(pts
			(arc
				(start 79.581756 -348.58579)
				(mid 79.332328 -348.58579)
				(end 79.581756 -348.58579)
			)
		)
		(stroke
			(width 0)
			(type solid)
		)
		(fill yes)
		(layer "B.Cu")
		(net "GND")
	)
	(gr_poly
		(pts
			(arc
				(start 79.581756 -345.465146)
				(mid 79.332328 -345.465146)
				(end 79.581756 -345.465146)
			)
		)
		(stroke
			(width 0)
			(type solid)
		)
		(fill yes)
		(layer "B.Cu")
		(net "GND")
	)
	(gr_poly
		(pts
			(arc
				(start 79.581756 -342.439498)
				(mid 79.332328 -342.439498)
				(end 79.581756 -342.439498)
			)
		)
		(stroke
			(width 0)
			(type solid)
		)
		(fill yes)
		(layer "B.Cu")
		(net "GND")
	)
	(gr_poly
		(pts
			(arc
				(start 80.272636 -410.041852)
				(mid 80.023208 -410.041852)
				(end 80.272636 -410.041852)
			)
		)
		(stroke
			(width 0)
			(type solid)
		)
		(fill yes)
		(layer "B.Cu")
		(net "GND")
	)
	(gr_poly
		(pts
			(arc
				(start 80.272636 -408.840178)
				(mid 80.023208 -408.840178)
				(end 80.272636 -408.840178)
			)
		)
		(stroke
			(width 0)
			(type solid)
		)
		(fill yes)
		(layer "B.Cu")
		(net "GND")
	)
	(gr_poly
		(pts
			(arc
				(start 80.272636 -407.638504)
				(mid 80.023208 -407.638504)
				(end 80.272636 -407.638504)
			)
		)
		(stroke
			(width 0)
			(type solid)
		)
		(fill yes)
		(layer "B.Cu")
		(net "GND")
	)
	(gr_poly
		(pts
			(arc
				(start 80.272636 -406.141936)
				(mid 80.023208 -406.141936)
				(end 80.272636 -406.141936)
			)
		)
		(stroke
			(width 0)
			(type solid)
		)
		(fill yes)
		(layer "B.Cu")
		(net "GND")
	)
	(gr_poly
		(pts
			(arc
				(start 80.272636 -404.940262)
				(mid 80.023208 -404.940262)
				(end 80.272636 -404.940262)
			)
		)
		(stroke
			(width 0)
			(type solid)
		)
		(fill yes)
		(layer "B.Cu")
		(net "GND")
	)
	(gr_poly
		(pts
			(arc
				(start 80.272636 -403.738588)
				(mid 80.023208 -403.738588)
				(end 80.272636 -403.738588)
			)
		)
		(stroke
			(width 0)
			(type solid)
		)
		(fill yes)
		(layer "B.Cu")
		(net "GND")
	)
	(gr_poly
		(pts
			(arc
				(start 80.272636 -402.241766)
				(mid 80.023208 -402.241766)
				(end 80.272636 -402.241766)
			)
		)
		(stroke
			(width 0)
			(type solid)
		)
		(fill yes)
		(layer "B.Cu")
		(net "GND")
	)
	(gr_poly
		(pts
			(arc
				(start 80.272636 -401.040092)
				(mid 80.023208 -401.040092)
				(end 80.272636 -401.040092)
			)
		)
		(stroke
			(width 0)
			(type solid)
		)
		(fill yes)
		(layer "B.Cu")
		(net "GND")
	)
	(gr_poly
		(pts
			(arc
				(start 80.272636 -399.838418)
				(mid 80.023208 -399.838418)
				(end 80.272636 -399.838418)
			)
		)
		(stroke
			(width 0)
			(type solid)
		)
		(fill yes)
		(layer "B.Cu")
		(net "GND")
	)
	(gr_poly
		(pts
			(arc
				(start 80.272636 -398.34185)
				(mid 80.023208 -398.34185)
				(end 80.272636 -398.34185)
			)
		)
		(stroke
			(width 0)
			(type solid)
		)
		(fill yes)
		(layer "B.Cu")
		(net "GND")
	)
	(gr_poly
		(pts
			(arc
				(start 80.272636 -397.140176)
				(mid 80.023208 -397.140176)
				(end 80.272636 -397.140176)
			)
		)
		(stroke
			(width 0)
			(type solid)
		)
		(fill yes)
		(layer "B.Cu")
		(net "GND")
	)
	(gr_poly
		(pts
			(arc
				(start 80.272636 -395.938502)
				(mid 80.023208 -395.938502)
				(end 80.272636 -395.938502)
			)
		)
		(stroke
			(width 0)
			(type solid)
		)
		(fill yes)
		(layer "B.Cu")
		(net "GND")
	)
	(gr_poly
		(pts
			(arc
				(start 80.272636 -384.041904)
				(mid 80.023208 -384.041904)
				(end 80.272636 -384.041904)
			)
		)
		(stroke
			(width 0)
			(type solid)
		)
		(fill yes)
		(layer "B.Cu")
		(net "GND")
	)
	(gr_poly
		(pts
			(arc
				(start 80.272636 -382.84023)
				(mid 80.023208 -382.84023)
				(end 80.272636 -382.84023)
			)
		)
		(stroke
			(width 0)
			(type solid)
		)
		(fill yes)
		(layer "B.Cu")
		(net "GND")
	)
	(gr_poly
		(pts
			(arc
				(start 80.272636 -381.638556)
				(mid 80.023208 -381.638556)
				(end 80.272636 -381.638556)
			)
		)
		(stroke
			(width 0)
			(type solid)
		)
		(fill yes)
		(layer "B.Cu")
		(net "GND")
	)
	(gr_poly
		(pts
			(arc
				(start 80.272636 -380.141988)
				(mid 80.023208 -380.141988)
				(end 80.272636 -380.141988)
			)
		)
		(stroke
			(width 0)
			(type solid)
		)
		(fill yes)
		(layer "B.Cu")
		(net "GND")
	)
	(gr_poly
		(pts
			(arc
				(start 80.272636 -378.940314)
				(mid 80.023208 -378.940314)
				(end 80.272636 -378.940314)
			)
		)
		(stroke
			(width 0)
			(type solid)
		)
		(fill yes)
		(layer "B.Cu")
		(net "GND")
	)
	(gr_poly
		(pts
			(arc
				(start 80.272636 -377.73864)
				(mid 80.023208 -377.73864)
				(end 80.272636 -377.73864)
			)
		)
		(stroke
			(width 0)
			(type solid)
		)
		(fill yes)
		(layer "B.Cu")
		(net "GND")
	)
	(gr_poly
		(pts
			(arc
				(start 80.272636 -376.241818)
				(mid 80.023208 -376.241818)
				(end 80.272636 -376.241818)
			)
		)
		(stroke
			(width 0)
			(type solid)
		)
		(fill yes)
		(layer "B.Cu")
		(net "GND")
	)
	(gr_poly
		(pts
			(arc
				(start 80.272636 -375.040144)
				(mid 80.023208 -375.040144)
				(end 80.272636 -375.040144)
			)
		)
		(stroke
			(width 0)
			(type solid)
		)
		(fill yes)
		(layer "B.Cu")
		(net "GND")
	)
	(gr_poly
		(pts
			(arc
				(start 80.272636 -373.83847)
				(mid 80.023208 -373.83847)
				(end 80.272636 -373.83847)
			)
		)
		(stroke
			(width 0)
			(type solid)
		)
		(fill yes)
		(layer "B.Cu")
		(net "GND")
	)
	(gr_poly
		(pts
			(arc
				(start 80.272636 -372.341902)
				(mid 80.023208 -372.341902)
				(end 80.272636 -372.341902)
			)
		)
		(stroke
			(width 0)
			(type solid)
		)
		(fill yes)
		(layer "B.Cu")
		(net "GND")
	)
	(gr_poly
		(pts
			(arc
				(start 80.272636 -371.140228)
				(mid 80.023208 -371.140228)
				(end 80.272636 -371.140228)
			)
		)
		(stroke
			(width 0)
			(type solid)
		)
		(fill yes)
		(layer "B.Cu")
		(net "GND")
	)
	(gr_poly
		(pts
			(arc
				(start 80.272636 -369.938554)
				(mid 80.023208 -369.938554)
				(end 80.272636 -369.938554)
			)
		)
		(stroke
			(width 0)
			(type solid)
		)
		(fill yes)
		(layer "B.Cu")
		(net "GND")
	)
	(gr_poly
		(pts
			(arc
				(start 81.583276 -357.75773)
				(mid 81.333848 -357.75773)
				(end 81.583276 -357.75773)
			)
		)
		(stroke
			(width 0)
			(type solid)
		)
		(fill yes)
		(layer "B.Cu")
		(net "GND")
	)
	(gr_poly
		(pts
			(arc
				(start 81.583276 -354.732082)
				(mid 81.333848 -354.732082)
				(end 81.583276 -354.732082)
			)
		)
		(stroke
			(width 0)
			(type solid)
		)
		(fill yes)
		(layer "B.Cu")
		(net "GND")
	)
	(gr_poly
		(pts
			(arc
				(start 81.583276 -351.611438)
				(mid 81.333848 -351.611438)
				(end 81.583276 -351.611438)
			)
		)
		(stroke
			(width 0)
			(type solid)
		)
		(fill yes)
		(layer "B.Cu")
		(net "GND")
	)
	(gr_poly
		(pts
			(arc
				(start 81.583276 -348.58579)
				(mid 81.333848 -348.58579)
				(end 81.583276 -348.58579)
			)
		)
		(stroke
			(width 0)
			(type solid)
		)
		(fill yes)
		(layer "B.Cu")
		(net "GND")
	)
	(gr_poly
		(pts
			(arc
				(start 81.583276 -345.465146)
				(mid 81.333848 -345.465146)
				(end 81.583276 -345.465146)
			)
		)
		(stroke
			(width 0)
			(type solid)
		)
		(fill yes)
		(layer "B.Cu")
		(net "GND")
	)
	(gr_poly
		(pts
			(arc
				(start 81.583276 -342.439498)
				(mid 81.333848 -342.439498)
				(end 81.583276 -342.439498)
			)
		)
		(stroke
			(width 0)
			(type solid)
		)
		(fill yes)
		(layer "B.Cu")
		(net "GND")
	)
	(gr_poly
		(pts
			(arc
				(start 82.47253 -411.141926)
				(mid 82.223102 -411.141926)
				(end 82.47253 -411.141926)
			)
		)
		(stroke
			(width 0)
			(type solid)
		)
		(fill yes)
		(layer "B.Cu")
		(net "GND")
	)
	(gr_poly
		(pts
			(arc
				(start 82.47253 -409.940252)
				(mid 82.223102 -409.940252)
				(end 82.47253 -409.940252)
			)
		)
		(stroke
			(width 0)
			(type solid)
		)
		(fill yes)
		(layer "B.Cu")
		(net "GND")
	)
	(gr_poly
		(pts
			(arc
				(start 82.47253 -408.738578)
				(mid 82.223102 -408.738578)
				(end 82.47253 -408.738578)
			)
		)
		(stroke
			(width 0)
			(type solid)
		)
		(fill yes)
		(layer "B.Cu")
		(net "GND")
	)
	(gr_poly
		(pts
			(arc
				(start 82.47253 -407.24201)
				(mid 82.223102 -407.24201)
				(end 82.47253 -407.24201)
			)
		)
		(stroke
			(width 0)
			(type solid)
		)
		(fill yes)
		(layer "B.Cu")
		(net "GND")
	)
	(gr_poly
		(pts
			(arc
				(start 82.47253 -406.040336)
				(mid 82.223102 -406.040336)
				(end 82.47253 -406.040336)
			)
		)
		(stroke
			(width 0)
			(type solid)
		)
		(fill yes)
		(layer "B.Cu")
		(net "GND")
	)
	(gr_poly
		(pts
			(arc
				(start 82.47253 -404.838662)
				(mid 82.223102 -404.838662)
				(end 82.47253 -404.838662)
			)
		)
		(stroke
			(width 0)
			(type solid)
		)
		(fill yes)
		(layer "B.Cu")
		(net "GND")
	)
	(gr_poly
		(pts
			(arc
				(start 82.47253 -403.34184)
				(mid 82.223102 -403.34184)
				(end 82.47253 -403.34184)
			)
		)
		(stroke
			(width 0)
			(type solid)
		)
		(fill yes)
		(layer "B.Cu")
		(net "GND")
	)
	(gr_poly
		(pts
			(arc
				(start 82.47253 -402.140166)
				(mid 82.223102 -402.140166)
				(end 82.47253 -402.140166)
			)
		)
		(stroke
			(width 0)
			(type solid)
		)
		(fill yes)
		(layer "B.Cu")
		(net "GND")
	)
	(gr_poly
		(pts
			(arc
				(start 82.47253 -400.938492)
				(mid 82.223102 -400.938492)
				(end 82.47253 -400.938492)
			)
		)
		(stroke
			(width 0)
			(type solid)
		)
		(fill yes)
		(layer "B.Cu")
		(net "GND")
	)
	(gr_poly
		(pts
			(arc
				(start 82.47253 -399.441924)
				(mid 82.223102 -399.441924)
				(end 82.47253 -399.441924)
			)
		)
		(stroke
			(width 0)
			(type solid)
		)
		(fill yes)
		(layer "B.Cu")
		(net "GND")
	)
	(gr_poly
		(pts
			(arc
				(start 82.47253 -398.24025)
				(mid 82.223102 -398.24025)
				(end 82.47253 -398.24025)
			)
		)
		(stroke
			(width 0)
			(type solid)
		)
		(fill yes)
		(layer "B.Cu")
		(net "GND")
	)
	(gr_poly
		(pts
			(arc
				(start 82.47253 -397.038576)
				(mid 82.223102 -397.038576)
				(end 82.47253 -397.038576)
			)
		)
		(stroke
			(width 0)
			(type solid)
		)
		(fill yes)
		(layer "B.Cu")
		(net "GND")
	)
	(gr_poly
		(pts
			(arc
				(start 82.47253 -385.141978)
				(mid 82.223102 -385.141978)
				(end 82.47253 -385.141978)
			)
		)
		(stroke
			(width 0)
			(type solid)
		)
		(fill yes)
		(layer "B.Cu")
		(net "GND")
	)
	(gr_poly
		(pts
			(arc
				(start 82.47253 -383.940304)
				(mid 82.223102 -383.940304)
				(end 82.47253 -383.940304)
			)
		)
		(stroke
			(width 0)
			(type solid)
		)
		(fill yes)
		(layer "B.Cu")
		(net "GND")
	)
	(gr_poly
		(pts
			(arc
				(start 82.47253 -382.73863)
				(mid 82.223102 -382.73863)
				(end 82.47253 -382.73863)
			)
		)
		(stroke
			(width 0)
			(type solid)
		)
		(fill yes)
		(layer "B.Cu")
		(net "GND")
	)
	(gr_poly
		(pts
			(arc
				(start 82.47253 -381.242062)
				(mid 82.223102 -381.242062)
				(end 82.47253 -381.242062)
			)
		)
		(stroke
			(width 0)
			(type solid)
		)
		(fill yes)
		(layer "B.Cu")
		(net "GND")
	)
	(gr_poly
		(pts
			(arc
				(start 82.47253 -380.040388)
				(mid 82.223102 -380.040388)
				(end 82.47253 -380.040388)
			)
		)
		(stroke
			(width 0)
			(type solid)
		)
		(fill yes)
		(layer "B.Cu")
		(net "GND")
	)
	(gr_poly
		(pts
			(arc
				(start 82.47253 -378.838714)
				(mid 82.223102 -378.838714)
				(end 82.47253 -378.838714)
			)
		)
		(stroke
			(width 0)
			(type solid)
		)
		(fill yes)
		(layer "B.Cu")
		(net "GND")
	)
	(gr_poly
		(pts
			(arc
				(start 82.47253 -377.341892)
				(mid 82.223102 -377.341892)
				(end 82.47253 -377.341892)
			)
		)
		(stroke
			(width 0)
			(type solid)
		)
		(fill yes)
		(layer "B.Cu")
		(net "GND")
	)
	(gr_poly
		(pts
			(arc
				(start 82.47253 -376.140218)
				(mid 82.223102 -376.140218)
				(end 82.47253 -376.140218)
			)
		)
		(stroke
			(width 0)
			(type solid)
		)
		(fill yes)
		(layer "B.Cu")
		(net "GND")
	)
	(gr_poly
		(pts
			(arc
				(start 82.47253 -374.938544)
				(mid 82.223102 -374.938544)
				(end 82.47253 -374.938544)
			)
		)
		(stroke
			(width 0)
			(type solid)
		)
		(fill yes)
		(layer "B.Cu")
		(net "GND")
	)
	(gr_poly
		(pts
			(arc
				(start 82.47253 -373.441976)
				(mid 82.223102 -373.441976)
				(end 82.47253 -373.441976)
			)
		)
		(stroke
			(width 0)
			(type solid)
		)
		(fill yes)
		(layer "B.Cu")
		(net "GND")
	)
	(gr_poly
		(pts
			(arc
				(start 82.47253 -372.240302)
				(mid 82.223102 -372.240302)
				(end 82.47253 -372.240302)
			)
		)
		(stroke
			(width 0)
			(type solid)
		)
		(fill yes)
		(layer "B.Cu")
		(net "GND")
	)
	(gr_poly
		(pts
			(arc
				(start 82.47253 -371.038628)
				(mid 82.223102 -371.038628)
				(end 82.47253 -371.038628)
			)
		)
		(stroke
			(width 0)
			(type solid)
		)
		(fill yes)
		(layer "B.Cu")
		(net "GND")
	)
	(gr_poly
		(pts
			(arc
				(start 82.690716 -357.75773)
				(mid 82.441288 -357.75773)
				(end 82.690716 -357.75773)
			)
		)
		(stroke
			(width 0)
			(type solid)
		)
		(fill yes)
		(layer "B.Cu")
		(net "GND")
	)
	(gr_poly
		(pts
			(arc
				(start 82.690716 -354.732082)
				(mid 82.441288 -354.732082)
				(end 82.690716 -354.732082)
			)
		)
		(stroke
			(width 0)
			(type solid)
		)
		(fill yes)
		(layer "B.Cu")
		(net "GND")
	)
	(gr_poly
		(pts
			(arc
				(start 82.690716 -351.611438)
				(mid 82.441288 -351.611438)
				(end 82.690716 -351.611438)
			)
		)
		(stroke
			(width 0)
			(type solid)
		)
		(fill yes)
		(layer "B.Cu")
		(net "GND")
	)
	(gr_poly
		(pts
			(arc
				(start 82.690716 -348.58579)
				(mid 82.441288 -348.58579)
				(end 82.690716 -348.58579)
			)
		)
		(stroke
			(width 0)
			(type solid)
		)
		(fill yes)
		(layer "B.Cu")
		(net "GND")
	)
	(gr_poly
		(pts
			(arc
				(start 82.690716 -345.465146)
				(mid 82.441288 -345.465146)
				(end 82.690716 -345.465146)
			)
		)
		(stroke
			(width 0)
			(type solid)
		)
		(fill yes)
		(layer "B.Cu")
		(net "GND")
	)
	(gr_poly
		(pts
			(arc
				(start 82.690716 -342.439498)
				(mid 82.441288 -342.439498)
				(end 82.690716 -342.439498)
			)
		)
		(stroke
			(width 0)
			(type solid)
		)
		(fill yes)
		(layer "B.Cu")
		(net "GND")
	)
	(gr_poly
		(pts
			(arc
				(start 84.672424 -410.041852)
				(mid 84.422996 -410.041852)
				(end 84.672424 -410.041852)
			)
		)
		(stroke
			(width 0)
			(type solid)
		)
		(fill yes)
		(layer "B.Cu")
		(net "GND")
	)
	(gr_poly
		(pts
			(arc
				(start 84.672424 -408.840178)
				(mid 84.422996 -408.840178)
				(end 84.672424 -408.840178)
			)
		)
		(stroke
			(width 0)
			(type solid)
		)
		(fill yes)
		(layer "B.Cu")
		(net "GND")
	)
	(gr_poly
		(pts
			(arc
				(start 84.672424 -407.638504)
				(mid 84.422996 -407.638504)
				(end 84.672424 -407.638504)
			)
		)
		(stroke
			(width 0)
			(type solid)
		)
		(fill yes)
		(layer "B.Cu")
		(net "GND")
	)
	(gr_poly
		(pts
			(arc
				(start 84.672424 -406.141936)
				(mid 84.422996 -406.141936)
				(end 84.672424 -406.141936)
			)
		)
		(stroke
			(width 0)
			(type solid)
		)
		(fill yes)
		(layer "B.Cu")
		(net "GND")
	)
	(gr_poly
		(pts
			(arc
				(start 84.672424 -404.940262)
				(mid 84.422996 -404.940262)
				(end 84.672424 -404.940262)
			)
		)
		(stroke
			(width 0)
			(type solid)
		)
		(fill yes)
		(layer "B.Cu")
		(net "GND")
	)
	(gr_poly
		(pts
			(arc
				(start 84.672424 -403.738588)
				(mid 84.422996 -403.738588)
				(end 84.672424 -403.738588)
			)
		)
		(stroke
			(width 0)
			(type solid)
		)
		(fill yes)
		(layer "B.Cu")
		(net "GND")
	)
	(gr_poly
		(pts
			(arc
				(start 84.672424 -402.241766)
				(mid 84.422996 -402.241766)
				(end 84.672424 -402.241766)
			)
		)
		(stroke
			(width 0)
			(type solid)
		)
		(fill yes)
		(layer "B.Cu")
		(net "GND")
	)
	(gr_poly
		(pts
			(arc
				(start 84.672424 -401.040092)
				(mid 84.422996 -401.040092)
				(end 84.672424 -401.040092)
			)
		)
		(stroke
			(width 0)
			(type solid)
		)
		(fill yes)
		(layer "B.Cu")
		(net "GND")
	)
	(gr_poly
		(pts
			(arc
				(start 84.672424 -399.838418)
				(mid 84.422996 -399.838418)
				(end 84.672424 -399.838418)
			)
		)
		(stroke
			(width 0)
			(type solid)
		)
		(fill yes)
		(layer "B.Cu")
		(net "GND")
	)
	(gr_poly
		(pts
			(arc
				(start 84.672424 -398.34185)
				(mid 84.422996 -398.34185)
				(end 84.672424 -398.34185)
			)
		)
		(stroke
			(width 0)
			(type solid)
		)
		(fill yes)
		(layer "B.Cu")
		(net "GND")
	)
	(gr_poly
		(pts
			(arc
				(start 84.672424 -397.140176)
				(mid 84.422996 -397.140176)
				(end 84.672424 -397.140176)
			)
		)
		(stroke
			(width 0)
			(type solid)
		)
		(fill yes)
		(layer "B.Cu")
		(net "GND")
	)
	(gr_poly
		(pts
			(arc
				(start 84.672424 -395.938502)
				(mid 84.422996 -395.938502)
				(end 84.672424 -395.938502)
			)
		)
		(stroke
			(width 0)
			(type solid)
		)
		(fill yes)
		(layer "B.Cu")
		(net "GND")
	)
	(gr_poly
		(pts
			(arc
				(start 84.672424 -384.041904)
				(mid 84.422996 -384.041904)
				(end 84.672424 -384.041904)
			)
		)
		(stroke
			(width 0)
			(type solid)
		)
		(fill yes)
		(layer "B.Cu")
		(net "GND")
	)
	(gr_poly
		(pts
			(arc
				(start 84.672424 -382.84023)
				(mid 84.422996 -382.84023)
				(end 84.672424 -382.84023)
			)
		)
		(stroke
			(width 0)
			(type solid)
		)
		(fill yes)
		(layer "B.Cu")
		(net "GND")
	)
	(gr_poly
		(pts
			(arc
				(start 84.672424 -381.638556)
				(mid 84.422996 -381.638556)
				(end 84.672424 -381.638556)
			)
		)
		(stroke
			(width 0)
			(type solid)
		)
		(fill yes)
		(layer "B.Cu")
		(net "GND")
	)
	(gr_poly
		(pts
			(arc
				(start 84.672424 -380.141988)
				(mid 84.422996 -380.141988)
				(end 84.672424 -380.141988)
			)
		)
		(stroke
			(width 0)
			(type solid)
		)
		(fill yes)
		(layer "B.Cu")
		(net "GND")
	)
	(gr_poly
		(pts
			(arc
				(start 84.672424 -378.940314)
				(mid 84.422996 -378.940314)
				(end 84.672424 -378.940314)
			)
		)
		(stroke
			(width 0)
			(type solid)
		)
		(fill yes)
		(layer "B.Cu")
		(net "GND")
	)
	(gr_poly
		(pts
			(arc
				(start 84.672424 -377.73864)
				(mid 84.422996 -377.73864)
				(end 84.672424 -377.73864)
			)
		)
		(stroke
			(width 0)
			(type solid)
		)
		(fill yes)
		(layer "B.Cu")
		(net "GND")
	)
	(gr_poly
		(pts
			(arc
				(start 84.672424 -376.241818)
				(mid 84.422996 -376.241818)
				(end 84.672424 -376.241818)
			)
		)
		(stroke
			(width 0)
			(type solid)
		)
		(fill yes)
		(layer "B.Cu")
		(net "GND")
	)
	(gr_poly
		(pts
			(arc
				(start 84.672424 -375.040144)
				(mid 84.422996 -375.040144)
				(end 84.672424 -375.040144)
			)
		)
		(stroke
			(width 0)
			(type solid)
		)
		(fill yes)
		(layer "B.Cu")
		(net "GND")
	)
	(gr_poly
		(pts
			(arc
				(start 84.672424 -373.83847)
				(mid 84.422996 -373.83847)
				(end 84.672424 -373.83847)
			)
		)
		(stroke
			(width 0)
			(type solid)
		)
		(fill yes)
		(layer "B.Cu")
		(net "GND")
	)
	(gr_poly
		(pts
			(arc
				(start 84.672424 -372.341902)
				(mid 84.422996 -372.341902)
				(end 84.672424 -372.341902)
			)
		)
		(stroke
			(width 0)
			(type solid)
		)
		(fill yes)
		(layer "B.Cu")
		(net "GND")
	)
	(gr_poly
		(pts
			(arc
				(start 84.672424 -371.140228)
				(mid 84.422996 -371.140228)
				(end 84.672424 -371.140228)
			)
		)
		(stroke
			(width 0)
			(type solid)
		)
		(fill yes)
		(layer "B.Cu")
		(net "GND")
	)
	(gr_poly
		(pts
			(arc
				(start 84.672424 -369.938554)
				(mid 84.422996 -369.938554)
				(end 84.672424 -369.938554)
			)
		)
		(stroke
			(width 0)
			(type solid)
		)
		(fill yes)
		(layer "B.Cu")
		(net "GND")
	)
	(gr_poly
		(pts
			(arc
				(start 84.692236 -357.75773)
				(mid 84.442808 -357.75773)
				(end 84.692236 -357.75773)
			)
		)
		(stroke
			(width 0)
			(type solid)
		)
		(fill yes)
		(layer "B.Cu")
		(net "GND")
	)
	(gr_poly
		(pts
			(arc
				(start 84.692236 -354.732082)
				(mid 84.442808 -354.732082)
				(end 84.692236 -354.732082)
			)
		)
		(stroke
			(width 0)
			(type solid)
		)
		(fill yes)
		(layer "B.Cu")
		(net "GND")
	)
	(gr_poly
		(pts
			(arc
				(start 84.692236 -351.611438)
				(mid 84.442808 -351.611438)
				(end 84.692236 -351.611438)
			)
		)
		(stroke
			(width 0)
			(type solid)
		)
		(fill yes)
		(layer "B.Cu")
		(net "GND")
	)
	(gr_poly
		(pts
			(arc
				(start 84.692236 -348.58579)
				(mid 84.442808 -348.58579)
				(end 84.692236 -348.58579)
			)
		)
		(stroke
			(width 0)
			(type solid)
		)
		(fill yes)
		(layer "B.Cu")
		(net "GND")
	)
	(gr_poly
		(pts
			(arc
				(start 84.692236 -345.465146)
				(mid 84.442808 -345.465146)
				(end 84.692236 -345.465146)
			)
		)
		(stroke
			(width 0)
			(type solid)
		)
		(fill yes)
		(layer "B.Cu")
		(net "GND")
	)
	(gr_poly
		(pts
			(arc
				(start 84.692236 -342.439498)
				(mid 84.442808 -342.439498)
				(end 84.692236 -342.439498)
			)
		)
		(stroke
			(width 0)
			(type solid)
		)
		(fill yes)
		(layer "B.Cu")
		(net "GND")
	)
	(gr_poly
		(pts
			(arc
				(start 85.799676 -357.75773)
				(mid 85.550248 -357.75773)
				(end 85.799676 -357.75773)
			)
		)
		(stroke
			(width 0)
			(type solid)
		)
		(fill yes)
		(layer "B.Cu")
		(net "GND")
	)
	(gr_poly
		(pts
			(arc
				(start 85.799676 -354.732082)
				(mid 85.550248 -354.732082)
				(end 85.799676 -354.732082)
			)
		)
		(stroke
			(width 0)
			(type solid)
		)
		(fill yes)
		(layer "B.Cu")
		(net "GND")
	)
	(gr_poly
		(pts
			(arc
				(start 85.799676 -351.611438)
				(mid 85.550248 -351.611438)
				(end 85.799676 -351.611438)
			)
		)
		(stroke
			(width 0)
			(type solid)
		)
		(fill yes)
		(layer "B.Cu")
		(net "GND")
	)
	(gr_poly
		(pts
			(arc
				(start 85.799676 -348.58579)
				(mid 85.550248 -348.58579)
				(end 85.799676 -348.58579)
			)
		)
		(stroke
			(width 0)
			(type solid)
		)
		(fill yes)
		(layer "B.Cu")
		(net "GND")
	)
	(gr_poly
		(pts
			(arc
				(start 85.799676 -345.465146)
				(mid 85.550248 -345.465146)
				(end 85.799676 -345.465146)
			)
		)
		(stroke
			(width 0)
			(type solid)
		)
		(fill yes)
		(layer "B.Cu")
		(net "GND")
	)
	(gr_poly
		(pts
			(arc
				(start 85.799676 -342.439498)
				(mid 85.550248 -342.439498)
				(end 85.799676 -342.439498)
			)
		)
		(stroke
			(width 0)
			(type solid)
		)
		(fill yes)
		(layer "B.Cu")
		(net "GND")
	)
	(gr_poly
		(pts
			(arc
				(start 86.872572 -411.141926)
				(mid 86.623144 -411.141926)
				(end 86.872572 -411.141926)
			)
		)
		(stroke
			(width 0)
			(type solid)
		)
		(fill yes)
		(layer "B.Cu")
		(net "GND")
	)
	(gr_poly
		(pts
			(arc
				(start 86.872572 -409.940252)
				(mid 86.623144 -409.940252)
				(end 86.872572 -409.940252)
			)
		)
		(stroke
			(width 0)
			(type solid)
		)
		(fill yes)
		(layer "B.Cu")
		(net "GND")
	)
	(gr_poly
		(pts
			(arc
				(start 86.872572 -408.738578)
				(mid 86.623144 -408.738578)
				(end 86.872572 -408.738578)
			)
		)
		(stroke
			(width 0)
			(type solid)
		)
		(fill yes)
		(layer "B.Cu")
		(net "GND")
	)
	(gr_poly
		(pts
			(arc
				(start 86.872572 -407.24201)
				(mid 86.623144 -407.24201)
				(end 86.872572 -407.24201)
			)
		)
		(stroke
			(width 0)
			(type solid)
		)
		(fill yes)
		(layer "B.Cu")
		(net "GND")
	)
	(gr_poly
		(pts
			(arc
				(start 86.872572 -406.040336)
				(mid 86.623144 -406.040336)
				(end 86.872572 -406.040336)
			)
		)
		(stroke
			(width 0)
			(type solid)
		)
		(fill yes)
		(layer "B.Cu")
		(net "GND")
	)
	(gr_poly
		(pts
			(arc
				(start 86.872572 -404.838662)
				(mid 86.623144 -404.838662)
				(end 86.872572 -404.838662)
			)
		)
		(stroke
			(width 0)
			(type solid)
		)
		(fill yes)
		(layer "B.Cu")
		(net "GND")
	)
	(gr_poly
		(pts
			(arc
				(start 86.872572 -403.34184)
				(mid 86.623144 -403.34184)
				(end 86.872572 -403.34184)
			)
		)
		(stroke
			(width 0)
			(type solid)
		)
		(fill yes)
		(layer "B.Cu")
		(net "GND")
	)
	(gr_poly
		(pts
			(arc
				(start 86.872572 -402.140166)
				(mid 86.623144 -402.140166)
				(end 86.872572 -402.140166)
			)
		)
		(stroke
			(width 0)
			(type solid)
		)
		(fill yes)
		(layer "B.Cu")
		(net "GND")
	)
	(gr_poly
		(pts
			(arc
				(start 86.872572 -400.938492)
				(mid 86.623144 -400.938492)
				(end 86.872572 -400.938492)
			)
		)
		(stroke
			(width 0)
			(type solid)
		)
		(fill yes)
		(layer "B.Cu")
		(net "GND")
	)
	(gr_poly
		(pts
			(arc
				(start 86.872572 -399.441924)
				(mid 86.623144 -399.441924)
				(end 86.872572 -399.441924)
			)
		)
		(stroke
			(width 0)
			(type solid)
		)
		(fill yes)
		(layer "B.Cu")
		(net "GND")
	)
	(gr_poly
		(pts
			(arc
				(start 86.872572 -398.24025)
				(mid 86.623144 -398.24025)
				(end 86.872572 -398.24025)
			)
		)
		(stroke
			(width 0)
			(type solid)
		)
		(fill yes)
		(layer "B.Cu")
		(net "GND")
	)
	(gr_poly
		(pts
			(arc
				(start 86.872572 -397.038576)
				(mid 86.623144 -397.038576)
				(end 86.872572 -397.038576)
			)
		)
		(stroke
			(width 0)
			(type solid)
		)
		(fill yes)
		(layer "B.Cu")
		(net "GND")
	)
	(gr_poly
		(pts
			(arc
				(start 86.872572 -385.141978)
				(mid 86.623144 -385.141978)
				(end 86.872572 -385.141978)
			)
		)
		(stroke
			(width 0)
			(type solid)
		)
		(fill yes)
		(layer "B.Cu")
		(net "GND")
	)
	(gr_poly
		(pts
			(arc
				(start 86.872572 -383.940304)
				(mid 86.623144 -383.940304)
				(end 86.872572 -383.940304)
			)
		)
		(stroke
			(width 0)
			(type solid)
		)
		(fill yes)
		(layer "B.Cu")
		(net "GND")
	)
	(gr_poly
		(pts
			(arc
				(start 86.872572 -382.73863)
				(mid 86.623144 -382.73863)
				(end 86.872572 -382.73863)
			)
		)
		(stroke
			(width 0)
			(type solid)
		)
		(fill yes)
		(layer "B.Cu")
		(net "GND")
	)
	(gr_poly
		(pts
			(arc
				(start 86.872572 -381.242062)
				(mid 86.623144 -381.242062)
				(end 86.872572 -381.242062)
			)
		)
		(stroke
			(width 0)
			(type solid)
		)
		(fill yes)
		(layer "B.Cu")
		(net "GND")
	)
	(gr_poly
		(pts
			(arc
				(start 86.872572 -380.040388)
				(mid 86.623144 -380.040388)
				(end 86.872572 -380.040388)
			)
		)
		(stroke
			(width 0)
			(type solid)
		)
		(fill yes)
		(layer "B.Cu")
		(net "GND")
	)
	(gr_poly
		(pts
			(arc
				(start 86.872572 -378.838714)
				(mid 86.623144 -378.838714)
				(end 86.872572 -378.838714)
			)
		)
		(stroke
			(width 0)
			(type solid)
		)
		(fill yes)
		(layer "B.Cu")
		(net "GND")
	)
	(gr_poly
		(pts
			(arc
				(start 86.872572 -377.341892)
				(mid 86.623144 -377.341892)
				(end 86.872572 -377.341892)
			)
		)
		(stroke
			(width 0)
			(type solid)
		)
		(fill yes)
		(layer "B.Cu")
		(net "GND")
	)
	(gr_poly
		(pts
			(arc
				(start 86.872572 -376.140218)
				(mid 86.623144 -376.140218)
				(end 86.872572 -376.140218)
			)
		)
		(stroke
			(width 0)
			(type solid)
		)
		(fill yes)
		(layer "B.Cu")
		(net "GND")
	)
	(gr_poly
		(pts
			(arc
				(start 86.872572 -374.938544)
				(mid 86.623144 -374.938544)
				(end 86.872572 -374.938544)
			)
		)
		(stroke
			(width 0)
			(type solid)
		)
		(fill yes)
		(layer "B.Cu")
		(net "GND")
	)
	(gr_poly
		(pts
			(arc
				(start 86.872572 -373.441976)
				(mid 86.623144 -373.441976)
				(end 86.872572 -373.441976)
			)
		)
		(stroke
			(width 0)
			(type solid)
		)
		(fill yes)
		(layer "B.Cu")
		(net "GND")
	)
	(gr_poly
		(pts
			(arc
				(start 86.872572 -372.240302)
				(mid 86.623144 -372.240302)
				(end 86.872572 -372.240302)
			)
		)
		(stroke
			(width 0)
			(type solid)
		)
		(fill yes)
		(layer "B.Cu")
		(net "GND")
	)
	(gr_poly
		(pts
			(arc
				(start 86.872572 -371.038628)
				(mid 86.623144 -371.038628)
				(end 86.872572 -371.038628)
			)
		)
		(stroke
			(width 0)
			(type solid)
		)
		(fill yes)
		(layer "B.Cu")
		(net "GND")
	)
	(gr_poly
		(pts
			(arc
				(start 87.801196 -357.75773)
				(mid 87.551768 -357.75773)
				(end 87.801196 -357.75773)
			)
		)
		(stroke
			(width 0)
			(type solid)
		)
		(fill yes)
		(layer "B.Cu")
		(net "GND")
	)
	(gr_poly
		(pts
			(arc
				(start 87.801196 -354.732082)
				(mid 87.551768 -354.732082)
				(end 87.801196 -354.732082)
			)
		)
		(stroke
			(width 0)
			(type solid)
		)
		(fill yes)
		(layer "B.Cu")
		(net "GND")
	)
	(gr_poly
		(pts
			(arc
				(start 87.801196 -351.611438)
				(mid 87.551768 -351.611438)
				(end 87.801196 -351.611438)
			)
		)
		(stroke
			(width 0)
			(type solid)
		)
		(fill yes)
		(layer "B.Cu")
		(net "GND")
	)
	(gr_poly
		(pts
			(arc
				(start 87.801196 -348.58579)
				(mid 87.551768 -348.58579)
				(end 87.801196 -348.58579)
			)
		)
		(stroke
			(width 0)
			(type solid)
		)
		(fill yes)
		(layer "B.Cu")
		(net "GND")
	)
	(gr_poly
		(pts
			(arc
				(start 87.801196 -345.465146)
				(mid 87.551768 -345.465146)
				(end 87.801196 -345.465146)
			)
		)
		(stroke
			(width 0)
			(type solid)
		)
		(fill yes)
		(layer "B.Cu")
		(net "GND")
	)
	(gr_poly
		(pts
			(arc
				(start 87.801196 -342.439498)
				(mid 87.551768 -342.439498)
				(end 87.801196 -342.439498)
			)
		)
		(stroke
			(width 0)
			(type solid)
		)
		(fill yes)
		(layer "B.Cu")
		(net "GND")
	)
	(gr_poly
		(pts
			(arc
				(start 88.908636 -357.75773)
				(mid 88.659208 -357.75773)
				(end 88.908636 -357.75773)
			)
		)
		(stroke
			(width 0)
			(type solid)
		)
		(fill yes)
		(layer "B.Cu")
		(net "GND")
	)
	(gr_poly
		(pts
			(arc
				(start 88.908636 -354.732082)
				(mid 88.659208 -354.732082)
				(end 88.908636 -354.732082)
			)
		)
		(stroke
			(width 0)
			(type solid)
		)
		(fill yes)
		(layer "B.Cu")
		(net "GND")
	)
	(gr_poly
		(pts
			(arc
				(start 88.908636 -351.611438)
				(mid 88.659208 -351.611438)
				(end 88.908636 -351.611438)
			)
		)
		(stroke
			(width 0)
			(type solid)
		)
		(fill yes)
		(layer "B.Cu")
		(net "GND")
	)
	(gr_poly
		(pts
			(arc
				(start 88.908636 -348.58579)
				(mid 88.659208 -348.58579)
				(end 88.908636 -348.58579)
			)
		)
		(stroke
			(width 0)
			(type solid)
		)
		(fill yes)
		(layer "B.Cu")
		(net "GND")
	)
	(gr_poly
		(pts
			(arc
				(start 88.908636 -345.465146)
				(mid 88.659208 -345.465146)
				(end 88.908636 -345.465146)
			)
		)
		(stroke
			(width 0)
			(type solid)
		)
		(fill yes)
		(layer "B.Cu")
		(net "GND")
	)
	(gr_poly
		(pts
			(arc
				(start 88.908636 -342.439498)
				(mid 88.659208 -342.439498)
				(end 88.908636 -342.439498)
			)
		)
		(stroke
			(width 0)
			(type solid)
		)
		(fill yes)
		(layer "B.Cu")
		(net "GND")
	)
	(gr_poly
		(pts
			(arc
				(start 89.072466 -410.041852)
				(mid 88.823038 -410.041852)
				(end 89.072466 -410.041852)
			)
		)
		(stroke
			(width 0)
			(type solid)
		)
		(fill yes)
		(layer "B.Cu")
		(net "GND")
	)
	(gr_poly
		(pts
			(arc
				(start 89.072466 -408.840178)
				(mid 88.823038 -408.840178)
				(end 89.072466 -408.840178)
			)
		)
		(stroke
			(width 0)
			(type solid)
		)
		(fill yes)
		(layer "B.Cu")
		(net "GND")
	)
	(gr_poly
		(pts
			(arc
				(start 89.072466 -407.638504)
				(mid 88.823038 -407.638504)
				(end 89.072466 -407.638504)
			)
		)
		(stroke
			(width 0)
			(type solid)
		)
		(fill yes)
		(layer "B.Cu")
		(net "GND")
	)
	(gr_poly
		(pts
			(arc
				(start 89.072466 -406.141936)
				(mid 88.823038 -406.141936)
				(end 89.072466 -406.141936)
			)
		)
		(stroke
			(width 0)
			(type solid)
		)
		(fill yes)
		(layer "B.Cu")
		(net "GND")
	)
	(gr_poly
		(pts
			(arc
				(start 89.072466 -404.940262)
				(mid 88.823038 -404.940262)
				(end 89.072466 -404.940262)
			)
		)
		(stroke
			(width 0)
			(type solid)
		)
		(fill yes)
		(layer "B.Cu")
		(net "GND")
	)
	(gr_poly
		(pts
			(arc
				(start 89.072466 -403.738588)
				(mid 88.823038 -403.738588)
				(end 89.072466 -403.738588)
			)
		)
		(stroke
			(width 0)
			(type solid)
		)
		(fill yes)
		(layer "B.Cu")
		(net "GND")
	)
	(gr_poly
		(pts
			(arc
				(start 89.072466 -402.241766)
				(mid 88.823038 -402.241766)
				(end 89.072466 -402.241766)
			)
		)
		(stroke
			(width 0)
			(type solid)
		)
		(fill yes)
		(layer "B.Cu")
		(net "GND")
	)
	(gr_poly
		(pts
			(arc
				(start 89.072466 -401.040092)
				(mid 88.823038 -401.040092)
				(end 89.072466 -401.040092)
			)
		)
		(stroke
			(width 0)
			(type solid)
		)
		(fill yes)
		(layer "B.Cu")
		(net "GND")
	)
	(gr_poly
		(pts
			(arc
				(start 89.072466 -399.838418)
				(mid 88.823038 -399.838418)
				(end 89.072466 -399.838418)
			)
		)
		(stroke
			(width 0)
			(type solid)
		)
		(fill yes)
		(layer "B.Cu")
		(net "GND")
	)
	(gr_poly
		(pts
			(arc
				(start 89.072466 -398.34185)
				(mid 88.823038 -398.34185)
				(end 89.072466 -398.34185)
			)
		)
		(stroke
			(width 0)
			(type solid)
		)
		(fill yes)
		(layer "B.Cu")
		(net "GND")
	)
	(gr_poly
		(pts
			(arc
				(start 89.072466 -397.140176)
				(mid 88.823038 -397.140176)
				(end 89.072466 -397.140176)
			)
		)
		(stroke
			(width 0)
			(type solid)
		)
		(fill yes)
		(layer "B.Cu")
		(net "GND")
	)
	(gr_poly
		(pts
			(arc
				(start 89.072466 -395.938502)
				(mid 88.823038 -395.938502)
				(end 89.072466 -395.938502)
			)
		)
		(stroke
			(width 0)
			(type solid)
		)
		(fill yes)
		(layer "B.Cu")
		(net "GND")
	)
	(gr_poly
		(pts
			(arc
				(start 89.072466 -384.042158)
				(mid 88.823038 -384.042158)
				(end 89.072466 -384.042158)
			)
		)
		(stroke
			(width 0)
			(type solid)
		)
		(fill yes)
		(layer "B.Cu")
		(net "GND")
	)
	(gr_poly
		(pts
			(arc
				(start 89.072466 -382.840484)
				(mid 88.823038 -382.840484)
				(end 89.072466 -382.840484)
			)
		)
		(stroke
			(width 0)
			(type solid)
		)
		(fill yes)
		(layer "B.Cu")
		(net "GND")
	)
	(gr_poly
		(pts
			(arc
				(start 89.072466 -381.63881)
				(mid 88.823038 -381.63881)
				(end 89.072466 -381.63881)
			)
		)
		(stroke
			(width 0)
			(type solid)
		)
		(fill yes)
		(layer "B.Cu")
		(net "GND")
	)
	(gr_poly
		(pts
			(arc
				(start 89.072466 -380.141988)
				(mid 88.823038 -380.141988)
				(end 89.072466 -380.141988)
			)
		)
		(stroke
			(width 0)
			(type solid)
		)
		(fill yes)
		(layer "B.Cu")
		(net "GND")
	)
	(gr_poly
		(pts
			(arc
				(start 89.072466 -378.940314)
				(mid 88.823038 -378.940314)
				(end 89.072466 -378.940314)
			)
		)
		(stroke
			(width 0)
			(type solid)
		)
		(fill yes)
		(layer "B.Cu")
		(net "GND")
	)
	(gr_poly
		(pts
			(arc
				(start 89.072466 -377.73864)
				(mid 88.823038 -377.73864)
				(end 89.072466 -377.73864)
			)
		)
		(stroke
			(width 0)
			(type solid)
		)
		(fill yes)
		(layer "B.Cu")
		(net "GND")
	)
	(gr_poly
		(pts
			(arc
				(start 90.910156 -357.75773)
				(mid 90.660728 -357.75773)
				(end 90.910156 -357.75773)
			)
		)
		(stroke
			(width 0)
			(type solid)
		)
		(fill yes)
		(layer "B.Cu")
		(net "GND")
	)
	(gr_poly
		(pts
			(arc
				(start 90.910156 -354.732082)
				(mid 90.660728 -354.732082)
				(end 90.910156 -354.732082)
			)
		)
		(stroke
			(width 0)
			(type solid)
		)
		(fill yes)
		(layer "B.Cu")
		(net "GND")
	)
	(gr_poly
		(pts
			(arc
				(start 90.910156 -351.611438)
				(mid 90.660728 -351.611438)
				(end 90.910156 -351.611438)
			)
		)
		(stroke
			(width 0)
			(type solid)
		)
		(fill yes)
		(layer "B.Cu")
		(net "GND")
	)
	(gr_poly
		(pts
			(arc
				(start 90.910156 -348.58579)
				(mid 90.660728 -348.58579)
				(end 90.910156 -348.58579)
			)
		)
		(stroke
			(width 0)
			(type solid)
		)
		(fill yes)
		(layer "B.Cu")
		(net "GND")
	)
	(gr_poly
		(pts
			(arc
				(start 90.910156 -345.465146)
				(mid 90.660728 -345.465146)
				(end 90.910156 -345.465146)
			)
		)
		(stroke
			(width 0)
			(type solid)
		)
		(fill yes)
		(layer "B.Cu")
		(net "GND")
	)
	(gr_poly
		(pts
			(arc
				(start 90.910156 -342.439498)
				(mid 90.660728 -342.439498)
				(end 90.910156 -342.439498)
			)
		)
		(stroke
			(width 0)
			(type solid)
		)
		(fill yes)
		(layer "B.Cu")
		(net "GND")
	)
	(gr_poly
		(pts
			(arc
				(start 92.017596 -357.75773)
				(mid 91.768168 -357.75773)
				(end 92.017596 -357.75773)
			)
		)
		(stroke
			(width 0)
			(type solid)
		)
		(fill yes)
		(layer "B.Cu")
		(net "GND")
	)
	(gr_poly
		(pts
			(arc
				(start 92.017596 -354.732082)
				(mid 91.768168 -354.732082)
				(end 92.017596 -354.732082)
			)
		)
		(stroke
			(width 0)
			(type solid)
		)
		(fill yes)
		(layer "B.Cu")
		(net "GND")
	)
	(gr_poly
		(pts
			(arc
				(start 92.017596 -351.611438)
				(mid 91.768168 -351.611438)
				(end 92.017596 -351.611438)
			)
		)
		(stroke
			(width 0)
			(type solid)
		)
		(fill yes)
		(layer "B.Cu")
		(net "GND")
	)
	(gr_poly
		(pts
			(arc
				(start 92.017596 -348.58579)
				(mid 91.768168 -348.58579)
				(end 92.017596 -348.58579)
			)
		)
		(stroke
			(width 0)
			(type solid)
		)
		(fill yes)
		(layer "B.Cu")
		(net "GND")
	)
	(gr_poly
		(pts
			(arc
				(start 92.017596 -345.465146)
				(mid 91.768168 -345.465146)
				(end 92.017596 -345.465146)
			)
		)
		(stroke
			(width 0)
			(type solid)
		)
		(fill yes)
		(layer "B.Cu")
		(net "GND")
	)
	(gr_poly
		(pts
			(arc
				(start 92.017596 -342.439498)
				(mid 91.768168 -342.439498)
				(end 92.017596 -342.439498)
			)
		)
		(stroke
			(width 0)
			(type solid)
		)
		(fill yes)
		(layer "B.Cu")
		(net "GND")
	)
	(gr_poly
		(pts
			(arc
				(start 94.019116 -357.75773)
				(mid 93.769688 -357.75773)
				(end 94.019116 -357.75773)
			)
		)
		(stroke
			(width 0)
			(type solid)
		)
		(fill yes)
		(layer "B.Cu")
		(net "GND")
	)
	(gr_poly
		(pts
			(arc
				(start 94.019116 -354.732082)
				(mid 93.769688 -354.732082)
				(end 94.019116 -354.732082)
			)
		)
		(stroke
			(width 0)
			(type solid)
		)
		(fill yes)
		(layer "B.Cu")
		(net "GND")
	)
	(gr_poly
		(pts
			(arc
				(start 94.019116 -351.611438)
				(mid 93.769688 -351.611438)
				(end 94.019116 -351.611438)
			)
		)
		(stroke
			(width 0)
			(type solid)
		)
		(fill yes)
		(layer "B.Cu")
		(net "GND")
	)
	(gr_poly
		(pts
			(arc
				(start 94.019116 -348.58579)
				(mid 93.769688 -348.58579)
				(end 94.019116 -348.58579)
			)
		)
		(stroke
			(width 0)
			(type solid)
		)
		(fill yes)
		(layer "B.Cu")
		(net "GND")
	)
	(gr_poly
		(pts
			(arc
				(start 94.019116 -345.465146)
				(mid 93.769688 -345.465146)
				(end 94.019116 -345.465146)
			)
		)
		(stroke
			(width 0)
			(type solid)
		)
		(fill yes)
		(layer "B.Cu")
		(net "GND")
	)
	(gr_poly
		(pts
			(arc
				(start 94.019116 -342.439498)
				(mid 93.769688 -342.439498)
				(end 94.019116 -342.439498)
			)
		)
		(stroke
			(width 0)
			(type solid)
		)
		(fill yes)
		(layer "B.Cu")
		(net "GND")
	)
	(gr_poly
		(pts
			(arc
				(start 111.417862 -351.611438)
				(mid 111.168434 -351.611438)
				(end 111.417862 -351.611438)
			)
		)
		(stroke
			(width 0)
			(type solid)
		)
		(fill yes)
		(layer "B.Cu")
		(net "GND")
	)
	(gr_poly
		(pts
			(arc
				(start 111.417862 -348.58579)
				(mid 111.168434 -348.58579)
				(end 111.417862 -348.58579)
			)
		)
		(stroke
			(width 0)
			(type solid)
		)
		(fill yes)
		(layer "B.Cu")
		(net "GND")
	)
	(gr_poly
		(pts
			(arc
				(start 111.417862 -345.465146)
				(mid 111.168434 -345.465146)
				(end 111.417862 -345.465146)
			)
		)
		(stroke
			(width 0)
			(type solid)
		)
		(fill yes)
		(layer "B.Cu")
		(net "GND")
	)
	(gr_poly
		(pts
			(arc
				(start 111.417862 -342.439498)
				(mid 111.168434 -342.439498)
				(end 111.417862 -342.439498)
			)
		)
		(stroke
			(width 0)
			(type solid)
		)
		(fill yes)
		(layer "B.Cu")
		(net "GND")
	)
	(gr_poly
		(pts
			(arc
				(start 113.419382 -351.611438)
				(mid 113.169954 -351.611438)
				(end 113.419382 -351.611438)
			)
		)
		(stroke
			(width 0)
			(type solid)
		)
		(fill yes)
		(layer "B.Cu")
		(net "GND")
	)
	(gr_poly
		(pts
			(arc
				(start 113.419382 -348.58579)
				(mid 113.169954 -348.58579)
				(end 113.419382 -348.58579)
			)
		)
		(stroke
			(width 0)
			(type solid)
		)
		(fill yes)
		(layer "B.Cu")
		(net "GND")
	)
	(gr_poly
		(pts
			(arc
				(start 113.419382 -345.465146)
				(mid 113.169954 -345.465146)
				(end 113.419382 -345.465146)
			)
		)
		(stroke
			(width 0)
			(type solid)
		)
		(fill yes)
		(layer "B.Cu")
		(net "GND")
	)
	(gr_poly
		(pts
			(arc
				(start 113.419382 -342.439498)
				(mid 113.169954 -342.439498)
				(end 113.419382 -342.439498)
			)
		)
		(stroke
			(width 0)
			(type solid)
		)
		(fill yes)
		(layer "B.Cu")
		(net "GND")
	)
	(gr_poly
		(pts
			(arc
				(start 114.526822 -357.75773)
				(mid 114.277394 -357.75773)
				(end 114.526822 -357.75773)
			)
		)
		(stroke
			(width 0)
			(type solid)
		)
		(fill yes)
		(layer "B.Cu")
		(net "GND")
	)
	(gr_poly
		(pts
			(arc
				(start 114.526822 -354.732082)
				(mid 114.277394 -354.732082)
				(end 114.526822 -354.732082)
			)
		)
		(stroke
			(width 0)
			(type solid)
		)
		(fill yes)
		(layer "B.Cu")
		(net "GND")
	)
	(gr_poly
		(pts
			(arc
				(start 114.526822 -351.611438)
				(mid 114.277394 -351.611438)
				(end 114.526822 -351.611438)
			)
		)
		(stroke
			(width 0)
			(type solid)
		)
		(fill yes)
		(layer "B.Cu")
		(net "GND")
	)
	(gr_poly
		(pts
			(arc
				(start 114.526822 -348.58579)
				(mid 114.277394 -348.58579)
				(end 114.526822 -348.58579)
			)
		)
		(stroke
			(width 0)
			(type solid)
		)
		(fill yes)
		(layer "B.Cu")
		(net "GND")
	)
	(gr_poly
		(pts
			(arc
				(start 114.526822 -345.465146)
				(mid 114.277394 -345.465146)
				(end 114.526822 -345.465146)
			)
		)
		(stroke
			(width 0)
			(type solid)
		)
		(fill yes)
		(layer "B.Cu")
		(net "GND")
	)
	(gr_poly
		(pts
			(arc
				(start 114.526822 -342.439498)
				(mid 114.277394 -342.439498)
				(end 114.526822 -342.439498)
			)
		)
		(stroke
			(width 0)
			(type solid)
		)
		(fill yes)
		(layer "B.Cu")
		(net "GND")
	)
	(gr_poly
		(pts
			(arc
				(start 115.472464 -410.041852)
				(mid 115.223036 -410.041852)
				(end 115.472464 -410.041852)
			)
		)
		(stroke
			(width 0)
			(type solid)
		)
		(fill yes)
		(layer "B.Cu")
		(net "GND")
	)
	(gr_poly
		(pts
			(arc
				(start 115.472464 -408.840178)
				(mid 115.223036 -408.840178)
				(end 115.472464 -408.840178)
			)
		)
		(stroke
			(width 0)
			(type solid)
		)
		(fill yes)
		(layer "B.Cu")
		(net "GND")
	)
	(gr_poly
		(pts
			(arc
				(start 115.472464 -407.638504)
				(mid 115.223036 -407.638504)
				(end 115.472464 -407.638504)
			)
		)
		(stroke
			(width 0)
			(type solid)
		)
		(fill yes)
		(layer "B.Cu")
		(net "GND")
	)
	(gr_poly
		(pts
			(arc
				(start 115.472464 -406.141936)
				(mid 115.223036 -406.141936)
				(end 115.472464 -406.141936)
			)
		)
		(stroke
			(width 0)
			(type solid)
		)
		(fill yes)
		(layer "B.Cu")
		(net "GND")
	)
	(gr_poly
		(pts
			(arc
				(start 115.472464 -404.940262)
				(mid 115.223036 -404.940262)
				(end 115.472464 -404.940262)
			)
		)
		(stroke
			(width 0)
			(type solid)
		)
		(fill yes)
		(layer "B.Cu")
		(net "GND")
	)
	(gr_poly
		(pts
			(arc
				(start 115.472464 -403.738588)
				(mid 115.223036 -403.738588)
				(end 115.472464 -403.738588)
			)
		)
		(stroke
			(width 0)
			(type solid)
		)
		(fill yes)
		(layer "B.Cu")
		(net "GND")
	)
	(gr_poly
		(pts
			(arc
				(start 115.472464 -402.241766)
				(mid 115.223036 -402.241766)
				(end 115.472464 -402.241766)
			)
		)
		(stroke
			(width 0)
			(type solid)
		)
		(fill yes)
		(layer "B.Cu")
		(net "GND")
	)
	(gr_poly
		(pts
			(arc
				(start 115.472464 -401.040092)
				(mid 115.223036 -401.040092)
				(end 115.472464 -401.040092)
			)
		)
		(stroke
			(width 0)
			(type solid)
		)
		(fill yes)
		(layer "B.Cu")
		(net "GND")
	)
	(gr_poly
		(pts
			(arc
				(start 115.472464 -399.838418)
				(mid 115.223036 -399.838418)
				(end 115.472464 -399.838418)
			)
		)
		(stroke
			(width 0)
			(type solid)
		)
		(fill yes)
		(layer "B.Cu")
		(net "GND")
	)
	(gr_poly
		(pts
			(arc
				(start 115.472464 -398.34185)
				(mid 115.223036 -398.34185)
				(end 115.472464 -398.34185)
			)
		)
		(stroke
			(width 0)
			(type solid)
		)
		(fill yes)
		(layer "B.Cu")
		(net "GND")
	)
	(gr_poly
		(pts
			(arc
				(start 115.472464 -397.140176)
				(mid 115.223036 -397.140176)
				(end 115.472464 -397.140176)
			)
		)
		(stroke
			(width 0)
			(type solid)
		)
		(fill yes)
		(layer "B.Cu")
		(net "GND")
	)
	(gr_poly
		(pts
			(arc
				(start 115.472464 -395.938502)
				(mid 115.223036 -395.938502)
				(end 115.472464 -395.938502)
			)
		)
		(stroke
			(width 0)
			(type solid)
		)
		(fill yes)
		(layer "B.Cu")
		(net "GND")
	)
	(gr_poly
		(pts
			(arc
				(start 115.472464 -384.041904)
				(mid 115.223036 -384.041904)
				(end 115.472464 -384.041904)
			)
		)
		(stroke
			(width 0)
			(type solid)
		)
		(fill yes)
		(layer "B.Cu")
		(net "GND")
	)
	(gr_poly
		(pts
			(arc
				(start 115.472464 -382.84023)
				(mid 115.223036 -382.84023)
				(end 115.472464 -382.84023)
			)
		)
		(stroke
			(width 0)
			(type solid)
		)
		(fill yes)
		(layer "B.Cu")
		(net "GND")
	)
	(gr_poly
		(pts
			(arc
				(start 115.472464 -381.638556)
				(mid 115.223036 -381.638556)
				(end 115.472464 -381.638556)
			)
		)
		(stroke
			(width 0)
			(type solid)
		)
		(fill yes)
		(layer "B.Cu")
		(net "GND")
	)
	(gr_poly
		(pts
			(arc
				(start 115.472464 -380.141988)
				(mid 115.223036 -380.141988)
				(end 115.472464 -380.141988)
			)
		)
		(stroke
			(width 0)
			(type solid)
		)
		(fill yes)
		(layer "B.Cu")
		(net "GND")
	)
	(gr_poly
		(pts
			(arc
				(start 115.472464 -378.940314)
				(mid 115.223036 -378.940314)
				(end 115.472464 -378.940314)
			)
		)
		(stroke
			(width 0)
			(type solid)
		)
		(fill yes)
		(layer "B.Cu")
		(net "GND")
	)
	(gr_poly
		(pts
			(arc
				(start 115.472464 -377.73864)
				(mid 115.223036 -377.73864)
				(end 115.472464 -377.73864)
			)
		)
		(stroke
			(width 0)
			(type solid)
		)
		(fill yes)
		(layer "B.Cu")
		(net "GND")
	)
	(gr_poly
		(pts
			(arc
				(start 115.472464 -376.241818)
				(mid 115.223036 -376.241818)
				(end 115.472464 -376.241818)
			)
		)
		(stroke
			(width 0)
			(type solid)
		)
		(fill yes)
		(layer "B.Cu")
		(net "GND")
	)
	(gr_poly
		(pts
			(arc
				(start 115.472464 -375.040144)
				(mid 115.223036 -375.040144)
				(end 115.472464 -375.040144)
			)
		)
		(stroke
			(width 0)
			(type solid)
		)
		(fill yes)
		(layer "B.Cu")
		(net "GND")
	)
	(gr_poly
		(pts
			(arc
				(start 115.472464 -373.83847)
				(mid 115.223036 -373.83847)
				(end 115.472464 -373.83847)
			)
		)
		(stroke
			(width 0)
			(type solid)
		)
		(fill yes)
		(layer "B.Cu")
		(net "GND")
	)
	(gr_poly
		(pts
			(arc
				(start 115.472464 -372.341902)
				(mid 115.223036 -372.341902)
				(end 115.472464 -372.341902)
			)
		)
		(stroke
			(width 0)
			(type solid)
		)
		(fill yes)
		(layer "B.Cu")
		(net "GND")
	)
	(gr_poly
		(pts
			(arc
				(start 115.472464 -371.140228)
				(mid 115.223036 -371.140228)
				(end 115.472464 -371.140228)
			)
		)
		(stroke
			(width 0)
			(type solid)
		)
		(fill yes)
		(layer "B.Cu")
		(net "GND")
	)
	(gr_poly
		(pts
			(arc
				(start 116.528342 -357.75773)
				(mid 116.278914 -357.75773)
				(end 116.528342 -357.75773)
			)
		)
		(stroke
			(width 0)
			(type solid)
		)
		(fill yes)
		(layer "B.Cu")
		(net "GND")
	)
	(gr_poly
		(pts
			(arc
				(start 116.528342 -354.732082)
				(mid 116.278914 -354.732082)
				(end 116.528342 -354.732082)
			)
		)
		(stroke
			(width 0)
			(type solid)
		)
		(fill yes)
		(layer "B.Cu")
		(net "GND")
	)
	(gr_poly
		(pts
			(arc
				(start 116.528342 -351.611438)
				(mid 116.278914 -351.611438)
				(end 116.528342 -351.611438)
			)
		)
		(stroke
			(width 0)
			(type solid)
		)
		(fill yes)
		(layer "B.Cu")
		(net "GND")
	)
	(gr_poly
		(pts
			(arc
				(start 116.528342 -348.58579)
				(mid 116.278914 -348.58579)
				(end 116.528342 -348.58579)
			)
		)
		(stroke
			(width 0)
			(type solid)
		)
		(fill yes)
		(layer "B.Cu")
		(net "GND")
	)
	(gr_poly
		(pts
			(arc
				(start 116.528342 -345.465146)
				(mid 116.278914 -345.465146)
				(end 116.528342 -345.465146)
			)
		)
		(stroke
			(width 0)
			(type solid)
		)
		(fill yes)
		(layer "B.Cu")
		(net "GND")
	)
	(gr_poly
		(pts
			(arc
				(start 116.528342 -342.439498)
				(mid 116.278914 -342.439498)
				(end 116.528342 -342.439498)
			)
		)
		(stroke
			(width 0)
			(type solid)
		)
		(fill yes)
		(layer "B.Cu")
		(net "GND")
	)
	(gr_poly
		(pts
			(arc
				(start 117.635782 -357.75773)
				(mid 117.386354 -357.75773)
				(end 117.635782 -357.75773)
			)
		)
		(stroke
			(width 0)
			(type solid)
		)
		(fill yes)
		(layer "B.Cu")
		(net "GND")
	)
	(gr_poly
		(pts
			(arc
				(start 117.635782 -354.732082)
				(mid 117.386354 -354.732082)
				(end 117.635782 -354.732082)
			)
		)
		(stroke
			(width 0)
			(type solid)
		)
		(fill yes)
		(layer "B.Cu")
		(net "GND")
	)
	(gr_poly
		(pts
			(arc
				(start 117.635782 -351.611438)
				(mid 117.386354 -351.611438)
				(end 117.635782 -351.611438)
			)
		)
		(stroke
			(width 0)
			(type solid)
		)
		(fill yes)
		(layer "B.Cu")
		(net "GND")
	)
	(gr_poly
		(pts
			(arc
				(start 117.635782 -348.58579)
				(mid 117.386354 -348.58579)
				(end 117.635782 -348.58579)
			)
		)
		(stroke
			(width 0)
			(type solid)
		)
		(fill yes)
		(layer "B.Cu")
		(net "GND")
	)
	(gr_poly
		(pts
			(arc
				(start 117.635782 -345.465146)
				(mid 117.386354 -345.465146)
				(end 117.635782 -345.465146)
			)
		)
		(stroke
			(width 0)
			(type solid)
		)
		(fill yes)
		(layer "B.Cu")
		(net "GND")
	)
	(gr_poly
		(pts
			(arc
				(start 117.635782 -342.439498)
				(mid 117.386354 -342.439498)
				(end 117.635782 -342.439498)
			)
		)
		(stroke
			(width 0)
			(type solid)
		)
		(fill yes)
		(layer "B.Cu")
		(net "GND")
	)
	(gr_poly
		(pts
			(arc
				(start 117.672358 -411.141926)
				(mid 117.42293 -411.141926)
				(end 117.672358 -411.141926)
			)
		)
		(stroke
			(width 0)
			(type solid)
		)
		(fill yes)
		(layer "B.Cu")
		(net "GND")
	)
	(gr_poly
		(pts
			(arc
				(start 117.672358 -409.940252)
				(mid 117.42293 -409.940252)
				(end 117.672358 -409.940252)
			)
		)
		(stroke
			(width 0)
			(type solid)
		)
		(fill yes)
		(layer "B.Cu")
		(net "GND")
	)
	(gr_poly
		(pts
			(arc
				(start 117.672358 -408.738578)
				(mid 117.42293 -408.738578)
				(end 117.672358 -408.738578)
			)
		)
		(stroke
			(width 0)
			(type solid)
		)
		(fill yes)
		(layer "B.Cu")
		(net "GND")
	)
	(gr_poly
		(pts
			(arc
				(start 117.672358 -407.24201)
				(mid 117.42293 -407.24201)
				(end 117.672358 -407.24201)
			)
		)
		(stroke
			(width 0)
			(type solid)
		)
		(fill yes)
		(layer "B.Cu")
		(net "GND")
	)
	(gr_poly
		(pts
			(arc
				(start 117.672358 -406.040336)
				(mid 117.42293 -406.040336)
				(end 117.672358 -406.040336)
			)
		)
		(stroke
			(width 0)
			(type solid)
		)
		(fill yes)
		(layer "B.Cu")
		(net "GND")
	)
	(gr_poly
		(pts
			(arc
				(start 117.672358 -404.838662)
				(mid 117.42293 -404.838662)
				(end 117.672358 -404.838662)
			)
		)
		(stroke
			(width 0)
			(type solid)
		)
		(fill yes)
		(layer "B.Cu")
		(net "GND")
	)
	(gr_poly
		(pts
			(arc
				(start 117.672358 -403.34184)
				(mid 117.42293 -403.34184)
				(end 117.672358 -403.34184)
			)
		)
		(stroke
			(width 0)
			(type solid)
		)
		(fill yes)
		(layer "B.Cu")
		(net "GND")
	)
	(gr_poly
		(pts
			(arc
				(start 117.672358 -402.140166)
				(mid 117.42293 -402.140166)
				(end 117.672358 -402.140166)
			)
		)
		(stroke
			(width 0)
			(type solid)
		)
		(fill yes)
		(layer "B.Cu")
		(net "GND")
	)
	(gr_poly
		(pts
			(arc
				(start 117.672358 -400.938492)
				(mid 117.42293 -400.938492)
				(end 117.672358 -400.938492)
			)
		)
		(stroke
			(width 0)
			(type solid)
		)
		(fill yes)
		(layer "B.Cu")
		(net "GND")
	)
	(gr_poly
		(pts
			(arc
				(start 117.672358 -399.441924)
				(mid 117.42293 -399.441924)
				(end 117.672358 -399.441924)
			)
		)
		(stroke
			(width 0)
			(type solid)
		)
		(fill yes)
		(layer "B.Cu")
		(net "GND")
	)
	(gr_poly
		(pts
			(arc
				(start 117.672358 -398.24025)
				(mid 117.42293 -398.24025)
				(end 117.672358 -398.24025)
			)
		)
		(stroke
			(width 0)
			(type solid)
		)
		(fill yes)
		(layer "B.Cu")
		(net "GND")
	)
	(gr_poly
		(pts
			(arc
				(start 117.672358 -397.038576)
				(mid 117.42293 -397.038576)
				(end 117.672358 -397.038576)
			)
		)
		(stroke
			(width 0)
			(type solid)
		)
		(fill yes)
		(layer "B.Cu")
		(net "GND")
	)
	(gr_poly
		(pts
			(arc
				(start 117.672358 -385.141978)
				(mid 117.42293 -385.141978)
				(end 117.672358 -385.141978)
			)
		)
		(stroke
			(width 0)
			(type solid)
		)
		(fill yes)
		(layer "B.Cu")
		(net "GND")
	)
	(gr_poly
		(pts
			(arc
				(start 117.672358 -383.940304)
				(mid 117.42293 -383.940304)
				(end 117.672358 -383.940304)
			)
		)
		(stroke
			(width 0)
			(type solid)
		)
		(fill yes)
		(layer "B.Cu")
		(net "GND")
	)
	(gr_poly
		(pts
			(arc
				(start 117.672358 -382.73863)
				(mid 117.42293 -382.73863)
				(end 117.672358 -382.73863)
			)
		)
		(stroke
			(width 0)
			(type solid)
		)
		(fill yes)
		(layer "B.Cu")
		(net "GND")
	)
	(gr_poly
		(pts
			(arc
				(start 117.672358 -381.242062)
				(mid 117.42293 -381.242062)
				(end 117.672358 -381.242062)
			)
		)
		(stroke
			(width 0)
			(type solid)
		)
		(fill yes)
		(layer "B.Cu")
		(net "GND")
	)
	(gr_poly
		(pts
			(arc
				(start 117.672358 -380.040388)
				(mid 117.42293 -380.040388)
				(end 117.672358 -380.040388)
			)
		)
		(stroke
			(width 0)
			(type solid)
		)
		(fill yes)
		(layer "B.Cu")
		(net "GND")
	)
	(gr_poly
		(pts
			(arc
				(start 117.672358 -378.838714)
				(mid 117.42293 -378.838714)
				(end 117.672358 -378.838714)
			)
		)
		(stroke
			(width 0)
			(type solid)
		)
		(fill yes)
		(layer "B.Cu")
		(net "GND")
	)
	(gr_poly
		(pts
			(arc
				(start 117.672358 -377.341892)
				(mid 117.42293 -377.341892)
				(end 117.672358 -377.341892)
			)
		)
		(stroke
			(width 0)
			(type solid)
		)
		(fill yes)
		(layer "B.Cu")
		(net "GND")
	)
	(gr_poly
		(pts
			(arc
				(start 117.672358 -376.140218)
				(mid 117.42293 -376.140218)
				(end 117.672358 -376.140218)
			)
		)
		(stroke
			(width 0)
			(type solid)
		)
		(fill yes)
		(layer "B.Cu")
		(net "GND")
	)
	(gr_poly
		(pts
			(arc
				(start 117.672358 -374.938544)
				(mid 117.42293 -374.938544)
				(end 117.672358 -374.938544)
			)
		)
		(stroke
			(width 0)
			(type solid)
		)
		(fill yes)
		(layer "B.Cu")
		(net "GND")
	)
	(gr_poly
		(pts
			(arc
				(start 117.672358 -373.441976)
				(mid 117.42293 -373.441976)
				(end 117.672358 -373.441976)
			)
		)
		(stroke
			(width 0)
			(type solid)
		)
		(fill yes)
		(layer "B.Cu")
		(net "GND")
	)
	(gr_poly
		(pts
			(arc
				(start 117.672358 -372.240302)
				(mid 117.42293 -372.240302)
				(end 117.672358 -372.240302)
			)
		)
		(stroke
			(width 0)
			(type solid)
		)
		(fill yes)
		(layer "B.Cu")
		(net "GND")
	)
	(gr_poly
		(pts
			(arc
				(start 117.672358 -371.038628)
				(mid 117.42293 -371.038628)
				(end 117.672358 -371.038628)
			)
		)
		(stroke
			(width 0)
			(type solid)
		)
		(fill yes)
		(layer "B.Cu")
		(net "GND")
	)
	(gr_poly
		(pts
			(arc
				(start 119.637302 -357.75773)
				(mid 119.387874 -357.75773)
				(end 119.637302 -357.75773)
			)
		)
		(stroke
			(width 0)
			(type solid)
		)
		(fill yes)
		(layer "B.Cu")
		(net "GND")
	)
	(gr_poly
		(pts
			(arc
				(start 119.637302 -354.732082)
				(mid 119.387874 -354.732082)
				(end 119.637302 -354.732082)
			)
		)
		(stroke
			(width 0)
			(type solid)
		)
		(fill yes)
		(layer "B.Cu")
		(net "GND")
	)
	(gr_poly
		(pts
			(arc
				(start 119.637302 -351.611438)
				(mid 119.387874 -351.611438)
				(end 119.637302 -351.611438)
			)
		)
		(stroke
			(width 0)
			(type solid)
		)
		(fill yes)
		(layer "B.Cu")
		(net "GND")
	)
	(gr_poly
		(pts
			(arc
				(start 119.637302 -348.58579)
				(mid 119.387874 -348.58579)
				(end 119.637302 -348.58579)
			)
		)
		(stroke
			(width 0)
			(type solid)
		)
		(fill yes)
		(layer "B.Cu")
		(net "GND")
	)
	(gr_poly
		(pts
			(arc
				(start 119.637302 -345.465146)
				(mid 119.387874 -345.465146)
				(end 119.637302 -345.465146)
			)
		)
		(stroke
			(width 0)
			(type solid)
		)
		(fill yes)
		(layer "B.Cu")
		(net "GND")
	)
	(gr_poly
		(pts
			(arc
				(start 119.637302 -342.439498)
				(mid 119.387874 -342.439498)
				(end 119.637302 -342.439498)
			)
		)
		(stroke
			(width 0)
			(type solid)
		)
		(fill yes)
		(layer "B.Cu")
		(net "GND")
	)
	(gr_poly
		(pts
			(arc
				(start 119.872506 -410.041852)
				(mid 119.623078 -410.041852)
				(end 119.872506 -410.041852)
			)
		)
		(stroke
			(width 0)
			(type solid)
		)
		(fill yes)
		(layer "B.Cu")
		(net "GND")
	)
	(gr_poly
		(pts
			(arc
				(start 119.872506 -408.840178)
				(mid 119.623078 -408.840178)
				(end 119.872506 -408.840178)
			)
		)
		(stroke
			(width 0)
			(type solid)
		)
		(fill yes)
		(layer "B.Cu")
		(net "GND")
	)
	(gr_poly
		(pts
			(arc
				(start 119.872506 -407.638504)
				(mid 119.623078 -407.638504)
				(end 119.872506 -407.638504)
			)
		)
		(stroke
			(width 0)
			(type solid)
		)
		(fill yes)
		(layer "B.Cu")
		(net "GND")
	)
	(gr_poly
		(pts
			(arc
				(start 119.872506 -406.141936)
				(mid 119.623078 -406.141936)
				(end 119.872506 -406.141936)
			)
		)
		(stroke
			(width 0)
			(type solid)
		)
		(fill yes)
		(layer "B.Cu")
		(net "GND")
	)
	(gr_poly
		(pts
			(arc
				(start 119.872506 -404.940262)
				(mid 119.623078 -404.940262)
				(end 119.872506 -404.940262)
			)
		)
		(stroke
			(width 0)
			(type solid)
		)
		(fill yes)
		(layer "B.Cu")
		(net "GND")
	)
	(gr_poly
		(pts
			(arc
				(start 119.872506 -403.738588)
				(mid 119.623078 -403.738588)
				(end 119.872506 -403.738588)
			)
		)
		(stroke
			(width 0)
			(type solid)
		)
		(fill yes)
		(layer "B.Cu")
		(net "GND")
	)
	(gr_poly
		(pts
			(arc
				(start 119.872506 -402.241766)
				(mid 119.623078 -402.241766)
				(end 119.872506 -402.241766)
			)
		)
		(stroke
			(width 0)
			(type solid)
		)
		(fill yes)
		(layer "B.Cu")
		(net "GND")
	)
	(gr_poly
		(pts
			(arc
				(start 119.872506 -401.040092)
				(mid 119.623078 -401.040092)
				(end 119.872506 -401.040092)
			)
		)
		(stroke
			(width 0)
			(type solid)
		)
		(fill yes)
		(layer "B.Cu")
		(net "GND")
	)
	(gr_poly
		(pts
			(arc
				(start 119.872506 -399.838418)
				(mid 119.623078 -399.838418)
				(end 119.872506 -399.838418)
			)
		)
		(stroke
			(width 0)
			(type solid)
		)
		(fill yes)
		(layer "B.Cu")
		(net "GND")
	)
	(gr_poly
		(pts
			(arc
				(start 119.872506 -398.34185)
				(mid 119.623078 -398.34185)
				(end 119.872506 -398.34185)
			)
		)
		(stroke
			(width 0)
			(type solid)
		)
		(fill yes)
		(layer "B.Cu")
		(net "GND")
	)
	(gr_poly
		(pts
			(arc
				(start 119.872506 -397.140176)
				(mid 119.623078 -397.140176)
				(end 119.872506 -397.140176)
			)
		)
		(stroke
			(width 0)
			(type solid)
		)
		(fill yes)
		(layer "B.Cu")
		(net "GND")
	)
	(gr_poly
		(pts
			(arc
				(start 119.872506 -395.938502)
				(mid 119.623078 -395.938502)
				(end 119.872506 -395.938502)
			)
		)
		(stroke
			(width 0)
			(type solid)
		)
		(fill yes)
		(layer "B.Cu")
		(net "GND")
	)
	(gr_poly
		(pts
			(arc
				(start 119.872506 -384.041904)
				(mid 119.623078 -384.041904)
				(end 119.872506 -384.041904)
			)
		)
		(stroke
			(width 0)
			(type solid)
		)
		(fill yes)
		(layer "B.Cu")
		(net "GND")
	)
	(gr_poly
		(pts
			(arc
				(start 119.872506 -382.84023)
				(mid 119.623078 -382.84023)
				(end 119.872506 -382.84023)
			)
		)
		(stroke
			(width 0)
			(type solid)
		)
		(fill yes)
		(layer "B.Cu")
		(net "GND")
	)
	(gr_poly
		(pts
			(arc
				(start 119.872506 -381.638556)
				(mid 119.623078 -381.638556)
				(end 119.872506 -381.638556)
			)
		)
		(stroke
			(width 0)
			(type solid)
		)
		(fill yes)
		(layer "B.Cu")
		(net "GND")
	)
	(gr_poly
		(pts
			(arc
				(start 119.872506 -380.141988)
				(mid 119.623078 -380.141988)
				(end 119.872506 -380.141988)
			)
		)
		(stroke
			(width 0)
			(type solid)
		)
		(fill yes)
		(layer "B.Cu")
		(net "GND")
	)
	(gr_poly
		(pts
			(arc
				(start 119.872506 -378.940314)
				(mid 119.623078 -378.940314)
				(end 119.872506 -378.940314)
			)
		)
		(stroke
			(width 0)
			(type solid)
		)
		(fill yes)
		(layer "B.Cu")
		(net "GND")
	)
	(gr_poly
		(pts
			(arc
				(start 119.872506 -377.73864)
				(mid 119.623078 -377.73864)
				(end 119.872506 -377.73864)
			)
		)
		(stroke
			(width 0)
			(type solid)
		)
		(fill yes)
		(layer "B.Cu")
		(net "GND")
	)
	(gr_poly
		(pts
			(arc
				(start 119.872506 -376.241818)
				(mid 119.623078 -376.241818)
				(end 119.872506 -376.241818)
			)
		)
		(stroke
			(width 0)
			(type solid)
		)
		(fill yes)
		(layer "B.Cu")
		(net "GND")
	)
	(gr_poly
		(pts
			(arc
				(start 119.872506 -375.040144)
				(mid 119.623078 -375.040144)
				(end 119.872506 -375.040144)
			)
		)
		(stroke
			(width 0)
			(type solid)
		)
		(fill yes)
		(layer "B.Cu")
		(net "GND")
	)
	(gr_poly
		(pts
			(arc
				(start 119.872506 -373.83847)
				(mid 119.623078 -373.83847)
				(end 119.872506 -373.83847)
			)
		)
		(stroke
			(width 0)
			(type solid)
		)
		(fill yes)
		(layer "B.Cu")
		(net "GND")
	)
	(gr_poly
		(pts
			(arc
				(start 119.872506 -372.341902)
				(mid 119.623078 -372.341902)
				(end 119.872506 -372.341902)
			)
		)
		(stroke
			(width 0)
			(type solid)
		)
		(fill yes)
		(layer "B.Cu")
		(net "GND")
	)
	(gr_poly
		(pts
			(arc
				(start 119.872506 -371.140228)
				(mid 119.623078 -371.140228)
				(end 119.872506 -371.140228)
			)
		)
		(stroke
			(width 0)
			(type solid)
		)
		(fill yes)
		(layer "B.Cu")
		(net "GND")
	)
	(gr_poly
		(pts
			(arc
				(start 120.744742 -357.75773)
				(mid 120.495314 -357.75773)
				(end 120.744742 -357.75773)
			)
		)
		(stroke
			(width 0)
			(type solid)
		)
		(fill yes)
		(layer "B.Cu")
		(net "GND")
	)
	(gr_poly
		(pts
			(arc
				(start 120.744742 -354.732082)
				(mid 120.495314 -354.732082)
				(end 120.744742 -354.732082)
			)
		)
		(stroke
			(width 0)
			(type solid)
		)
		(fill yes)
		(layer "B.Cu")
		(net "GND")
	)
	(gr_poly
		(pts
			(arc
				(start 120.744742 -351.611438)
				(mid 120.495314 -351.611438)
				(end 120.744742 -351.611438)
			)
		)
		(stroke
			(width 0)
			(type solid)
		)
		(fill yes)
		(layer "B.Cu")
		(net "GND")
	)
	(gr_poly
		(pts
			(arc
				(start 120.744742 -348.58579)
				(mid 120.495314 -348.58579)
				(end 120.744742 -348.58579)
			)
		)
		(stroke
			(width 0)
			(type solid)
		)
		(fill yes)
		(layer "B.Cu")
		(net "GND")
	)
	(gr_poly
		(pts
			(arc
				(start 120.744742 -345.465146)
				(mid 120.495314 -345.465146)
				(end 120.744742 -345.465146)
			)
		)
		(stroke
			(width 0)
			(type solid)
		)
		(fill yes)
		(layer "B.Cu")
		(net "GND")
	)
	(gr_poly
		(pts
			(arc
				(start 120.744742 -342.439498)
				(mid 120.495314 -342.439498)
				(end 120.744742 -342.439498)
			)
		)
		(stroke
			(width 0)
			(type solid)
		)
		(fill yes)
		(layer "B.Cu")
		(net "GND")
	)
	(gr_poly
		(pts
			(arc
				(start 122.0724 -411.141926)
				(mid 121.822972 -411.141926)
				(end 122.0724 -411.141926)
			)
		)
		(stroke
			(width 0)
			(type solid)
		)
		(fill yes)
		(layer "B.Cu")
		(net "GND")
	)
	(gr_poly
		(pts
			(arc
				(start 122.0724 -409.940252)
				(mid 121.822972 -409.940252)
				(end 122.0724 -409.940252)
			)
		)
		(stroke
			(width 0)
			(type solid)
		)
		(fill yes)
		(layer "B.Cu")
		(net "GND")
	)
	(gr_poly
		(pts
			(arc
				(start 122.0724 -408.738578)
				(mid 121.822972 -408.738578)
				(end 122.0724 -408.738578)
			)
		)
		(stroke
			(width 0)
			(type solid)
		)
		(fill yes)
		(layer "B.Cu")
		(net "GND")
	)
	(gr_poly
		(pts
			(arc
				(start 122.0724 -407.24201)
				(mid 121.822972 -407.24201)
				(end 122.0724 -407.24201)
			)
		)
		(stroke
			(width 0)
			(type solid)
		)
		(fill yes)
		(layer "B.Cu")
		(net "GND")
	)
	(gr_poly
		(pts
			(arc
				(start 122.0724 -406.040336)
				(mid 121.822972 -406.040336)
				(end 122.0724 -406.040336)
			)
		)
		(stroke
			(width 0)
			(type solid)
		)
		(fill yes)
		(layer "B.Cu")
		(net "GND")
	)
	(gr_poly
		(pts
			(arc
				(start 122.0724 -404.838662)
				(mid 121.822972 -404.838662)
				(end 122.0724 -404.838662)
			)
		)
		(stroke
			(width 0)
			(type solid)
		)
		(fill yes)
		(layer "B.Cu")
		(net "GND")
	)
	(gr_poly
		(pts
			(arc
				(start 122.0724 -403.34184)
				(mid 121.822972 -403.34184)
				(end 122.0724 -403.34184)
			)
		)
		(stroke
			(width 0)
			(type solid)
		)
		(fill yes)
		(layer "B.Cu")
		(net "GND")
	)
	(gr_poly
		(pts
			(arc
				(start 122.0724 -402.140166)
				(mid 121.822972 -402.140166)
				(end 122.0724 -402.140166)
			)
		)
		(stroke
			(width 0)
			(type solid)
		)
		(fill yes)
		(layer "B.Cu")
		(net "GND")
	)
	(gr_poly
		(pts
			(arc
				(start 122.0724 -400.938492)
				(mid 121.822972 -400.938492)
				(end 122.0724 -400.938492)
			)
		)
		(stroke
			(width 0)
			(type solid)
		)
		(fill yes)
		(layer "B.Cu")
		(net "GND")
	)
	(gr_poly
		(pts
			(arc
				(start 122.0724 -399.441924)
				(mid 121.822972 -399.441924)
				(end 122.0724 -399.441924)
			)
		)
		(stroke
			(width 0)
			(type solid)
		)
		(fill yes)
		(layer "B.Cu")
		(net "GND")
	)
	(gr_poly
		(pts
			(arc
				(start 122.0724 -398.24025)
				(mid 121.822972 -398.24025)
				(end 122.0724 -398.24025)
			)
		)
		(stroke
			(width 0)
			(type solid)
		)
		(fill yes)
		(layer "B.Cu")
		(net "GND")
	)
	(gr_poly
		(pts
			(arc
				(start 122.0724 -397.038576)
				(mid 121.822972 -397.038576)
				(end 122.0724 -397.038576)
			)
		)
		(stroke
			(width 0)
			(type solid)
		)
		(fill yes)
		(layer "B.Cu")
		(net "GND")
	)
	(gr_poly
		(pts
			(arc
				(start 122.0724 -385.141978)
				(mid 121.822972 -385.141978)
				(end 122.0724 -385.141978)
			)
		)
		(stroke
			(width 0)
			(type solid)
		)
		(fill yes)
		(layer "B.Cu")
		(net "GND")
	)
	(gr_poly
		(pts
			(arc
				(start 122.0724 -383.940304)
				(mid 121.822972 -383.940304)
				(end 122.0724 -383.940304)
			)
		)
		(stroke
			(width 0)
			(type solid)
		)
		(fill yes)
		(layer "B.Cu")
		(net "GND")
	)
	(gr_poly
		(pts
			(arc
				(start 122.0724 -382.73863)
				(mid 121.822972 -382.73863)
				(end 122.0724 -382.73863)
			)
		)
		(stroke
			(width 0)
			(type solid)
		)
		(fill yes)
		(layer "B.Cu")
		(net "GND")
	)
	(gr_poly
		(pts
			(arc
				(start 122.0724 -381.242062)
				(mid 121.822972 -381.242062)
				(end 122.0724 -381.242062)
			)
		)
		(stroke
			(width 0)
			(type solid)
		)
		(fill yes)
		(layer "B.Cu")
		(net "GND")
	)
	(gr_poly
		(pts
			(arc
				(start 122.0724 -380.040388)
				(mid 121.822972 -380.040388)
				(end 122.0724 -380.040388)
			)
		)
		(stroke
			(width 0)
			(type solid)
		)
		(fill yes)
		(layer "B.Cu")
		(net "GND")
	)
	(gr_poly
		(pts
			(arc
				(start 122.0724 -378.838714)
				(mid 121.822972 -378.838714)
				(end 122.0724 -378.838714)
			)
		)
		(stroke
			(width 0)
			(type solid)
		)
		(fill yes)
		(layer "B.Cu")
		(net "GND")
	)
	(gr_poly
		(pts
			(arc
				(start 122.0724 -377.341892)
				(mid 121.822972 -377.341892)
				(end 122.0724 -377.341892)
			)
		)
		(stroke
			(width 0)
			(type solid)
		)
		(fill yes)
		(layer "B.Cu")
		(net "GND")
	)
	(gr_poly
		(pts
			(arc
				(start 122.0724 -376.140218)
				(mid 121.822972 -376.140218)
				(end 122.0724 -376.140218)
			)
		)
		(stroke
			(width 0)
			(type solid)
		)
		(fill yes)
		(layer "B.Cu")
		(net "GND")
	)
	(gr_poly
		(pts
			(arc
				(start 122.0724 -374.938544)
				(mid 121.822972 -374.938544)
				(end 122.0724 -374.938544)
			)
		)
		(stroke
			(width 0)
			(type solid)
		)
		(fill yes)
		(layer "B.Cu")
		(net "GND")
	)
	(gr_poly
		(pts
			(arc
				(start 122.0724 -373.441976)
				(mid 121.822972 -373.441976)
				(end 122.0724 -373.441976)
			)
		)
		(stroke
			(width 0)
			(type solid)
		)
		(fill yes)
		(layer "B.Cu")
		(net "GND")
	)
	(gr_poly
		(pts
			(arc
				(start 122.0724 -372.240302)
				(mid 121.822972 -372.240302)
				(end 122.0724 -372.240302)
			)
		)
		(stroke
			(width 0)
			(type solid)
		)
		(fill yes)
		(layer "B.Cu")
		(net "GND")
	)
	(gr_poly
		(pts
			(arc
				(start 122.0724 -371.038628)
				(mid 121.822972 -371.038628)
				(end 122.0724 -371.038628)
			)
		)
		(stroke
			(width 0)
			(type solid)
		)
		(fill yes)
		(layer "B.Cu")
		(net "GND")
	)
	(gr_poly
		(pts
			(arc
				(start 122.746262 -357.75773)
				(mid 122.496834 -357.75773)
				(end 122.746262 -357.75773)
			)
		)
		(stroke
			(width 0)
			(type solid)
		)
		(fill yes)
		(layer "B.Cu")
		(net "GND")
	)
	(gr_poly
		(pts
			(arc
				(start 122.746262 -354.732082)
				(mid 122.496834 -354.732082)
				(end 122.746262 -354.732082)
			)
		)
		(stroke
			(width 0)
			(type solid)
		)
		(fill yes)
		(layer "B.Cu")
		(net "GND")
	)
	(gr_poly
		(pts
			(arc
				(start 122.746262 -351.611438)
				(mid 122.496834 -351.611438)
				(end 122.746262 -351.611438)
			)
		)
		(stroke
			(width 0)
			(type solid)
		)
		(fill yes)
		(layer "B.Cu")
		(net "GND")
	)
	(gr_poly
		(pts
			(arc
				(start 122.746262 -348.58579)
				(mid 122.496834 -348.58579)
				(end 122.746262 -348.58579)
			)
		)
		(stroke
			(width 0)
			(type solid)
		)
		(fill yes)
		(layer "B.Cu")
		(net "GND")
	)
	(gr_poly
		(pts
			(arc
				(start 122.746262 -345.465146)
				(mid 122.496834 -345.465146)
				(end 122.746262 -345.465146)
			)
		)
		(stroke
			(width 0)
			(type solid)
		)
		(fill yes)
		(layer "B.Cu")
		(net "GND")
	)
	(gr_poly
		(pts
			(arc
				(start 122.746262 -342.439498)
				(mid 122.496834 -342.439498)
				(end 122.746262 -342.439498)
			)
		)
		(stroke
			(width 0)
			(type solid)
		)
		(fill yes)
		(layer "B.Cu")
		(net "GND")
	)
	(gr_poly
		(pts
			(arc
				(start 123.853702 -357.75773)
				(mid 123.604274 -357.75773)
				(end 123.853702 -357.75773)
			)
		)
		(stroke
			(width 0)
			(type solid)
		)
		(fill yes)
		(layer "B.Cu")
		(net "GND")
	)
	(gr_poly
		(pts
			(arc
				(start 123.853702 -354.732082)
				(mid 123.604274 -354.732082)
				(end 123.853702 -354.732082)
			)
		)
		(stroke
			(width 0)
			(type solid)
		)
		(fill yes)
		(layer "B.Cu")
		(net "GND")
	)
	(gr_poly
		(pts
			(arc
				(start 123.853702 -351.611438)
				(mid 123.604274 -351.611438)
				(end 123.853702 -351.611438)
			)
		)
		(stroke
			(width 0)
			(type solid)
		)
		(fill yes)
		(layer "B.Cu")
		(net "GND")
	)
	(gr_poly
		(pts
			(arc
				(start 123.853702 -348.58579)
				(mid 123.604274 -348.58579)
				(end 123.853702 -348.58579)
			)
		)
		(stroke
			(width 0)
			(type solid)
		)
		(fill yes)
		(layer "B.Cu")
		(net "GND")
	)
	(gr_poly
		(pts
			(arc
				(start 123.853702 -345.465146)
				(mid 123.604274 -345.465146)
				(end 123.853702 -345.465146)
			)
		)
		(stroke
			(width 0)
			(type solid)
		)
		(fill yes)
		(layer "B.Cu")
		(net "GND")
	)
	(gr_poly
		(pts
			(arc
				(start 123.853702 -342.439498)
				(mid 123.604274 -342.439498)
				(end 123.853702 -342.439498)
			)
		)
		(stroke
			(width 0)
			(type solid)
		)
		(fill yes)
		(layer "B.Cu")
		(net "GND")
	)
	(gr_poly
		(pts
			(arc
				(start 124.272548 -410.041852)
				(mid 124.02312 -410.041852)
				(end 124.272548 -410.041852)
			)
		)
		(stroke
			(width 0)
			(type solid)
		)
		(fill yes)
		(layer "B.Cu")
		(net "GND")
	)
	(gr_poly
		(pts
			(arc
				(start 124.272548 -408.840178)
				(mid 124.02312 -408.840178)
				(end 124.272548 -408.840178)
			)
		)
		(stroke
			(width 0)
			(type solid)
		)
		(fill yes)
		(layer "B.Cu")
		(net "GND")
	)
	(gr_poly
		(pts
			(arc
				(start 124.272548 -407.638504)
				(mid 124.02312 -407.638504)
				(end 124.272548 -407.638504)
			)
		)
		(stroke
			(width 0)
			(type solid)
		)
		(fill yes)
		(layer "B.Cu")
		(net "GND")
	)
	(gr_poly
		(pts
			(arc
				(start 124.272548 -406.141936)
				(mid 124.02312 -406.141936)
				(end 124.272548 -406.141936)
			)
		)
		(stroke
			(width 0)
			(type solid)
		)
		(fill yes)
		(layer "B.Cu")
		(net "GND")
	)
	(gr_poly
		(pts
			(arc
				(start 124.272548 -404.940262)
				(mid 124.02312 -404.940262)
				(end 124.272548 -404.940262)
			)
		)
		(stroke
			(width 0)
			(type solid)
		)
		(fill yes)
		(layer "B.Cu")
		(net "GND")
	)
	(gr_poly
		(pts
			(arc
				(start 124.272548 -403.738588)
				(mid 124.02312 -403.738588)
				(end 124.272548 -403.738588)
			)
		)
		(stroke
			(width 0)
			(type solid)
		)
		(fill yes)
		(layer "B.Cu")
		(net "GND")
	)
	(gr_poly
		(pts
			(arc
				(start 124.272548 -402.241766)
				(mid 124.02312 -402.241766)
				(end 124.272548 -402.241766)
			)
		)
		(stroke
			(width 0)
			(type solid)
		)
		(fill yes)
		(layer "B.Cu")
		(net "GND")
	)
	(gr_poly
		(pts
			(arc
				(start 124.272548 -401.040092)
				(mid 124.02312 -401.040092)
				(end 124.272548 -401.040092)
			)
		)
		(stroke
			(width 0)
			(type solid)
		)
		(fill yes)
		(layer "B.Cu")
		(net "GND")
	)
	(gr_poly
		(pts
			(arc
				(start 124.272548 -399.838418)
				(mid 124.02312 -399.838418)
				(end 124.272548 -399.838418)
			)
		)
		(stroke
			(width 0)
			(type solid)
		)
		(fill yes)
		(layer "B.Cu")
		(net "GND")
	)
	(gr_poly
		(pts
			(arc
				(start 124.272548 -398.34185)
				(mid 124.02312 -398.34185)
				(end 124.272548 -398.34185)
			)
		)
		(stroke
			(width 0)
			(type solid)
		)
		(fill yes)
		(layer "B.Cu")
		(net "GND")
	)
	(gr_poly
		(pts
			(arc
				(start 124.272548 -397.140176)
				(mid 124.02312 -397.140176)
				(end 124.272548 -397.140176)
			)
		)
		(stroke
			(width 0)
			(type solid)
		)
		(fill yes)
		(layer "B.Cu")
		(net "GND")
	)
	(gr_poly
		(pts
			(arc
				(start 124.272548 -395.938502)
				(mid 124.02312 -395.938502)
				(end 124.272548 -395.938502)
			)
		)
		(stroke
			(width 0)
			(type solid)
		)
		(fill yes)
		(layer "B.Cu")
		(net "GND")
	)
	(gr_poly
		(pts
			(arc
				(start 124.272548 -384.041904)
				(mid 124.02312 -384.041904)
				(end 124.272548 -384.041904)
			)
		)
		(stroke
			(width 0)
			(type solid)
		)
		(fill yes)
		(layer "B.Cu")
		(net "GND")
	)
	(gr_poly
		(pts
			(arc
				(start 124.272548 -382.84023)
				(mid 124.02312 -382.84023)
				(end 124.272548 -382.84023)
			)
		)
		(stroke
			(width 0)
			(type solid)
		)
		(fill yes)
		(layer "B.Cu")
		(net "GND")
	)
	(gr_poly
		(pts
			(arc
				(start 124.272548 -381.638556)
				(mid 124.02312 -381.638556)
				(end 124.272548 -381.638556)
			)
		)
		(stroke
			(width 0)
			(type solid)
		)
		(fill yes)
		(layer "B.Cu")
		(net "GND")
	)
	(gr_poly
		(pts
			(arc
				(start 124.272548 -380.141988)
				(mid 124.02312 -380.141988)
				(end 124.272548 -380.141988)
			)
		)
		(stroke
			(width 0)
			(type solid)
		)
		(fill yes)
		(layer "B.Cu")
		(net "GND")
	)
	(gr_poly
		(pts
			(arc
				(start 124.272548 -378.940314)
				(mid 124.02312 -378.940314)
				(end 124.272548 -378.940314)
			)
		)
		(stroke
			(width 0)
			(type solid)
		)
		(fill yes)
		(layer "B.Cu")
		(net "GND")
	)
	(gr_poly
		(pts
			(arc
				(start 124.272548 -377.73864)
				(mid 124.02312 -377.73864)
				(end 124.272548 -377.73864)
			)
		)
		(stroke
			(width 0)
			(type solid)
		)
		(fill yes)
		(layer "B.Cu")
		(net "GND")
	)
	(gr_poly
		(pts
			(arc
				(start 124.272548 -376.241818)
				(mid 124.02312 -376.241818)
				(end 124.272548 -376.241818)
			)
		)
		(stroke
			(width 0)
			(type solid)
		)
		(fill yes)
		(layer "B.Cu")
		(net "GND")
	)
	(gr_poly
		(pts
			(arc
				(start 124.272548 -375.040144)
				(mid 124.02312 -375.040144)
				(end 124.272548 -375.040144)
			)
		)
		(stroke
			(width 0)
			(type solid)
		)
		(fill yes)
		(layer "B.Cu")
		(net "GND")
	)
	(gr_poly
		(pts
			(arc
				(start 124.272548 -373.83847)
				(mid 124.02312 -373.83847)
				(end 124.272548 -373.83847)
			)
		)
		(stroke
			(width 0)
			(type solid)
		)
		(fill yes)
		(layer "B.Cu")
		(net "GND")
	)
	(gr_poly
		(pts
			(arc
				(start 124.272548 -372.341902)
				(mid 124.02312 -372.341902)
				(end 124.272548 -372.341902)
			)
		)
		(stroke
			(width 0)
			(type solid)
		)
		(fill yes)
		(layer "B.Cu")
		(net "GND")
	)
	(gr_poly
		(pts
			(arc
				(start 124.272548 -371.140228)
				(mid 124.02312 -371.140228)
				(end 124.272548 -371.140228)
			)
		)
		(stroke
			(width 0)
			(type solid)
		)
		(fill yes)
		(layer "B.Cu")
		(net "GND")
	)
	(gr_poly
		(pts
			(arc
				(start 125.855222 -357.75773)
				(mid 125.605794 -357.75773)
				(end 125.855222 -357.75773)
			)
		)
		(stroke
			(width 0)
			(type solid)
		)
		(fill yes)
		(layer "B.Cu")
		(net "GND")
	)
	(gr_poly
		(pts
			(arc
				(start 125.855222 -354.732082)
				(mid 125.605794 -354.732082)
				(end 125.855222 -354.732082)
			)
		)
		(stroke
			(width 0)
			(type solid)
		)
		(fill yes)
		(layer "B.Cu")
		(net "GND")
	)
	(gr_poly
		(pts
			(arc
				(start 125.855222 -351.611438)
				(mid 125.605794 -351.611438)
				(end 125.855222 -351.611438)
			)
		)
		(stroke
			(width 0)
			(type solid)
		)
		(fill yes)
		(layer "B.Cu")
		(net "GND")
	)
	(gr_poly
		(pts
			(arc
				(start 125.855222 -348.58579)
				(mid 125.605794 -348.58579)
				(end 125.855222 -348.58579)
			)
		)
		(stroke
			(width 0)
			(type solid)
		)
		(fill yes)
		(layer "B.Cu")
		(net "GND")
	)
	(gr_poly
		(pts
			(arc
				(start 125.855222 -345.465146)
				(mid 125.605794 -345.465146)
				(end 125.855222 -345.465146)
			)
		)
		(stroke
			(width 0)
			(type solid)
		)
		(fill yes)
		(layer "B.Cu")
		(net "GND")
	)
	(gr_poly
		(pts
			(arc
				(start 125.855222 -342.439498)
				(mid 125.605794 -342.439498)
				(end 125.855222 -342.439498)
			)
		)
		(stroke
			(width 0)
			(type solid)
		)
		(fill yes)
		(layer "B.Cu")
		(net "GND")
	)
	(gr_poly
		(pts
			(arc
				(start 126.472442 -411.141926)
				(mid 126.223014 -411.141926)
				(end 126.472442 -411.141926)
			)
		)
		(stroke
			(width 0)
			(type solid)
		)
		(fill yes)
		(layer "B.Cu")
		(net "GND")
	)
	(gr_poly
		(pts
			(arc
				(start 126.472442 -409.940252)
				(mid 126.223014 -409.940252)
				(end 126.472442 -409.940252)
			)
		)
		(stroke
			(width 0)
			(type solid)
		)
		(fill yes)
		(layer "B.Cu")
		(net "GND")
	)
	(gr_poly
		(pts
			(arc
				(start 126.472442 -408.738578)
				(mid 126.223014 -408.738578)
				(end 126.472442 -408.738578)
			)
		)
		(stroke
			(width 0)
			(type solid)
		)
		(fill yes)
		(layer "B.Cu")
		(net "GND")
	)
	(gr_poly
		(pts
			(arc
				(start 126.472442 -407.24201)
				(mid 126.223014 -407.24201)
				(end 126.472442 -407.24201)
			)
		)
		(stroke
			(width 0)
			(type solid)
		)
		(fill yes)
		(layer "B.Cu")
		(net "GND")
	)
	(gr_poly
		(pts
			(arc
				(start 126.472442 -406.040336)
				(mid 126.223014 -406.040336)
				(end 126.472442 -406.040336)
			)
		)
		(stroke
			(width 0)
			(type solid)
		)
		(fill yes)
		(layer "B.Cu")
		(net "GND")
	)
	(gr_poly
		(pts
			(arc
				(start 126.472442 -404.838662)
				(mid 126.223014 -404.838662)
				(end 126.472442 -404.838662)
			)
		)
		(stroke
			(width 0)
			(type solid)
		)
		(fill yes)
		(layer "B.Cu")
		(net "GND")
	)
	(gr_poly
		(pts
			(arc
				(start 126.472442 -403.34184)
				(mid 126.223014 -403.34184)
				(end 126.472442 -403.34184)
			)
		)
		(stroke
			(width 0)
			(type solid)
		)
		(fill yes)
		(layer "B.Cu")
		(net "GND")
	)
	(gr_poly
		(pts
			(arc
				(start 126.472442 -402.140166)
				(mid 126.223014 -402.140166)
				(end 126.472442 -402.140166)
			)
		)
		(stroke
			(width 0)
			(type solid)
		)
		(fill yes)
		(layer "B.Cu")
		(net "GND")
	)
	(gr_poly
		(pts
			(arc
				(start 126.472442 -400.938492)
				(mid 126.223014 -400.938492)
				(end 126.472442 -400.938492)
			)
		)
		(stroke
			(width 0)
			(type solid)
		)
		(fill yes)
		(layer "B.Cu")
		(net "GND")
	)
	(gr_poly
		(pts
			(arc
				(start 126.472442 -399.441924)
				(mid 126.223014 -399.441924)
				(end 126.472442 -399.441924)
			)
		)
		(stroke
			(width 0)
			(type solid)
		)
		(fill yes)
		(layer "B.Cu")
		(net "GND")
	)
	(gr_poly
		(pts
			(arc
				(start 126.472442 -398.24025)
				(mid 126.223014 -398.24025)
				(end 126.472442 -398.24025)
			)
		)
		(stroke
			(width 0)
			(type solid)
		)
		(fill yes)
		(layer "B.Cu")
		(net "GND")
	)
	(gr_poly
		(pts
			(arc
				(start 126.472442 -397.038576)
				(mid 126.223014 -397.038576)
				(end 126.472442 -397.038576)
			)
		)
		(stroke
			(width 0)
			(type solid)
		)
		(fill yes)
		(layer "B.Cu")
		(net "GND")
	)
	(gr_poly
		(pts
			(arc
				(start 126.472442 -385.141978)
				(mid 126.223014 -385.141978)
				(end 126.472442 -385.141978)
			)
		)
		(stroke
			(width 0)
			(type solid)
		)
		(fill yes)
		(layer "B.Cu")
		(net "GND")
	)
	(gr_poly
		(pts
			(arc
				(start 126.472442 -383.940304)
				(mid 126.223014 -383.940304)
				(end 126.472442 -383.940304)
			)
		)
		(stroke
			(width 0)
			(type solid)
		)
		(fill yes)
		(layer "B.Cu")
		(net "GND")
	)
	(gr_poly
		(pts
			(arc
				(start 126.472442 -382.73863)
				(mid 126.223014 -382.73863)
				(end 126.472442 -382.73863)
			)
		)
		(stroke
			(width 0)
			(type solid)
		)
		(fill yes)
		(layer "B.Cu")
		(net "GND")
	)
	(gr_poly
		(pts
			(arc
				(start 126.472442 -381.242062)
				(mid 126.223014 -381.242062)
				(end 126.472442 -381.242062)
			)
		)
		(stroke
			(width 0)
			(type solid)
		)
		(fill yes)
		(layer "B.Cu")
		(net "GND")
	)
	(gr_poly
		(pts
			(arc
				(start 126.472442 -380.040388)
				(mid 126.223014 -380.040388)
				(end 126.472442 -380.040388)
			)
		)
		(stroke
			(width 0)
			(type solid)
		)
		(fill yes)
		(layer "B.Cu")
		(net "GND")
	)
	(gr_poly
		(pts
			(arc
				(start 126.472442 -378.838714)
				(mid 126.223014 -378.838714)
				(end 126.472442 -378.838714)
			)
		)
		(stroke
			(width 0)
			(type solid)
		)
		(fill yes)
		(layer "B.Cu")
		(net "GND")
	)
	(gr_poly
		(pts
			(arc
				(start 126.472442 -377.341892)
				(mid 126.223014 -377.341892)
				(end 126.472442 -377.341892)
			)
		)
		(stroke
			(width 0)
			(type solid)
		)
		(fill yes)
		(layer "B.Cu")
		(net "GND")
	)
	(gr_poly
		(pts
			(arc
				(start 126.472442 -376.140218)
				(mid 126.223014 -376.140218)
				(end 126.472442 -376.140218)
			)
		)
		(stroke
			(width 0)
			(type solid)
		)
		(fill yes)
		(layer "B.Cu")
		(net "GND")
	)
	(gr_poly
		(pts
			(arc
				(start 126.472442 -374.938544)
				(mid 126.223014 -374.938544)
				(end 126.472442 -374.938544)
			)
		)
		(stroke
			(width 0)
			(type solid)
		)
		(fill yes)
		(layer "B.Cu")
		(net "GND")
	)
	(gr_poly
		(pts
			(arc
				(start 126.472442 -373.441976)
				(mid 126.223014 -373.441976)
				(end 126.472442 -373.441976)
			)
		)
		(stroke
			(width 0)
			(type solid)
		)
		(fill yes)
		(layer "B.Cu")
		(net "GND")
	)
	(gr_poly
		(pts
			(arc
				(start 126.472442 -372.240302)
				(mid 126.223014 -372.240302)
				(end 126.472442 -372.240302)
			)
		)
		(stroke
			(width 0)
			(type solid)
		)
		(fill yes)
		(layer "B.Cu")
		(net "GND")
	)
	(gr_poly
		(pts
			(arc
				(start 126.472442 -371.038628)
				(mid 126.223014 -371.038628)
				(end 126.472442 -371.038628)
			)
		)
		(stroke
			(width 0)
			(type solid)
		)
		(fill yes)
		(layer "B.Cu")
		(net "GND")
	)
	(gr_poly
		(pts
			(arc
				(start 126.962662 -357.75773)
				(mid 126.713234 -357.75773)
				(end 126.962662 -357.75773)
			)
		)
		(stroke
			(width 0)
			(type solid)
		)
		(fill yes)
		(layer "B.Cu")
		(net "GND")
	)
	(gr_poly
		(pts
			(arc
				(start 126.962662 -354.732082)
				(mid 126.713234 -354.732082)
				(end 126.962662 -354.732082)
			)
		)
		(stroke
			(width 0)
			(type solid)
		)
		(fill yes)
		(layer "B.Cu")
		(net "GND")
	)
	(gr_poly
		(pts
			(arc
				(start 126.962662 -351.611438)
				(mid 126.713234 -351.611438)
				(end 126.962662 -351.611438)
			)
		)
		(stroke
			(width 0)
			(type solid)
		)
		(fill yes)
		(layer "B.Cu")
		(net "GND")
	)
	(gr_poly
		(pts
			(arc
				(start 126.962662 -348.58579)
				(mid 126.713234 -348.58579)
				(end 126.962662 -348.58579)
			)
		)
		(stroke
			(width 0)
			(type solid)
		)
		(fill yes)
		(layer "B.Cu")
		(net "GND")
	)
	(gr_poly
		(pts
			(arc
				(start 126.962662 -345.465146)
				(mid 126.713234 -345.465146)
				(end 126.962662 -345.465146)
			)
		)
		(stroke
			(width 0)
			(type solid)
		)
		(fill yes)
		(layer "B.Cu")
		(net "GND")
	)
	(gr_poly
		(pts
			(arc
				(start 126.962662 -342.439498)
				(mid 126.713234 -342.439498)
				(end 126.962662 -342.439498)
			)
		)
		(stroke
			(width 0)
			(type solid)
		)
		(fill yes)
		(layer "B.Cu")
		(net "GND")
	)
	(gr_poly
		(pts
			(arc
				(start 128.672336 -410.041852)
				(mid 128.422908 -410.041852)
				(end 128.672336 -410.041852)
			)
		)
		(stroke
			(width 0)
			(type solid)
		)
		(fill yes)
		(layer "B.Cu")
		(net "GND")
	)
	(gr_poly
		(pts
			(arc
				(start 128.672336 -408.840178)
				(mid 128.422908 -408.840178)
				(end 128.672336 -408.840178)
			)
		)
		(stroke
			(width 0)
			(type solid)
		)
		(fill yes)
		(layer "B.Cu")
		(net "GND")
	)
	(gr_poly
		(pts
			(arc
				(start 128.672336 -407.638504)
				(mid 128.422908 -407.638504)
				(end 128.672336 -407.638504)
			)
		)
		(stroke
			(width 0)
			(type solid)
		)
		(fill yes)
		(layer "B.Cu")
		(net "GND")
	)
	(gr_poly
		(pts
			(arc
				(start 128.672336 -406.141936)
				(mid 128.422908 -406.141936)
				(end 128.672336 -406.141936)
			)
		)
		(stroke
			(width 0)
			(type solid)
		)
		(fill yes)
		(layer "B.Cu")
		(net "GND")
	)
	(gr_poly
		(pts
			(arc
				(start 128.672336 -404.940262)
				(mid 128.422908 -404.940262)
				(end 128.672336 -404.940262)
			)
		)
		(stroke
			(width 0)
			(type solid)
		)
		(fill yes)
		(layer "B.Cu")
		(net "GND")
	)
	(gr_poly
		(pts
			(arc
				(start 128.672336 -403.738588)
				(mid 128.422908 -403.738588)
				(end 128.672336 -403.738588)
			)
		)
		(stroke
			(width 0)
			(type solid)
		)
		(fill yes)
		(layer "B.Cu")
		(net "GND")
	)
	(gr_poly
		(pts
			(arc
				(start 128.672336 -402.241766)
				(mid 128.422908 -402.241766)
				(end 128.672336 -402.241766)
			)
		)
		(stroke
			(width 0)
			(type solid)
		)
		(fill yes)
		(layer "B.Cu")
		(net "GND")
	)
	(gr_poly
		(pts
			(arc
				(start 128.672336 -401.040092)
				(mid 128.422908 -401.040092)
				(end 128.672336 -401.040092)
			)
		)
		(stroke
			(width 0)
			(type solid)
		)
		(fill yes)
		(layer "B.Cu")
		(net "GND")
	)
	(gr_poly
		(pts
			(arc
				(start 128.672336 -399.838418)
				(mid 128.422908 -399.838418)
				(end 128.672336 -399.838418)
			)
		)
		(stroke
			(width 0)
			(type solid)
		)
		(fill yes)
		(layer "B.Cu")
		(net "GND")
	)
	(gr_poly
		(pts
			(arc
				(start 128.672336 -398.34185)
				(mid 128.422908 -398.34185)
				(end 128.672336 -398.34185)
			)
		)
		(stroke
			(width 0)
			(type solid)
		)
		(fill yes)
		(layer "B.Cu")
		(net "GND")
	)
	(gr_poly
		(pts
			(arc
				(start 128.672336 -397.140176)
				(mid 128.422908 -397.140176)
				(end 128.672336 -397.140176)
			)
		)
		(stroke
			(width 0)
			(type solid)
		)
		(fill yes)
		(layer "B.Cu")
		(net "GND")
	)
	(gr_poly
		(pts
			(arc
				(start 128.672336 -395.938502)
				(mid 128.422908 -395.938502)
				(end 128.672336 -395.938502)
			)
		)
		(stroke
			(width 0)
			(type solid)
		)
		(fill yes)
		(layer "B.Cu")
		(net "GND")
	)
	(gr_poly
		(pts
			(arc
				(start 128.672336 -384.041904)
				(mid 128.422908 -384.041904)
				(end 128.672336 -384.041904)
			)
		)
		(stroke
			(width 0)
			(type solid)
		)
		(fill yes)
		(layer "B.Cu")
		(net "GND")
	)
	(gr_poly
		(pts
			(arc
				(start 128.672336 -382.84023)
				(mid 128.422908 -382.84023)
				(end 128.672336 -382.84023)
			)
		)
		(stroke
			(width 0)
			(type solid)
		)
		(fill yes)
		(layer "B.Cu")
		(net "GND")
	)
	(gr_poly
		(pts
			(arc
				(start 128.672336 -381.638556)
				(mid 128.422908 -381.638556)
				(end 128.672336 -381.638556)
			)
		)
		(stroke
			(width 0)
			(type solid)
		)
		(fill yes)
		(layer "B.Cu")
		(net "GND")
	)
	(gr_poly
		(pts
			(arc
				(start 128.672336 -380.141988)
				(mid 128.422908 -380.141988)
				(end 128.672336 -380.141988)
			)
		)
		(stroke
			(width 0)
			(type solid)
		)
		(fill yes)
		(layer "B.Cu")
		(net "GND")
	)
	(gr_poly
		(pts
			(arc
				(start 128.672336 -378.940314)
				(mid 128.422908 -378.940314)
				(end 128.672336 -378.940314)
			)
		)
		(stroke
			(width 0)
			(type solid)
		)
		(fill yes)
		(layer "B.Cu")
		(net "GND")
	)
	(gr_poly
		(pts
			(arc
				(start 128.672336 -377.73864)
				(mid 128.422908 -377.73864)
				(end 128.672336 -377.73864)
			)
		)
		(stroke
			(width 0)
			(type solid)
		)
		(fill yes)
		(layer "B.Cu")
		(net "GND")
	)
	(gr_poly
		(pts
			(arc
				(start 128.672336 -376.241818)
				(mid 128.422908 -376.241818)
				(end 128.672336 -376.241818)
			)
		)
		(stroke
			(width 0)
			(type solid)
		)
		(fill yes)
		(layer "B.Cu")
		(net "GND")
	)
	(gr_poly
		(pts
			(arc
				(start 128.672336 -375.040144)
				(mid 128.422908 -375.040144)
				(end 128.672336 -375.040144)
			)
		)
		(stroke
			(width 0)
			(type solid)
		)
		(fill yes)
		(layer "B.Cu")
		(net "GND")
	)
	(gr_poly
		(pts
			(arc
				(start 128.672336 -373.83847)
				(mid 128.422908 -373.83847)
				(end 128.672336 -373.83847)
			)
		)
		(stroke
			(width 0)
			(type solid)
		)
		(fill yes)
		(layer "B.Cu")
		(net "GND")
	)
	(gr_poly
		(pts
			(arc
				(start 128.672336 -372.341902)
				(mid 128.422908 -372.341902)
				(end 128.672336 -372.341902)
			)
		)
		(stroke
			(width 0)
			(type solid)
		)
		(fill yes)
		(layer "B.Cu")
		(net "GND")
	)
	(gr_poly
		(pts
			(arc
				(start 128.672336 -371.140228)
				(mid 128.422908 -371.140228)
				(end 128.672336 -371.140228)
			)
		)
		(stroke
			(width 0)
			(type solid)
		)
		(fill yes)
		(layer "B.Cu")
		(net "GND")
	)
	(gr_poly
		(pts
			(arc
				(start 128.964182 -357.75773)
				(mid 128.714754 -357.75773)
				(end 128.964182 -357.75773)
			)
		)
		(stroke
			(width 0)
			(type solid)
		)
		(fill yes)
		(layer "B.Cu")
		(net "GND")
	)
	(gr_poly
		(pts
			(arc
				(start 128.964182 -354.732082)
				(mid 128.714754 -354.732082)
				(end 128.964182 -354.732082)
			)
		)
		(stroke
			(width 0)
			(type solid)
		)
		(fill yes)
		(layer "B.Cu")
		(net "GND")
	)
	(gr_poly
		(pts
			(arc
				(start 128.964182 -351.611438)
				(mid 128.714754 -351.611438)
				(end 128.964182 -351.611438)
			)
		)
		(stroke
			(width 0)
			(type solid)
		)
		(fill yes)
		(layer "B.Cu")
		(net "GND")
	)
	(gr_poly
		(pts
			(arc
				(start 128.964182 -348.58579)
				(mid 128.714754 -348.58579)
				(end 128.964182 -348.58579)
			)
		)
		(stroke
			(width 0)
			(type solid)
		)
		(fill yes)
		(layer "B.Cu")
		(net "GND")
	)
	(gr_poly
		(pts
			(arc
				(start 128.964182 -345.465146)
				(mid 128.714754 -345.465146)
				(end 128.964182 -345.465146)
			)
		)
		(stroke
			(width 0)
			(type solid)
		)
		(fill yes)
		(layer "B.Cu")
		(net "GND")
	)
	(gr_poly
		(pts
			(arc
				(start 128.964182 -342.439498)
				(mid 128.714754 -342.439498)
				(end 128.964182 -342.439498)
			)
		)
		(stroke
			(width 0)
			(type solid)
		)
		(fill yes)
		(layer "B.Cu")
		(net "GND")
	)
	(gr_poly
		(pts
			(arc
				(start 130.071622 -357.75773)
				(mid 129.822194 -357.75773)
				(end 130.071622 -357.75773)
			)
		)
		(stroke
			(width 0)
			(type solid)
		)
		(fill yes)
		(layer "B.Cu")
		(net "GND")
	)
	(gr_poly
		(pts
			(arc
				(start 130.071622 -354.732082)
				(mid 129.822194 -354.732082)
				(end 130.071622 -354.732082)
			)
		)
		(stroke
			(width 0)
			(type solid)
		)
		(fill yes)
		(layer "B.Cu")
		(net "GND")
	)
	(gr_poly
		(pts
			(arc
				(start 130.071622 -351.611438)
				(mid 129.822194 -351.611438)
				(end 130.071622 -351.611438)
			)
		)
		(stroke
			(width 0)
			(type solid)
		)
		(fill yes)
		(layer "B.Cu")
		(net "GND")
	)
	(gr_poly
		(pts
			(arc
				(start 130.071622 -348.58579)
				(mid 129.822194 -348.58579)
				(end 130.071622 -348.58579)
			)
		)
		(stroke
			(width 0)
			(type solid)
		)
		(fill yes)
		(layer "B.Cu")
		(net "GND")
	)
	(gr_poly
		(pts
			(arc
				(start 130.071622 -345.465146)
				(mid 129.822194 -345.465146)
				(end 130.071622 -345.465146)
			)
		)
		(stroke
			(width 0)
			(type solid)
		)
		(fill yes)
		(layer "B.Cu")
		(net "GND")
	)
	(gr_poly
		(pts
			(arc
				(start 130.071622 -342.439498)
				(mid 129.822194 -342.439498)
				(end 130.071622 -342.439498)
			)
		)
		(stroke
			(width 0)
			(type solid)
		)
		(fill yes)
		(layer "B.Cu")
		(net "GND")
	)
	(gr_poly
		(pts
			(arc
				(start 130.872484 -411.141926)
				(mid 130.623056 -411.141926)
				(end 130.872484 -411.141926)
			)
		)
		(stroke
			(width 0)
			(type solid)
		)
		(fill yes)
		(layer "B.Cu")
		(net "GND")
	)
	(gr_poly
		(pts
			(arc
				(start 130.872484 -409.940252)
				(mid 130.623056 -409.940252)
				(end 130.872484 -409.940252)
			)
		)
		(stroke
			(width 0)
			(type solid)
		)
		(fill yes)
		(layer "B.Cu")
		(net "GND")
	)
	(gr_poly
		(pts
			(arc
				(start 130.872484 -408.738578)
				(mid 130.623056 -408.738578)
				(end 130.872484 -408.738578)
			)
		)
		(stroke
			(width 0)
			(type solid)
		)
		(fill yes)
		(layer "B.Cu")
		(net "GND")
	)
	(gr_poly
		(pts
			(arc
				(start 130.872484 -407.24201)
				(mid 130.623056 -407.24201)
				(end 130.872484 -407.24201)
			)
		)
		(stroke
			(width 0)
			(type solid)
		)
		(fill yes)
		(layer "B.Cu")
		(net "GND")
	)
	(gr_poly
		(pts
			(arc
				(start 130.872484 -406.040336)
				(mid 130.623056 -406.040336)
				(end 130.872484 -406.040336)
			)
		)
		(stroke
			(width 0)
			(type solid)
		)
		(fill yes)
		(layer "B.Cu")
		(net "GND")
	)
	(gr_poly
		(pts
			(arc
				(start 130.872484 -404.838662)
				(mid 130.623056 -404.838662)
				(end 130.872484 -404.838662)
			)
		)
		(stroke
			(width 0)
			(type solid)
		)
		(fill yes)
		(layer "B.Cu")
		(net "GND")
	)
	(gr_poly
		(pts
			(arc
				(start 130.872484 -403.34184)
				(mid 130.623056 -403.34184)
				(end 130.872484 -403.34184)
			)
		)
		(stroke
			(width 0)
			(type solid)
		)
		(fill yes)
		(layer "B.Cu")
		(net "GND")
	)
	(gr_poly
		(pts
			(arc
				(start 130.872484 -402.140166)
				(mid 130.623056 -402.140166)
				(end 130.872484 -402.140166)
			)
		)
		(stroke
			(width 0)
			(type solid)
		)
		(fill yes)
		(layer "B.Cu")
		(net "GND")
	)
	(gr_poly
		(pts
			(arc
				(start 130.872484 -400.938492)
				(mid 130.623056 -400.938492)
				(end 130.872484 -400.938492)
			)
		)
		(stroke
			(width 0)
			(type solid)
		)
		(fill yes)
		(layer "B.Cu")
		(net "GND")
	)
	(gr_poly
		(pts
			(arc
				(start 130.872484 -399.441924)
				(mid 130.623056 -399.441924)
				(end 130.872484 -399.441924)
			)
		)
		(stroke
			(width 0)
			(type solid)
		)
		(fill yes)
		(layer "B.Cu")
		(net "GND")
	)
	(gr_poly
		(pts
			(arc
				(start 130.872484 -398.24025)
				(mid 130.623056 -398.24025)
				(end 130.872484 -398.24025)
			)
		)
		(stroke
			(width 0)
			(type solid)
		)
		(fill yes)
		(layer "B.Cu")
		(net "GND")
	)
	(gr_poly
		(pts
			(arc
				(start 130.872484 -397.038576)
				(mid 130.623056 -397.038576)
				(end 130.872484 -397.038576)
			)
		)
		(stroke
			(width 0)
			(type solid)
		)
		(fill yes)
		(layer "B.Cu")
		(net "GND")
	)
	(gr_poly
		(pts
			(arc
				(start 130.872484 -385.141978)
				(mid 130.623056 -385.141978)
				(end 130.872484 -385.141978)
			)
		)
		(stroke
			(width 0)
			(type solid)
		)
		(fill yes)
		(layer "B.Cu")
		(net "GND")
	)
	(gr_poly
		(pts
			(arc
				(start 130.872484 -383.940304)
				(mid 130.623056 -383.940304)
				(end 130.872484 -383.940304)
			)
		)
		(stroke
			(width 0)
			(type solid)
		)
		(fill yes)
		(layer "B.Cu")
		(net "GND")
	)
	(gr_poly
		(pts
			(arc
				(start 130.872484 -382.73863)
				(mid 130.623056 -382.73863)
				(end 130.872484 -382.73863)
			)
		)
		(stroke
			(width 0)
			(type solid)
		)
		(fill yes)
		(layer "B.Cu")
		(net "GND")
	)
	(gr_poly
		(pts
			(arc
				(start 130.872484 -381.242062)
				(mid 130.623056 -381.242062)
				(end 130.872484 -381.242062)
			)
		)
		(stroke
			(width 0)
			(type solid)
		)
		(fill yes)
		(layer "B.Cu")
		(net "GND")
	)
	(gr_poly
		(pts
			(arc
				(start 130.872484 -380.040388)
				(mid 130.623056 -380.040388)
				(end 130.872484 -380.040388)
			)
		)
		(stroke
			(width 0)
			(type solid)
		)
		(fill yes)
		(layer "B.Cu")
		(net "GND")
	)
	(gr_poly
		(pts
			(arc
				(start 130.872484 -378.838714)
				(mid 130.623056 -378.838714)
				(end 130.872484 -378.838714)
			)
		)
		(stroke
			(width 0)
			(type solid)
		)
		(fill yes)
		(layer "B.Cu")
		(net "GND")
	)
	(gr_poly
		(pts
			(arc
				(start 130.872484 -377.341892)
				(mid 130.623056 -377.341892)
				(end 130.872484 -377.341892)
			)
		)
		(stroke
			(width 0)
			(type solid)
		)
		(fill yes)
		(layer "B.Cu")
		(net "GND")
	)
	(gr_poly
		(pts
			(arc
				(start 130.872484 -376.140218)
				(mid 130.623056 -376.140218)
				(end 130.872484 -376.140218)
			)
		)
		(stroke
			(width 0)
			(type solid)
		)
		(fill yes)
		(layer "B.Cu")
		(net "GND")
	)
	(gr_poly
		(pts
			(arc
				(start 130.872484 -374.938544)
				(mid 130.623056 -374.938544)
				(end 130.872484 -374.938544)
			)
		)
		(stroke
			(width 0)
			(type solid)
		)
		(fill yes)
		(layer "B.Cu")
		(net "GND")
	)
	(gr_poly
		(pts
			(arc
				(start 130.872484 -373.441976)
				(mid 130.623056 -373.441976)
				(end 130.872484 -373.441976)
			)
		)
		(stroke
			(width 0)
			(type solid)
		)
		(fill yes)
		(layer "B.Cu")
		(net "GND")
	)
	(gr_poly
		(pts
			(arc
				(start 130.872484 -372.240302)
				(mid 130.623056 -372.240302)
				(end 130.872484 -372.240302)
			)
		)
		(stroke
			(width 0)
			(type solid)
		)
		(fill yes)
		(layer "B.Cu")
		(net "GND")
	)
	(gr_poly
		(pts
			(arc
				(start 130.872484 -371.038628)
				(mid 130.623056 -371.038628)
				(end 130.872484 -371.038628)
			)
		)
		(stroke
			(width 0)
			(type solid)
		)
		(fill yes)
		(layer "B.Cu")
		(net "GND")
	)
	(gr_poly
		(pts
			(arc
				(start 132.073142 -357.75773)
				(mid 131.823714 -357.75773)
				(end 132.073142 -357.75773)
			)
		)
		(stroke
			(width 0)
			(type solid)
		)
		(fill yes)
		(layer "B.Cu")
		(net "GND")
	)
	(gr_poly
		(pts
			(arc
				(start 132.073142 -354.732082)
				(mid 131.823714 -354.732082)
				(end 132.073142 -354.732082)
			)
		)
		(stroke
			(width 0)
			(type solid)
		)
		(fill yes)
		(layer "B.Cu")
		(net "GND")
	)
	(gr_poly
		(pts
			(arc
				(start 132.073142 -351.611438)
				(mid 131.823714 -351.611438)
				(end 132.073142 -351.611438)
			)
		)
		(stroke
			(width 0)
			(type solid)
		)
		(fill yes)
		(layer "B.Cu")
		(net "GND")
	)
	(gr_poly
		(pts
			(arc
				(start 132.073142 -348.58579)
				(mid 131.823714 -348.58579)
				(end 132.073142 -348.58579)
			)
		)
		(stroke
			(width 0)
			(type solid)
		)
		(fill yes)
		(layer "B.Cu")
		(net "GND")
	)
	(gr_poly
		(pts
			(arc
				(start 132.073142 -345.465146)
				(mid 131.823714 -345.465146)
				(end 132.073142 -345.465146)
			)
		)
		(stroke
			(width 0)
			(type solid)
		)
		(fill yes)
		(layer "B.Cu")
		(net "GND")
	)
	(gr_poly
		(pts
			(arc
				(start 132.073142 -342.439498)
				(mid 131.823714 -342.439498)
				(end 132.073142 -342.439498)
			)
		)
		(stroke
			(width 0)
			(type solid)
		)
		(fill yes)
		(layer "B.Cu")
		(net "GND")
	)
	(gr_poly
		(pts
			(arc
				(start 133.180582 -357.75773)
				(mid 132.931154 -357.75773)
				(end 133.180582 -357.75773)
			)
		)
		(stroke
			(width 0)
			(type solid)
		)
		(fill yes)
		(layer "B.Cu")
		(net "GND")
	)
	(gr_poly
		(pts
			(arc
				(start 133.180582 -354.732082)
				(mid 132.931154 -354.732082)
				(end 133.180582 -354.732082)
			)
		)
		(stroke
			(width 0)
			(type solid)
		)
		(fill yes)
		(layer "B.Cu")
		(net "GND")
	)
	(gr_poly
		(pts
			(arc
				(start 133.180582 -351.611438)
				(mid 132.931154 -351.611438)
				(end 133.180582 -351.611438)
			)
		)
		(stroke
			(width 0)
			(type solid)
		)
		(fill yes)
		(layer "B.Cu")
		(net "GND")
	)
	(gr_poly
		(pts
			(arc
				(start 133.180582 -348.58579)
				(mid 132.931154 -348.58579)
				(end 133.180582 -348.58579)
			)
		)
		(stroke
			(width 0)
			(type solid)
		)
		(fill yes)
		(layer "B.Cu")
		(net "GND")
	)
	(gr_poly
		(pts
			(arc
				(start 133.180582 -345.465146)
				(mid 132.931154 -345.465146)
				(end 133.180582 -345.465146)
			)
		)
		(stroke
			(width 0)
			(type solid)
		)
		(fill yes)
		(layer "B.Cu")
		(net "GND")
	)
	(gr_poly
		(pts
			(arc
				(start 133.180582 -342.439498)
				(mid 132.931154 -342.439498)
				(end 133.180582 -342.439498)
			)
		)
		(stroke
			(width 0)
			(type solid)
		)
		(fill yes)
		(layer "B.Cu")
		(net "GND")
	)
	(gr_poly
		(pts
			(arc
				(start 135.182102 -357.75773)
				(mid 134.932674 -357.75773)
				(end 135.182102 -357.75773)
			)
		)
		(stroke
			(width 0)
			(type solid)
		)
		(fill yes)
		(layer "B.Cu")
		(net "GND")
	)
	(gr_poly
		(pts
			(arc
				(start 135.182102 -354.732082)
				(mid 134.932674 -354.732082)
				(end 135.182102 -354.732082)
			)
		)
		(stroke
			(width 0)
			(type solid)
		)
		(fill yes)
		(layer "B.Cu")
		(net "GND")
	)
	(gr_poly
		(pts
			(arc
				(start 135.182102 -351.611438)
				(mid 134.932674 -351.611438)
				(end 135.182102 -351.611438)
			)
		)
		(stroke
			(width 0)
			(type solid)
		)
		(fill yes)
		(layer "B.Cu")
		(net "GND")
	)
	(gr_poly
		(pts
			(arc
				(start 135.182102 -348.58579)
				(mid 134.932674 -348.58579)
				(end 135.182102 -348.58579)
			)
		)
		(stroke
			(width 0)
			(type solid)
		)
		(fill yes)
		(layer "B.Cu")
		(net "GND")
	)
	(gr_poly
		(pts
			(arc
				(start 135.182102 -345.465146)
				(mid 134.932674 -345.465146)
				(end 135.182102 -345.465146)
			)
		)
		(stroke
			(width 0)
			(type solid)
		)
		(fill yes)
		(layer "B.Cu")
		(net "GND")
	)
	(gr_poly
		(pts
			(arc
				(start 135.182102 -342.439498)
				(mid 134.932674 -342.439498)
				(end 135.182102 -342.439498)
			)
		)
		(stroke
			(width 0)
			(type solid)
		)
		(fill yes)
		(layer "B.Cu")
		(net "GND")
	)
	(gr_poly
		(pts
			(arc
				(start 136.289542 -357.75773)
				(mid 136.040114 -357.75773)
				(end 136.289542 -357.75773)
			)
		)
		(stroke
			(width 0)
			(type solid)
		)
		(fill yes)
		(layer "B.Cu")
		(net "GND")
	)
	(gr_poly
		(pts
			(arc
				(start 136.289542 -354.732082)
				(mid 136.040114 -354.732082)
				(end 136.289542 -354.732082)
			)
		)
		(stroke
			(width 0)
			(type solid)
		)
		(fill yes)
		(layer "B.Cu")
		(net "GND")
	)
	(gr_poly
		(pts
			(arc
				(start 136.289542 -351.611438)
				(mid 136.040114 -351.611438)
				(end 136.289542 -351.611438)
			)
		)
		(stroke
			(width 0)
			(type solid)
		)
		(fill yes)
		(layer "B.Cu")
		(net "GND")
	)
	(gr_poly
		(pts
			(arc
				(start 136.289542 -348.58579)
				(mid 136.040114 -348.58579)
				(end 136.289542 -348.58579)
			)
		)
		(stroke
			(width 0)
			(type solid)
		)
		(fill yes)
		(layer "B.Cu")
		(net "GND")
	)
	(gr_poly
		(pts
			(arc
				(start 136.289542 -345.465146)
				(mid 136.040114 -345.465146)
				(end 136.289542 -345.465146)
			)
		)
		(stroke
			(width 0)
			(type solid)
		)
		(fill yes)
		(layer "B.Cu")
		(net "GND")
	)
	(gr_poly
		(pts
			(arc
				(start 136.289542 -342.439498)
				(mid 136.040114 -342.439498)
				(end 136.289542 -342.439498)
			)
		)
		(stroke
			(width 0)
			(type solid)
		)
		(fill yes)
		(layer "B.Cu")
		(net "GND")
	)
	(gr_poly
		(pts
			(arc
				(start 138.291062 -357.75773)
				(mid 138.041634 -357.75773)
				(end 138.291062 -357.75773)
			)
		)
		(stroke
			(width 0)
			(type solid)
		)
		(fill yes)
		(layer "B.Cu")
		(net "GND")
	)
	(gr_poly
		(pts
			(arc
				(start 138.291062 -354.732082)
				(mid 138.041634 -354.732082)
				(end 138.291062 -354.732082)
			)
		)
		(stroke
			(width 0)
			(type solid)
		)
		(fill yes)
		(layer "B.Cu")
		(net "GND")
	)
	(gr_poly
		(pts
			(arc
				(start 138.291062 -351.611438)
				(mid 138.041634 -351.611438)
				(end 138.291062 -351.611438)
			)
		)
		(stroke
			(width 0)
			(type solid)
		)
		(fill yes)
		(layer "B.Cu")
		(net "GND")
	)
	(gr_poly
		(pts
			(arc
				(start 138.291062 -348.58579)
				(mid 138.041634 -348.58579)
				(end 138.291062 -348.58579)
			)
		)
		(stroke
			(width 0)
			(type solid)
		)
		(fill yes)
		(layer "B.Cu")
		(net "GND")
	)
	(gr_poly
		(pts
			(arc
				(start 138.291062 -345.465146)
				(mid 138.041634 -345.465146)
				(end 138.291062 -345.465146)
			)
		)
		(stroke
			(width 0)
			(type solid)
		)
		(fill yes)
		(layer "B.Cu")
		(net "GND")
	)
	(gr_poly
		(pts
			(arc
				(start 138.291062 -342.439498)
				(mid 138.041634 -342.439498)
				(end 138.291062 -342.439498)
			)
		)
		(stroke
			(width 0)
			(type solid)
		)
		(fill yes)
		(layer "B.Cu")
		(net "GND")
	)
	(gr_poly
		(pts
			(arc
				(start 139.398502 -357.75773)
				(mid 139.149074 -357.75773)
				(end 139.398502 -357.75773)
			)
		)
		(stroke
			(width 0)
			(type solid)
		)
		(fill yes)
		(layer "B.Cu")
		(net "GND")
	)
	(gr_poly
		(pts
			(arc
				(start 139.398502 -354.732082)
				(mid 139.149074 -354.732082)
				(end 139.398502 -354.732082)
			)
		)
		(stroke
			(width 0)
			(type solid)
		)
		(fill yes)
		(layer "B.Cu")
		(net "GND")
	)
	(gr_poly
		(pts
			(arc
				(start 139.398502 -351.611438)
				(mid 139.149074 -351.611438)
				(end 139.398502 -351.611438)
			)
		)
		(stroke
			(width 0)
			(type solid)
		)
		(fill yes)
		(layer "B.Cu")
		(net "GND")
	)
	(gr_poly
		(pts
			(arc
				(start 139.398502 -348.58579)
				(mid 139.149074 -348.58579)
				(end 139.398502 -348.58579)
			)
		)
		(stroke
			(width 0)
			(type solid)
		)
		(fill yes)
		(layer "B.Cu")
		(net "GND")
	)
	(gr_poly
		(pts
			(arc
				(start 139.398502 -345.465146)
				(mid 139.149074 -345.465146)
				(end 139.398502 -345.465146)
			)
		)
		(stroke
			(width 0)
			(type solid)
		)
		(fill yes)
		(layer "B.Cu")
		(net "GND")
	)
	(gr_poly
		(pts
			(arc
				(start 139.398502 -342.439498)
				(mid 139.149074 -342.439498)
				(end 139.398502 -342.439498)
			)
		)
		(stroke
			(width 0)
			(type solid)
		)
		(fill yes)
		(layer "B.Cu")
		(net "GND")
	)
	(gr_poly
		(pts
			(arc
				(start 141.400022 -357.75773)
				(mid 141.150594 -357.75773)
				(end 141.400022 -357.75773)
			)
		)
		(stroke
			(width 0)
			(type solid)
		)
		(fill yes)
		(layer "B.Cu")
		(net "GND")
	)
	(gr_poly
		(pts
			(arc
				(start 141.400022 -354.732082)
				(mid 141.150594 -354.732082)
				(end 141.400022 -354.732082)
			)
		)
		(stroke
			(width 0)
			(type solid)
		)
		(fill yes)
		(layer "B.Cu")
		(net "GND")
	)
	(gr_poly
		(pts
			(arc
				(start 141.400022 -351.611438)
				(mid 141.150594 -351.611438)
				(end 141.400022 -351.611438)
			)
		)
		(stroke
			(width 0)
			(type solid)
		)
		(fill yes)
		(layer "B.Cu")
		(net "GND")
	)
	(gr_poly
		(pts
			(arc
				(start 141.400022 -348.58579)
				(mid 141.150594 -348.58579)
				(end 141.400022 -348.58579)
			)
		)
		(stroke
			(width 0)
			(type solid)
		)
		(fill yes)
		(layer "B.Cu")
		(net "GND")
	)
	(gr_poly
		(pts
			(arc
				(start 141.400022 -345.465146)
				(mid 141.150594 -345.465146)
				(end 141.400022 -345.465146)
			)
		)
		(stroke
			(width 0)
			(type solid)
		)
		(fill yes)
		(layer "B.Cu")
		(net "GND")
	)
	(gr_poly
		(pts
			(arc
				(start 141.400022 -342.439498)
				(mid 141.150594 -342.439498)
				(end 141.400022 -342.439498)
			)
		)
		(stroke
			(width 0)
			(type solid)
		)
		(fill yes)
		(layer "B.Cu")
		(net "GND")
	)
	(gr_poly
		(pts
			(arc
				(start 142.507462 -357.75773)
				(mid 142.258034 -357.75773)
				(end 142.507462 -357.75773)
			)
		)
		(stroke
			(width 0)
			(type solid)
		)
		(fill yes)
		(layer "B.Cu")
		(net "GND")
	)
	(gr_poly
		(pts
			(arc
				(start 142.507462 -354.732082)
				(mid 142.258034 -354.732082)
				(end 142.507462 -354.732082)
			)
		)
		(stroke
			(width 0)
			(type solid)
		)
		(fill yes)
		(layer "B.Cu")
		(net "GND")
	)
	(gr_poly
		(pts
			(arc
				(start 142.507462 -351.611438)
				(mid 142.258034 -351.611438)
				(end 142.507462 -351.611438)
			)
		)
		(stroke
			(width 0)
			(type solid)
		)
		(fill yes)
		(layer "B.Cu")
		(net "GND")
	)
	(gr_poly
		(pts
			(arc
				(start 142.507462 -348.58579)
				(mid 142.258034 -348.58579)
				(end 142.507462 -348.58579)
			)
		)
		(stroke
			(width 0)
			(type solid)
		)
		(fill yes)
		(layer "B.Cu")
		(net "GND")
	)
	(gr_poly
		(pts
			(arc
				(start 142.507462 -345.465146)
				(mid 142.258034 -345.465146)
				(end 142.507462 -345.465146)
			)
		)
		(stroke
			(width 0)
			(type solid)
		)
		(fill yes)
		(layer "B.Cu")
		(net "GND")
	)
	(gr_poly
		(pts
			(arc
				(start 142.507462 -342.439498)
				(mid 142.258034 -342.439498)
				(end 142.507462 -342.439498)
			)
		)
		(stroke
			(width 0)
			(type solid)
		)
		(fill yes)
		(layer "B.Cu")
		(net "GND")
	)
	(gr_poly
		(pts
			(arc
				(start 144.508982 -357.75773)
				(mid 144.259554 -357.75773)
				(end 144.508982 -357.75773)
			)
		)
		(stroke
			(width 0)
			(type solid)
		)
		(fill yes)
		(layer "B.Cu")
		(net "GND")
	)
	(gr_poly
		(pts
			(arc
				(start 144.508982 -354.732082)
				(mid 144.259554 -354.732082)
				(end 144.508982 -354.732082)
			)
		)
		(stroke
			(width 0)
			(type solid)
		)
		(fill yes)
		(layer "B.Cu")
		(net "GND")
	)
	(gr_poly
		(pts
			(arc
				(start 144.508982 -351.611438)
				(mid 144.259554 -351.611438)
				(end 144.508982 -351.611438)
			)
		)
		(stroke
			(width 0)
			(type solid)
		)
		(fill yes)
		(layer "B.Cu")
		(net "GND")
	)
	(gr_poly
		(pts
			(arc
				(start 144.508982 -348.58579)
				(mid 144.259554 -348.58579)
				(end 144.508982 -348.58579)
			)
		)
		(stroke
			(width 0)
			(type solid)
		)
		(fill yes)
		(layer "B.Cu")
		(net "GND")
	)
	(gr_poly
		(pts
			(arc
				(start 144.508982 -345.465146)
				(mid 144.259554 -345.465146)
				(end 144.508982 -345.465146)
			)
		)
		(stroke
			(width 0)
			(type solid)
		)
		(fill yes)
		(layer "B.Cu")
		(net "GND")
	)
	(gr_poly
		(pts
			(arc
				(start 144.508982 -342.439498)
				(mid 144.259554 -342.439498)
				(end 144.508982 -342.439498)
			)
		)
		(stroke
			(width 0)
			(type solid)
		)
		(fill yes)
		(layer "B.Cu")
		(net "GND")
	)
	(gr_poly
		(pts
			(arc
				(start 158.632906 -357.75773)
				(mid 158.383478 -357.75773)
				(end 158.632906 -357.75773)
			)
		)
		(stroke
			(width 0)
			(type solid)
		)
		(fill yes)
		(layer "B.Cu")
		(net "GND")
	)
	(gr_poly
		(pts
			(arc
				(start 158.632906 -354.732082)
				(mid 158.383478 -354.732082)
				(end 158.632906 -354.732082)
			)
		)
		(stroke
			(width 0)
			(type solid)
		)
		(fill yes)
		(layer "B.Cu")
		(net "GND")
	)
	(gr_poly
		(pts
			(arc
				(start 159.47263 -410.041852)
				(mid 159.223202 -410.041852)
				(end 159.47263 -410.041852)
			)
		)
		(stroke
			(width 0)
			(type solid)
		)
		(fill yes)
		(layer "B.Cu")
		(net "GND")
	)
	(gr_poly
		(pts
			(arc
				(start 159.47263 -408.840178)
				(mid 159.223202 -408.840178)
				(end 159.47263 -408.840178)
			)
		)
		(stroke
			(width 0)
			(type solid)
		)
		(fill yes)
		(layer "B.Cu")
		(net "GND")
	)
	(gr_poly
		(pts
			(arc
				(start 159.47263 -407.638504)
				(mid 159.223202 -407.638504)
				(end 159.47263 -407.638504)
			)
		)
		(stroke
			(width 0)
			(type solid)
		)
		(fill yes)
		(layer "B.Cu")
		(net "GND")
	)
	(gr_poly
		(pts
			(arc
				(start 159.47263 -406.141936)
				(mid 159.223202 -406.141936)
				(end 159.47263 -406.141936)
			)
		)
		(stroke
			(width 0)
			(type solid)
		)
		(fill yes)
		(layer "B.Cu")
		(net "GND")
	)
	(gr_poly
		(pts
			(arc
				(start 159.47263 -404.940262)
				(mid 159.223202 -404.940262)
				(end 159.47263 -404.940262)
			)
		)
		(stroke
			(width 0)
			(type solid)
		)
		(fill yes)
		(layer "B.Cu")
		(net "GND")
	)
	(gr_poly
		(pts
			(arc
				(start 159.47263 -403.738588)
				(mid 159.223202 -403.738588)
				(end 159.47263 -403.738588)
			)
		)
		(stroke
			(width 0)
			(type solid)
		)
		(fill yes)
		(layer "B.Cu")
		(net "GND")
	)
	(gr_poly
		(pts
			(arc
				(start 159.47263 -402.241766)
				(mid 159.223202 -402.241766)
				(end 159.47263 -402.241766)
			)
		)
		(stroke
			(width 0)
			(type solid)
		)
		(fill yes)
		(layer "B.Cu")
		(net "GND")
	)
	(gr_poly
		(pts
			(arc
				(start 159.47263 -401.040092)
				(mid 159.223202 -401.040092)
				(end 159.47263 -401.040092)
			)
		)
		(stroke
			(width 0)
			(type solid)
		)
		(fill yes)
		(layer "B.Cu")
		(net "GND")
	)
	(gr_poly
		(pts
			(arc
				(start 159.47263 -399.838418)
				(mid 159.223202 -399.838418)
				(end 159.47263 -399.838418)
			)
		)
		(stroke
			(width 0)
			(type solid)
		)
		(fill yes)
		(layer "B.Cu")
		(net "GND")
	)
	(gr_poly
		(pts
			(arc
				(start 159.47263 -398.34185)
				(mid 159.223202 -398.34185)
				(end 159.47263 -398.34185)
			)
		)
		(stroke
			(width 0)
			(type solid)
		)
		(fill yes)
		(layer "B.Cu")
		(net "GND")
	)
	(gr_poly
		(pts
			(arc
				(start 159.47263 -397.140176)
				(mid 159.223202 -397.140176)
				(end 159.47263 -397.140176)
			)
		)
		(stroke
			(width 0)
			(type solid)
		)
		(fill yes)
		(layer "B.Cu")
		(net "GND")
	)
	(gr_poly
		(pts
			(arc
				(start 159.47263 -395.938502)
				(mid 159.223202 -395.938502)
				(end 159.47263 -395.938502)
			)
		)
		(stroke
			(width 0)
			(type solid)
		)
		(fill yes)
		(layer "B.Cu")
		(net "GND")
	)
	(gr_poly
		(pts
			(arc
				(start 159.47263 -384.041904)
				(mid 159.223202 -384.041904)
				(end 159.47263 -384.041904)
			)
		)
		(stroke
			(width 0)
			(type solid)
		)
		(fill yes)
		(layer "B.Cu")
		(net "GND")
	)
	(gr_poly
		(pts
			(arc
				(start 159.47263 -382.84023)
				(mid 159.223202 -382.84023)
				(end 159.47263 -382.84023)
			)
		)
		(stroke
			(width 0)
			(type solid)
		)
		(fill yes)
		(layer "B.Cu")
		(net "GND")
	)
	(gr_poly
		(pts
			(arc
				(start 159.47263 -381.638556)
				(mid 159.223202 -381.638556)
				(end 159.47263 -381.638556)
			)
		)
		(stroke
			(width 0)
			(type solid)
		)
		(fill yes)
		(layer "B.Cu")
		(net "GND")
	)
	(gr_poly
		(pts
			(arc
				(start 159.47263 -380.141988)
				(mid 159.223202 -380.141988)
				(end 159.47263 -380.141988)
			)
		)
		(stroke
			(width 0)
			(type solid)
		)
		(fill yes)
		(layer "B.Cu")
		(net "GND")
	)
	(gr_poly
		(pts
			(arc
				(start 159.47263 -378.940314)
				(mid 159.223202 -378.940314)
				(end 159.47263 -378.940314)
			)
		)
		(stroke
			(width 0)
			(type solid)
		)
		(fill yes)
		(layer "B.Cu")
		(net "GND")
	)
	(gr_poly
		(pts
			(arc
				(start 159.47263 -377.73864)
				(mid 159.223202 -377.73864)
				(end 159.47263 -377.73864)
			)
		)
		(stroke
			(width 0)
			(type solid)
		)
		(fill yes)
		(layer "B.Cu")
		(net "GND")
	)
	(gr_poly
		(pts
			(arc
				(start 159.47263 -376.241818)
				(mid 159.223202 -376.241818)
				(end 159.47263 -376.241818)
			)
		)
		(stroke
			(width 0)
			(type solid)
		)
		(fill yes)
		(layer "B.Cu")
		(net "GND")
	)
	(gr_poly
		(pts
			(arc
				(start 159.47263 -375.040144)
				(mid 159.223202 -375.040144)
				(end 159.47263 -375.040144)
			)
		)
		(stroke
			(width 0)
			(type solid)
		)
		(fill yes)
		(layer "B.Cu")
		(net "GND")
	)
	(gr_poly
		(pts
			(arc
				(start 159.47263 -373.83847)
				(mid 159.223202 -373.83847)
				(end 159.47263 -373.83847)
			)
		)
		(stroke
			(width 0)
			(type solid)
		)
		(fill yes)
		(layer "B.Cu")
		(net "GND")
	)
	(gr_poly
		(pts
			(arc
				(start 159.47263 -372.341902)
				(mid 159.223202 -372.341902)
				(end 159.47263 -372.341902)
			)
		)
		(stroke
			(width 0)
			(type solid)
		)
		(fill yes)
		(layer "B.Cu")
		(net "GND")
	)
	(gr_poly
		(pts
			(arc
				(start 159.47263 -371.140228)
				(mid 159.223202 -371.140228)
				(end 159.47263 -371.140228)
			)
		)
		(stroke
			(width 0)
			(type solid)
		)
		(fill yes)
		(layer "B.Cu")
		(net "GND")
	)
	(gr_poly
		(pts
			(arc
				(start 159.47263 -369.938554)
				(mid 159.223202 -369.938554)
				(end 159.47263 -369.938554)
			)
		)
		(stroke
			(width 0)
			(type solid)
		)
		(fill yes)
		(layer "B.Cu")
		(net "GND")
	)
	(gr_poly
		(pts
			(arc
				(start 160.634426 -357.75773)
				(mid 160.384998 -357.75773)
				(end 160.634426 -357.75773)
			)
		)
		(stroke
			(width 0)
			(type solid)
		)
		(fill yes)
		(layer "B.Cu")
		(net "GND")
	)
	(gr_poly
		(pts
			(arc
				(start 160.634426 -354.732082)
				(mid 160.384998 -354.732082)
				(end 160.634426 -354.732082)
			)
		)
		(stroke
			(width 0)
			(type solid)
		)
		(fill yes)
		(layer "B.Cu")
		(net "GND")
	)
	(gr_poly
		(pts
			(arc
				(start 161.672524 -411.141926)
				(mid 161.423096 -411.141926)
				(end 161.672524 -411.141926)
			)
		)
		(stroke
			(width 0)
			(type solid)
		)
		(fill yes)
		(layer "B.Cu")
		(net "GND")
	)
	(gr_poly
		(pts
			(arc
				(start 161.672524 -409.940252)
				(mid 161.423096 -409.940252)
				(end 161.672524 -409.940252)
			)
		)
		(stroke
			(width 0)
			(type solid)
		)
		(fill yes)
		(layer "B.Cu")
		(net "GND")
	)
	(gr_poly
		(pts
			(arc
				(start 161.672524 -408.738578)
				(mid 161.423096 -408.738578)
				(end 161.672524 -408.738578)
			)
		)
		(stroke
			(width 0)
			(type solid)
		)
		(fill yes)
		(layer "B.Cu")
		(net "GND")
	)
	(gr_poly
		(pts
			(arc
				(start 161.672524 -407.24201)
				(mid 161.423096 -407.24201)
				(end 161.672524 -407.24201)
			)
		)
		(stroke
			(width 0)
			(type solid)
		)
		(fill yes)
		(layer "B.Cu")
		(net "GND")
	)
	(gr_poly
		(pts
			(arc
				(start 161.672524 -406.040336)
				(mid 161.423096 -406.040336)
				(end 161.672524 -406.040336)
			)
		)
		(stroke
			(width 0)
			(type solid)
		)
		(fill yes)
		(layer "B.Cu")
		(net "GND")
	)
	(gr_poly
		(pts
			(arc
				(start 161.672524 -404.838662)
				(mid 161.423096 -404.838662)
				(end 161.672524 -404.838662)
			)
		)
		(stroke
			(width 0)
			(type solid)
		)
		(fill yes)
		(layer "B.Cu")
		(net "GND")
	)
	(gr_poly
		(pts
			(arc
				(start 161.672524 -403.34184)
				(mid 161.423096 -403.34184)
				(end 161.672524 -403.34184)
			)
		)
		(stroke
			(width 0)
			(type solid)
		)
		(fill yes)
		(layer "B.Cu")
		(net "GND")
	)
	(gr_poly
		(pts
			(arc
				(start 161.672524 -402.140166)
				(mid 161.423096 -402.140166)
				(end 161.672524 -402.140166)
			)
		)
		(stroke
			(width 0)
			(type solid)
		)
		(fill yes)
		(layer "B.Cu")
		(net "GND")
	)
	(gr_poly
		(pts
			(arc
				(start 161.672524 -400.938492)
				(mid 161.423096 -400.938492)
				(end 161.672524 -400.938492)
			)
		)
		(stroke
			(width 0)
			(type solid)
		)
		(fill yes)
		(layer "B.Cu")
		(net "GND")
	)
	(gr_poly
		(pts
			(arc
				(start 161.672524 -399.441924)
				(mid 161.423096 -399.441924)
				(end 161.672524 -399.441924)
			)
		)
		(stroke
			(width 0)
			(type solid)
		)
		(fill yes)
		(layer "B.Cu")
		(net "GND")
	)
	(gr_poly
		(pts
			(arc
				(start 161.672524 -398.24025)
				(mid 161.423096 -398.24025)
				(end 161.672524 -398.24025)
			)
		)
		(stroke
			(width 0)
			(type solid)
		)
		(fill yes)
		(layer "B.Cu")
		(net "GND")
	)
	(gr_poly
		(pts
			(arc
				(start 161.672524 -397.038576)
				(mid 161.423096 -397.038576)
				(end 161.672524 -397.038576)
			)
		)
		(stroke
			(width 0)
			(type solid)
		)
		(fill yes)
		(layer "B.Cu")
		(net "GND")
	)
	(gr_poly
		(pts
			(arc
				(start 161.672524 -385.141978)
				(mid 161.423096 -385.141978)
				(end 161.672524 -385.141978)
			)
		)
		(stroke
			(width 0)
			(type solid)
		)
		(fill yes)
		(layer "B.Cu")
		(net "GND")
	)
	(gr_poly
		(pts
			(arc
				(start 161.672524 -383.940304)
				(mid 161.423096 -383.940304)
				(end 161.672524 -383.940304)
			)
		)
		(stroke
			(width 0)
			(type solid)
		)
		(fill yes)
		(layer "B.Cu")
		(net "GND")
	)
	(gr_poly
		(pts
			(arc
				(start 161.672524 -382.73863)
				(mid 161.423096 -382.73863)
				(end 161.672524 -382.73863)
			)
		)
		(stroke
			(width 0)
			(type solid)
		)
		(fill yes)
		(layer "B.Cu")
		(net "GND")
	)
	(gr_poly
		(pts
			(arc
				(start 161.672524 -381.242062)
				(mid 161.423096 -381.242062)
				(end 161.672524 -381.242062)
			)
		)
		(stroke
			(width 0)
			(type solid)
		)
		(fill yes)
		(layer "B.Cu")
		(net "GND")
	)
	(gr_poly
		(pts
			(arc
				(start 161.672524 -380.040388)
				(mid 161.423096 -380.040388)
				(end 161.672524 -380.040388)
			)
		)
		(stroke
			(width 0)
			(type solid)
		)
		(fill yes)
		(layer "B.Cu")
		(net "GND")
	)
	(gr_poly
		(pts
			(arc
				(start 161.672524 -378.838714)
				(mid 161.423096 -378.838714)
				(end 161.672524 -378.838714)
			)
		)
		(stroke
			(width 0)
			(type solid)
		)
		(fill yes)
		(layer "B.Cu")
		(net "GND")
	)
	(gr_poly
		(pts
			(arc
				(start 161.672524 -377.341892)
				(mid 161.423096 -377.341892)
				(end 161.672524 -377.341892)
			)
		)
		(stroke
			(width 0)
			(type solid)
		)
		(fill yes)
		(layer "B.Cu")
		(net "GND")
	)
	(gr_poly
		(pts
			(arc
				(start 161.672524 -376.140218)
				(mid 161.423096 -376.140218)
				(end 161.672524 -376.140218)
			)
		)
		(stroke
			(width 0)
			(type solid)
		)
		(fill yes)
		(layer "B.Cu")
		(net "GND")
	)
	(gr_poly
		(pts
			(arc
				(start 161.672524 -374.938544)
				(mid 161.423096 -374.938544)
				(end 161.672524 -374.938544)
			)
		)
		(stroke
			(width 0)
			(type solid)
		)
		(fill yes)
		(layer "B.Cu")
		(net "GND")
	)
	(gr_poly
		(pts
			(arc
				(start 161.672524 -373.441976)
				(mid 161.423096 -373.441976)
				(end 161.672524 -373.441976)
			)
		)
		(stroke
			(width 0)
			(type solid)
		)
		(fill yes)
		(layer "B.Cu")
		(net "GND")
	)
	(gr_poly
		(pts
			(arc
				(start 161.672524 -372.240302)
				(mid 161.423096 -372.240302)
				(end 161.672524 -372.240302)
			)
		)
		(stroke
			(width 0)
			(type solid)
		)
		(fill yes)
		(layer "B.Cu")
		(net "GND")
	)
	(gr_poly
		(pts
			(arc
				(start 161.672524 -371.038628)
				(mid 161.423096 -371.038628)
				(end 161.672524 -371.038628)
			)
		)
		(stroke
			(width 0)
			(type solid)
		)
		(fill yes)
		(layer "B.Cu")
		(net "GND")
	)
	(gr_poly
		(pts
			(arc
				(start 161.741866 -357.75773)
				(mid 161.492438 -357.75773)
				(end 161.741866 -357.75773)
			)
		)
		(stroke
			(width 0)
			(type solid)
		)
		(fill yes)
		(layer "B.Cu")
		(net "GND")
	)
	(gr_poly
		(pts
			(arc
				(start 161.741866 -354.732082)
				(mid 161.492438 -354.732082)
				(end 161.741866 -354.732082)
			)
		)
		(stroke
			(width 0)
			(type solid)
		)
		(fill yes)
		(layer "B.Cu")
		(net "GND")
	)
	(gr_poly
		(pts
			(arc
				(start 161.741866 -351.611438)
				(mid 161.492438 -351.611438)
				(end 161.741866 -351.611438)
			)
		)
		(stroke
			(width 0)
			(type solid)
		)
		(fill yes)
		(layer "B.Cu")
		(net "GND")
	)
	(gr_poly
		(pts
			(arc
				(start 161.741866 -348.58579)
				(mid 161.492438 -348.58579)
				(end 161.741866 -348.58579)
			)
		)
		(stroke
			(width 0)
			(type solid)
		)
		(fill yes)
		(layer "B.Cu")
		(net "GND")
	)
	(gr_poly
		(pts
			(arc
				(start 163.743386 -357.75773)
				(mid 163.493958 -357.75773)
				(end 163.743386 -357.75773)
			)
		)
		(stroke
			(width 0)
			(type solid)
		)
		(fill yes)
		(layer "B.Cu")
		(net "GND")
	)
	(gr_poly
		(pts
			(arc
				(start 163.743386 -354.732082)
				(mid 163.493958 -354.732082)
				(end 163.743386 -354.732082)
			)
		)
		(stroke
			(width 0)
			(type solid)
		)
		(fill yes)
		(layer "B.Cu")
		(net "GND")
	)
	(gr_poly
		(pts
			(arc
				(start 163.743386 -351.611438)
				(mid 163.493958 -351.611438)
				(end 163.743386 -351.611438)
			)
		)
		(stroke
			(width 0)
			(type solid)
		)
		(fill yes)
		(layer "B.Cu")
		(net "GND")
	)
	(gr_poly
		(pts
			(arc
				(start 163.743386 -348.58579)
				(mid 163.493958 -348.58579)
				(end 163.743386 -348.58579)
			)
		)
		(stroke
			(width 0)
			(type solid)
		)
		(fill yes)
		(layer "B.Cu")
		(net "GND")
	)
	(gr_poly
		(pts
			(arc
				(start 163.872672 -410.041852)
				(mid 163.623244 -410.041852)
				(end 163.872672 -410.041852)
			)
		)
		(stroke
			(width 0)
			(type solid)
		)
		(fill yes)
		(layer "B.Cu")
		(net "GND")
	)
	(gr_poly
		(pts
			(arc
				(start 163.872672 -408.840178)
				(mid 163.623244 -408.840178)
				(end 163.872672 -408.840178)
			)
		)
		(stroke
			(width 0)
			(type solid)
		)
		(fill yes)
		(layer "B.Cu")
		(net "GND")
	)
	(gr_poly
		(pts
			(arc
				(start 163.872672 -407.638504)
				(mid 163.623244 -407.638504)
				(end 163.872672 -407.638504)
			)
		)
		(stroke
			(width 0)
			(type solid)
		)
		(fill yes)
		(layer "B.Cu")
		(net "GND")
	)
	(gr_poly
		(pts
			(arc
				(start 163.872672 -406.141936)
				(mid 163.623244 -406.141936)
				(end 163.872672 -406.141936)
			)
		)
		(stroke
			(width 0)
			(type solid)
		)
		(fill yes)
		(layer "B.Cu")
		(net "GND")
	)
	(gr_poly
		(pts
			(arc
				(start 163.872672 -404.940262)
				(mid 163.623244 -404.940262)
				(end 163.872672 -404.940262)
			)
		)
		(stroke
			(width 0)
			(type solid)
		)
		(fill yes)
		(layer "B.Cu")
		(net "GND")
	)
	(gr_poly
		(pts
			(arc
				(start 163.872672 -403.738588)
				(mid 163.623244 -403.738588)
				(end 163.872672 -403.738588)
			)
		)
		(stroke
			(width 0)
			(type solid)
		)
		(fill yes)
		(layer "B.Cu")
		(net "GND")
	)
	(gr_poly
		(pts
			(arc
				(start 163.872672 -402.241766)
				(mid 163.623244 -402.241766)
				(end 163.872672 -402.241766)
			)
		)
		(stroke
			(width 0)
			(type solid)
		)
		(fill yes)
		(layer "B.Cu")
		(net "GND")
	)
	(gr_poly
		(pts
			(arc
				(start 163.872672 -401.040092)
				(mid 163.623244 -401.040092)
				(end 163.872672 -401.040092)
			)
		)
		(stroke
			(width 0)
			(type solid)
		)
		(fill yes)
		(layer "B.Cu")
		(net "GND")
	)
	(gr_poly
		(pts
			(arc
				(start 163.872672 -399.838418)
				(mid 163.623244 -399.838418)
				(end 163.872672 -399.838418)
			)
		)
		(stroke
			(width 0)
			(type solid)
		)
		(fill yes)
		(layer "B.Cu")
		(net "GND")
	)
	(gr_poly
		(pts
			(arc
				(start 163.872672 -398.34185)
				(mid 163.623244 -398.34185)
				(end 163.872672 -398.34185)
			)
		)
		(stroke
			(width 0)
			(type solid)
		)
		(fill yes)
		(layer "B.Cu")
		(net "GND")
	)
	(gr_poly
		(pts
			(arc
				(start 163.872672 -397.140176)
				(mid 163.623244 -397.140176)
				(end 163.872672 -397.140176)
			)
		)
		(stroke
			(width 0)
			(type solid)
		)
		(fill yes)
		(layer "B.Cu")
		(net "GND")
	)
	(gr_poly
		(pts
			(arc
				(start 163.872672 -395.938502)
				(mid 163.623244 -395.938502)
				(end 163.872672 -395.938502)
			)
		)
		(stroke
			(width 0)
			(type solid)
		)
		(fill yes)
		(layer "B.Cu")
		(net "GND")
	)
	(gr_poly
		(pts
			(arc
				(start 163.872672 -384.041904)
				(mid 163.623244 -384.041904)
				(end 163.872672 -384.041904)
			)
		)
		(stroke
			(width 0)
			(type solid)
		)
		(fill yes)
		(layer "B.Cu")
		(net "GND")
	)
	(gr_poly
		(pts
			(arc
				(start 163.872672 -382.84023)
				(mid 163.623244 -382.84023)
				(end 163.872672 -382.84023)
			)
		)
		(stroke
			(width 0)
			(type solid)
		)
		(fill yes)
		(layer "B.Cu")
		(net "GND")
	)
	(gr_poly
		(pts
			(arc
				(start 163.872672 -381.638556)
				(mid 163.623244 -381.638556)
				(end 163.872672 -381.638556)
			)
		)
		(stroke
			(width 0)
			(type solid)
		)
		(fill yes)
		(layer "B.Cu")
		(net "GND")
	)
	(gr_poly
		(pts
			(arc
				(start 163.872672 -380.141988)
				(mid 163.623244 -380.141988)
				(end 163.872672 -380.141988)
			)
		)
		(stroke
			(width 0)
			(type solid)
		)
		(fill yes)
		(layer "B.Cu")
		(net "GND")
	)
	(gr_poly
		(pts
			(arc
				(start 163.872672 -378.940314)
				(mid 163.623244 -378.940314)
				(end 163.872672 -378.940314)
			)
		)
		(stroke
			(width 0)
			(type solid)
		)
		(fill yes)
		(layer "B.Cu")
		(net "GND")
	)
	(gr_poly
		(pts
			(arc
				(start 163.872672 -377.73864)
				(mid 163.623244 -377.73864)
				(end 163.872672 -377.73864)
			)
		)
		(stroke
			(width 0)
			(type solid)
		)
		(fill yes)
		(layer "B.Cu")
		(net "GND")
	)
	(gr_poly
		(pts
			(arc
				(start 163.872672 -376.241818)
				(mid 163.623244 -376.241818)
				(end 163.872672 -376.241818)
			)
		)
		(stroke
			(width 0)
			(type solid)
		)
		(fill yes)
		(layer "B.Cu")
		(net "GND")
	)
	(gr_poly
		(pts
			(arc
				(start 163.872672 -375.040144)
				(mid 163.623244 -375.040144)
				(end 163.872672 -375.040144)
			)
		)
		(stroke
			(width 0)
			(type solid)
		)
		(fill yes)
		(layer "B.Cu")
		(net "GND")
	)
	(gr_poly
		(pts
			(arc
				(start 163.872672 -373.83847)
				(mid 163.623244 -373.83847)
				(end 163.872672 -373.83847)
			)
		)
		(stroke
			(width 0)
			(type solid)
		)
		(fill yes)
		(layer "B.Cu")
		(net "GND")
	)
	(gr_poly
		(pts
			(arc
				(start 163.872672 -372.341902)
				(mid 163.623244 -372.341902)
				(end 163.872672 -372.341902)
			)
		)
		(stroke
			(width 0)
			(type solid)
		)
		(fill yes)
		(layer "B.Cu")
		(net "GND")
	)
	(gr_poly
		(pts
			(arc
				(start 163.872672 -371.140228)
				(mid 163.623244 -371.140228)
				(end 163.872672 -371.140228)
			)
		)
		(stroke
			(width 0)
			(type solid)
		)
		(fill yes)
		(layer "B.Cu")
		(net "GND")
	)
	(gr_poly
		(pts
			(arc
				(start 163.872672 -369.938554)
				(mid 163.623244 -369.938554)
				(end 163.872672 -369.938554)
			)
		)
		(stroke
			(width 0)
			(type solid)
		)
		(fill yes)
		(layer "B.Cu")
		(net "GND")
	)
	(gr_poly
		(pts
			(arc
				(start 164.850826 -357.75773)
				(mid 164.601398 -357.75773)
				(end 164.850826 -357.75773)
			)
		)
		(stroke
			(width 0)
			(type solid)
		)
		(fill yes)
		(layer "B.Cu")
		(net "GND")
	)
	(gr_poly
		(pts
			(arc
				(start 164.850826 -354.732082)
				(mid 164.601398 -354.732082)
				(end 164.850826 -354.732082)
			)
		)
		(stroke
			(width 0)
			(type solid)
		)
		(fill yes)
		(layer "B.Cu")
		(net "GND")
	)
	(gr_poly
		(pts
			(arc
				(start 164.850826 -351.611438)
				(mid 164.601398 -351.611438)
				(end 164.850826 -351.611438)
			)
		)
		(stroke
			(width 0)
			(type solid)
		)
		(fill yes)
		(layer "B.Cu")
		(net "GND")
	)
	(gr_poly
		(pts
			(arc
				(start 164.850826 -348.58579)
				(mid 164.601398 -348.58579)
				(end 164.850826 -348.58579)
			)
		)
		(stroke
			(width 0)
			(type solid)
		)
		(fill yes)
		(layer "B.Cu")
		(net "GND")
	)
	(gr_poly
		(pts
			(arc
				(start 164.850826 -345.465146)
				(mid 164.601398 -345.465146)
				(end 164.850826 -345.465146)
			)
		)
		(stroke
			(width 0)
			(type solid)
		)
		(fill yes)
		(layer "B.Cu")
		(net "GND")
	)
	(gr_poly
		(pts
			(arc
				(start 164.850826 -342.439498)
				(mid 164.601398 -342.439498)
				(end 164.850826 -342.439498)
			)
		)
		(stroke
			(width 0)
			(type solid)
		)
		(fill yes)
		(layer "B.Cu")
		(net "GND")
	)
	(gr_poly
		(pts
			(arc
				(start 166.072566 -411.141926)
				(mid 165.823138 -411.141926)
				(end 166.072566 -411.141926)
			)
		)
		(stroke
			(width 0)
			(type solid)
		)
		(fill yes)
		(layer "B.Cu")
		(net "GND")
	)
	(gr_poly
		(pts
			(arc
				(start 166.072566 -409.940252)
				(mid 165.823138 -409.940252)
				(end 166.072566 -409.940252)
			)
		)
		(stroke
			(width 0)
			(type solid)
		)
		(fill yes)
		(layer "B.Cu")
		(net "GND")
	)
	(gr_poly
		(pts
			(arc
				(start 166.072566 -408.738578)
				(mid 165.823138 -408.738578)
				(end 166.072566 -408.738578)
			)
		)
		(stroke
			(width 0)
			(type solid)
		)
		(fill yes)
		(layer "B.Cu")
		(net "GND")
	)
	(gr_poly
		(pts
			(arc
				(start 166.072566 -407.24201)
				(mid 165.823138 -407.24201)
				(end 166.072566 -407.24201)
			)
		)
		(stroke
			(width 0)
			(type solid)
		)
		(fill yes)
		(layer "B.Cu")
		(net "GND")
	)
	(gr_poly
		(pts
			(arc
				(start 166.072566 -406.040336)
				(mid 165.823138 -406.040336)
				(end 166.072566 -406.040336)
			)
		)
		(stroke
			(width 0)
			(type solid)
		)
		(fill yes)
		(layer "B.Cu")
		(net "GND")
	)
	(gr_poly
		(pts
			(arc
				(start 166.072566 -404.838662)
				(mid 165.823138 -404.838662)
				(end 166.072566 -404.838662)
			)
		)
		(stroke
			(width 0)
			(type solid)
		)
		(fill yes)
		(layer "B.Cu")
		(net "GND")
	)
	(gr_poly
		(pts
			(arc
				(start 166.072566 -403.34184)
				(mid 165.823138 -403.34184)
				(end 166.072566 -403.34184)
			)
		)
		(stroke
			(width 0)
			(type solid)
		)
		(fill yes)
		(layer "B.Cu")
		(net "GND")
	)
	(gr_poly
		(pts
			(arc
				(start 166.072566 -402.140166)
				(mid 165.823138 -402.140166)
				(end 166.072566 -402.140166)
			)
		)
		(stroke
			(width 0)
			(type solid)
		)
		(fill yes)
		(layer "B.Cu")
		(net "GND")
	)
	(gr_poly
		(pts
			(arc
				(start 166.072566 -400.938492)
				(mid 165.823138 -400.938492)
				(end 166.072566 -400.938492)
			)
		)
		(stroke
			(width 0)
			(type solid)
		)
		(fill yes)
		(layer "B.Cu")
		(net "GND")
	)
	(gr_poly
		(pts
			(arc
				(start 166.072566 -399.441924)
				(mid 165.823138 -399.441924)
				(end 166.072566 -399.441924)
			)
		)
		(stroke
			(width 0)
			(type solid)
		)
		(fill yes)
		(layer "B.Cu")
		(net "GND")
	)
	(gr_poly
		(pts
			(arc
				(start 166.072566 -398.24025)
				(mid 165.823138 -398.24025)
				(end 166.072566 -398.24025)
			)
		)
		(stroke
			(width 0)
			(type solid)
		)
		(fill yes)
		(layer "B.Cu")
		(net "GND")
	)
	(gr_poly
		(pts
			(arc
				(start 166.072566 -397.038576)
				(mid 165.823138 -397.038576)
				(end 166.072566 -397.038576)
			)
		)
		(stroke
			(width 0)
			(type solid)
		)
		(fill yes)
		(layer "B.Cu")
		(net "GND")
	)
	(gr_poly
		(pts
			(arc
				(start 166.072566 -385.141978)
				(mid 165.823138 -385.141978)
				(end 166.072566 -385.141978)
			)
		)
		(stroke
			(width 0)
			(type solid)
		)
		(fill yes)
		(layer "B.Cu")
		(net "GND")
	)
	(gr_poly
		(pts
			(arc
				(start 166.072566 -383.940304)
				(mid 165.823138 -383.940304)
				(end 166.072566 -383.940304)
			)
		)
		(stroke
			(width 0)
			(type solid)
		)
		(fill yes)
		(layer "B.Cu")
		(net "GND")
	)
	(gr_poly
		(pts
			(arc
				(start 166.072566 -382.73863)
				(mid 165.823138 -382.73863)
				(end 166.072566 -382.73863)
			)
		)
		(stroke
			(width 0)
			(type solid)
		)
		(fill yes)
		(layer "B.Cu")
		(net "GND")
	)
	(gr_poly
		(pts
			(arc
				(start 166.072566 -381.242062)
				(mid 165.823138 -381.242062)
				(end 166.072566 -381.242062)
			)
		)
		(stroke
			(width 0)
			(type solid)
		)
		(fill yes)
		(layer "B.Cu")
		(net "GND")
	)
	(gr_poly
		(pts
			(arc
				(start 166.072566 -380.040388)
				(mid 165.823138 -380.040388)
				(end 166.072566 -380.040388)
			)
		)
		(stroke
			(width 0)
			(type solid)
		)
		(fill yes)
		(layer "B.Cu")
		(net "GND")
	)
	(gr_poly
		(pts
			(arc
				(start 166.072566 -378.838714)
				(mid 165.823138 -378.838714)
				(end 166.072566 -378.838714)
			)
		)
		(stroke
			(width 0)
			(type solid)
		)
		(fill yes)
		(layer "B.Cu")
		(net "GND")
	)
	(gr_poly
		(pts
			(arc
				(start 166.072566 -377.341892)
				(mid 165.823138 -377.341892)
				(end 166.072566 -377.341892)
			)
		)
		(stroke
			(width 0)
			(type solid)
		)
		(fill yes)
		(layer "B.Cu")
		(net "GND")
	)
	(gr_poly
		(pts
			(arc
				(start 166.072566 -376.140218)
				(mid 165.823138 -376.140218)
				(end 166.072566 -376.140218)
			)
		)
		(stroke
			(width 0)
			(type solid)
		)
		(fill yes)
		(layer "B.Cu")
		(net "GND")
	)
	(gr_poly
		(pts
			(arc
				(start 166.072566 -374.938544)
				(mid 165.823138 -374.938544)
				(end 166.072566 -374.938544)
			)
		)
		(stroke
			(width 0)
			(type solid)
		)
		(fill yes)
		(layer "B.Cu")
		(net "GND")
	)
	(gr_poly
		(pts
			(arc
				(start 166.072566 -373.441976)
				(mid 165.823138 -373.441976)
				(end 166.072566 -373.441976)
			)
		)
		(stroke
			(width 0)
			(type solid)
		)
		(fill yes)
		(layer "B.Cu")
		(net "GND")
	)
	(gr_poly
		(pts
			(arc
				(start 166.072566 -372.240302)
				(mid 165.823138 -372.240302)
				(end 166.072566 -372.240302)
			)
		)
		(stroke
			(width 0)
			(type solid)
		)
		(fill yes)
		(layer "B.Cu")
		(net "GND")
	)
	(gr_poly
		(pts
			(arc
				(start 166.072566 -371.038628)
				(mid 165.823138 -371.038628)
				(end 166.072566 -371.038628)
			)
		)
		(stroke
			(width 0)
			(type solid)
		)
		(fill yes)
		(layer "B.Cu")
		(net "GND")
	)
	(gr_poly
		(pts
			(arc
				(start 166.852346 -357.75773)
				(mid 166.602918 -357.75773)
				(end 166.852346 -357.75773)
			)
		)
		(stroke
			(width 0)
			(type solid)
		)
		(fill yes)
		(layer "B.Cu")
		(net "GND")
	)
	(gr_poly
		(pts
			(arc
				(start 166.852346 -354.732082)
				(mid 166.602918 -354.732082)
				(end 166.852346 -354.732082)
			)
		)
		(stroke
			(width 0)
			(type solid)
		)
		(fill yes)
		(layer "B.Cu")
		(net "GND")
	)
	(gr_poly
		(pts
			(arc
				(start 166.852346 -351.611438)
				(mid 166.602918 -351.611438)
				(end 166.852346 -351.611438)
			)
		)
		(stroke
			(width 0)
			(type solid)
		)
		(fill yes)
		(layer "B.Cu")
		(net "GND")
	)
	(gr_poly
		(pts
			(arc
				(start 166.852346 -348.58579)
				(mid 166.602918 -348.58579)
				(end 166.852346 -348.58579)
			)
		)
		(stroke
			(width 0)
			(type solid)
		)
		(fill yes)
		(layer "B.Cu")
		(net "GND")
	)
	(gr_poly
		(pts
			(arc
				(start 166.852346 -345.465146)
				(mid 166.602918 -345.465146)
				(end 166.852346 -345.465146)
			)
		)
		(stroke
			(width 0)
			(type solid)
		)
		(fill yes)
		(layer "B.Cu")
		(net "GND")
	)
	(gr_poly
		(pts
			(arc
				(start 166.852346 -342.439498)
				(mid 166.602918 -342.439498)
				(end 166.852346 -342.439498)
			)
		)
		(stroke
			(width 0)
			(type solid)
		)
		(fill yes)
		(layer "B.Cu")
		(net "GND")
	)
	(gr_poly
		(pts
			(arc
				(start 167.959786 -357.75773)
				(mid 167.710358 -357.75773)
				(end 167.959786 -357.75773)
			)
		)
		(stroke
			(width 0)
			(type solid)
		)
		(fill yes)
		(layer "B.Cu")
		(net "GND")
	)
	(gr_poly
		(pts
			(arc
				(start 167.959786 -354.732082)
				(mid 167.710358 -354.732082)
				(end 167.959786 -354.732082)
			)
		)
		(stroke
			(width 0)
			(type solid)
		)
		(fill yes)
		(layer "B.Cu")
		(net "GND")
	)
	(gr_poly
		(pts
			(arc
				(start 167.959786 -351.611438)
				(mid 167.710358 -351.611438)
				(end 167.959786 -351.611438)
			)
		)
		(stroke
			(width 0)
			(type solid)
		)
		(fill yes)
		(layer "B.Cu")
		(net "GND")
	)
	(gr_poly
		(pts
			(arc
				(start 167.959786 -348.58579)
				(mid 167.710358 -348.58579)
				(end 167.959786 -348.58579)
			)
		)
		(stroke
			(width 0)
			(type solid)
		)
		(fill yes)
		(layer "B.Cu")
		(net "GND")
	)
	(gr_poly
		(pts
			(arc
				(start 167.959786 -345.465146)
				(mid 167.710358 -345.465146)
				(end 167.959786 -345.465146)
			)
		)
		(stroke
			(width 0)
			(type solid)
		)
		(fill yes)
		(layer "B.Cu")
		(net "GND")
	)
	(gr_poly
		(pts
			(arc
				(start 167.959786 -342.439498)
				(mid 167.710358 -342.439498)
				(end 167.959786 -342.439498)
			)
		)
		(stroke
			(width 0)
			(type solid)
		)
		(fill yes)
		(layer "B.Cu")
		(net "GND")
	)
	(gr_poly
		(pts
			(arc
				(start 168.272714 -410.041852)
				(mid 168.023286 -410.041852)
				(end 168.272714 -410.041852)
			)
		)
		(stroke
			(width 0)
			(type solid)
		)
		(fill yes)
		(layer "B.Cu")
		(net "GND")
	)
	(gr_poly
		(pts
			(arc
				(start 168.272714 -408.840178)
				(mid 168.023286 -408.840178)
				(end 168.272714 -408.840178)
			)
		)
		(stroke
			(width 0)
			(type solid)
		)
		(fill yes)
		(layer "B.Cu")
		(net "GND")
	)
	(gr_poly
		(pts
			(arc
				(start 168.272714 -407.638504)
				(mid 168.023286 -407.638504)
				(end 168.272714 -407.638504)
			)
		)
		(stroke
			(width 0)
			(type solid)
		)
		(fill yes)
		(layer "B.Cu")
		(net "GND")
	)
	(gr_poly
		(pts
			(arc
				(start 168.272714 -406.141936)
				(mid 168.023286 -406.141936)
				(end 168.272714 -406.141936)
			)
		)
		(stroke
			(width 0)
			(type solid)
		)
		(fill yes)
		(layer "B.Cu")
		(net "GND")
	)
	(gr_poly
		(pts
			(arc
				(start 168.272714 -404.940262)
				(mid 168.023286 -404.940262)
				(end 168.272714 -404.940262)
			)
		)
		(stroke
			(width 0)
			(type solid)
		)
		(fill yes)
		(layer "B.Cu")
		(net "GND")
	)
	(gr_poly
		(pts
			(arc
				(start 168.272714 -403.738588)
				(mid 168.023286 -403.738588)
				(end 168.272714 -403.738588)
			)
		)
		(stroke
			(width 0)
			(type solid)
		)
		(fill yes)
		(layer "B.Cu")
		(net "GND")
	)
	(gr_poly
		(pts
			(arc
				(start 168.272714 -402.241766)
				(mid 168.023286 -402.241766)
				(end 168.272714 -402.241766)
			)
		)
		(stroke
			(width 0)
			(type solid)
		)
		(fill yes)
		(layer "B.Cu")
		(net "GND")
	)
	(gr_poly
		(pts
			(arc
				(start 168.272714 -401.040092)
				(mid 168.023286 -401.040092)
				(end 168.272714 -401.040092)
			)
		)
		(stroke
			(width 0)
			(type solid)
		)
		(fill yes)
		(layer "B.Cu")
		(net "GND")
	)
	(gr_poly
		(pts
			(arc
				(start 168.272714 -399.838418)
				(mid 168.023286 -399.838418)
				(end 168.272714 -399.838418)
			)
		)
		(stroke
			(width 0)
			(type solid)
		)
		(fill yes)
		(layer "B.Cu")
		(net "GND")
	)
	(gr_poly
		(pts
			(arc
				(start 168.272714 -398.34185)
				(mid 168.023286 -398.34185)
				(end 168.272714 -398.34185)
			)
		)
		(stroke
			(width 0)
			(type solid)
		)
		(fill yes)
		(layer "B.Cu")
		(net "GND")
	)
	(gr_poly
		(pts
			(arc
				(start 168.272714 -397.140176)
				(mid 168.023286 -397.140176)
				(end 168.272714 -397.140176)
			)
		)
		(stroke
			(width 0)
			(type solid)
		)
		(fill yes)
		(layer "B.Cu")
		(net "GND")
	)
	(gr_poly
		(pts
			(arc
				(start 168.272714 -395.938502)
				(mid 168.023286 -395.938502)
				(end 168.272714 -395.938502)
			)
		)
		(stroke
			(width 0)
			(type solid)
		)
		(fill yes)
		(layer "B.Cu")
		(net "GND")
	)
	(gr_poly
		(pts
			(arc
				(start 168.272714 -384.041904)
				(mid 168.023286 -384.041904)
				(end 168.272714 -384.041904)
			)
		)
		(stroke
			(width 0)
			(type solid)
		)
		(fill yes)
		(layer "B.Cu")
		(net "GND")
	)
	(gr_poly
		(pts
			(arc
				(start 168.272714 -382.84023)
				(mid 168.023286 -382.84023)
				(end 168.272714 -382.84023)
			)
		)
		(stroke
			(width 0)
			(type solid)
		)
		(fill yes)
		(layer "B.Cu")
		(net "GND")
	)
	(gr_poly
		(pts
			(arc
				(start 168.272714 -381.638556)
				(mid 168.023286 -381.638556)
				(end 168.272714 -381.638556)
			)
		)
		(stroke
			(width 0)
			(type solid)
		)
		(fill yes)
		(layer "B.Cu")
		(net "GND")
	)
	(gr_poly
		(pts
			(arc
				(start 168.272714 -380.141988)
				(mid 168.023286 -380.141988)
				(end 168.272714 -380.141988)
			)
		)
		(stroke
			(width 0)
			(type solid)
		)
		(fill yes)
		(layer "B.Cu")
		(net "GND")
	)
	(gr_poly
		(pts
			(arc
				(start 168.272714 -378.940314)
				(mid 168.023286 -378.940314)
				(end 168.272714 -378.940314)
			)
		)
		(stroke
			(width 0)
			(type solid)
		)
		(fill yes)
		(layer "B.Cu")
		(net "GND")
	)
	(gr_poly
		(pts
			(arc
				(start 168.272714 -377.73864)
				(mid 168.023286 -377.73864)
				(end 168.272714 -377.73864)
			)
		)
		(stroke
			(width 0)
			(type solid)
		)
		(fill yes)
		(layer "B.Cu")
		(net "GND")
	)
	(gr_poly
		(pts
			(arc
				(start 168.272714 -376.241818)
				(mid 168.023286 -376.241818)
				(end 168.272714 -376.241818)
			)
		)
		(stroke
			(width 0)
			(type solid)
		)
		(fill yes)
		(layer "B.Cu")
		(net "GND")
	)
	(gr_poly
		(pts
			(arc
				(start 168.272714 -375.040144)
				(mid 168.023286 -375.040144)
				(end 168.272714 -375.040144)
			)
		)
		(stroke
			(width 0)
			(type solid)
		)
		(fill yes)
		(layer "B.Cu")
		(net "GND")
	)
	(gr_poly
		(pts
			(arc
				(start 168.272714 -373.83847)
				(mid 168.023286 -373.83847)
				(end 168.272714 -373.83847)
			)
		)
		(stroke
			(width 0)
			(type solid)
		)
		(fill yes)
		(layer "B.Cu")
		(net "GND")
	)
	(gr_poly
		(pts
			(arc
				(start 168.272714 -372.341902)
				(mid 168.023286 -372.341902)
				(end 168.272714 -372.341902)
			)
		)
		(stroke
			(width 0)
			(type solid)
		)
		(fill yes)
		(layer "B.Cu")
		(net "GND")
	)
	(gr_poly
		(pts
			(arc
				(start 168.272714 -371.140228)
				(mid 168.023286 -371.140228)
				(end 168.272714 -371.140228)
			)
		)
		(stroke
			(width 0)
			(type solid)
		)
		(fill yes)
		(layer "B.Cu")
		(net "GND")
	)
	(gr_poly
		(pts
			(arc
				(start 168.272714 -369.938554)
				(mid 168.023286 -369.938554)
				(end 168.272714 -369.938554)
			)
		)
		(stroke
			(width 0)
			(type solid)
		)
		(fill yes)
		(layer "B.Cu")
		(net "GND")
	)
	(gr_poly
		(pts
			(arc
				(start 169.961306 -357.75773)
				(mid 169.711878 -357.75773)
				(end 169.961306 -357.75773)
			)
		)
		(stroke
			(width 0)
			(type solid)
		)
		(fill yes)
		(layer "B.Cu")
		(net "GND")
	)
	(gr_poly
		(pts
			(arc
				(start 169.961306 -354.732082)
				(mid 169.711878 -354.732082)
				(end 169.961306 -354.732082)
			)
		)
		(stroke
			(width 0)
			(type solid)
		)
		(fill yes)
		(layer "B.Cu")
		(net "GND")
	)
	(gr_poly
		(pts
			(arc
				(start 169.961306 -351.611438)
				(mid 169.711878 -351.611438)
				(end 169.961306 -351.611438)
			)
		)
		(stroke
			(width 0)
			(type solid)
		)
		(fill yes)
		(layer "B.Cu")
		(net "GND")
	)
	(gr_poly
		(pts
			(arc
				(start 169.961306 -348.58579)
				(mid 169.711878 -348.58579)
				(end 169.961306 -348.58579)
			)
		)
		(stroke
			(width 0)
			(type solid)
		)
		(fill yes)
		(layer "B.Cu")
		(net "GND")
	)
	(gr_poly
		(pts
			(arc
				(start 169.961306 -345.465146)
				(mid 169.711878 -345.465146)
				(end 169.961306 -345.465146)
			)
		)
		(stroke
			(width 0)
			(type solid)
		)
		(fill yes)
		(layer "B.Cu")
		(net "GND")
	)
	(gr_poly
		(pts
			(arc
				(start 169.961306 -342.439498)
				(mid 169.711878 -342.439498)
				(end 169.961306 -342.439498)
			)
		)
		(stroke
			(width 0)
			(type solid)
		)
		(fill yes)
		(layer "B.Cu")
		(net "GND")
	)
	(gr_poly
		(pts
			(arc
				(start 170.472608 -411.141926)
				(mid 170.22318 -411.141926)
				(end 170.472608 -411.141926)
			)
		)
		(stroke
			(width 0)
			(type solid)
		)
		(fill yes)
		(layer "B.Cu")
		(net "GND")
	)
	(gr_poly
		(pts
			(arc
				(start 170.472608 -409.940252)
				(mid 170.22318 -409.940252)
				(end 170.472608 -409.940252)
			)
		)
		(stroke
			(width 0)
			(type solid)
		)
		(fill yes)
		(layer "B.Cu")
		(net "GND")
	)
	(gr_poly
		(pts
			(arc
				(start 170.472608 -408.738578)
				(mid 170.22318 -408.738578)
				(end 170.472608 -408.738578)
			)
		)
		(stroke
			(width 0)
			(type solid)
		)
		(fill yes)
		(layer "B.Cu")
		(net "GND")
	)
	(gr_poly
		(pts
			(arc
				(start 170.472608 -407.24201)
				(mid 170.22318 -407.24201)
				(end 170.472608 -407.24201)
			)
		)
		(stroke
			(width 0)
			(type solid)
		)
		(fill yes)
		(layer "B.Cu")
		(net "GND")
	)
	(gr_poly
		(pts
			(arc
				(start 170.472608 -406.040336)
				(mid 170.22318 -406.040336)
				(end 170.472608 -406.040336)
			)
		)
		(stroke
			(width 0)
			(type solid)
		)
		(fill yes)
		(layer "B.Cu")
		(net "GND")
	)
	(gr_poly
		(pts
			(arc
				(start 170.472608 -404.838662)
				(mid 170.22318 -404.838662)
				(end 170.472608 -404.838662)
			)
		)
		(stroke
			(width 0)
			(type solid)
		)
		(fill yes)
		(layer "B.Cu")
		(net "GND")
	)
	(gr_poly
		(pts
			(arc
				(start 170.472608 -403.34184)
				(mid 170.22318 -403.34184)
				(end 170.472608 -403.34184)
			)
		)
		(stroke
			(width 0)
			(type solid)
		)
		(fill yes)
		(layer "B.Cu")
		(net "GND")
	)
	(gr_poly
		(pts
			(arc
				(start 170.472608 -402.140166)
				(mid 170.22318 -402.140166)
				(end 170.472608 -402.140166)
			)
		)
		(stroke
			(width 0)
			(type solid)
		)
		(fill yes)
		(layer "B.Cu")
		(net "GND")
	)
	(gr_poly
		(pts
			(arc
				(start 170.472608 -400.938492)
				(mid 170.22318 -400.938492)
				(end 170.472608 -400.938492)
			)
		)
		(stroke
			(width 0)
			(type solid)
		)
		(fill yes)
		(layer "B.Cu")
		(net "GND")
	)
	(gr_poly
		(pts
			(arc
				(start 170.472608 -399.441924)
				(mid 170.22318 -399.441924)
				(end 170.472608 -399.441924)
			)
		)
		(stroke
			(width 0)
			(type solid)
		)
		(fill yes)
		(layer "B.Cu")
		(net "GND")
	)
	(gr_poly
		(pts
			(arc
				(start 170.472608 -398.24025)
				(mid 170.22318 -398.24025)
				(end 170.472608 -398.24025)
			)
		)
		(stroke
			(width 0)
			(type solid)
		)
		(fill yes)
		(layer "B.Cu")
		(net "GND")
	)
	(gr_poly
		(pts
			(arc
				(start 170.472608 -397.038576)
				(mid 170.22318 -397.038576)
				(end 170.472608 -397.038576)
			)
		)
		(stroke
			(width 0)
			(type solid)
		)
		(fill yes)
		(layer "B.Cu")
		(net "GND")
	)
	(gr_poly
		(pts
			(arc
				(start 170.472608 -385.141978)
				(mid 170.22318 -385.141978)
				(end 170.472608 -385.141978)
			)
		)
		(stroke
			(width 0)
			(type solid)
		)
		(fill yes)
		(layer "B.Cu")
		(net "GND")
	)
	(gr_poly
		(pts
			(arc
				(start 170.472608 -383.940304)
				(mid 170.22318 -383.940304)
				(end 170.472608 -383.940304)
			)
		)
		(stroke
			(width 0)
			(type solid)
		)
		(fill yes)
		(layer "B.Cu")
		(net "GND")
	)
	(gr_poly
		(pts
			(arc
				(start 170.472608 -382.73863)
				(mid 170.22318 -382.73863)
				(end 170.472608 -382.73863)
			)
		)
		(stroke
			(width 0)
			(type solid)
		)
		(fill yes)
		(layer "B.Cu")
		(net "GND")
	)
	(gr_poly
		(pts
			(arc
				(start 170.472608 -381.242062)
				(mid 170.22318 -381.242062)
				(end 170.472608 -381.242062)
			)
		)
		(stroke
			(width 0)
			(type solid)
		)
		(fill yes)
		(layer "B.Cu")
		(net "GND")
	)
	(gr_poly
		(pts
			(arc
				(start 170.472608 -380.040388)
				(mid 170.22318 -380.040388)
				(end 170.472608 -380.040388)
			)
		)
		(stroke
			(width 0)
			(type solid)
		)
		(fill yes)
		(layer "B.Cu")
		(net "GND")
	)
	(gr_poly
		(pts
			(arc
				(start 170.472608 -378.838714)
				(mid 170.22318 -378.838714)
				(end 170.472608 -378.838714)
			)
		)
		(stroke
			(width 0)
			(type solid)
		)
		(fill yes)
		(layer "B.Cu")
		(net "GND")
	)
	(gr_poly
		(pts
			(arc
				(start 170.472608 -377.341892)
				(mid 170.22318 -377.341892)
				(end 170.472608 -377.341892)
			)
		)
		(stroke
			(width 0)
			(type solid)
		)
		(fill yes)
		(layer "B.Cu")
		(net "GND")
	)
	(gr_poly
		(pts
			(arc
				(start 170.472608 -376.140218)
				(mid 170.22318 -376.140218)
				(end 170.472608 -376.140218)
			)
		)
		(stroke
			(width 0)
			(type solid)
		)
		(fill yes)
		(layer "B.Cu")
		(net "GND")
	)
	(gr_poly
		(pts
			(arc
				(start 170.472608 -374.938544)
				(mid 170.22318 -374.938544)
				(end 170.472608 -374.938544)
			)
		)
		(stroke
			(width 0)
			(type solid)
		)
		(fill yes)
		(layer "B.Cu")
		(net "GND")
	)
	(gr_poly
		(pts
			(arc
				(start 170.472608 -373.441976)
				(mid 170.22318 -373.441976)
				(end 170.472608 -373.441976)
			)
		)
		(stroke
			(width 0)
			(type solid)
		)
		(fill yes)
		(layer "B.Cu")
		(net "GND")
	)
	(gr_poly
		(pts
			(arc
				(start 170.472608 -372.240302)
				(mid 170.22318 -372.240302)
				(end 170.472608 -372.240302)
			)
		)
		(stroke
			(width 0)
			(type solid)
		)
		(fill yes)
		(layer "B.Cu")
		(net "GND")
	)
	(gr_poly
		(pts
			(arc
				(start 170.472608 -371.038628)
				(mid 170.22318 -371.038628)
				(end 170.472608 -371.038628)
			)
		)
		(stroke
			(width 0)
			(type solid)
		)
		(fill yes)
		(layer "B.Cu")
		(net "GND")
	)
	(gr_poly
		(pts
			(arc
				(start 171.068746 -357.75773)
				(mid 170.819318 -357.75773)
				(end 171.068746 -357.75773)
			)
		)
		(stroke
			(width 0)
			(type solid)
		)
		(fill yes)
		(layer "B.Cu")
		(net "GND")
	)
	(gr_poly
		(pts
			(arc
				(start 171.068746 -354.732082)
				(mid 170.819318 -354.732082)
				(end 171.068746 -354.732082)
			)
		)
		(stroke
			(width 0)
			(type solid)
		)
		(fill yes)
		(layer "B.Cu")
		(net "GND")
	)
	(gr_poly
		(pts
			(arc
				(start 171.068746 -351.611438)
				(mid 170.819318 -351.611438)
				(end 171.068746 -351.611438)
			)
		)
		(stroke
			(width 0)
			(type solid)
		)
		(fill yes)
		(layer "B.Cu")
		(net "GND")
	)
	(gr_poly
		(pts
			(arc
				(start 171.068746 -348.58579)
				(mid 170.819318 -348.58579)
				(end 171.068746 -348.58579)
			)
		)
		(stroke
			(width 0)
			(type solid)
		)
		(fill yes)
		(layer "B.Cu")
		(net "GND")
	)
	(gr_poly
		(pts
			(arc
				(start 171.068746 -345.465146)
				(mid 170.819318 -345.465146)
				(end 171.068746 -345.465146)
			)
		)
		(stroke
			(width 0)
			(type solid)
		)
		(fill yes)
		(layer "B.Cu")
		(net "GND")
	)
	(gr_poly
		(pts
			(arc
				(start 171.068746 -342.439498)
				(mid 170.819318 -342.439498)
				(end 171.068746 -342.439498)
			)
		)
		(stroke
			(width 0)
			(type solid)
		)
		(fill yes)
		(layer "B.Cu")
		(net "GND")
	)
	(gr_poly
		(pts
			(arc
				(start 172.672502 -410.041852)
				(mid 172.423074 -410.041852)
				(end 172.672502 -410.041852)
			)
		)
		(stroke
			(width 0)
			(type solid)
		)
		(fill yes)
		(layer "B.Cu")
		(net "GND")
	)
	(gr_poly
		(pts
			(arc
				(start 172.672502 -408.840178)
				(mid 172.423074 -408.840178)
				(end 172.672502 -408.840178)
			)
		)
		(stroke
			(width 0)
			(type solid)
		)
		(fill yes)
		(layer "B.Cu")
		(net "GND")
	)
	(gr_poly
		(pts
			(arc
				(start 172.672502 -407.638504)
				(mid 172.423074 -407.638504)
				(end 172.672502 -407.638504)
			)
		)
		(stroke
			(width 0)
			(type solid)
		)
		(fill yes)
		(layer "B.Cu")
		(net "GND")
	)
	(gr_poly
		(pts
			(arc
				(start 172.672502 -406.141936)
				(mid 172.423074 -406.141936)
				(end 172.672502 -406.141936)
			)
		)
		(stroke
			(width 0)
			(type solid)
		)
		(fill yes)
		(layer "B.Cu")
		(net "GND")
	)
	(gr_poly
		(pts
			(arc
				(start 172.672502 -404.940262)
				(mid 172.423074 -404.940262)
				(end 172.672502 -404.940262)
			)
		)
		(stroke
			(width 0)
			(type solid)
		)
		(fill yes)
		(layer "B.Cu")
		(net "GND")
	)
	(gr_poly
		(pts
			(arc
				(start 172.672502 -403.738588)
				(mid 172.423074 -403.738588)
				(end 172.672502 -403.738588)
			)
		)
		(stroke
			(width 0)
			(type solid)
		)
		(fill yes)
		(layer "B.Cu")
		(net "GND")
	)
	(gr_poly
		(pts
			(arc
				(start 172.672502 -402.241766)
				(mid 172.423074 -402.241766)
				(end 172.672502 -402.241766)
			)
		)
		(stroke
			(width 0)
			(type solid)
		)
		(fill yes)
		(layer "B.Cu")
		(net "GND")
	)
	(gr_poly
		(pts
			(arc
				(start 172.672502 -401.040092)
				(mid 172.423074 -401.040092)
				(end 172.672502 -401.040092)
			)
		)
		(stroke
			(width 0)
			(type solid)
		)
		(fill yes)
		(layer "B.Cu")
		(net "GND")
	)
	(gr_poly
		(pts
			(arc
				(start 172.672502 -399.838418)
				(mid 172.423074 -399.838418)
				(end 172.672502 -399.838418)
			)
		)
		(stroke
			(width 0)
			(type solid)
		)
		(fill yes)
		(layer "B.Cu")
		(net "GND")
	)
	(gr_poly
		(pts
			(arc
				(start 172.672502 -398.34185)
				(mid 172.423074 -398.34185)
				(end 172.672502 -398.34185)
			)
		)
		(stroke
			(width 0)
			(type solid)
		)
		(fill yes)
		(layer "B.Cu")
		(net "GND")
	)
	(gr_poly
		(pts
			(arc
				(start 172.672502 -397.140176)
				(mid 172.423074 -397.140176)
				(end 172.672502 -397.140176)
			)
		)
		(stroke
			(width 0)
			(type solid)
		)
		(fill yes)
		(layer "B.Cu")
		(net "GND")
	)
	(gr_poly
		(pts
			(arc
				(start 172.672502 -395.938502)
				(mid 172.423074 -395.938502)
				(end 172.672502 -395.938502)
			)
		)
		(stroke
			(width 0)
			(type solid)
		)
		(fill yes)
		(layer "B.Cu")
		(net "GND")
	)
	(gr_poly
		(pts
			(arc
				(start 172.672502 -384.041904)
				(mid 172.423074 -384.041904)
				(end 172.672502 -384.041904)
			)
		)
		(stroke
			(width 0)
			(type solid)
		)
		(fill yes)
		(layer "B.Cu")
		(net "GND")
	)
	(gr_poly
		(pts
			(arc
				(start 172.672502 -382.84023)
				(mid 172.423074 -382.84023)
				(end 172.672502 -382.84023)
			)
		)
		(stroke
			(width 0)
			(type solid)
		)
		(fill yes)
		(layer "B.Cu")
		(net "GND")
	)
	(gr_poly
		(pts
			(arc
				(start 172.672502 -381.638556)
				(mid 172.423074 -381.638556)
				(end 172.672502 -381.638556)
			)
		)
		(stroke
			(width 0)
			(type solid)
		)
		(fill yes)
		(layer "B.Cu")
		(net "GND")
	)
	(gr_poly
		(pts
			(arc
				(start 172.672502 -380.141988)
				(mid 172.423074 -380.141988)
				(end 172.672502 -380.141988)
			)
		)
		(stroke
			(width 0)
			(type solid)
		)
		(fill yes)
		(layer "B.Cu")
		(net "GND")
	)
	(gr_poly
		(pts
			(arc
				(start 172.672502 -378.940314)
				(mid 172.423074 -378.940314)
				(end 172.672502 -378.940314)
			)
		)
		(stroke
			(width 0)
			(type solid)
		)
		(fill yes)
		(layer "B.Cu")
		(net "GND")
	)
	(gr_poly
		(pts
			(arc
				(start 172.672502 -377.73864)
				(mid 172.423074 -377.73864)
				(end 172.672502 -377.73864)
			)
		)
		(stroke
			(width 0)
			(type solid)
		)
		(fill yes)
		(layer "B.Cu")
		(net "GND")
	)
	(gr_poly
		(pts
			(arc
				(start 172.672502 -376.241818)
				(mid 172.423074 -376.241818)
				(end 172.672502 -376.241818)
			)
		)
		(stroke
			(width 0)
			(type solid)
		)
		(fill yes)
		(layer "B.Cu")
		(net "GND")
	)
	(gr_poly
		(pts
			(arc
				(start 172.672502 -375.040144)
				(mid 172.423074 -375.040144)
				(end 172.672502 -375.040144)
			)
		)
		(stroke
			(width 0)
			(type solid)
		)
		(fill yes)
		(layer "B.Cu")
		(net "GND")
	)
	(gr_poly
		(pts
			(arc
				(start 172.672502 -373.83847)
				(mid 172.423074 -373.83847)
				(end 172.672502 -373.83847)
			)
		)
		(stroke
			(width 0)
			(type solid)
		)
		(fill yes)
		(layer "B.Cu")
		(net "GND")
	)
	(gr_poly
		(pts
			(arc
				(start 172.672502 -372.341902)
				(mid 172.423074 -372.341902)
				(end 172.672502 -372.341902)
			)
		)
		(stroke
			(width 0)
			(type solid)
		)
		(fill yes)
		(layer "B.Cu")
		(net "GND")
	)
	(gr_poly
		(pts
			(arc
				(start 172.672502 -371.140228)
				(mid 172.423074 -371.140228)
				(end 172.672502 -371.140228)
			)
		)
		(stroke
			(width 0)
			(type solid)
		)
		(fill yes)
		(layer "B.Cu")
		(net "GND")
	)
	(gr_poly
		(pts
			(arc
				(start 172.672502 -369.938554)
				(mid 172.423074 -369.938554)
				(end 172.672502 -369.938554)
			)
		)
		(stroke
			(width 0)
			(type solid)
		)
		(fill yes)
		(layer "B.Cu")
		(net "GND")
	)
	(gr_poly
		(pts
			(arc
				(start 173.070266 -357.75773)
				(mid 172.820838 -357.75773)
				(end 173.070266 -357.75773)
			)
		)
		(stroke
			(width 0)
			(type solid)
		)
		(fill yes)
		(layer "B.Cu")
		(net "GND")
	)
	(gr_poly
		(pts
			(arc
				(start 173.070266 -354.732082)
				(mid 172.820838 -354.732082)
				(end 173.070266 -354.732082)
			)
		)
		(stroke
			(width 0)
			(type solid)
		)
		(fill yes)
		(layer "B.Cu")
		(net "GND")
	)
	(gr_poly
		(pts
			(arc
				(start 173.070266 -351.611438)
				(mid 172.820838 -351.611438)
				(end 173.070266 -351.611438)
			)
		)
		(stroke
			(width 0)
			(type solid)
		)
		(fill yes)
		(layer "B.Cu")
		(net "GND")
	)
	(gr_poly
		(pts
			(arc
				(start 173.070266 -348.58579)
				(mid 172.820838 -348.58579)
				(end 173.070266 -348.58579)
			)
		)
		(stroke
			(width 0)
			(type solid)
		)
		(fill yes)
		(layer "B.Cu")
		(net "GND")
	)
	(gr_poly
		(pts
			(arc
				(start 173.070266 -345.465146)
				(mid 172.820838 -345.465146)
				(end 173.070266 -345.465146)
			)
		)
		(stroke
			(width 0)
			(type solid)
		)
		(fill yes)
		(layer "B.Cu")
		(net "GND")
	)
	(gr_poly
		(pts
			(arc
				(start 173.070266 -342.439498)
				(mid 172.820838 -342.439498)
				(end 173.070266 -342.439498)
			)
		)
		(stroke
			(width 0)
			(type solid)
		)
		(fill yes)
		(layer "B.Cu")
		(net "GND")
	)
	(gr_poly
		(pts
			(arc
				(start 174.177706 -357.75773)
				(mid 173.928278 -357.75773)
				(end 174.177706 -357.75773)
			)
		)
		(stroke
			(width 0)
			(type solid)
		)
		(fill yes)
		(layer "B.Cu")
		(net "GND")
	)
	(gr_poly
		(pts
			(arc
				(start 174.177706 -354.732082)
				(mid 173.928278 -354.732082)
				(end 174.177706 -354.732082)
			)
		)
		(stroke
			(width 0)
			(type solid)
		)
		(fill yes)
		(layer "B.Cu")
		(net "GND")
	)
	(gr_poly
		(pts
			(arc
				(start 174.177706 -351.611438)
				(mid 173.928278 -351.611438)
				(end 174.177706 -351.611438)
			)
		)
		(stroke
			(width 0)
			(type solid)
		)
		(fill yes)
		(layer "B.Cu")
		(net "GND")
	)
	(gr_poly
		(pts
			(arc
				(start 174.177706 -348.58579)
				(mid 173.928278 -348.58579)
				(end 174.177706 -348.58579)
			)
		)
		(stroke
			(width 0)
			(type solid)
		)
		(fill yes)
		(layer "B.Cu")
		(net "GND")
	)
	(gr_poly
		(pts
			(arc
				(start 174.177706 -345.465146)
				(mid 173.928278 -345.465146)
				(end 174.177706 -345.465146)
			)
		)
		(stroke
			(width 0)
			(type solid)
		)
		(fill yes)
		(layer "B.Cu")
		(net "GND")
	)
	(gr_poly
		(pts
			(arc
				(start 174.177706 -342.439498)
				(mid 173.928278 -342.439498)
				(end 174.177706 -342.439498)
			)
		)
		(stroke
			(width 0)
			(type solid)
		)
		(fill yes)
		(layer "B.Cu")
		(net "GND")
	)
	(gr_poly
		(pts
			(arc
				(start 174.87265 -411.141926)
				(mid 174.623222 -411.141926)
				(end 174.87265 -411.141926)
			)
		)
		(stroke
			(width 0)
			(type solid)
		)
		(fill yes)
		(layer "B.Cu")
		(net "GND")
	)
	(gr_poly
		(pts
			(arc
				(start 174.87265 -409.940252)
				(mid 174.623222 -409.940252)
				(end 174.87265 -409.940252)
			)
		)
		(stroke
			(width 0)
			(type solid)
		)
		(fill yes)
		(layer "B.Cu")
		(net "GND")
	)
	(gr_poly
		(pts
			(arc
				(start 174.87265 -408.738578)
				(mid 174.623222 -408.738578)
				(end 174.87265 -408.738578)
			)
		)
		(stroke
			(width 0)
			(type solid)
		)
		(fill yes)
		(layer "B.Cu")
		(net "GND")
	)
	(gr_poly
		(pts
			(arc
				(start 174.87265 -407.24201)
				(mid 174.623222 -407.24201)
				(end 174.87265 -407.24201)
			)
		)
		(stroke
			(width 0)
			(type solid)
		)
		(fill yes)
		(layer "B.Cu")
		(net "GND")
	)
	(gr_poly
		(pts
			(arc
				(start 174.87265 -406.040336)
				(mid 174.623222 -406.040336)
				(end 174.87265 -406.040336)
			)
		)
		(stroke
			(width 0)
			(type solid)
		)
		(fill yes)
		(layer "B.Cu")
		(net "GND")
	)
	(gr_poly
		(pts
			(arc
				(start 174.87265 -404.838662)
				(mid 174.623222 -404.838662)
				(end 174.87265 -404.838662)
			)
		)
		(stroke
			(width 0)
			(type solid)
		)
		(fill yes)
		(layer "B.Cu")
		(net "GND")
	)
	(gr_poly
		(pts
			(arc
				(start 174.87265 -403.34184)
				(mid 174.623222 -403.34184)
				(end 174.87265 -403.34184)
			)
		)
		(stroke
			(width 0)
			(type solid)
		)
		(fill yes)
		(layer "B.Cu")
		(net "GND")
	)
	(gr_poly
		(pts
			(arc
				(start 174.87265 -402.140166)
				(mid 174.623222 -402.140166)
				(end 174.87265 -402.140166)
			)
		)
		(stroke
			(width 0)
			(type solid)
		)
		(fill yes)
		(layer "B.Cu")
		(net "GND")
	)
	(gr_poly
		(pts
			(arc
				(start 174.87265 -400.938492)
				(mid 174.623222 -400.938492)
				(end 174.87265 -400.938492)
			)
		)
		(stroke
			(width 0)
			(type solid)
		)
		(fill yes)
		(layer "B.Cu")
		(net "GND")
	)
	(gr_poly
		(pts
			(arc
				(start 174.87265 -399.441924)
				(mid 174.623222 -399.441924)
				(end 174.87265 -399.441924)
			)
		)
		(stroke
			(width 0)
			(type solid)
		)
		(fill yes)
		(layer "B.Cu")
		(net "GND")
	)
	(gr_poly
		(pts
			(arc
				(start 174.87265 -398.24025)
				(mid 174.623222 -398.24025)
				(end 174.87265 -398.24025)
			)
		)
		(stroke
			(width 0)
			(type solid)
		)
		(fill yes)
		(layer "B.Cu")
		(net "GND")
	)
	(gr_poly
		(pts
			(arc
				(start 174.87265 -397.038576)
				(mid 174.623222 -397.038576)
				(end 174.87265 -397.038576)
			)
		)
		(stroke
			(width 0)
			(type solid)
		)
		(fill yes)
		(layer "B.Cu")
		(net "GND")
	)
	(gr_poly
		(pts
			(arc
				(start 174.87265 -385.141978)
				(mid 174.623222 -385.141978)
				(end 174.87265 -385.141978)
			)
		)
		(stroke
			(width 0)
			(type solid)
		)
		(fill yes)
		(layer "B.Cu")
		(net "GND")
	)
	(gr_poly
		(pts
			(arc
				(start 174.87265 -383.940304)
				(mid 174.623222 -383.940304)
				(end 174.87265 -383.940304)
			)
		)
		(stroke
			(width 0)
			(type solid)
		)
		(fill yes)
		(layer "B.Cu")
		(net "GND")
	)
	(gr_poly
		(pts
			(arc
				(start 174.87265 -382.73863)
				(mid 174.623222 -382.73863)
				(end 174.87265 -382.73863)
			)
		)
		(stroke
			(width 0)
			(type solid)
		)
		(fill yes)
		(layer "B.Cu")
		(net "GND")
	)
	(gr_poly
		(pts
			(arc
				(start 174.87265 -381.242062)
				(mid 174.623222 -381.242062)
				(end 174.87265 -381.242062)
			)
		)
		(stroke
			(width 0)
			(type solid)
		)
		(fill yes)
		(layer "B.Cu")
		(net "GND")
	)
	(gr_poly
		(pts
			(arc
				(start 174.87265 -380.040388)
				(mid 174.623222 -380.040388)
				(end 174.87265 -380.040388)
			)
		)
		(stroke
			(width 0)
			(type solid)
		)
		(fill yes)
		(layer "B.Cu")
		(net "GND")
	)
	(gr_poly
		(pts
			(arc
				(start 174.87265 -378.838714)
				(mid 174.623222 -378.838714)
				(end 174.87265 -378.838714)
			)
		)
		(stroke
			(width 0)
			(type solid)
		)
		(fill yes)
		(layer "B.Cu")
		(net "GND")
	)
	(gr_poly
		(pts
			(arc
				(start 174.87265 -377.341892)
				(mid 174.623222 -377.341892)
				(end 174.87265 -377.341892)
			)
		)
		(stroke
			(width 0)
			(type solid)
		)
		(fill yes)
		(layer "B.Cu")
		(net "GND")
	)
	(gr_poly
		(pts
			(arc
				(start 174.87265 -376.140218)
				(mid 174.623222 -376.140218)
				(end 174.87265 -376.140218)
			)
		)
		(stroke
			(width 0)
			(type solid)
		)
		(fill yes)
		(layer "B.Cu")
		(net "GND")
	)
	(gr_poly
		(pts
			(arc
				(start 174.87265 -374.938544)
				(mid 174.623222 -374.938544)
				(end 174.87265 -374.938544)
			)
		)
		(stroke
			(width 0)
			(type solid)
		)
		(fill yes)
		(layer "B.Cu")
		(net "GND")
	)
	(gr_poly
		(pts
			(arc
				(start 174.87265 -373.441976)
				(mid 174.623222 -373.441976)
				(end 174.87265 -373.441976)
			)
		)
		(stroke
			(width 0)
			(type solid)
		)
		(fill yes)
		(layer "B.Cu")
		(net "GND")
	)
	(gr_poly
		(pts
			(arc
				(start 174.87265 -372.240302)
				(mid 174.623222 -372.240302)
				(end 174.87265 -372.240302)
			)
		)
		(stroke
			(width 0)
			(type solid)
		)
		(fill yes)
		(layer "B.Cu")
		(net "GND")
	)
	(gr_poly
		(pts
			(arc
				(start 174.87265 -371.038628)
				(mid 174.623222 -371.038628)
				(end 174.87265 -371.038628)
			)
		)
		(stroke
			(width 0)
			(type solid)
		)
		(fill yes)
		(layer "B.Cu")
		(net "GND")
	)
	(gr_poly
		(pts
			(arc
				(start 176.179226 -357.75773)
				(mid 175.929798 -357.75773)
				(end 176.179226 -357.75773)
			)
		)
		(stroke
			(width 0)
			(type solid)
		)
		(fill yes)
		(layer "B.Cu")
		(net "GND")
	)
	(gr_poly
		(pts
			(arc
				(start 176.179226 -354.732082)
				(mid 175.929798 -354.732082)
				(end 176.179226 -354.732082)
			)
		)
		(stroke
			(width 0)
			(type solid)
		)
		(fill yes)
		(layer "B.Cu")
		(net "GND")
	)
	(gr_poly
		(pts
			(arc
				(start 176.179226 -351.611438)
				(mid 175.929798 -351.611438)
				(end 176.179226 -351.611438)
			)
		)
		(stroke
			(width 0)
			(type solid)
		)
		(fill yes)
		(layer "B.Cu")
		(net "GND")
	)
	(gr_poly
		(pts
			(arc
				(start 176.179226 -348.58579)
				(mid 175.929798 -348.58579)
				(end 176.179226 -348.58579)
			)
		)
		(stroke
			(width 0)
			(type solid)
		)
		(fill yes)
		(layer "B.Cu")
		(net "GND")
	)
	(gr_poly
		(pts
			(arc
				(start 176.179226 -345.465146)
				(mid 175.929798 -345.465146)
				(end 176.179226 -345.465146)
			)
		)
		(stroke
			(width 0)
			(type solid)
		)
		(fill yes)
		(layer "B.Cu")
		(net "GND")
	)
	(gr_poly
		(pts
			(arc
				(start 176.179226 -342.439498)
				(mid 175.929798 -342.439498)
				(end 176.179226 -342.439498)
			)
		)
		(stroke
			(width 0)
			(type solid)
		)
		(fill yes)
		(layer "B.Cu")
		(net "GND")
	)
	(gr_poly
		(pts
			(arc
				(start 177.072544 -410.041852)
				(mid 176.823116 -410.041852)
				(end 177.072544 -410.041852)
			)
		)
		(stroke
			(width 0)
			(type solid)
		)
		(fill yes)
		(layer "B.Cu")
		(net "GND")
	)
	(gr_poly
		(pts
			(arc
				(start 177.072544 -408.840178)
				(mid 176.823116 -408.840178)
				(end 177.072544 -408.840178)
			)
		)
		(stroke
			(width 0)
			(type solid)
		)
		(fill yes)
		(layer "B.Cu")
		(net "GND")
	)
	(gr_poly
		(pts
			(arc
				(start 177.072544 -407.638504)
				(mid 176.823116 -407.638504)
				(end 177.072544 -407.638504)
			)
		)
		(stroke
			(width 0)
			(type solid)
		)
		(fill yes)
		(layer "B.Cu")
		(net "GND")
	)
	(gr_poly
		(pts
			(arc
				(start 177.072544 -406.141936)
				(mid 176.823116 -406.141936)
				(end 177.072544 -406.141936)
			)
		)
		(stroke
			(width 0)
			(type solid)
		)
		(fill yes)
		(layer "B.Cu")
		(net "GND")
	)
	(gr_poly
		(pts
			(arc
				(start 177.072544 -404.940262)
				(mid 176.823116 -404.940262)
				(end 177.072544 -404.940262)
			)
		)
		(stroke
			(width 0)
			(type solid)
		)
		(fill yes)
		(layer "B.Cu")
		(net "GND")
	)
	(gr_poly
		(pts
			(arc
				(start 177.072544 -403.738588)
				(mid 176.823116 -403.738588)
				(end 177.072544 -403.738588)
			)
		)
		(stroke
			(width 0)
			(type solid)
		)
		(fill yes)
		(layer "B.Cu")
		(net "GND")
	)
	(gr_poly
		(pts
			(arc
				(start 177.072544 -402.241766)
				(mid 176.823116 -402.241766)
				(end 177.072544 -402.241766)
			)
		)
		(stroke
			(width 0)
			(type solid)
		)
		(fill yes)
		(layer "B.Cu")
		(net "GND")
	)
	(gr_poly
		(pts
			(arc
				(start 177.072544 -401.040092)
				(mid 176.823116 -401.040092)
				(end 177.072544 -401.040092)
			)
		)
		(stroke
			(width 0)
			(type solid)
		)
		(fill yes)
		(layer "B.Cu")
		(net "GND")
	)
	(gr_poly
		(pts
			(arc
				(start 177.072544 -399.838418)
				(mid 176.823116 -399.838418)
				(end 177.072544 -399.838418)
			)
		)
		(stroke
			(width 0)
			(type solid)
		)
		(fill yes)
		(layer "B.Cu")
		(net "GND")
	)
	(gr_poly
		(pts
			(arc
				(start 177.072544 -398.34185)
				(mid 176.823116 -398.34185)
				(end 177.072544 -398.34185)
			)
		)
		(stroke
			(width 0)
			(type solid)
		)
		(fill yes)
		(layer "B.Cu")
		(net "GND")
	)
	(gr_poly
		(pts
			(arc
				(start 177.072544 -397.140176)
				(mid 176.823116 -397.140176)
				(end 177.072544 -397.140176)
			)
		)
		(stroke
			(width 0)
			(type solid)
		)
		(fill yes)
		(layer "B.Cu")
		(net "GND")
	)
	(gr_poly
		(pts
			(arc
				(start 177.072544 -395.938502)
				(mid 176.823116 -395.938502)
				(end 177.072544 -395.938502)
			)
		)
		(stroke
			(width 0)
			(type solid)
		)
		(fill yes)
		(layer "B.Cu")
		(net "GND")
	)
	(gr_poly
		(pts
			(arc
				(start 177.072544 -384.042158)
				(mid 176.823116 -384.042158)
				(end 177.072544 -384.042158)
			)
		)
		(stroke
			(width 0)
			(type solid)
		)
		(fill yes)
		(layer "B.Cu")
		(net "GND")
	)
	(gr_poly
		(pts
			(arc
				(start 177.072544 -382.840484)
				(mid 176.823116 -382.840484)
				(end 177.072544 -382.840484)
			)
		)
		(stroke
			(width 0)
			(type solid)
		)
		(fill yes)
		(layer "B.Cu")
		(net "GND")
	)
	(gr_poly
		(pts
			(arc
				(start 177.072544 -381.63881)
				(mid 176.823116 -381.63881)
				(end 177.072544 -381.63881)
			)
		)
		(stroke
			(width 0)
			(type solid)
		)
		(fill yes)
		(layer "B.Cu")
		(net "GND")
	)
	(gr_poly
		(pts
			(arc
				(start 177.072544 -380.141988)
				(mid 176.823116 -380.141988)
				(end 177.072544 -380.141988)
			)
		)
		(stroke
			(width 0)
			(type solid)
		)
		(fill yes)
		(layer "B.Cu")
		(net "GND")
	)
	(gr_poly
		(pts
			(arc
				(start 177.072544 -378.940314)
				(mid 176.823116 -378.940314)
				(end 177.072544 -378.940314)
			)
		)
		(stroke
			(width 0)
			(type solid)
		)
		(fill yes)
		(layer "B.Cu")
		(net "GND")
	)
	(gr_poly
		(pts
			(arc
				(start 177.072544 -377.73864)
				(mid 176.823116 -377.73864)
				(end 177.072544 -377.73864)
			)
		)
		(stroke
			(width 0)
			(type solid)
		)
		(fill yes)
		(layer "B.Cu")
		(net "GND")
	)
	(gr_poly
		(pts
			(arc
				(start 177.072544 -376.242072)
				(mid 176.823116 -376.242072)
				(end 177.072544 -376.242072)
			)
		)
		(stroke
			(width 0)
			(type solid)
		)
		(fill yes)
		(layer "B.Cu")
		(net "GND")
	)
	(gr_poly
		(pts
			(arc
				(start 177.072544 -375.040398)
				(mid 176.823116 -375.040398)
				(end 177.072544 -375.040398)
			)
		)
		(stroke
			(width 0)
			(type solid)
		)
		(fill yes)
		(layer "B.Cu")
		(net "GND")
	)
	(gr_poly
		(pts
			(arc
				(start 177.072544 -373.838724)
				(mid 176.823116 -373.838724)
				(end 177.072544 -373.838724)
			)
		)
		(stroke
			(width 0)
			(type solid)
		)
		(fill yes)
		(layer "B.Cu")
		(net "GND")
	)
	(gr_poly
		(pts
			(arc
				(start 177.072544 -372.342156)
				(mid 176.823116 -372.342156)
				(end 177.072544 -372.342156)
			)
		)
		(stroke
			(width 0)
			(type solid)
		)
		(fill yes)
		(layer "B.Cu")
		(net "GND")
	)
	(gr_poly
		(pts
			(arc
				(start 177.072544 -371.140482)
				(mid 176.823116 -371.140482)
				(end 177.072544 -371.140482)
			)
		)
		(stroke
			(width 0)
			(type solid)
		)
		(fill yes)
		(layer "B.Cu")
		(net "GND")
	)
	(gr_poly
		(pts
			(arc
				(start 177.072544 -369.938808)
				(mid 176.823116 -369.938808)
				(end 177.072544 -369.938808)
			)
		)
		(stroke
			(width 0)
			(type solid)
		)
		(fill yes)
		(layer "B.Cu")
		(net "GND")
	)
	(gr_poly
		(pts
			(arc
				(start 177.286666 -357.75773)
				(mid 177.037238 -357.75773)
				(end 177.286666 -357.75773)
			)
		)
		(stroke
			(width 0)
			(type solid)
		)
		(fill yes)
		(layer "B.Cu")
		(net "GND")
	)
	(gr_poly
		(pts
			(arc
				(start 177.286666 -354.732082)
				(mid 177.037238 -354.732082)
				(end 177.286666 -354.732082)
			)
		)
		(stroke
			(width 0)
			(type solid)
		)
		(fill yes)
		(layer "B.Cu")
		(net "GND")
	)
	(gr_poly
		(pts
			(arc
				(start 177.286666 -351.611438)
				(mid 177.037238 -351.611438)
				(end 177.286666 -351.611438)
			)
		)
		(stroke
			(width 0)
			(type solid)
		)
		(fill yes)
		(layer "B.Cu")
		(net "GND")
	)
	(gr_poly
		(pts
			(arc
				(start 177.286666 -348.58579)
				(mid 177.037238 -348.58579)
				(end 177.286666 -348.58579)
			)
		)
		(stroke
			(width 0)
			(type solid)
		)
		(fill yes)
		(layer "B.Cu")
		(net "GND")
	)
	(gr_poly
		(pts
			(arc
				(start 177.286666 -345.465146)
				(mid 177.037238 -345.465146)
				(end 177.286666 -345.465146)
			)
		)
		(stroke
			(width 0)
			(type solid)
		)
		(fill yes)
		(layer "B.Cu")
		(net "GND")
	)
	(gr_poly
		(pts
			(arc
				(start 177.286666 -342.439498)
				(mid 177.037238 -342.439498)
				(end 177.286666 -342.439498)
			)
		)
		(stroke
			(width 0)
			(type solid)
		)
		(fill yes)
		(layer "B.Cu")
		(net "GND")
	)
	(gr_poly
		(pts
			(arc
				(start 179.288186 -357.75773)
				(mid 179.038758 -357.75773)
				(end 179.288186 -357.75773)
			)
		)
		(stroke
			(width 0)
			(type solid)
		)
		(fill yes)
		(layer "B.Cu")
		(net "GND")
	)
	(gr_poly
		(pts
			(arc
				(start 179.288186 -354.732082)
				(mid 179.038758 -354.732082)
				(end 179.288186 -354.732082)
			)
		)
		(stroke
			(width 0)
			(type solid)
		)
		(fill yes)
		(layer "B.Cu")
		(net "GND")
	)
	(gr_poly
		(pts
			(arc
				(start 179.288186 -351.611438)
				(mid 179.038758 -351.611438)
				(end 179.288186 -351.611438)
			)
		)
		(stroke
			(width 0)
			(type solid)
		)
		(fill yes)
		(layer "B.Cu")
		(net "GND")
	)
	(gr_poly
		(pts
			(arc
				(start 179.288186 -348.58579)
				(mid 179.038758 -348.58579)
				(end 179.288186 -348.58579)
			)
		)
		(stroke
			(width 0)
			(type solid)
		)
		(fill yes)
		(layer "B.Cu")
		(net "GND")
	)
	(gr_poly
		(pts
			(arc
				(start 179.288186 -345.465146)
				(mid 179.038758 -345.465146)
				(end 179.288186 -345.465146)
			)
		)
		(stroke
			(width 0)
			(type solid)
		)
		(fill yes)
		(layer "B.Cu")
		(net "GND")
	)
	(gr_poly
		(pts
			(arc
				(start 179.288186 -342.439498)
				(mid 179.038758 -342.439498)
				(end 179.288186 -342.439498)
			)
		)
		(stroke
			(width 0)
			(type solid)
		)
		(fill yes)
		(layer "B.Cu")
		(net "GND")
	)
	(gr_poly
		(pts
			(arc
				(start 180.395626 -357.75773)
				(mid 180.146198 -357.75773)
				(end 180.395626 -357.75773)
			)
		)
		(stroke
			(width 0)
			(type solid)
		)
		(fill yes)
		(layer "B.Cu")
		(net "GND")
	)
	(gr_poly
		(pts
			(arc
				(start 180.395626 -354.732082)
				(mid 180.146198 -354.732082)
				(end 180.395626 -354.732082)
			)
		)
		(stroke
			(width 0)
			(type solid)
		)
		(fill yes)
		(layer "B.Cu")
		(net "GND")
	)
	(gr_poly
		(pts
			(arc
				(start 180.395626 -351.611438)
				(mid 180.146198 -351.611438)
				(end 180.395626 -351.611438)
			)
		)
		(stroke
			(width 0)
			(type solid)
		)
		(fill yes)
		(layer "B.Cu")
		(net "GND")
	)
	(gr_poly
		(pts
			(arc
				(start 180.395626 -348.58579)
				(mid 180.146198 -348.58579)
				(end 180.395626 -348.58579)
			)
		)
		(stroke
			(width 0)
			(type solid)
		)
		(fill yes)
		(layer "B.Cu")
		(net "GND")
	)
	(gr_poly
		(pts
			(arc
				(start 180.395626 -345.465146)
				(mid 180.146198 -345.465146)
				(end 180.395626 -345.465146)
			)
		)
		(stroke
			(width 0)
			(type solid)
		)
		(fill yes)
		(layer "B.Cu")
		(net "GND")
	)
	(gr_poly
		(pts
			(arc
				(start 180.395626 -342.439498)
				(mid 180.146198 -342.439498)
				(end 180.395626 -342.439498)
			)
		)
		(stroke
			(width 0)
			(type solid)
		)
		(fill yes)
		(layer "B.Cu")
		(net "GND")
	)
	(gr_poly
		(pts
			(arc
				(start 182.397146 -357.75773)
				(mid 182.147718 -357.75773)
				(end 182.397146 -357.75773)
			)
		)
		(stroke
			(width 0)
			(type solid)
		)
		(fill yes)
		(layer "B.Cu")
		(net "GND")
	)
	(gr_poly
		(pts
			(arc
				(start 182.397146 -354.732082)
				(mid 182.147718 -354.732082)
				(end 182.397146 -354.732082)
			)
		)
		(stroke
			(width 0)
			(type solid)
		)
		(fill yes)
		(layer "B.Cu")
		(net "GND")
	)
	(gr_poly
		(pts
			(arc
				(start 182.397146 -351.611438)
				(mid 182.147718 -351.611438)
				(end 182.397146 -351.611438)
			)
		)
		(stroke
			(width 0)
			(type solid)
		)
		(fill yes)
		(layer "B.Cu")
		(net "GND")
	)
	(gr_poly
		(pts
			(arc
				(start 182.397146 -348.58579)
				(mid 182.147718 -348.58579)
				(end 182.397146 -348.58579)
			)
		)
		(stroke
			(width 0)
			(type solid)
		)
		(fill yes)
		(layer "B.Cu")
		(net "GND")
	)
	(gr_poly
		(pts
			(arc
				(start 182.397146 -345.465146)
				(mid 182.147718 -345.465146)
				(end 182.397146 -345.465146)
			)
		)
		(stroke
			(width 0)
			(type solid)
		)
		(fill yes)
		(layer "B.Cu")
		(net "GND")
	)
	(gr_poly
		(pts
			(arc
				(start 182.397146 -342.439498)
				(mid 182.147718 -342.439498)
				(end 182.397146 -342.439498)
			)
		)
		(stroke
			(width 0)
			(type solid)
		)
		(fill yes)
		(layer "B.Cu")
		(net "GND")
	)
	(gr_poly
		(pts
			(arc
				(start 183.504586 -357.733854)
				(mid 183.255158 -357.733854)
				(end 183.504586 -357.733854)
			)
		)
		(stroke
			(width 0)
			(type solid)
		)
		(fill yes)
		(layer "B.Cu")
		(net "GND")
	)
	(gr_poly
		(pts
			(arc
				(start 183.504586 -354.708206)
				(mid 183.255158 -354.708206)
				(end 183.504586 -354.708206)
			)
		)
		(stroke
			(width 0)
			(type solid)
		)
		(fill yes)
		(layer "B.Cu")
		(net "GND")
	)
	(gr_poly
		(pts
			(arc
				(start 183.504586 -351.611438)
				(mid 183.255158 -351.611438)
				(end 183.504586 -351.611438)
			)
		)
		(stroke
			(width 0)
			(type solid)
		)
		(fill yes)
		(layer "B.Cu")
		(net "GND")
	)
	(gr_poly
		(pts
			(arc
				(start 183.504586 -348.58579)
				(mid 183.255158 -348.58579)
				(end 183.504586 -348.58579)
			)
		)
		(stroke
			(width 0)
			(type solid)
		)
		(fill yes)
		(layer "B.Cu")
		(net "GND")
	)
	(gr_poly
		(pts
			(arc
				(start 183.504586 -345.465146)
				(mid 183.255158 -345.465146)
				(end 183.504586 -345.465146)
			)
		)
		(stroke
			(width 0)
			(type solid)
		)
		(fill yes)
		(layer "B.Cu")
		(net "GND")
	)
	(gr_poly
		(pts
			(arc
				(start 183.504586 -342.439498)
				(mid 183.255158 -342.439498)
				(end 183.504586 -342.439498)
			)
		)
		(stroke
			(width 0)
			(type solid)
		)
		(fill yes)
		(layer "B.Cu")
		(net "GND")
	)
	(gr_poly
		(pts
			(arc
				(start 184.062624 -290.066984)
				(mid 184.082011 -290.063034)
				(end 184.098438 -290.051998)
			)
			(xy 184.100978 -290.049458) (xy 184.108598 -290.030916)
			(arc
				(start 184.108598 -289.559492)
				(mid 184.093719 -289.523571)
				(end 184.057798 -289.508692)
			)
			(arc
				(start 166.628572 -289.508692)
				(mid 166.609185 -289.512642)
				(end 166.592758 -289.523678)
			)
			(arc
				(start 166.521384 -289.595052)
				(mid 166.510273 -289.611586)
				(end 166.506398 -289.63112)
			)
			(xy 166.506398 -290.030916) (xy 166.514018 -290.049458)
			(arc
				(start 166.516558 -290.051998)
				(mid 166.532975 -290.06306)
				(end 166.552372 -290.066984)
			)
		)
		(stroke
			(width 0)
			(type solid)
		)
		(fill yes)
		(layer "B.Cu")
		(net "GND")
	)
	(gr_poly
		(pts
			(arc
				(start 185.506106 -357.733854)
				(mid 185.256678 -357.733854)
				(end 185.506106 -357.733854)
			)
		)
		(stroke
			(width 0)
			(type solid)
		)
		(fill yes)
		(layer "B.Cu")
		(net "GND")
	)
	(gr_poly
		(pts
			(arc
				(start 185.506106 -354.708206)
				(mid 185.256678 -354.708206)
				(end 185.506106 -354.708206)
			)
		)
		(stroke
			(width 0)
			(type solid)
		)
		(fill yes)
		(layer "B.Cu")
		(net "GND")
	)
	(gr_poly
		(pts
			(arc
				(start 185.506106 -351.611438)
				(mid 185.256678 -351.611438)
				(end 185.506106 -351.611438)
			)
		)
		(stroke
			(width 0)
			(type solid)
		)
		(fill yes)
		(layer "B.Cu")
		(net "GND")
	)
	(gr_poly
		(pts
			(arc
				(start 185.506106 -348.58579)
				(mid 185.256678 -348.58579)
				(end 185.506106 -348.58579)
			)
		)
		(stroke
			(width 0)
			(type solid)
		)
		(fill yes)
		(layer "B.Cu")
		(net "GND")
	)
	(gr_poly
		(pts
			(arc
				(start 185.506106 -345.465146)
				(mid 185.256678 -345.465146)
				(end 185.506106 -345.465146)
			)
		)
		(stroke
			(width 0)
			(type solid)
		)
		(fill yes)
		(layer "B.Cu")
		(net "GND")
	)
	(gr_poly
		(pts
			(arc
				(start 185.506106 -342.439498)
				(mid 185.256678 -342.439498)
				(end 185.506106 -342.439498)
			)
		)
		(stroke
			(width 0)
			(type solid)
		)
		(fill yes)
		(layer "B.Cu")
		(net "GND")
	)
	(gr_poly
		(pts
			(arc
				(start 186.613546 -357.733854)
				(mid 186.364118 -357.733854)
				(end 186.613546 -357.733854)
			)
		)
		(stroke
			(width 0)
			(type solid)
		)
		(fill yes)
		(layer "B.Cu")
		(net "GND")
	)
	(gr_poly
		(pts
			(arc
				(start 186.613546 -354.708206)
				(mid 186.364118 -354.708206)
				(end 186.613546 -354.708206)
			)
		)
		(stroke
			(width 0)
			(type solid)
		)
		(fill yes)
		(layer "B.Cu")
		(net "GND")
	)
	(gr_poly
		(pts
			(arc
				(start 186.613546 -351.611438)
				(mid 186.364118 -351.611438)
				(end 186.613546 -351.611438)
			)
		)
		(stroke
			(width 0)
			(type solid)
		)
		(fill yes)
		(layer "B.Cu")
		(net "GND")
	)
	(gr_poly
		(pts
			(arc
				(start 186.613546 -348.58579)
				(mid 186.364118 -348.58579)
				(end 186.613546 -348.58579)
			)
		)
		(stroke
			(width 0)
			(type solid)
		)
		(fill yes)
		(layer "B.Cu")
		(net "GND")
	)
	(gr_poly
		(pts
			(arc
				(start 186.613546 -345.465146)
				(mid 186.364118 -345.465146)
				(end 186.613546 -345.465146)
			)
		)
		(stroke
			(width 0)
			(type solid)
		)
		(fill yes)
		(layer "B.Cu")
		(net "GND")
	)
	(gr_poly
		(pts
			(arc
				(start 186.613546 -342.439498)
				(mid 186.364118 -342.439498)
				(end 186.613546 -342.439498)
			)
		)
		(stroke
			(width 0)
			(type solid)
		)
		(fill yes)
		(layer "B.Cu")
		(net "GND")
	)
	(gr_poly
		(pts
			(arc
				(start 188.615066 -357.733854)
				(mid 188.365638 -357.733854)
				(end 188.615066 -357.733854)
			)
		)
		(stroke
			(width 0)
			(type solid)
		)
		(fill yes)
		(layer "B.Cu")
		(net "GND")
	)
	(gr_poly
		(pts
			(arc
				(start 188.615066 -354.708206)
				(mid 188.365638 -354.708206)
				(end 188.615066 -354.708206)
			)
		)
		(stroke
			(width 0)
			(type solid)
		)
		(fill yes)
		(layer "B.Cu")
		(net "GND")
	)
	(gr_poly
		(pts
			(arc
				(start 188.615066 -351.611438)
				(mid 188.365638 -351.611438)
				(end 188.615066 -351.611438)
			)
		)
		(stroke
			(width 0)
			(type solid)
		)
		(fill yes)
		(layer "B.Cu")
		(net "GND")
	)
	(gr_poly
		(pts
			(arc
				(start 188.615066 -348.58579)
				(mid 188.365638 -348.58579)
				(end 188.615066 -348.58579)
			)
		)
		(stroke
			(width 0)
			(type solid)
		)
		(fill yes)
		(layer "B.Cu")
		(net "GND")
	)
	(gr_poly
		(pts
			(arc
				(start 188.615066 -345.465146)
				(mid 188.365638 -345.465146)
				(end 188.615066 -345.465146)
			)
		)
		(stroke
			(width 0)
			(type solid)
		)
		(fill yes)
		(layer "B.Cu")
		(net "GND")
	)
	(gr_poly
		(pts
			(arc
				(start 188.615066 -342.439498)
				(mid 188.365638 -342.439498)
				(end 188.615066 -342.439498)
			)
		)
		(stroke
			(width 0)
			(type solid)
		)
		(fill yes)
		(layer "B.Cu")
		(net "GND")
	)
	(gr_poly
		(pts
			(arc
				(start 189.722506 -351.611438)
				(mid 189.473078 -351.611438)
				(end 189.722506 -351.611438)
			)
		)
		(stroke
			(width 0)
			(type solid)
		)
		(fill yes)
		(layer "B.Cu")
		(net "GND")
	)
	(gr_poly
		(pts
			(arc
				(start 189.722506 -348.58579)
				(mid 189.473078 -348.58579)
				(end 189.722506 -348.58579)
			)
		)
		(stroke
			(width 0)
			(type solid)
		)
		(fill yes)
		(layer "B.Cu")
		(net "GND")
	)
	(gr_poly
		(pts
			(arc
				(start 189.722506 -345.465146)
				(mid 189.473078 -345.465146)
				(end 189.722506 -345.465146)
			)
		)
		(stroke
			(width 0)
			(type solid)
		)
		(fill yes)
		(layer "B.Cu")
		(net "GND")
	)
	(gr_poly
		(pts
			(arc
				(start 189.722506 -342.439498)
				(mid 189.473078 -342.439498)
				(end 189.722506 -342.439498)
			)
		)
		(stroke
			(width 0)
			(type solid)
		)
		(fill yes)
		(layer "B.Cu")
		(net "GND")
	)
	(gr_poly
		(pts
			(arc
				(start 191.724026 -351.611438)
				(mid 191.474598 -351.611438)
				(end 191.724026 -351.611438)
			)
		)
		(stroke
			(width 0)
			(type solid)
		)
		(fill yes)
		(layer "B.Cu")
		(net "GND")
	)
	(gr_poly
		(pts
			(arc
				(start 191.724026 -348.58579)
				(mid 191.474598 -348.58579)
				(end 191.724026 -348.58579)
			)
		)
		(stroke
			(width 0)
			(type solid)
		)
		(fill yes)
		(layer "B.Cu")
		(net "GND")
	)
	(gr_poly
		(pts
			(arc
				(start 191.724026 -345.465146)
				(mid 191.474598 -345.465146)
				(end 191.724026 -345.465146)
			)
		)
		(stroke
			(width 0)
			(type solid)
		)
		(fill yes)
		(layer "B.Cu")
		(net "GND")
	)
	(gr_poly
		(pts
			(arc
				(start 191.724026 -342.439498)
				(mid 191.474598 -342.439498)
				(end 191.724026 -342.439498)
			)
		)
		(stroke
			(width 0)
			(type solid)
		)
		(fill yes)
		(layer "B.Cu")
		(net "GND")
	)
	(gr_poly
		(pts
			(arc
				(start 192.831466 -351.611438)
				(mid 192.582038 -351.611438)
				(end 192.831466 -351.611438)
			)
		)
		(stroke
			(width 0)
			(type solid)
		)
		(fill yes)
		(layer "B.Cu")
		(net "GND")
	)
	(gr_poly
		(pts
			(arc
				(start 192.831466 -348.58579)
				(mid 192.582038 -348.58579)
				(end 192.831466 -348.58579)
			)
		)
		(stroke
			(width 0)
			(type solid)
		)
		(fill yes)
		(layer "B.Cu")
		(net "GND")
	)
	(gr_poly
		(pts
			(arc
				(start 192.831466 -345.465146)
				(mid 192.582038 -345.465146)
				(end 192.831466 -345.465146)
			)
		)
		(stroke
			(width 0)
			(type solid)
		)
		(fill yes)
		(layer "B.Cu")
		(net "GND")
	)
	(gr_poly
		(pts
			(arc
				(start 192.831466 -342.439498)
				(mid 192.582038 -342.439498)
				(end 192.831466 -342.439498)
			)
		)
		(stroke
			(width 0)
			(type solid)
		)
		(fill yes)
		(layer "B.Cu")
		(net "GND")
	)
	(gr_poly
		(pts
			(arc
				(start 194.832986 -351.611438)
				(mid 194.583558 -351.611438)
				(end 194.832986 -351.611438)
			)
		)
		(stroke
			(width 0)
			(type solid)
		)
		(fill yes)
		(layer "B.Cu")
		(net "GND")
	)
	(gr_poly
		(pts
			(arc
				(start 194.832986 -348.58579)
				(mid 194.583558 -348.58579)
				(end 194.832986 -348.58579)
			)
		)
		(stroke
			(width 0)
			(type solid)
		)
		(fill yes)
		(layer "B.Cu")
		(net "GND")
	)
	(gr_poly
		(pts
			(arc
				(start 194.832986 -345.465146)
				(mid 194.583558 -345.465146)
				(end 194.832986 -345.465146)
			)
		)
		(stroke
			(width 0)
			(type solid)
		)
		(fill yes)
		(layer "B.Cu")
		(net "GND")
	)
	(gr_poly
		(pts
			(arc
				(start 194.832986 -342.439498)
				(mid 194.583558 -342.439498)
				(end 194.832986 -342.439498)
			)
		)
		(stroke
			(width 0)
			(type solid)
		)
		(fill yes)
		(layer "B.Cu")
		(net "GND")
	)
	(gr_poly
		(pts
			(arc
				(start 195.940426 -345.465146)
				(mid 195.690998 -345.465146)
				(end 195.940426 -345.465146)
			)
		)
		(stroke
			(width 0)
			(type solid)
		)
		(fill yes)
		(layer "B.Cu")
		(net "GND")
	)
	(gr_poly
		(pts
			(arc
				(start 195.940426 -342.439498)
				(mid 195.690998 -342.439498)
				(end 195.940426 -342.439498)
			)
		)
		(stroke
			(width 0)
			(type solid)
		)
		(fill yes)
		(layer "B.Cu")
		(net "GND")
	)
	(gr_poly
		(pts
			(arc
				(start 197.941946 -345.465146)
				(mid 197.692518 -345.465146)
				(end 197.941946 -345.465146)
			)
		)
		(stroke
			(width 0)
			(type solid)
		)
		(fill yes)
		(layer "B.Cu")
		(net "GND")
	)
	(gr_poly
		(pts
			(arc
				(start 197.941946 -342.439498)
				(mid 197.692518 -342.439498)
				(end 197.941946 -342.439498)
			)
		)
		(stroke
			(width 0)
			(type solid)
		)
		(fill yes)
		(layer "B.Cu")
		(net "GND")
	)
	(gr_poly
		(pts
			(arc
				(start 201.606912 -35.635184)
				(mid 201.349356 -35.635184)
				(end 201.606912 -35.635184)
			)
		)
		(stroke
			(width 0)
			(type solid)
		)
		(fill yes)
		(layer "B.Cu")
		(net "GND")
	)
	(gr_poly
		(pts
			(arc
				(start 267.452856 -351.611438)
				(mid 267.203428 -351.611438)
				(end 267.452856 -351.611438)
			)
		)
		(stroke
			(width 0)
			(type solid)
		)
		(fill yes)
		(layer "B.Cu")
		(net "GND")
	)
	(gr_poly
		(pts
			(arc
				(start 267.452856 -348.58579)
				(mid 267.203428 -348.58579)
				(end 267.452856 -348.58579)
			)
		)
		(stroke
			(width 0)
			(type solid)
		)
		(fill yes)
		(layer "B.Cu")
		(net "GND")
	)
	(gr_poly
		(pts
			(arc
				(start 267.452856 -345.465146)
				(mid 267.203428 -345.465146)
				(end 267.452856 -345.465146)
			)
		)
		(stroke
			(width 0)
			(type solid)
		)
		(fill yes)
		(layer "B.Cu")
		(net "GND")
	)
	(gr_poly
		(pts
			(arc
				(start 267.452856 -342.439498)
				(mid 267.203428 -342.439498)
				(end 267.452856 -342.439498)
			)
		)
		(stroke
			(width 0)
			(type solid)
		)
		(fill yes)
		(layer "B.Cu")
		(net "GND")
	)
	(gr_poly
		(pts
			(arc
				(start 269.454376 -351.611438)
				(mid 269.204948 -351.611438)
				(end 269.454376 -351.611438)
			)
		)
		(stroke
			(width 0)
			(type solid)
		)
		(fill yes)
		(layer "B.Cu")
		(net "GND")
	)
	(gr_poly
		(pts
			(arc
				(start 269.454376 -348.58579)
				(mid 269.204948 -348.58579)
				(end 269.454376 -348.58579)
			)
		)
		(stroke
			(width 0)
			(type solid)
		)
		(fill yes)
		(layer "B.Cu")
		(net "GND")
	)
	(gr_poly
		(pts
			(arc
				(start 269.454376 -345.465146)
				(mid 269.204948 -345.465146)
				(end 269.454376 -345.465146)
			)
		)
		(stroke
			(width 0)
			(type solid)
		)
		(fill yes)
		(layer "B.Cu")
		(net "GND")
	)
	(gr_poly
		(pts
			(arc
				(start 269.454376 -342.439498)
				(mid 269.204948 -342.439498)
				(end 269.454376 -342.439498)
			)
		)
		(stroke
			(width 0)
			(type solid)
		)
		(fill yes)
		(layer "B.Cu")
		(net "GND")
	)
	(gr_poly
		(pts
			(arc
				(start 270.561816 -357.75773)
				(mid 270.312388 -357.75773)
				(end 270.561816 -357.75773)
			)
		)
		(stroke
			(width 0)
			(type solid)
		)
		(fill yes)
		(layer "B.Cu")
		(net "GND")
	)
	(gr_poly
		(pts
			(arc
				(start 270.561816 -354.732082)
				(mid 270.312388 -354.732082)
				(end 270.561816 -354.732082)
			)
		)
		(stroke
			(width 0)
			(type solid)
		)
		(fill yes)
		(layer "B.Cu")
		(net "GND")
	)
	(gr_poly
		(pts
			(arc
				(start 270.561816 -351.611438)
				(mid 270.312388 -351.611438)
				(end 270.561816 -351.611438)
			)
		)
		(stroke
			(width 0)
			(type solid)
		)
		(fill yes)
		(layer "B.Cu")
		(net "GND")
	)
	(gr_poly
		(pts
			(arc
				(start 270.561816 -348.58579)
				(mid 270.312388 -348.58579)
				(end 270.561816 -348.58579)
			)
		)
		(stroke
			(width 0)
			(type solid)
		)
		(fill yes)
		(layer "B.Cu")
		(net "GND")
	)
	(gr_poly
		(pts
			(arc
				(start 270.561816 -345.465146)
				(mid 270.312388 -345.465146)
				(end 270.561816 -345.465146)
			)
		)
		(stroke
			(width 0)
			(type solid)
		)
		(fill yes)
		(layer "B.Cu")
		(net "GND")
	)
	(gr_poly
		(pts
			(arc
				(start 270.561816 -342.439498)
				(mid 270.312388 -342.439498)
				(end 270.561816 -342.439498)
			)
		)
		(stroke
			(width 0)
			(type solid)
		)
		(fill yes)
		(layer "B.Cu")
		(net "GND")
	)
	(gr_poly
		(pts
			(arc
				(start 272.563336 -357.75773)
				(mid 272.313908 -357.75773)
				(end 272.563336 -357.75773)
			)
		)
		(stroke
			(width 0)
			(type solid)
		)
		(fill yes)
		(layer "B.Cu")
		(net "GND")
	)
	(gr_poly
		(pts
			(arc
				(start 272.563336 -354.732082)
				(mid 272.313908 -354.732082)
				(end 272.563336 -354.732082)
			)
		)
		(stroke
			(width 0)
			(type solid)
		)
		(fill yes)
		(layer "B.Cu")
		(net "GND")
	)
	(gr_poly
		(pts
			(arc
				(start 272.563336 -351.611438)
				(mid 272.313908 -351.611438)
				(end 272.563336 -351.611438)
			)
		)
		(stroke
			(width 0)
			(type solid)
		)
		(fill yes)
		(layer "B.Cu")
		(net "GND")
	)
	(gr_poly
		(pts
			(arc
				(start 272.563336 -348.58579)
				(mid 272.313908 -348.58579)
				(end 272.563336 -348.58579)
			)
		)
		(stroke
			(width 0)
			(type solid)
		)
		(fill yes)
		(layer "B.Cu")
		(net "GND")
	)
	(gr_poly
		(pts
			(arc
				(start 272.563336 -345.465146)
				(mid 272.313908 -345.465146)
				(end 272.563336 -345.465146)
			)
		)
		(stroke
			(width 0)
			(type solid)
		)
		(fill yes)
		(layer "B.Cu")
		(net "GND")
	)
	(gr_poly
		(pts
			(arc
				(start 272.563336 -342.439498)
				(mid 272.313908 -342.439498)
				(end 272.563336 -342.439498)
			)
		)
		(stroke
			(width 0)
			(type solid)
		)
		(fill yes)
		(layer "B.Cu")
		(net "GND")
	)
	(gr_poly
		(pts
			(arc
				(start 273.670776 -357.75773)
				(mid 273.421348 -357.75773)
				(end 273.670776 -357.75773)
			)
		)
		(stroke
			(width 0)
			(type solid)
		)
		(fill yes)
		(layer "B.Cu")
		(net "GND")
	)
	(gr_poly
		(pts
			(arc
				(start 273.670776 -354.732082)
				(mid 273.421348 -354.732082)
				(end 273.670776 -354.732082)
			)
		)
		(stroke
			(width 0)
			(type solid)
		)
		(fill yes)
		(layer "B.Cu")
		(net "GND")
	)
	(gr_poly
		(pts
			(arc
				(start 273.670776 -351.611438)
				(mid 273.421348 -351.611438)
				(end 273.670776 -351.611438)
			)
		)
		(stroke
			(width 0)
			(type solid)
		)
		(fill yes)
		(layer "B.Cu")
		(net "GND")
	)
	(gr_poly
		(pts
			(arc
				(start 273.670776 -348.58579)
				(mid 273.421348 -348.58579)
				(end 273.670776 -348.58579)
			)
		)
		(stroke
			(width 0)
			(type solid)
		)
		(fill yes)
		(layer "B.Cu")
		(net "GND")
	)
	(gr_poly
		(pts
			(arc
				(start 273.670776 -345.465146)
				(mid 273.421348 -345.465146)
				(end 273.670776 -345.465146)
			)
		)
		(stroke
			(width 0)
			(type solid)
		)
		(fill yes)
		(layer "B.Cu")
		(net "GND")
	)
	(gr_poly
		(pts
			(arc
				(start 273.670776 -342.439498)
				(mid 273.421348 -342.439498)
				(end 273.670776 -342.439498)
			)
		)
		(stroke
			(width 0)
			(type solid)
		)
		(fill yes)
		(layer "B.Cu")
		(net "GND")
	)
	(gr_poly
		(pts
			(arc
				(start 275.672296 -357.75773)
				(mid 275.422868 -357.75773)
				(end 275.672296 -357.75773)
			)
		)
		(stroke
			(width 0)
			(type solid)
		)
		(fill yes)
		(layer "B.Cu")
		(net "GND")
	)
	(gr_poly
		(pts
			(arc
				(start 275.672296 -354.732082)
				(mid 275.422868 -354.732082)
				(end 275.672296 -354.732082)
			)
		)
		(stroke
			(width 0)
			(type solid)
		)
		(fill yes)
		(layer "B.Cu")
		(net "GND")
	)
	(gr_poly
		(pts
			(arc
				(start 275.672296 -351.611438)
				(mid 275.422868 -351.611438)
				(end 275.672296 -351.611438)
			)
		)
		(stroke
			(width 0)
			(type solid)
		)
		(fill yes)
		(layer "B.Cu")
		(net "GND")
	)
	(gr_poly
		(pts
			(arc
				(start 275.672296 -348.58579)
				(mid 275.422868 -348.58579)
				(end 275.672296 -348.58579)
			)
		)
		(stroke
			(width 0)
			(type solid)
		)
		(fill yes)
		(layer "B.Cu")
		(net "GND")
	)
	(gr_poly
		(pts
			(arc
				(start 275.672296 -345.465146)
				(mid 275.422868 -345.465146)
				(end 275.672296 -345.465146)
			)
		)
		(stroke
			(width 0)
			(type solid)
		)
		(fill yes)
		(layer "B.Cu")
		(net "GND")
	)
	(gr_poly
		(pts
			(arc
				(start 275.672296 -342.439498)
				(mid 275.422868 -342.439498)
				(end 275.672296 -342.439498)
			)
		)
		(stroke
			(width 0)
			(type solid)
		)
		(fill yes)
		(layer "B.Cu")
		(net "GND")
	)
	(gr_poly
		(pts
			(arc
				(start 276.779736 -357.75773)
				(mid 276.530308 -357.75773)
				(end 276.779736 -357.75773)
			)
		)
		(stroke
			(width 0)
			(type solid)
		)
		(fill yes)
		(layer "B.Cu")
		(net "GND")
	)
	(gr_poly
		(pts
			(arc
				(start 276.779736 -354.732082)
				(mid 276.530308 -354.732082)
				(end 276.779736 -354.732082)
			)
		)
		(stroke
			(width 0)
			(type solid)
		)
		(fill yes)
		(layer "B.Cu")
		(net "GND")
	)
	(gr_poly
		(pts
			(arc
				(start 276.779736 -351.611438)
				(mid 276.530308 -351.611438)
				(end 276.779736 -351.611438)
			)
		)
		(stroke
			(width 0)
			(type solid)
		)
		(fill yes)
		(layer "B.Cu")
		(net "GND")
	)
	(gr_poly
		(pts
			(arc
				(start 276.779736 -348.58579)
				(mid 276.530308 -348.58579)
				(end 276.779736 -348.58579)
			)
		)
		(stroke
			(width 0)
			(type solid)
		)
		(fill yes)
		(layer "B.Cu")
		(net "GND")
	)
	(gr_poly
		(pts
			(arc
				(start 276.779736 -345.465146)
				(mid 276.530308 -345.465146)
				(end 276.779736 -345.465146)
			)
		)
		(stroke
			(width 0)
			(type solid)
		)
		(fill yes)
		(layer "B.Cu")
		(net "GND")
	)
	(gr_poly
		(pts
			(arc
				(start 276.779736 -342.439498)
				(mid 276.530308 -342.439498)
				(end 276.779736 -342.439498)
			)
		)
		(stroke
			(width 0)
			(type solid)
		)
		(fill yes)
		(layer "B.Cu")
		(net "GND")
	)
	(gr_poly
		(pts
			(arc
				(start 278.781256 -357.75773)
				(mid 278.531828 -357.75773)
				(end 278.781256 -357.75773)
			)
		)
		(stroke
			(width 0)
			(type solid)
		)
		(fill yes)
		(layer "B.Cu")
		(net "GND")
	)
	(gr_poly
		(pts
			(arc
				(start 278.781256 -354.732082)
				(mid 278.531828 -354.732082)
				(end 278.781256 -354.732082)
			)
		)
		(stroke
			(width 0)
			(type solid)
		)
		(fill yes)
		(layer "B.Cu")
		(net "GND")
	)
	(gr_poly
		(pts
			(arc
				(start 278.781256 -351.611438)
				(mid 278.531828 -351.611438)
				(end 278.781256 -351.611438)
			)
		)
		(stroke
			(width 0)
			(type solid)
		)
		(fill yes)
		(layer "B.Cu")
		(net "GND")
	)
	(gr_poly
		(pts
			(arc
				(start 278.781256 -348.58579)
				(mid 278.531828 -348.58579)
				(end 278.781256 -348.58579)
			)
		)
		(stroke
			(width 0)
			(type solid)
		)
		(fill yes)
		(layer "B.Cu")
		(net "GND")
	)
	(gr_poly
		(pts
			(arc
				(start 278.781256 -345.465146)
				(mid 278.531828 -345.465146)
				(end 278.781256 -345.465146)
			)
		)
		(stroke
			(width 0)
			(type solid)
		)
		(fill yes)
		(layer "B.Cu")
		(net "GND")
	)
	(gr_poly
		(pts
			(arc
				(start 278.781256 -342.439498)
				(mid 278.531828 -342.439498)
				(end 278.781256 -342.439498)
			)
		)
		(stroke
			(width 0)
			(type solid)
		)
		(fill yes)
		(layer "B.Cu")
		(net "GND")
	)
	(gr_poly
		(pts
			(arc
				(start 279.888696 -357.75773)
				(mid 279.639268 -357.75773)
				(end 279.888696 -357.75773)
			)
		)
		(stroke
			(width 0)
			(type solid)
		)
		(fill yes)
		(layer "B.Cu")
		(net "GND")
	)
	(gr_poly
		(pts
			(arc
				(start 279.888696 -354.732082)
				(mid 279.639268 -354.732082)
				(end 279.888696 -354.732082)
			)
		)
		(stroke
			(width 0)
			(type solid)
		)
		(fill yes)
		(layer "B.Cu")
		(net "GND")
	)
	(gr_poly
		(pts
			(arc
				(start 279.888696 -351.611438)
				(mid 279.639268 -351.611438)
				(end 279.888696 -351.611438)
			)
		)
		(stroke
			(width 0)
			(type solid)
		)
		(fill yes)
		(layer "B.Cu")
		(net "GND")
	)
	(gr_poly
		(pts
			(arc
				(start 279.888696 -348.58579)
				(mid 279.639268 -348.58579)
				(end 279.888696 -348.58579)
			)
		)
		(stroke
			(width 0)
			(type solid)
		)
		(fill yes)
		(layer "B.Cu")
		(net "GND")
	)
	(gr_poly
		(pts
			(arc
				(start 279.888696 -345.465146)
				(mid 279.639268 -345.465146)
				(end 279.888696 -345.465146)
			)
		)
		(stroke
			(width 0)
			(type solid)
		)
		(fill yes)
		(layer "B.Cu")
		(net "GND")
	)
	(gr_poly
		(pts
			(arc
				(start 279.888696 -342.439498)
				(mid 279.639268 -342.439498)
				(end 279.888696 -342.439498)
			)
		)
		(stroke
			(width 0)
			(type solid)
		)
		(fill yes)
		(layer "B.Cu")
		(net "GND")
	)
	(gr_poly
		(pts
			(arc
				(start 281.890216 -357.75773)
				(mid 281.640788 -357.75773)
				(end 281.890216 -357.75773)
			)
		)
		(stroke
			(width 0)
			(type solid)
		)
		(fill yes)
		(layer "B.Cu")
		(net "GND")
	)
	(gr_poly
		(pts
			(arc
				(start 281.890216 -354.732082)
				(mid 281.640788 -354.732082)
				(end 281.890216 -354.732082)
			)
		)
		(stroke
			(width 0)
			(type solid)
		)
		(fill yes)
		(layer "B.Cu")
		(net "GND")
	)
	(gr_poly
		(pts
			(arc
				(start 281.890216 -351.611438)
				(mid 281.640788 -351.611438)
				(end 281.890216 -351.611438)
			)
		)
		(stroke
			(width 0)
			(type solid)
		)
		(fill yes)
		(layer "B.Cu")
		(net "GND")
	)
	(gr_poly
		(pts
			(arc
				(start 281.890216 -348.58579)
				(mid 281.640788 -348.58579)
				(end 281.890216 -348.58579)
			)
		)
		(stroke
			(width 0)
			(type solid)
		)
		(fill yes)
		(layer "B.Cu")
		(net "GND")
	)
	(gr_poly
		(pts
			(arc
				(start 281.890216 -345.465146)
				(mid 281.640788 -345.465146)
				(end 281.890216 -345.465146)
			)
		)
		(stroke
			(width 0)
			(type solid)
		)
		(fill yes)
		(layer "B.Cu")
		(net "GND")
	)
	(gr_poly
		(pts
			(arc
				(start 281.890216 -342.439498)
				(mid 281.640788 -342.439498)
				(end 281.890216 -342.439498)
			)
		)
		(stroke
			(width 0)
			(type solid)
		)
		(fill yes)
		(layer "B.Cu")
		(net "GND")
	)
	(gr_poly
		(pts
			(arc
				(start 282.997656 -357.75773)
				(mid 282.748228 -357.75773)
				(end 282.997656 -357.75773)
			)
		)
		(stroke
			(width 0)
			(type solid)
		)
		(fill yes)
		(layer "B.Cu")
		(net "GND")
	)
	(gr_poly
		(pts
			(arc
				(start 282.997656 -354.732082)
				(mid 282.748228 -354.732082)
				(end 282.997656 -354.732082)
			)
		)
		(stroke
			(width 0)
			(type solid)
		)
		(fill yes)
		(layer "B.Cu")
		(net "GND")
	)
	(gr_poly
		(pts
			(arc
				(start 282.997656 -351.611438)
				(mid 282.748228 -351.611438)
				(end 282.997656 -351.611438)
			)
		)
		(stroke
			(width 0)
			(type solid)
		)
		(fill yes)
		(layer "B.Cu")
		(net "GND")
	)
	(gr_poly
		(pts
			(arc
				(start 282.997656 -348.58579)
				(mid 282.748228 -348.58579)
				(end 282.997656 -348.58579)
			)
		)
		(stroke
			(width 0)
			(type solid)
		)
		(fill yes)
		(layer "B.Cu")
		(net "GND")
	)
	(gr_poly
		(pts
			(arc
				(start 282.997656 -345.465146)
				(mid 282.748228 -345.465146)
				(end 282.997656 -345.465146)
			)
		)
		(stroke
			(width 0)
			(type solid)
		)
		(fill yes)
		(layer "B.Cu")
		(net "GND")
	)
	(gr_poly
		(pts
			(arc
				(start 282.997656 -342.439498)
				(mid 282.748228 -342.439498)
				(end 282.997656 -342.439498)
			)
		)
		(stroke
			(width 0)
			(type solid)
		)
		(fill yes)
		(layer "B.Cu")
		(net "GND")
	)
	(gr_poly
		(pts
			(arc
				(start 284.999176 -357.75773)
				(mid 284.749748 -357.75773)
				(end 284.999176 -357.75773)
			)
		)
		(stroke
			(width 0)
			(type solid)
		)
		(fill yes)
		(layer "B.Cu")
		(net "GND")
	)
	(gr_poly
		(pts
			(arc
				(start 284.999176 -354.732082)
				(mid 284.749748 -354.732082)
				(end 284.999176 -354.732082)
			)
		)
		(stroke
			(width 0)
			(type solid)
		)
		(fill yes)
		(layer "B.Cu")
		(net "GND")
	)
	(gr_poly
		(pts
			(arc
				(start 284.999176 -351.611438)
				(mid 284.749748 -351.611438)
				(end 284.999176 -351.611438)
			)
		)
		(stroke
			(width 0)
			(type solid)
		)
		(fill yes)
		(layer "B.Cu")
		(net "GND")
	)
	(gr_poly
		(pts
			(arc
				(start 284.999176 -348.58579)
				(mid 284.749748 -348.58579)
				(end 284.999176 -348.58579)
			)
		)
		(stroke
			(width 0)
			(type solid)
		)
		(fill yes)
		(layer "B.Cu")
		(net "GND")
	)
	(gr_poly
		(pts
			(arc
				(start 284.999176 -345.465146)
				(mid 284.749748 -345.465146)
				(end 284.999176 -345.465146)
			)
		)
		(stroke
			(width 0)
			(type solid)
		)
		(fill yes)
		(layer "B.Cu")
		(net "GND")
	)
	(gr_poly
		(pts
			(arc
				(start 284.999176 -342.439498)
				(mid 284.749748 -342.439498)
				(end 284.999176 -342.439498)
			)
		)
		(stroke
			(width 0)
			(type solid)
		)
		(fill yes)
		(layer "B.Cu")
		(net "GND")
	)
	(gr_poly
		(pts
			(arc
				(start 286.106616 -357.75773)
				(mid 285.857188 -357.75773)
				(end 286.106616 -357.75773)
			)
		)
		(stroke
			(width 0)
			(type solid)
		)
		(fill yes)
		(layer "B.Cu")
		(net "GND")
	)
	(gr_poly
		(pts
			(arc
				(start 286.106616 -354.732082)
				(mid 285.857188 -354.732082)
				(end 286.106616 -354.732082)
			)
		)
		(stroke
			(width 0)
			(type solid)
		)
		(fill yes)
		(layer "B.Cu")
		(net "GND")
	)
	(gr_poly
		(pts
			(arc
				(start 286.106616 -351.611438)
				(mid 285.857188 -351.611438)
				(end 286.106616 -351.611438)
			)
		)
		(stroke
			(width 0)
			(type solid)
		)
		(fill yes)
		(layer "B.Cu")
		(net "GND")
	)
	(gr_poly
		(pts
			(arc
				(start 286.106616 -348.58579)
				(mid 285.857188 -348.58579)
				(end 286.106616 -348.58579)
			)
		)
		(stroke
			(width 0)
			(type solid)
		)
		(fill yes)
		(layer "B.Cu")
		(net "GND")
	)
	(gr_poly
		(pts
			(arc
				(start 286.106616 -345.465146)
				(mid 285.857188 -345.465146)
				(end 286.106616 -345.465146)
			)
		)
		(stroke
			(width 0)
			(type solid)
		)
		(fill yes)
		(layer "B.Cu")
		(net "GND")
	)
	(gr_poly
		(pts
			(arc
				(start 286.106616 -342.439498)
				(mid 285.857188 -342.439498)
				(end 286.106616 -342.439498)
			)
		)
		(stroke
			(width 0)
			(type solid)
		)
		(fill yes)
		(layer "B.Cu")
		(net "GND")
	)
	(gr_poly
		(pts
			(arc
				(start 287.052512 -410.041852)
				(mid 286.803084 -410.041852)
				(end 287.052512 -410.041852)
			)
		)
		(stroke
			(width 0)
			(type solid)
		)
		(fill yes)
		(layer "B.Cu")
		(net "GND")
	)
	(gr_poly
		(pts
			(arc
				(start 287.052512 -408.840178)
				(mid 286.803084 -408.840178)
				(end 287.052512 -408.840178)
			)
		)
		(stroke
			(width 0)
			(type solid)
		)
		(fill yes)
		(layer "B.Cu")
		(net "GND")
	)
	(gr_poly
		(pts
			(arc
				(start 287.052512 -407.638504)
				(mid 286.803084 -407.638504)
				(end 287.052512 -407.638504)
			)
		)
		(stroke
			(width 0)
			(type solid)
		)
		(fill yes)
		(layer "B.Cu")
		(net "GND")
	)
	(gr_poly
		(pts
			(arc
				(start 287.052512 -406.141936)
				(mid 286.803084 -406.141936)
				(end 287.052512 -406.141936)
			)
		)
		(stroke
			(width 0)
			(type solid)
		)
		(fill yes)
		(layer "B.Cu")
		(net "GND")
	)
	(gr_poly
		(pts
			(arc
				(start 287.052512 -404.940262)
				(mid 286.803084 -404.940262)
				(end 287.052512 -404.940262)
			)
		)
		(stroke
			(width 0)
			(type solid)
		)
		(fill yes)
		(layer "B.Cu")
		(net "GND")
	)
	(gr_poly
		(pts
			(arc
				(start 287.052512 -403.738588)
				(mid 286.803084 -403.738588)
				(end 287.052512 -403.738588)
			)
		)
		(stroke
			(width 0)
			(type solid)
		)
		(fill yes)
		(layer "B.Cu")
		(net "GND")
	)
	(gr_poly
		(pts
			(arc
				(start 287.052512 -402.241766)
				(mid 286.803084 -402.241766)
				(end 287.052512 -402.241766)
			)
		)
		(stroke
			(width 0)
			(type solid)
		)
		(fill yes)
		(layer "B.Cu")
		(net "GND")
	)
	(gr_poly
		(pts
			(arc
				(start 287.052512 -401.040092)
				(mid 286.803084 -401.040092)
				(end 287.052512 -401.040092)
			)
		)
		(stroke
			(width 0)
			(type solid)
		)
		(fill yes)
		(layer "B.Cu")
		(net "GND")
	)
	(gr_poly
		(pts
			(arc
				(start 287.052512 -399.838418)
				(mid 286.803084 -399.838418)
				(end 287.052512 -399.838418)
			)
		)
		(stroke
			(width 0)
			(type solid)
		)
		(fill yes)
		(layer "B.Cu")
		(net "GND")
	)
	(gr_poly
		(pts
			(arc
				(start 287.052512 -398.34185)
				(mid 286.803084 -398.34185)
				(end 287.052512 -398.34185)
			)
		)
		(stroke
			(width 0)
			(type solid)
		)
		(fill yes)
		(layer "B.Cu")
		(net "GND")
	)
	(gr_poly
		(pts
			(arc
				(start 287.052512 -397.140176)
				(mid 286.803084 -397.140176)
				(end 287.052512 -397.140176)
			)
		)
		(stroke
			(width 0)
			(type solid)
		)
		(fill yes)
		(layer "B.Cu")
		(net "GND")
	)
	(gr_poly
		(pts
			(arc
				(start 287.052512 -395.938502)
				(mid 286.803084 -395.938502)
				(end 287.052512 -395.938502)
			)
		)
		(stroke
			(width 0)
			(type solid)
		)
		(fill yes)
		(layer "B.Cu")
		(net "GND")
	)
	(gr_poly
		(pts
			(arc
				(start 287.052512 -384.041904)
				(mid 286.803084 -384.041904)
				(end 287.052512 -384.041904)
			)
		)
		(stroke
			(width 0)
			(type solid)
		)
		(fill yes)
		(layer "B.Cu")
		(net "GND")
	)
	(gr_poly
		(pts
			(arc
				(start 287.052512 -382.84023)
				(mid 286.803084 -382.84023)
				(end 287.052512 -382.84023)
			)
		)
		(stroke
			(width 0)
			(type solid)
		)
		(fill yes)
		(layer "B.Cu")
		(net "GND")
	)
	(gr_poly
		(pts
			(arc
				(start 287.052512 -381.638556)
				(mid 286.803084 -381.638556)
				(end 287.052512 -381.638556)
			)
		)
		(stroke
			(width 0)
			(type solid)
		)
		(fill yes)
		(layer "B.Cu")
		(net "GND")
	)
	(gr_poly
		(pts
			(arc
				(start 287.052512 -380.141988)
				(mid 286.803084 -380.141988)
				(end 287.052512 -380.141988)
			)
		)
		(stroke
			(width 0)
			(type solid)
		)
		(fill yes)
		(layer "B.Cu")
		(net "GND")
	)
	(gr_poly
		(pts
			(arc
				(start 287.052512 -378.940314)
				(mid 286.803084 -378.940314)
				(end 287.052512 -378.940314)
			)
		)
		(stroke
			(width 0)
			(type solid)
		)
		(fill yes)
		(layer "B.Cu")
		(net "GND")
	)
	(gr_poly
		(pts
			(arc
				(start 287.052512 -377.73864)
				(mid 286.803084 -377.73864)
				(end 287.052512 -377.73864)
			)
		)
		(stroke
			(width 0)
			(type solid)
		)
		(fill yes)
		(layer "B.Cu")
		(net "GND")
	)
	(gr_poly
		(pts
			(arc
				(start 287.052512 -376.241818)
				(mid 286.803084 -376.241818)
				(end 287.052512 -376.241818)
			)
		)
		(stroke
			(width 0)
			(type solid)
		)
		(fill yes)
		(layer "B.Cu")
		(net "GND")
	)
	(gr_poly
		(pts
			(arc
				(start 287.052512 -375.040144)
				(mid 286.803084 -375.040144)
				(end 287.052512 -375.040144)
			)
		)
		(stroke
			(width 0)
			(type solid)
		)
		(fill yes)
		(layer "B.Cu")
		(net "GND")
	)
	(gr_poly
		(pts
			(arc
				(start 287.052512 -373.83847)
				(mid 286.803084 -373.83847)
				(end 287.052512 -373.83847)
			)
		)
		(stroke
			(width 0)
			(type solid)
		)
		(fill yes)
		(layer "B.Cu")
		(net "GND")
	)
	(gr_poly
		(pts
			(arc
				(start 287.052512 -372.341902)
				(mid 286.803084 -372.341902)
				(end 287.052512 -372.341902)
			)
		)
		(stroke
			(width 0)
			(type solid)
		)
		(fill yes)
		(layer "B.Cu")
		(net "GND")
	)
	(gr_poly
		(pts
			(arc
				(start 287.052512 -371.140228)
				(mid 286.803084 -371.140228)
				(end 287.052512 -371.140228)
			)
		)
		(stroke
			(width 0)
			(type solid)
		)
		(fill yes)
		(layer "B.Cu")
		(net "GND")
	)
	(gr_poly
		(pts
			(arc
				(start 287.052512 -369.938554)
				(mid 286.803084 -369.938554)
				(end 287.052512 -369.938554)
			)
		)
		(stroke
			(width 0)
			(type solid)
		)
		(fill yes)
		(layer "B.Cu")
		(net "GND")
	)
	(gr_poly
		(pts
			(arc
				(start 288.108136 -357.75773)
				(mid 287.858708 -357.75773)
				(end 288.108136 -357.75773)
			)
		)
		(stroke
			(width 0)
			(type solid)
		)
		(fill yes)
		(layer "B.Cu")
		(net "GND")
	)
	(gr_poly
		(pts
			(arc
				(start 288.108136 -354.732082)
				(mid 287.858708 -354.732082)
				(end 288.108136 -354.732082)
			)
		)
		(stroke
			(width 0)
			(type solid)
		)
		(fill yes)
		(layer "B.Cu")
		(net "GND")
	)
	(gr_poly
		(pts
			(arc
				(start 288.108136 -351.611438)
				(mid 287.858708 -351.611438)
				(end 288.108136 -351.611438)
			)
		)
		(stroke
			(width 0)
			(type solid)
		)
		(fill yes)
		(layer "B.Cu")
		(net "GND")
	)
	(gr_poly
		(pts
			(arc
				(start 288.108136 -348.58579)
				(mid 287.858708 -348.58579)
				(end 288.108136 -348.58579)
			)
		)
		(stroke
			(width 0)
			(type solid)
		)
		(fill yes)
		(layer "B.Cu")
		(net "GND")
	)
	(gr_poly
		(pts
			(arc
				(start 288.108136 -345.465146)
				(mid 287.858708 -345.465146)
				(end 288.108136 -345.465146)
			)
		)
		(stroke
			(width 0)
			(type solid)
		)
		(fill yes)
		(layer "B.Cu")
		(net "GND")
	)
	(gr_poly
		(pts
			(arc
				(start 288.108136 -342.439498)
				(mid 287.858708 -342.439498)
				(end 288.108136 -342.439498)
			)
		)
		(stroke
			(width 0)
			(type solid)
		)
		(fill yes)
		(layer "B.Cu")
		(net "GND")
	)
	(gr_poly
		(pts
			(arc
				(start 289.215576 -357.75773)
				(mid 288.966148 -357.75773)
				(end 289.215576 -357.75773)
			)
		)
		(stroke
			(width 0)
			(type solid)
		)
		(fill yes)
		(layer "B.Cu")
		(net "GND")
	)
	(gr_poly
		(pts
			(arc
				(start 289.215576 -354.732082)
				(mid 288.966148 -354.732082)
				(end 289.215576 -354.732082)
			)
		)
		(stroke
			(width 0)
			(type solid)
		)
		(fill yes)
		(layer "B.Cu")
		(net "GND")
	)
	(gr_poly
		(pts
			(arc
				(start 289.215576 -351.611438)
				(mid 288.966148 -351.611438)
				(end 289.215576 -351.611438)
			)
		)
		(stroke
			(width 0)
			(type solid)
		)
		(fill yes)
		(layer "B.Cu")
		(net "GND")
	)
	(gr_poly
		(pts
			(arc
				(start 289.215576 -348.58579)
				(mid 288.966148 -348.58579)
				(end 289.215576 -348.58579)
			)
		)
		(stroke
			(width 0)
			(type solid)
		)
		(fill yes)
		(layer "B.Cu")
		(net "GND")
	)
	(gr_poly
		(pts
			(arc
				(start 289.215576 -345.465146)
				(mid 288.966148 -345.465146)
				(end 289.215576 -345.465146)
			)
		)
		(stroke
			(width 0)
			(type solid)
		)
		(fill yes)
		(layer "B.Cu")
		(net "GND")
	)
	(gr_poly
		(pts
			(arc
				(start 289.215576 -342.439498)
				(mid 288.966148 -342.439498)
				(end 289.215576 -342.439498)
			)
		)
		(stroke
			(width 0)
			(type solid)
		)
		(fill yes)
		(layer "B.Cu")
		(net "GND")
	)
	(gr_poly
		(pts
			(arc
				(start 289.252406 -411.141926)
				(mid 289.002978 -411.141926)
				(end 289.252406 -411.141926)
			)
		)
		(stroke
			(width 0)
			(type solid)
		)
		(fill yes)
		(layer "B.Cu")
		(net "GND")
	)
	(gr_poly
		(pts
			(arc
				(start 289.252406 -409.940252)
				(mid 289.002978 -409.940252)
				(end 289.252406 -409.940252)
			)
		)
		(stroke
			(width 0)
			(type solid)
		)
		(fill yes)
		(layer "B.Cu")
		(net "GND")
	)
	(gr_poly
		(pts
			(arc
				(start 289.252406 -408.738578)
				(mid 289.002978 -408.738578)
				(end 289.252406 -408.738578)
			)
		)
		(stroke
			(width 0)
			(type solid)
		)
		(fill yes)
		(layer "B.Cu")
		(net "GND")
	)
	(gr_poly
		(pts
			(arc
				(start 289.252406 -407.24201)
				(mid 289.002978 -407.24201)
				(end 289.252406 -407.24201)
			)
		)
		(stroke
			(width 0)
			(type solid)
		)
		(fill yes)
		(layer "B.Cu")
		(net "GND")
	)
	(gr_poly
		(pts
			(arc
				(start 289.252406 -406.040336)
				(mid 289.002978 -406.040336)
				(end 289.252406 -406.040336)
			)
		)
		(stroke
			(width 0)
			(type solid)
		)
		(fill yes)
		(layer "B.Cu")
		(net "GND")
	)
	(gr_poly
		(pts
			(arc
				(start 289.252406 -404.838662)
				(mid 289.002978 -404.838662)
				(end 289.252406 -404.838662)
			)
		)
		(stroke
			(width 0)
			(type solid)
		)
		(fill yes)
		(layer "B.Cu")
		(net "GND")
	)
	(gr_poly
		(pts
			(arc
				(start 289.252406 -403.34184)
				(mid 289.002978 -403.34184)
				(end 289.252406 -403.34184)
			)
		)
		(stroke
			(width 0)
			(type solid)
		)
		(fill yes)
		(layer "B.Cu")
		(net "GND")
	)
	(gr_poly
		(pts
			(arc
				(start 289.252406 -402.140166)
				(mid 289.002978 -402.140166)
				(end 289.252406 -402.140166)
			)
		)
		(stroke
			(width 0)
			(type solid)
		)
		(fill yes)
		(layer "B.Cu")
		(net "GND")
	)
	(gr_poly
		(pts
			(arc
				(start 289.252406 -400.938492)
				(mid 289.002978 -400.938492)
				(end 289.252406 -400.938492)
			)
		)
		(stroke
			(width 0)
			(type solid)
		)
		(fill yes)
		(layer "B.Cu")
		(net "GND")
	)
	(gr_poly
		(pts
			(arc
				(start 289.252406 -399.441924)
				(mid 289.002978 -399.441924)
				(end 289.252406 -399.441924)
			)
		)
		(stroke
			(width 0)
			(type solid)
		)
		(fill yes)
		(layer "B.Cu")
		(net "GND")
	)
	(gr_poly
		(pts
			(arc
				(start 289.252406 -398.24025)
				(mid 289.002978 -398.24025)
				(end 289.252406 -398.24025)
			)
		)
		(stroke
			(width 0)
			(type solid)
		)
		(fill yes)
		(layer "B.Cu")
		(net "GND")
	)
	(gr_poly
		(pts
			(arc
				(start 289.252406 -397.038576)
				(mid 289.002978 -397.038576)
				(end 289.252406 -397.038576)
			)
		)
		(stroke
			(width 0)
			(type solid)
		)
		(fill yes)
		(layer "B.Cu")
		(net "GND")
	)
	(gr_poly
		(pts
			(arc
				(start 289.252406 -385.141978)
				(mid 289.002978 -385.141978)
				(end 289.252406 -385.141978)
			)
		)
		(stroke
			(width 0)
			(type solid)
		)
		(fill yes)
		(layer "B.Cu")
		(net "GND")
	)
	(gr_poly
		(pts
			(arc
				(start 289.252406 -383.940304)
				(mid 289.002978 -383.940304)
				(end 289.252406 -383.940304)
			)
		)
		(stroke
			(width 0)
			(type solid)
		)
		(fill yes)
		(layer "B.Cu")
		(net "GND")
	)
	(gr_poly
		(pts
			(arc
				(start 289.252406 -382.73863)
				(mid 289.002978 -382.73863)
				(end 289.252406 -382.73863)
			)
		)
		(stroke
			(width 0)
			(type solid)
		)
		(fill yes)
		(layer "B.Cu")
		(net "GND")
	)
	(gr_poly
		(pts
			(arc
				(start 289.252406 -381.242062)
				(mid 289.002978 -381.242062)
				(end 289.252406 -381.242062)
			)
		)
		(stroke
			(width 0)
			(type solid)
		)
		(fill yes)
		(layer "B.Cu")
		(net "GND")
	)
	(gr_poly
		(pts
			(arc
				(start 289.252406 -380.040388)
				(mid 289.002978 -380.040388)
				(end 289.252406 -380.040388)
			)
		)
		(stroke
			(width 0)
			(type solid)
		)
		(fill yes)
		(layer "B.Cu")
		(net "GND")
	)
	(gr_poly
		(pts
			(arc
				(start 289.252406 -378.838714)
				(mid 289.002978 -378.838714)
				(end 289.252406 -378.838714)
			)
		)
		(stroke
			(width 0)
			(type solid)
		)
		(fill yes)
		(layer "B.Cu")
		(net "GND")
	)
	(gr_poly
		(pts
			(arc
				(start 289.252406 -377.341892)
				(mid 289.002978 -377.341892)
				(end 289.252406 -377.341892)
			)
		)
		(stroke
			(width 0)
			(type solid)
		)
		(fill yes)
		(layer "B.Cu")
		(net "GND")
	)
	(gr_poly
		(pts
			(arc
				(start 289.252406 -376.140218)
				(mid 289.002978 -376.140218)
				(end 289.252406 -376.140218)
			)
		)
		(stroke
			(width 0)
			(type solid)
		)
		(fill yes)
		(layer "B.Cu")
		(net "GND")
	)
	(gr_poly
		(pts
			(arc
				(start 289.252406 -374.938544)
				(mid 289.002978 -374.938544)
				(end 289.252406 -374.938544)
			)
		)
		(stroke
			(width 0)
			(type solid)
		)
		(fill yes)
		(layer "B.Cu")
		(net "GND")
	)
	(gr_poly
		(pts
			(arc
				(start 289.252406 -373.441976)
				(mid 289.002978 -373.441976)
				(end 289.252406 -373.441976)
			)
		)
		(stroke
			(width 0)
			(type solid)
		)
		(fill yes)
		(layer "B.Cu")
		(net "GND")
	)
	(gr_poly
		(pts
			(arc
				(start 289.252406 -372.240302)
				(mid 289.002978 -372.240302)
				(end 289.252406 -372.240302)
			)
		)
		(stroke
			(width 0)
			(type solid)
		)
		(fill yes)
		(layer "B.Cu")
		(net "GND")
	)
	(gr_poly
		(pts
			(arc
				(start 289.252406 -371.038628)
				(mid 289.002978 -371.038628)
				(end 289.252406 -371.038628)
			)
		)
		(stroke
			(width 0)
			(type solid)
		)
		(fill yes)
		(layer "B.Cu")
		(net "GND")
	)
	(gr_poly
		(pts
			(arc
				(start 291.217096 -357.75773)
				(mid 290.967668 -357.75773)
				(end 291.217096 -357.75773)
			)
		)
		(stroke
			(width 0)
			(type solid)
		)
		(fill yes)
		(layer "B.Cu")
		(net "GND")
	)
	(gr_poly
		(pts
			(arc
				(start 291.217096 -354.732082)
				(mid 290.967668 -354.732082)
				(end 291.217096 -354.732082)
			)
		)
		(stroke
			(width 0)
			(type solid)
		)
		(fill yes)
		(layer "B.Cu")
		(net "GND")
	)
	(gr_poly
		(pts
			(arc
				(start 291.217096 -351.611438)
				(mid 290.967668 -351.611438)
				(end 291.217096 -351.611438)
			)
		)
		(stroke
			(width 0)
			(type solid)
		)
		(fill yes)
		(layer "B.Cu")
		(net "GND")
	)
	(gr_poly
		(pts
			(arc
				(start 291.217096 -348.58579)
				(mid 290.967668 -348.58579)
				(end 291.217096 -348.58579)
			)
		)
		(stroke
			(width 0)
			(type solid)
		)
		(fill yes)
		(layer "B.Cu")
		(net "GND")
	)
	(gr_poly
		(pts
			(arc
				(start 291.217096 -345.465146)
				(mid 290.967668 -345.465146)
				(end 291.217096 -345.465146)
			)
		)
		(stroke
			(width 0)
			(type solid)
		)
		(fill yes)
		(layer "B.Cu")
		(net "GND")
	)
	(gr_poly
		(pts
			(arc
				(start 291.217096 -342.439498)
				(mid 290.967668 -342.439498)
				(end 291.217096 -342.439498)
			)
		)
		(stroke
			(width 0)
			(type solid)
		)
		(fill yes)
		(layer "B.Cu")
		(net "GND")
	)
	(gr_poly
		(pts
			(arc
				(start 291.452554 -410.041852)
				(mid 291.203126 -410.041852)
				(end 291.452554 -410.041852)
			)
		)
		(stroke
			(width 0)
			(type solid)
		)
		(fill yes)
		(layer "B.Cu")
		(net "GND")
	)
	(gr_poly
		(pts
			(arc
				(start 291.452554 -408.840178)
				(mid 291.203126 -408.840178)
				(end 291.452554 -408.840178)
			)
		)
		(stroke
			(width 0)
			(type solid)
		)
		(fill yes)
		(layer "B.Cu")
		(net "GND")
	)
	(gr_poly
		(pts
			(arc
				(start 291.452554 -407.638504)
				(mid 291.203126 -407.638504)
				(end 291.452554 -407.638504)
			)
		)
		(stroke
			(width 0)
			(type solid)
		)
		(fill yes)
		(layer "B.Cu")
		(net "GND")
	)
	(gr_poly
		(pts
			(arc
				(start 291.452554 -406.141936)
				(mid 291.203126 -406.141936)
				(end 291.452554 -406.141936)
			)
		)
		(stroke
			(width 0)
			(type solid)
		)
		(fill yes)
		(layer "B.Cu")
		(net "GND")
	)
	(gr_poly
		(pts
			(arc
				(start 291.452554 -404.940262)
				(mid 291.203126 -404.940262)
				(end 291.452554 -404.940262)
			)
		)
		(stroke
			(width 0)
			(type solid)
		)
		(fill yes)
		(layer "B.Cu")
		(net "GND")
	)
	(gr_poly
		(pts
			(arc
				(start 291.452554 -403.738588)
				(mid 291.203126 -403.738588)
				(end 291.452554 -403.738588)
			)
		)
		(stroke
			(width 0)
			(type solid)
		)
		(fill yes)
		(layer "B.Cu")
		(net "GND")
	)
	(gr_poly
		(pts
			(arc
				(start 291.452554 -402.241766)
				(mid 291.203126 -402.241766)
				(end 291.452554 -402.241766)
			)
		)
		(stroke
			(width 0)
			(type solid)
		)
		(fill yes)
		(layer "B.Cu")
		(net "GND")
	)
	(gr_poly
		(pts
			(arc
				(start 291.452554 -401.040092)
				(mid 291.203126 -401.040092)
				(end 291.452554 -401.040092)
			)
		)
		(stroke
			(width 0)
			(type solid)
		)
		(fill yes)
		(layer "B.Cu")
		(net "GND")
	)
	(gr_poly
		(pts
			(arc
				(start 291.452554 -399.838418)
				(mid 291.203126 -399.838418)
				(end 291.452554 -399.838418)
			)
		)
		(stroke
			(width 0)
			(type solid)
		)
		(fill yes)
		(layer "B.Cu")
		(net "GND")
	)
	(gr_poly
		(pts
			(arc
				(start 291.452554 -398.34185)
				(mid 291.203126 -398.34185)
				(end 291.452554 -398.34185)
			)
		)
		(stroke
			(width 0)
			(type solid)
		)
		(fill yes)
		(layer "B.Cu")
		(net "GND")
	)
	(gr_poly
		(pts
			(arc
				(start 291.452554 -397.140176)
				(mid 291.203126 -397.140176)
				(end 291.452554 -397.140176)
			)
		)
		(stroke
			(width 0)
			(type solid)
		)
		(fill yes)
		(layer "B.Cu")
		(net "GND")
	)
	(gr_poly
		(pts
			(arc
				(start 291.452554 -395.938502)
				(mid 291.203126 -395.938502)
				(end 291.452554 -395.938502)
			)
		)
		(stroke
			(width 0)
			(type solid)
		)
		(fill yes)
		(layer "B.Cu")
		(net "GND")
	)
	(gr_poly
		(pts
			(arc
				(start 291.452554 -384.041904)
				(mid 291.203126 -384.041904)
				(end 291.452554 -384.041904)
			)
		)
		(stroke
			(width 0)
			(type solid)
		)
		(fill yes)
		(layer "B.Cu")
		(net "GND")
	)
	(gr_poly
		(pts
			(arc
				(start 291.452554 -382.84023)
				(mid 291.203126 -382.84023)
				(end 291.452554 -382.84023)
			)
		)
		(stroke
			(width 0)
			(type solid)
		)
		(fill yes)
		(layer "B.Cu")
		(net "GND")
	)
	(gr_poly
		(pts
			(arc
				(start 291.452554 -381.638556)
				(mid 291.203126 -381.638556)
				(end 291.452554 -381.638556)
			)
		)
		(stroke
			(width 0)
			(type solid)
		)
		(fill yes)
		(layer "B.Cu")
		(net "GND")
	)
	(gr_poly
		(pts
			(arc
				(start 291.452554 -380.141988)
				(mid 291.203126 -380.141988)
				(end 291.452554 -380.141988)
			)
		)
		(stroke
			(width 0)
			(type solid)
		)
		(fill yes)
		(layer "B.Cu")
		(net "GND")
	)
	(gr_poly
		(pts
			(arc
				(start 291.452554 -378.940314)
				(mid 291.203126 -378.940314)
				(end 291.452554 -378.940314)
			)
		)
		(stroke
			(width 0)
			(type solid)
		)
		(fill yes)
		(layer "B.Cu")
		(net "GND")
	)
	(gr_poly
		(pts
			(arc
				(start 291.452554 -377.73864)
				(mid 291.203126 -377.73864)
				(end 291.452554 -377.73864)
			)
		)
		(stroke
			(width 0)
			(type solid)
		)
		(fill yes)
		(layer "B.Cu")
		(net "GND")
	)
	(gr_poly
		(pts
			(arc
				(start 291.452554 -376.241818)
				(mid 291.203126 -376.241818)
				(end 291.452554 -376.241818)
			)
		)
		(stroke
			(width 0)
			(type solid)
		)
		(fill yes)
		(layer "B.Cu")
		(net "GND")
	)
	(gr_poly
		(pts
			(arc
				(start 291.452554 -375.040144)
				(mid 291.203126 -375.040144)
				(end 291.452554 -375.040144)
			)
		)
		(stroke
			(width 0)
			(type solid)
		)
		(fill yes)
		(layer "B.Cu")
		(net "GND")
	)
	(gr_poly
		(pts
			(arc
				(start 291.452554 -373.83847)
				(mid 291.203126 -373.83847)
				(end 291.452554 -373.83847)
			)
		)
		(stroke
			(width 0)
			(type solid)
		)
		(fill yes)
		(layer "B.Cu")
		(net "GND")
	)
	(gr_poly
		(pts
			(arc
				(start 291.452554 -372.341902)
				(mid 291.203126 -372.341902)
				(end 291.452554 -372.341902)
			)
		)
		(stroke
			(width 0)
			(type solid)
		)
		(fill yes)
		(layer "B.Cu")
		(net "GND")
	)
	(gr_poly
		(pts
			(arc
				(start 291.452554 -371.140228)
				(mid 291.203126 -371.140228)
				(end 291.452554 -371.140228)
			)
		)
		(stroke
			(width 0)
			(type solid)
		)
		(fill yes)
		(layer "B.Cu")
		(net "GND")
	)
	(gr_poly
		(pts
			(arc
				(start 291.452554 -369.938554)
				(mid 291.203126 -369.938554)
				(end 291.452554 -369.938554)
			)
		)
		(stroke
			(width 0)
			(type solid)
		)
		(fill yes)
		(layer "B.Cu")
		(net "GND")
	)
	(gr_poly
		(pts
			(arc
				(start 292.324536 -357.75773)
				(mid 292.075108 -357.75773)
				(end 292.324536 -357.75773)
			)
		)
		(stroke
			(width 0)
			(type solid)
		)
		(fill yes)
		(layer "B.Cu")
		(net "GND")
	)
	(gr_poly
		(pts
			(arc
				(start 292.324536 -354.732082)
				(mid 292.075108 -354.732082)
				(end 292.324536 -354.732082)
			)
		)
		(stroke
			(width 0)
			(type solid)
		)
		(fill yes)
		(layer "B.Cu")
		(net "GND")
	)
	(gr_poly
		(pts
			(arc
				(start 292.324536 -351.611438)
				(mid 292.075108 -351.611438)
				(end 292.324536 -351.611438)
			)
		)
		(stroke
			(width 0)
			(type solid)
		)
		(fill yes)
		(layer "B.Cu")
		(net "GND")
	)
	(gr_poly
		(pts
			(arc
				(start 292.324536 -348.58579)
				(mid 292.075108 -348.58579)
				(end 292.324536 -348.58579)
			)
		)
		(stroke
			(width 0)
			(type solid)
		)
		(fill yes)
		(layer "B.Cu")
		(net "GND")
	)
	(gr_poly
		(pts
			(arc
				(start 292.324536 -345.465146)
				(mid 292.075108 -345.465146)
				(end 292.324536 -345.465146)
			)
		)
		(stroke
			(width 0)
			(type solid)
		)
		(fill yes)
		(layer "B.Cu")
		(net "GND")
	)
	(gr_poly
		(pts
			(arc
				(start 292.324536 -342.439498)
				(mid 292.075108 -342.439498)
				(end 292.324536 -342.439498)
			)
		)
		(stroke
			(width 0)
			(type solid)
		)
		(fill yes)
		(layer "B.Cu")
		(net "GND")
	)
	(gr_poly
		(pts
			(arc
				(start 293.652448 -411.141926)
				(mid 293.40302 -411.141926)
				(end 293.652448 -411.141926)
			)
		)
		(stroke
			(width 0)
			(type solid)
		)
		(fill yes)
		(layer "B.Cu")
		(net "GND")
	)
	(gr_poly
		(pts
			(arc
				(start 293.652448 -409.940252)
				(mid 293.40302 -409.940252)
				(end 293.652448 -409.940252)
			)
		)
		(stroke
			(width 0)
			(type solid)
		)
		(fill yes)
		(layer "B.Cu")
		(net "GND")
	)
	(gr_poly
		(pts
			(arc
				(start 293.652448 -408.738578)
				(mid 293.40302 -408.738578)
				(end 293.652448 -408.738578)
			)
		)
		(stroke
			(width 0)
			(type solid)
		)
		(fill yes)
		(layer "B.Cu")
		(net "GND")
	)
	(gr_poly
		(pts
			(arc
				(start 293.652448 -407.24201)
				(mid 293.40302 -407.24201)
				(end 293.652448 -407.24201)
			)
		)
		(stroke
			(width 0)
			(type solid)
		)
		(fill yes)
		(layer "B.Cu")
		(net "GND")
	)
	(gr_poly
		(pts
			(arc
				(start 293.652448 -406.040336)
				(mid 293.40302 -406.040336)
				(end 293.652448 -406.040336)
			)
		)
		(stroke
			(width 0)
			(type solid)
		)
		(fill yes)
		(layer "B.Cu")
		(net "GND")
	)
	(gr_poly
		(pts
			(arc
				(start 293.652448 -404.838662)
				(mid 293.40302 -404.838662)
				(end 293.652448 -404.838662)
			)
		)
		(stroke
			(width 0)
			(type solid)
		)
		(fill yes)
		(layer "B.Cu")
		(net "GND")
	)
	(gr_poly
		(pts
			(arc
				(start 293.652448 -403.34184)
				(mid 293.40302 -403.34184)
				(end 293.652448 -403.34184)
			)
		)
		(stroke
			(width 0)
			(type solid)
		)
		(fill yes)
		(layer "B.Cu")
		(net "GND")
	)
	(gr_poly
		(pts
			(arc
				(start 293.652448 -402.140166)
				(mid 293.40302 -402.140166)
				(end 293.652448 -402.140166)
			)
		)
		(stroke
			(width 0)
			(type solid)
		)
		(fill yes)
		(layer "B.Cu")
		(net "GND")
	)
	(gr_poly
		(pts
			(arc
				(start 293.652448 -400.938492)
				(mid 293.40302 -400.938492)
				(end 293.652448 -400.938492)
			)
		)
		(stroke
			(width 0)
			(type solid)
		)
		(fill yes)
		(layer "B.Cu")
		(net "GND")
	)
	(gr_poly
		(pts
			(arc
				(start 293.652448 -399.441924)
				(mid 293.40302 -399.441924)
				(end 293.652448 -399.441924)
			)
		)
		(stroke
			(width 0)
			(type solid)
		)
		(fill yes)
		(layer "B.Cu")
		(net "GND")
	)
	(gr_poly
		(pts
			(arc
				(start 293.652448 -398.24025)
				(mid 293.40302 -398.24025)
				(end 293.652448 -398.24025)
			)
		)
		(stroke
			(width 0)
			(type solid)
		)
		(fill yes)
		(layer "B.Cu")
		(net "GND")
	)
	(gr_poly
		(pts
			(arc
				(start 293.652448 -397.038576)
				(mid 293.40302 -397.038576)
				(end 293.652448 -397.038576)
			)
		)
		(stroke
			(width 0)
			(type solid)
		)
		(fill yes)
		(layer "B.Cu")
		(net "GND")
	)
	(gr_poly
		(pts
			(arc
				(start 293.652448 -385.141978)
				(mid 293.40302 -385.141978)
				(end 293.652448 -385.141978)
			)
		)
		(stroke
			(width 0)
			(type solid)
		)
		(fill yes)
		(layer "B.Cu")
		(net "GND")
	)
	(gr_poly
		(pts
			(arc
				(start 293.652448 -383.940304)
				(mid 293.40302 -383.940304)
				(end 293.652448 -383.940304)
			)
		)
		(stroke
			(width 0)
			(type solid)
		)
		(fill yes)
		(layer "B.Cu")
		(net "GND")
	)
	(gr_poly
		(pts
			(arc
				(start 293.652448 -382.73863)
				(mid 293.40302 -382.73863)
				(end 293.652448 -382.73863)
			)
		)
		(stroke
			(width 0)
			(type solid)
		)
		(fill yes)
		(layer "B.Cu")
		(net "GND")
	)
	(gr_poly
		(pts
			(arc
				(start 293.652448 -381.242062)
				(mid 293.40302 -381.242062)
				(end 293.652448 -381.242062)
			)
		)
		(stroke
			(width 0)
			(type solid)
		)
		(fill yes)
		(layer "B.Cu")
		(net "GND")
	)
	(gr_poly
		(pts
			(arc
				(start 293.652448 -380.040388)
				(mid 293.40302 -380.040388)
				(end 293.652448 -380.040388)
			)
		)
		(stroke
			(width 0)
			(type solid)
		)
		(fill yes)
		(layer "B.Cu")
		(net "GND")
	)
	(gr_poly
		(pts
			(arc
				(start 293.652448 -378.838714)
				(mid 293.40302 -378.838714)
				(end 293.652448 -378.838714)
			)
		)
		(stroke
			(width 0)
			(type solid)
		)
		(fill yes)
		(layer "B.Cu")
		(net "GND")
	)
	(gr_poly
		(pts
			(arc
				(start 293.652448 -377.341892)
				(mid 293.40302 -377.341892)
				(end 293.652448 -377.341892)
			)
		)
		(stroke
			(width 0)
			(type solid)
		)
		(fill yes)
		(layer "B.Cu")
		(net "GND")
	)
	(gr_poly
		(pts
			(arc
				(start 293.652448 -376.140218)
				(mid 293.40302 -376.140218)
				(end 293.652448 -376.140218)
			)
		)
		(stroke
			(width 0)
			(type solid)
		)
		(fill yes)
		(layer "B.Cu")
		(net "GND")
	)
	(gr_poly
		(pts
			(arc
				(start 293.652448 -374.938544)
				(mid 293.40302 -374.938544)
				(end 293.652448 -374.938544)
			)
		)
		(stroke
			(width 0)
			(type solid)
		)
		(fill yes)
		(layer "B.Cu")
		(net "GND")
	)
	(gr_poly
		(pts
			(arc
				(start 293.652448 -373.441976)
				(mid 293.40302 -373.441976)
				(end 293.652448 -373.441976)
			)
		)
		(stroke
			(width 0)
			(type solid)
		)
		(fill yes)
		(layer "B.Cu")
		(net "GND")
	)
	(gr_poly
		(pts
			(arc
				(start 293.652448 -372.240302)
				(mid 293.40302 -372.240302)
				(end 293.652448 -372.240302)
			)
		)
		(stroke
			(width 0)
			(type solid)
		)
		(fill yes)
		(layer "B.Cu")
		(net "GND")
	)
	(gr_poly
		(pts
			(arc
				(start 293.652448 -371.038628)
				(mid 293.40302 -371.038628)
				(end 293.652448 -371.038628)
			)
		)
		(stroke
			(width 0)
			(type solid)
		)
		(fill yes)
		(layer "B.Cu")
		(net "GND")
	)
	(gr_poly
		(pts
			(arc
				(start 294.326056 -357.75773)
				(mid 294.076628 -357.75773)
				(end 294.326056 -357.75773)
			)
		)
		(stroke
			(width 0)
			(type solid)
		)
		(fill yes)
		(layer "B.Cu")
		(net "GND")
	)
	(gr_poly
		(pts
			(arc
				(start 294.326056 -354.732082)
				(mid 294.076628 -354.732082)
				(end 294.326056 -354.732082)
			)
		)
		(stroke
			(width 0)
			(type solid)
		)
		(fill yes)
		(layer "B.Cu")
		(net "GND")
	)
	(gr_poly
		(pts
			(arc
				(start 294.326056 -351.611438)
				(mid 294.076628 -351.611438)
				(end 294.326056 -351.611438)
			)
		)
		(stroke
			(width 0)
			(type solid)
		)
		(fill yes)
		(layer "B.Cu")
		(net "GND")
	)
	(gr_poly
		(pts
			(arc
				(start 294.326056 -348.58579)
				(mid 294.076628 -348.58579)
				(end 294.326056 -348.58579)
			)
		)
		(stroke
			(width 0)
			(type solid)
		)
		(fill yes)
		(layer "B.Cu")
		(net "GND")
	)
	(gr_poly
		(pts
			(arc
				(start 294.326056 -345.465146)
				(mid 294.076628 -345.465146)
				(end 294.326056 -345.465146)
			)
		)
		(stroke
			(width 0)
			(type solid)
		)
		(fill yes)
		(layer "B.Cu")
		(net "GND")
	)
	(gr_poly
		(pts
			(arc
				(start 294.326056 -342.439498)
				(mid 294.076628 -342.439498)
				(end 294.326056 -342.439498)
			)
		)
		(stroke
			(width 0)
			(type solid)
		)
		(fill yes)
		(layer "B.Cu")
		(net "GND")
	)
	(gr_poly
		(pts
			(arc
				(start 295.433496 -357.75773)
				(mid 295.184068 -357.75773)
				(end 295.433496 -357.75773)
			)
		)
		(stroke
			(width 0)
			(type solid)
		)
		(fill yes)
		(layer "B.Cu")
		(net "GND")
	)
	(gr_poly
		(pts
			(arc
				(start 295.433496 -354.732082)
				(mid 295.184068 -354.732082)
				(end 295.433496 -354.732082)
			)
		)
		(stroke
			(width 0)
			(type solid)
		)
		(fill yes)
		(layer "B.Cu")
		(net "GND")
	)
	(gr_poly
		(pts
			(arc
				(start 295.433496 -351.611438)
				(mid 295.184068 -351.611438)
				(end 295.433496 -351.611438)
			)
		)
		(stroke
			(width 0)
			(type solid)
		)
		(fill yes)
		(layer "B.Cu")
		(net "GND")
	)
	(gr_poly
		(pts
			(arc
				(start 295.433496 -348.58579)
				(mid 295.184068 -348.58579)
				(end 295.433496 -348.58579)
			)
		)
		(stroke
			(width 0)
			(type solid)
		)
		(fill yes)
		(layer "B.Cu")
		(net "GND")
	)
	(gr_poly
		(pts
			(arc
				(start 295.433496 -345.465146)
				(mid 295.184068 -345.465146)
				(end 295.433496 -345.465146)
			)
		)
		(stroke
			(width 0)
			(type solid)
		)
		(fill yes)
		(layer "B.Cu")
		(net "GND")
	)
	(gr_poly
		(pts
			(arc
				(start 295.433496 -342.439498)
				(mid 295.184068 -342.439498)
				(end 295.433496 -342.439498)
			)
		)
		(stroke
			(width 0)
			(type solid)
		)
		(fill yes)
		(layer "B.Cu")
		(net "GND")
	)
	(gr_poly
		(pts
			(arc
				(start 295.852596 -410.041852)
				(mid 295.603168 -410.041852)
				(end 295.852596 -410.041852)
			)
		)
		(stroke
			(width 0)
			(type solid)
		)
		(fill yes)
		(layer "B.Cu")
		(net "GND")
	)
	(gr_poly
		(pts
			(arc
				(start 295.852596 -408.840178)
				(mid 295.603168 -408.840178)
				(end 295.852596 -408.840178)
			)
		)
		(stroke
			(width 0)
			(type solid)
		)
		(fill yes)
		(layer "B.Cu")
		(net "GND")
	)
	(gr_poly
		(pts
			(arc
				(start 295.852596 -407.638504)
				(mid 295.603168 -407.638504)
				(end 295.852596 -407.638504)
			)
		)
		(stroke
			(width 0)
			(type solid)
		)
		(fill yes)
		(layer "B.Cu")
		(net "GND")
	)
	(gr_poly
		(pts
			(arc
				(start 295.852596 -406.141936)
				(mid 295.603168 -406.141936)
				(end 295.852596 -406.141936)
			)
		)
		(stroke
			(width 0)
			(type solid)
		)
		(fill yes)
		(layer "B.Cu")
		(net "GND")
	)
	(gr_poly
		(pts
			(arc
				(start 295.852596 -404.940262)
				(mid 295.603168 -404.940262)
				(end 295.852596 -404.940262)
			)
		)
		(stroke
			(width 0)
			(type solid)
		)
		(fill yes)
		(layer "B.Cu")
		(net "GND")
	)
	(gr_poly
		(pts
			(arc
				(start 295.852596 -403.738588)
				(mid 295.603168 -403.738588)
				(end 295.852596 -403.738588)
			)
		)
		(stroke
			(width 0)
			(type solid)
		)
		(fill yes)
		(layer "B.Cu")
		(net "GND")
	)
	(gr_poly
		(pts
			(arc
				(start 295.852596 -402.241766)
				(mid 295.603168 -402.241766)
				(end 295.852596 -402.241766)
			)
		)
		(stroke
			(width 0)
			(type solid)
		)
		(fill yes)
		(layer "B.Cu")
		(net "GND")
	)
	(gr_poly
		(pts
			(arc
				(start 295.852596 -401.040092)
				(mid 295.603168 -401.040092)
				(end 295.852596 -401.040092)
			)
		)
		(stroke
			(width 0)
			(type solid)
		)
		(fill yes)
		(layer "B.Cu")
		(net "GND")
	)
	(gr_poly
		(pts
			(arc
				(start 295.852596 -399.838418)
				(mid 295.603168 -399.838418)
				(end 295.852596 -399.838418)
			)
		)
		(stroke
			(width 0)
			(type solid)
		)
		(fill yes)
		(layer "B.Cu")
		(net "GND")
	)
	(gr_poly
		(pts
			(arc
				(start 295.852596 -398.34185)
				(mid 295.603168 -398.34185)
				(end 295.852596 -398.34185)
			)
		)
		(stroke
			(width 0)
			(type solid)
		)
		(fill yes)
		(layer "B.Cu")
		(net "GND")
	)
	(gr_poly
		(pts
			(arc
				(start 295.852596 -397.140176)
				(mid 295.603168 -397.140176)
				(end 295.852596 -397.140176)
			)
		)
		(stroke
			(width 0)
			(type solid)
		)
		(fill yes)
		(layer "B.Cu")
		(net "GND")
	)
	(gr_poly
		(pts
			(arc
				(start 295.852596 -395.938502)
				(mid 295.603168 -395.938502)
				(end 295.852596 -395.938502)
			)
		)
		(stroke
			(width 0)
			(type solid)
		)
		(fill yes)
		(layer "B.Cu")
		(net "GND")
	)
	(gr_poly
		(pts
			(arc
				(start 295.852596 -384.041904)
				(mid 295.603168 -384.041904)
				(end 295.852596 -384.041904)
			)
		)
		(stroke
			(width 0)
			(type solid)
		)
		(fill yes)
		(layer "B.Cu")
		(net "GND")
	)
	(gr_poly
		(pts
			(arc
				(start 295.852596 -382.84023)
				(mid 295.603168 -382.84023)
				(end 295.852596 -382.84023)
			)
		)
		(stroke
			(width 0)
			(type solid)
		)
		(fill yes)
		(layer "B.Cu")
		(net "GND")
	)
	(gr_poly
		(pts
			(arc
				(start 295.852596 -381.638556)
				(mid 295.603168 -381.638556)
				(end 295.852596 -381.638556)
			)
		)
		(stroke
			(width 0)
			(type solid)
		)
		(fill yes)
		(layer "B.Cu")
		(net "GND")
	)
	(gr_poly
		(pts
			(arc
				(start 295.852596 -380.141988)
				(mid 295.603168 -380.141988)
				(end 295.852596 -380.141988)
			)
		)
		(stroke
			(width 0)
			(type solid)
		)
		(fill yes)
		(layer "B.Cu")
		(net "GND")
	)
	(gr_poly
		(pts
			(arc
				(start 295.852596 -378.940314)
				(mid 295.603168 -378.940314)
				(end 295.852596 -378.940314)
			)
		)
		(stroke
			(width 0)
			(type solid)
		)
		(fill yes)
		(layer "B.Cu")
		(net "GND")
	)
	(gr_poly
		(pts
			(arc
				(start 295.852596 -377.73864)
				(mid 295.603168 -377.73864)
				(end 295.852596 -377.73864)
			)
		)
		(stroke
			(width 0)
			(type solid)
		)
		(fill yes)
		(layer "B.Cu")
		(net "GND")
	)
	(gr_poly
		(pts
			(arc
				(start 295.852596 -376.241818)
				(mid 295.603168 -376.241818)
				(end 295.852596 -376.241818)
			)
		)
		(stroke
			(width 0)
			(type solid)
		)
		(fill yes)
		(layer "B.Cu")
		(net "GND")
	)
	(gr_poly
		(pts
			(arc
				(start 295.852596 -375.040144)
				(mid 295.603168 -375.040144)
				(end 295.852596 -375.040144)
			)
		)
		(stroke
			(width 0)
			(type solid)
		)
		(fill yes)
		(layer "B.Cu")
		(net "GND")
	)
	(gr_poly
		(pts
			(arc
				(start 295.852596 -373.83847)
				(mid 295.603168 -373.83847)
				(end 295.852596 -373.83847)
			)
		)
		(stroke
			(width 0)
			(type solid)
		)
		(fill yes)
		(layer "B.Cu")
		(net "GND")
	)
	(gr_poly
		(pts
			(arc
				(start 295.852596 -372.341902)
				(mid 295.603168 -372.341902)
				(end 295.852596 -372.341902)
			)
		)
		(stroke
			(width 0)
			(type solid)
		)
		(fill yes)
		(layer "B.Cu")
		(net "GND")
	)
	(gr_poly
		(pts
			(arc
				(start 295.852596 -371.140228)
				(mid 295.603168 -371.140228)
				(end 295.852596 -371.140228)
			)
		)
		(stroke
			(width 0)
			(type solid)
		)
		(fill yes)
		(layer "B.Cu")
		(net "GND")
	)
	(gr_poly
		(pts
			(arc
				(start 295.852596 -369.938554)
				(mid 295.603168 -369.938554)
				(end 295.852596 -369.938554)
			)
		)
		(stroke
			(width 0)
			(type solid)
		)
		(fill yes)
		(layer "B.Cu")
		(net "GND")
	)
	(gr_poly
		(pts
			(arc
				(start 297.435016 -357.75773)
				(mid 297.185588 -357.75773)
				(end 297.435016 -357.75773)
			)
		)
		(stroke
			(width 0)
			(type solid)
		)
		(fill yes)
		(layer "B.Cu")
		(net "GND")
	)
	(gr_poly
		(pts
			(arc
				(start 297.435016 -354.732082)
				(mid 297.185588 -354.732082)
				(end 297.435016 -354.732082)
			)
		)
		(stroke
			(width 0)
			(type solid)
		)
		(fill yes)
		(layer "B.Cu")
		(net "GND")
	)
	(gr_poly
		(pts
			(arc
				(start 297.435016 -351.611438)
				(mid 297.185588 -351.611438)
				(end 297.435016 -351.611438)
			)
		)
		(stroke
			(width 0)
			(type solid)
		)
		(fill yes)
		(layer "B.Cu")
		(net "GND")
	)
	(gr_poly
		(pts
			(arc
				(start 297.435016 -348.58579)
				(mid 297.185588 -348.58579)
				(end 297.435016 -348.58579)
			)
		)
		(stroke
			(width 0)
			(type solid)
		)
		(fill yes)
		(layer "B.Cu")
		(net "GND")
	)
	(gr_poly
		(pts
			(arc
				(start 297.435016 -345.465146)
				(mid 297.185588 -345.465146)
				(end 297.435016 -345.465146)
			)
		)
		(stroke
			(width 0)
			(type solid)
		)
		(fill yes)
		(layer "B.Cu")
		(net "GND")
	)
	(gr_poly
		(pts
			(arc
				(start 297.435016 -342.439498)
				(mid 297.185588 -342.439498)
				(end 297.435016 -342.439498)
			)
		)
		(stroke
			(width 0)
			(type solid)
		)
		(fill yes)
		(layer "B.Cu")
		(net "GND")
	)
	(gr_poly
		(pts
			(arc
				(start 298.05249 -411.141926)
				(mid 297.803062 -411.141926)
				(end 298.05249 -411.141926)
			)
		)
		(stroke
			(width 0)
			(type solid)
		)
		(fill yes)
		(layer "B.Cu")
		(net "GND")
	)
	(gr_poly
		(pts
			(arc
				(start 298.05249 -409.940252)
				(mid 297.803062 -409.940252)
				(end 298.05249 -409.940252)
			)
		)
		(stroke
			(width 0)
			(type solid)
		)
		(fill yes)
		(layer "B.Cu")
		(net "GND")
	)
	(gr_poly
		(pts
			(arc
				(start 298.05249 -408.738578)
				(mid 297.803062 -408.738578)
				(end 298.05249 -408.738578)
			)
		)
		(stroke
			(width 0)
			(type solid)
		)
		(fill yes)
		(layer "B.Cu")
		(net "GND")
	)
	(gr_poly
		(pts
			(arc
				(start 298.05249 -407.24201)
				(mid 297.803062 -407.24201)
				(end 298.05249 -407.24201)
			)
		)
		(stroke
			(width 0)
			(type solid)
		)
		(fill yes)
		(layer "B.Cu")
		(net "GND")
	)
	(gr_poly
		(pts
			(arc
				(start 298.05249 -406.040336)
				(mid 297.803062 -406.040336)
				(end 298.05249 -406.040336)
			)
		)
		(stroke
			(width 0)
			(type solid)
		)
		(fill yes)
		(layer "B.Cu")
		(net "GND")
	)
	(gr_poly
		(pts
			(arc
				(start 298.05249 -404.838662)
				(mid 297.803062 -404.838662)
				(end 298.05249 -404.838662)
			)
		)
		(stroke
			(width 0)
			(type solid)
		)
		(fill yes)
		(layer "B.Cu")
		(net "GND")
	)
	(gr_poly
		(pts
			(arc
				(start 298.05249 -403.34184)
				(mid 297.803062 -403.34184)
				(end 298.05249 -403.34184)
			)
		)
		(stroke
			(width 0)
			(type solid)
		)
		(fill yes)
		(layer "B.Cu")
		(net "GND")
	)
	(gr_poly
		(pts
			(arc
				(start 298.05249 -402.140166)
				(mid 297.803062 -402.140166)
				(end 298.05249 -402.140166)
			)
		)
		(stroke
			(width 0)
			(type solid)
		)
		(fill yes)
		(layer "B.Cu")
		(net "GND")
	)
	(gr_poly
		(pts
			(arc
				(start 298.05249 -400.938492)
				(mid 297.803062 -400.938492)
				(end 298.05249 -400.938492)
			)
		)
		(stroke
			(width 0)
			(type solid)
		)
		(fill yes)
		(layer "B.Cu")
		(net "GND")
	)
	(gr_poly
		(pts
			(arc
				(start 298.05249 -399.441924)
				(mid 297.803062 -399.441924)
				(end 298.05249 -399.441924)
			)
		)
		(stroke
			(width 0)
			(type solid)
		)
		(fill yes)
		(layer "B.Cu")
		(net "GND")
	)
	(gr_poly
		(pts
			(arc
				(start 298.05249 -398.24025)
				(mid 297.803062 -398.24025)
				(end 298.05249 -398.24025)
			)
		)
		(stroke
			(width 0)
			(type solid)
		)
		(fill yes)
		(layer "B.Cu")
		(net "GND")
	)
	(gr_poly
		(pts
			(arc
				(start 298.05249 -397.038576)
				(mid 297.803062 -397.038576)
				(end 298.05249 -397.038576)
			)
		)
		(stroke
			(width 0)
			(type solid)
		)
		(fill yes)
		(layer "B.Cu")
		(net "GND")
	)
	(gr_poly
		(pts
			(arc
				(start 298.05249 -385.141978)
				(mid 297.803062 -385.141978)
				(end 298.05249 -385.141978)
			)
		)
		(stroke
			(width 0)
			(type solid)
		)
		(fill yes)
		(layer "B.Cu")
		(net "GND")
	)
	(gr_poly
		(pts
			(arc
				(start 298.05249 -383.940304)
				(mid 297.803062 -383.940304)
				(end 298.05249 -383.940304)
			)
		)
		(stroke
			(width 0)
			(type solid)
		)
		(fill yes)
		(layer "B.Cu")
		(net "GND")
	)
	(gr_poly
		(pts
			(arc
				(start 298.05249 -382.73863)
				(mid 297.803062 -382.73863)
				(end 298.05249 -382.73863)
			)
		)
		(stroke
			(width 0)
			(type solid)
		)
		(fill yes)
		(layer "B.Cu")
		(net "GND")
	)
	(gr_poly
		(pts
			(arc
				(start 298.05249 -381.242062)
				(mid 297.803062 -381.242062)
				(end 298.05249 -381.242062)
			)
		)
		(stroke
			(width 0)
			(type solid)
		)
		(fill yes)
		(layer "B.Cu")
		(net "GND")
	)
	(gr_poly
		(pts
			(arc
				(start 298.05249 -380.040388)
				(mid 297.803062 -380.040388)
				(end 298.05249 -380.040388)
			)
		)
		(stroke
			(width 0)
			(type solid)
		)
		(fill yes)
		(layer "B.Cu")
		(net "GND")
	)
	(gr_poly
		(pts
			(arc
				(start 298.05249 -378.838714)
				(mid 297.803062 -378.838714)
				(end 298.05249 -378.838714)
			)
		)
		(stroke
			(width 0)
			(type solid)
		)
		(fill yes)
		(layer "B.Cu")
		(net "GND")
	)
	(gr_poly
		(pts
			(arc
				(start 298.05249 -377.341892)
				(mid 297.803062 -377.341892)
				(end 298.05249 -377.341892)
			)
		)
		(stroke
			(width 0)
			(type solid)
		)
		(fill yes)
		(layer "B.Cu")
		(net "GND")
	)
	(gr_poly
		(pts
			(arc
				(start 298.05249 -376.140218)
				(mid 297.803062 -376.140218)
				(end 298.05249 -376.140218)
			)
		)
		(stroke
			(width 0)
			(type solid)
		)
		(fill yes)
		(layer "B.Cu")
		(net "GND")
	)
	(gr_poly
		(pts
			(arc
				(start 298.05249 -374.938544)
				(mid 297.803062 -374.938544)
				(end 298.05249 -374.938544)
			)
		)
		(stroke
			(width 0)
			(type solid)
		)
		(fill yes)
		(layer "B.Cu")
		(net "GND")
	)
	(gr_poly
		(pts
			(arc
				(start 298.05249 -373.441976)
				(mid 297.803062 -373.441976)
				(end 298.05249 -373.441976)
			)
		)
		(stroke
			(width 0)
			(type solid)
		)
		(fill yes)
		(layer "B.Cu")
		(net "GND")
	)
	(gr_poly
		(pts
			(arc
				(start 298.05249 -372.240302)
				(mid 297.803062 -372.240302)
				(end 298.05249 -372.240302)
			)
		)
		(stroke
			(width 0)
			(type solid)
		)
		(fill yes)
		(layer "B.Cu")
		(net "GND")
	)
	(gr_poly
		(pts
			(arc
				(start 298.05249 -371.038628)
				(mid 297.803062 -371.038628)
				(end 298.05249 -371.038628)
			)
		)
		(stroke
			(width 0)
			(type solid)
		)
		(fill yes)
		(layer "B.Cu")
		(net "GND")
	)
	(gr_poly
		(pts
			(arc
				(start 298.542456 -357.75773)
				(mid 298.293028 -357.75773)
				(end 298.542456 -357.75773)
			)
		)
		(stroke
			(width 0)
			(type solid)
		)
		(fill yes)
		(layer "B.Cu")
		(net "GND")
	)
	(gr_poly
		(pts
			(arc
				(start 298.542456 -354.732082)
				(mid 298.293028 -354.732082)
				(end 298.542456 -354.732082)
			)
		)
		(stroke
			(width 0)
			(type solid)
		)
		(fill yes)
		(layer "B.Cu")
		(net "GND")
	)
	(gr_poly
		(pts
			(arc
				(start 298.542456 -351.611438)
				(mid 298.293028 -351.611438)
				(end 298.542456 -351.611438)
			)
		)
		(stroke
			(width 0)
			(type solid)
		)
		(fill yes)
		(layer "B.Cu")
		(net "GND")
	)
	(gr_poly
		(pts
			(arc
				(start 298.542456 -348.58579)
				(mid 298.293028 -348.58579)
				(end 298.542456 -348.58579)
			)
		)
		(stroke
			(width 0)
			(type solid)
		)
		(fill yes)
		(layer "B.Cu")
		(net "GND")
	)
	(gr_poly
		(pts
			(arc
				(start 298.542456 -345.465146)
				(mid 298.293028 -345.465146)
				(end 298.542456 -345.465146)
			)
		)
		(stroke
			(width 0)
			(type solid)
		)
		(fill yes)
		(layer "B.Cu")
		(net "GND")
	)
	(gr_poly
		(pts
			(arc
				(start 298.542456 -342.439498)
				(mid 298.293028 -342.439498)
				(end 298.542456 -342.439498)
			)
		)
		(stroke
			(width 0)
			(type solid)
		)
		(fill yes)
		(layer "B.Cu")
		(net "GND")
	)
	(gr_poly
		(pts
			(arc
				(start 300.162468 -290.066984)
				(mid 300.181855 -290.063034)
				(end 300.198282 -290.051998)
			)
			(xy 300.200822 -290.049458) (xy 300.208442 -290.030916)
			(arc
				(start 300.208442 -289.559492)
				(mid 300.193563 -289.523571)
				(end 300.157642 -289.508692)
			)
			(arc
				(start 282.728416 -289.508692)
				(mid 282.709029 -289.512642)
				(end 282.692602 -289.523678)
			)
			(arc
				(start 282.621228 -289.595052)
				(mid 282.610117 -289.611586)
				(end 282.606242 -289.63112)
			)
			(xy 282.606242 -290.030916) (xy 282.613862 -290.049458)
			(arc
				(start 282.616402 -290.051998)
				(mid 282.632819 -290.06306)
				(end 282.652216 -290.066984)
			)
		)
		(stroke
			(width 0)
			(type solid)
		)
		(fill yes)
		(layer "B.Cu")
		(net "GND")
	)
	(gr_poly
		(pts
			(arc
				(start 300.252384 -410.041852)
				(mid 300.002956 -410.041852)
				(end 300.252384 -410.041852)
			)
		)
		(stroke
			(width 0)
			(type solid)
		)
		(fill yes)
		(layer "B.Cu")
		(net "GND")
	)
	(gr_poly
		(pts
			(arc
				(start 300.252384 -408.840178)
				(mid 300.002956 -408.840178)
				(end 300.252384 -408.840178)
			)
		)
		(stroke
			(width 0)
			(type solid)
		)
		(fill yes)
		(layer "B.Cu")
		(net "GND")
	)
	(gr_poly
		(pts
			(arc
				(start 300.252384 -407.638504)
				(mid 300.002956 -407.638504)
				(end 300.252384 -407.638504)
			)
		)
		(stroke
			(width 0)
			(type solid)
		)
		(fill yes)
		(layer "B.Cu")
		(net "GND")
	)
	(gr_poly
		(pts
			(arc
				(start 300.252384 -406.141936)
				(mid 300.002956 -406.141936)
				(end 300.252384 -406.141936)
			)
		)
		(stroke
			(width 0)
			(type solid)
		)
		(fill yes)
		(layer "B.Cu")
		(net "GND")
	)
	(gr_poly
		(pts
			(arc
				(start 300.252384 -404.940262)
				(mid 300.002956 -404.940262)
				(end 300.252384 -404.940262)
			)
		)
		(stroke
			(width 0)
			(type solid)
		)
		(fill yes)
		(layer "B.Cu")
		(net "GND")
	)
	(gr_poly
		(pts
			(arc
				(start 300.252384 -403.738588)
				(mid 300.002956 -403.738588)
				(end 300.252384 -403.738588)
			)
		)
		(stroke
			(width 0)
			(type solid)
		)
		(fill yes)
		(layer "B.Cu")
		(net "GND")
	)
	(gr_poly
		(pts
			(arc
				(start 300.252384 -402.241766)
				(mid 300.002956 -402.241766)
				(end 300.252384 -402.241766)
			)
		)
		(stroke
			(width 0)
			(type solid)
		)
		(fill yes)
		(layer "B.Cu")
		(net "GND")
	)
	(gr_poly
		(pts
			(arc
				(start 300.252384 -401.040092)
				(mid 300.002956 -401.040092)
				(end 300.252384 -401.040092)
			)
		)
		(stroke
			(width 0)
			(type solid)
		)
		(fill yes)
		(layer "B.Cu")
		(net "GND")
	)
	(gr_poly
		(pts
			(arc
				(start 300.252384 -399.838418)
				(mid 300.002956 -399.838418)
				(end 300.252384 -399.838418)
			)
		)
		(stroke
			(width 0)
			(type solid)
		)
		(fill yes)
		(layer "B.Cu")
		(net "GND")
	)
	(gr_poly
		(pts
			(arc
				(start 300.252384 -398.34185)
				(mid 300.002956 -398.34185)
				(end 300.252384 -398.34185)
			)
		)
		(stroke
			(width 0)
			(type solid)
		)
		(fill yes)
		(layer "B.Cu")
		(net "GND")
	)
	(gr_poly
		(pts
			(arc
				(start 300.252384 -397.140176)
				(mid 300.002956 -397.140176)
				(end 300.252384 -397.140176)
			)
		)
		(stroke
			(width 0)
			(type solid)
		)
		(fill yes)
		(layer "B.Cu")
		(net "GND")
	)
	(gr_poly
		(pts
			(arc
				(start 300.252384 -395.938502)
				(mid 300.002956 -395.938502)
				(end 300.252384 -395.938502)
			)
		)
		(stroke
			(width 0)
			(type solid)
		)
		(fill yes)
		(layer "B.Cu")
		(net "GND")
	)
	(gr_poly
		(pts
			(arc
				(start 300.252384 -384.041904)
				(mid 300.002956 -384.041904)
				(end 300.252384 -384.041904)
			)
		)
		(stroke
			(width 0)
			(type solid)
		)
		(fill yes)
		(layer "B.Cu")
		(net "GND")
	)
	(gr_poly
		(pts
			(arc
				(start 300.252384 -382.84023)
				(mid 300.002956 -382.84023)
				(end 300.252384 -382.84023)
			)
		)
		(stroke
			(width 0)
			(type solid)
		)
		(fill yes)
		(layer "B.Cu")
		(net "GND")
	)
	(gr_poly
		(pts
			(arc
				(start 300.252384 -381.638556)
				(mid 300.002956 -381.638556)
				(end 300.252384 -381.638556)
			)
		)
		(stroke
			(width 0)
			(type solid)
		)
		(fill yes)
		(layer "B.Cu")
		(net "GND")
	)
	(gr_poly
		(pts
			(arc
				(start 300.252384 -380.141988)
				(mid 300.002956 -380.141988)
				(end 300.252384 -380.141988)
			)
		)
		(stroke
			(width 0)
			(type solid)
		)
		(fill yes)
		(layer "B.Cu")
		(net "GND")
	)
	(gr_poly
		(pts
			(arc
				(start 300.252384 -378.940314)
				(mid 300.002956 -378.940314)
				(end 300.252384 -378.940314)
			)
		)
		(stroke
			(width 0)
			(type solid)
		)
		(fill yes)
		(layer "B.Cu")
		(net "GND")
	)
	(gr_poly
		(pts
			(arc
				(start 300.252384 -377.73864)
				(mid 300.002956 -377.73864)
				(end 300.252384 -377.73864)
			)
		)
		(stroke
			(width 0)
			(type solid)
		)
		(fill yes)
		(layer "B.Cu")
		(net "GND")
	)
	(gr_poly
		(pts
			(arc
				(start 300.252384 -376.241818)
				(mid 300.002956 -376.241818)
				(end 300.252384 -376.241818)
			)
		)
		(stroke
			(width 0)
			(type solid)
		)
		(fill yes)
		(layer "B.Cu")
		(net "GND")
	)
	(gr_poly
		(pts
			(arc
				(start 300.252384 -375.040144)
				(mid 300.002956 -375.040144)
				(end 300.252384 -375.040144)
			)
		)
		(stroke
			(width 0)
			(type solid)
		)
		(fill yes)
		(layer "B.Cu")
		(net "GND")
	)
	(gr_poly
		(pts
			(arc
				(start 300.252384 -373.83847)
				(mid 300.002956 -373.83847)
				(end 300.252384 -373.83847)
			)
		)
		(stroke
			(width 0)
			(type solid)
		)
		(fill yes)
		(layer "B.Cu")
		(net "GND")
	)
	(gr_poly
		(pts
			(arc
				(start 300.252384 -372.341902)
				(mid 300.002956 -372.341902)
				(end 300.252384 -372.341902)
			)
		)
		(stroke
			(width 0)
			(type solid)
		)
		(fill yes)
		(layer "B.Cu")
		(net "GND")
	)
	(gr_poly
		(pts
			(arc
				(start 300.252384 -371.140228)
				(mid 300.002956 -371.140228)
				(end 300.252384 -371.140228)
			)
		)
		(stroke
			(width 0)
			(type solid)
		)
		(fill yes)
		(layer "B.Cu")
		(net "GND")
	)
	(gr_poly
		(pts
			(arc
				(start 300.252384 -369.938554)
				(mid 300.002956 -369.938554)
				(end 300.252384 -369.938554)
			)
		)
		(stroke
			(width 0)
			(type solid)
		)
		(fill yes)
		(layer "B.Cu")
		(net "GND")
	)
	(gr_poly
		(pts
			(arc
				(start 300.543976 -357.75773)
				(mid 300.294548 -357.75773)
				(end 300.543976 -357.75773)
			)
		)
		(stroke
			(width 0)
			(type solid)
		)
		(fill yes)
		(layer "B.Cu")
		(net "GND")
	)
	(gr_poly
		(pts
			(arc
				(start 300.543976 -354.732082)
				(mid 300.294548 -354.732082)
				(end 300.543976 -354.732082)
			)
		)
		(stroke
			(width 0)
			(type solid)
		)
		(fill yes)
		(layer "B.Cu")
		(net "GND")
	)
	(gr_poly
		(pts
			(arc
				(start 300.543976 -351.611438)
				(mid 300.294548 -351.611438)
				(end 300.543976 -351.611438)
			)
		)
		(stroke
			(width 0)
			(type solid)
		)
		(fill yes)
		(layer "B.Cu")
		(net "GND")
	)
	(gr_poly
		(pts
			(arc
				(start 300.543976 -348.58579)
				(mid 300.294548 -348.58579)
				(end 300.543976 -348.58579)
			)
		)
		(stroke
			(width 0)
			(type solid)
		)
		(fill yes)
		(layer "B.Cu")
		(net "GND")
	)
	(gr_poly
		(pts
			(arc
				(start 300.543976 -345.465146)
				(mid 300.294548 -345.465146)
				(end 300.543976 -345.465146)
			)
		)
		(stroke
			(width 0)
			(type solid)
		)
		(fill yes)
		(layer "B.Cu")
		(net "GND")
	)
	(gr_poly
		(pts
			(arc
				(start 300.543976 -342.439498)
				(mid 300.294548 -342.439498)
				(end 300.543976 -342.439498)
			)
		)
		(stroke
			(width 0)
			(type solid)
		)
		(fill yes)
		(layer "B.Cu")
		(net "GND")
	)
	(gr_poly
		(pts
			(arc
				(start 302.452532 -411.141926)
				(mid 302.203104 -411.141926)
				(end 302.452532 -411.141926)
			)
		)
		(stroke
			(width 0)
			(type solid)
		)
		(fill yes)
		(layer "B.Cu")
		(net "GND")
	)
	(gr_poly
		(pts
			(arc
				(start 302.452532 -409.940252)
				(mid 302.203104 -409.940252)
				(end 302.452532 -409.940252)
			)
		)
		(stroke
			(width 0)
			(type solid)
		)
		(fill yes)
		(layer "B.Cu")
		(net "GND")
	)
	(gr_poly
		(pts
			(arc
				(start 302.452532 -408.738578)
				(mid 302.203104 -408.738578)
				(end 302.452532 -408.738578)
			)
		)
		(stroke
			(width 0)
			(type solid)
		)
		(fill yes)
		(layer "B.Cu")
		(net "GND")
	)
	(gr_poly
		(pts
			(arc
				(start 302.452532 -407.24201)
				(mid 302.203104 -407.24201)
				(end 302.452532 -407.24201)
			)
		)
		(stroke
			(width 0)
			(type solid)
		)
		(fill yes)
		(layer "B.Cu")
		(net "GND")
	)
	(gr_poly
		(pts
			(arc
				(start 302.452532 -406.040336)
				(mid 302.203104 -406.040336)
				(end 302.452532 -406.040336)
			)
		)
		(stroke
			(width 0)
			(type solid)
		)
		(fill yes)
		(layer "B.Cu")
		(net "GND")
	)
	(gr_poly
		(pts
			(arc
				(start 302.452532 -404.838662)
				(mid 302.203104 -404.838662)
				(end 302.452532 -404.838662)
			)
		)
		(stroke
			(width 0)
			(type solid)
		)
		(fill yes)
		(layer "B.Cu")
		(net "GND")
	)
	(gr_poly
		(pts
			(arc
				(start 302.452532 -403.34184)
				(mid 302.203104 -403.34184)
				(end 302.452532 -403.34184)
			)
		)
		(stroke
			(width 0)
			(type solid)
		)
		(fill yes)
		(layer "B.Cu")
		(net "GND")
	)
	(gr_poly
		(pts
			(arc
				(start 302.452532 -402.140166)
				(mid 302.203104 -402.140166)
				(end 302.452532 -402.140166)
			)
		)
		(stroke
			(width 0)
			(type solid)
		)
		(fill yes)
		(layer "B.Cu")
		(net "GND")
	)
	(gr_poly
		(pts
			(arc
				(start 302.452532 -400.938492)
				(mid 302.203104 -400.938492)
				(end 302.452532 -400.938492)
			)
		)
		(stroke
			(width 0)
			(type solid)
		)
		(fill yes)
		(layer "B.Cu")
		(net "GND")
	)
	(gr_poly
		(pts
			(arc
				(start 302.452532 -399.441924)
				(mid 302.203104 -399.441924)
				(end 302.452532 -399.441924)
			)
		)
		(stroke
			(width 0)
			(type solid)
		)
		(fill yes)
		(layer "B.Cu")
		(net "GND")
	)
	(gr_poly
		(pts
			(arc
				(start 302.452532 -398.24025)
				(mid 302.203104 -398.24025)
				(end 302.452532 -398.24025)
			)
		)
		(stroke
			(width 0)
			(type solid)
		)
		(fill yes)
		(layer "B.Cu")
		(net "GND")
	)
	(gr_poly
		(pts
			(arc
				(start 302.452532 -397.038576)
				(mid 302.203104 -397.038576)
				(end 302.452532 -397.038576)
			)
		)
		(stroke
			(width 0)
			(type solid)
		)
		(fill yes)
		(layer "B.Cu")
		(net "GND")
	)
	(gr_poly
		(pts
			(arc
				(start 302.452532 -385.141978)
				(mid 302.203104 -385.141978)
				(end 302.452532 -385.141978)
			)
		)
		(stroke
			(width 0)
			(type solid)
		)
		(fill yes)
		(layer "B.Cu")
		(net "GND")
	)
	(gr_poly
		(pts
			(arc
				(start 302.452532 -383.940304)
				(mid 302.203104 -383.940304)
				(end 302.452532 -383.940304)
			)
		)
		(stroke
			(width 0)
			(type solid)
		)
		(fill yes)
		(layer "B.Cu")
		(net "GND")
	)
	(gr_poly
		(pts
			(arc
				(start 302.452532 -382.73863)
				(mid 302.203104 -382.73863)
				(end 302.452532 -382.73863)
			)
		)
		(stroke
			(width 0)
			(type solid)
		)
		(fill yes)
		(layer "B.Cu")
		(net "GND")
	)
	(gr_poly
		(pts
			(arc
				(start 302.452532 -381.242062)
				(mid 302.203104 -381.242062)
				(end 302.452532 -381.242062)
			)
		)
		(stroke
			(width 0)
			(type solid)
		)
		(fill yes)
		(layer "B.Cu")
		(net "GND")
	)
	(gr_poly
		(pts
			(arc
				(start 302.452532 -380.040388)
				(mid 302.203104 -380.040388)
				(end 302.452532 -380.040388)
			)
		)
		(stroke
			(width 0)
			(type solid)
		)
		(fill yes)
		(layer "B.Cu")
		(net "GND")
	)
	(gr_poly
		(pts
			(arc
				(start 302.452532 -378.838714)
				(mid 302.203104 -378.838714)
				(end 302.452532 -378.838714)
			)
		)
		(stroke
			(width 0)
			(type solid)
		)
		(fill yes)
		(layer "B.Cu")
		(net "GND")
	)
	(gr_poly
		(pts
			(arc
				(start 302.452532 -377.341892)
				(mid 302.203104 -377.341892)
				(end 302.452532 -377.341892)
			)
		)
		(stroke
			(width 0)
			(type solid)
		)
		(fill yes)
		(layer "B.Cu")
		(net "GND")
	)
	(gr_poly
		(pts
			(arc
				(start 302.452532 -376.140218)
				(mid 302.203104 -376.140218)
				(end 302.452532 -376.140218)
			)
		)
		(stroke
			(width 0)
			(type solid)
		)
		(fill yes)
		(layer "B.Cu")
		(net "GND")
	)
	(gr_poly
		(pts
			(arc
				(start 302.452532 -374.938544)
				(mid 302.203104 -374.938544)
				(end 302.452532 -374.938544)
			)
		)
		(stroke
			(width 0)
			(type solid)
		)
		(fill yes)
		(layer "B.Cu")
		(net "GND")
	)
	(gr_poly
		(pts
			(arc
				(start 302.452532 -373.441976)
				(mid 302.203104 -373.441976)
				(end 302.452532 -373.441976)
			)
		)
		(stroke
			(width 0)
			(type solid)
		)
		(fill yes)
		(layer "B.Cu")
		(net "GND")
	)
	(gr_poly
		(pts
			(arc
				(start 302.452532 -372.240302)
				(mid 302.203104 -372.240302)
				(end 302.452532 -372.240302)
			)
		)
		(stroke
			(width 0)
			(type solid)
		)
		(fill yes)
		(layer "B.Cu")
		(net "GND")
	)
	(gr_poly
		(pts
			(arc
				(start 302.452532 -371.038628)
				(mid 302.203104 -371.038628)
				(end 302.452532 -371.038628)
			)
		)
		(stroke
			(width 0)
			(type solid)
		)
		(fill yes)
		(layer "B.Cu")
		(net "GND")
	)
	(gr_poly
		(pts
			(arc
				(start 304.652426 -410.041852)
				(mid 304.402998 -410.041852)
				(end 304.652426 -410.041852)
			)
		)
		(stroke
			(width 0)
			(type solid)
		)
		(fill yes)
		(layer "B.Cu")
		(net "GND")
	)
	(gr_poly
		(pts
			(arc
				(start 304.652426 -408.840178)
				(mid 304.402998 -408.840178)
				(end 304.652426 -408.840178)
			)
		)
		(stroke
			(width 0)
			(type solid)
		)
		(fill yes)
		(layer "B.Cu")
		(net "GND")
	)
	(gr_poly
		(pts
			(arc
				(start 304.652426 -407.638504)
				(mid 304.402998 -407.638504)
				(end 304.652426 -407.638504)
			)
		)
		(stroke
			(width 0)
			(type solid)
		)
		(fill yes)
		(layer "B.Cu")
		(net "GND")
	)
	(gr_poly
		(pts
			(arc
				(start 304.652426 -406.141936)
				(mid 304.402998 -406.141936)
				(end 304.652426 -406.141936)
			)
		)
		(stroke
			(width 0)
			(type solid)
		)
		(fill yes)
		(layer "B.Cu")
		(net "GND")
	)
	(gr_poly
		(pts
			(arc
				(start 304.652426 -404.940262)
				(mid 304.402998 -404.940262)
				(end 304.652426 -404.940262)
			)
		)
		(stroke
			(width 0)
			(type solid)
		)
		(fill yes)
		(layer "B.Cu")
		(net "GND")
	)
	(gr_poly
		(pts
			(arc
				(start 304.652426 -403.738588)
				(mid 304.402998 -403.738588)
				(end 304.652426 -403.738588)
			)
		)
		(stroke
			(width 0)
			(type solid)
		)
		(fill yes)
		(layer "B.Cu")
		(net "GND")
	)
	(gr_poly
		(pts
			(arc
				(start 304.652426 -402.241766)
				(mid 304.402998 -402.241766)
				(end 304.652426 -402.241766)
			)
		)
		(stroke
			(width 0)
			(type solid)
		)
		(fill yes)
		(layer "B.Cu")
		(net "GND")
	)
	(gr_poly
		(pts
			(arc
				(start 304.652426 -401.040092)
				(mid 304.402998 -401.040092)
				(end 304.652426 -401.040092)
			)
		)
		(stroke
			(width 0)
			(type solid)
		)
		(fill yes)
		(layer "B.Cu")
		(net "GND")
	)
	(gr_poly
		(pts
			(arc
				(start 304.652426 -399.838418)
				(mid 304.402998 -399.838418)
				(end 304.652426 -399.838418)
			)
		)
		(stroke
			(width 0)
			(type solid)
		)
		(fill yes)
		(layer "B.Cu")
		(net "GND")
	)
	(gr_poly
		(pts
			(arc
				(start 304.652426 -398.34185)
				(mid 304.402998 -398.34185)
				(end 304.652426 -398.34185)
			)
		)
		(stroke
			(width 0)
			(type solid)
		)
		(fill yes)
		(layer "B.Cu")
		(net "GND")
	)
	(gr_poly
		(pts
			(arc
				(start 304.652426 -397.140176)
				(mid 304.402998 -397.140176)
				(end 304.652426 -397.140176)
			)
		)
		(stroke
			(width 0)
			(type solid)
		)
		(fill yes)
		(layer "B.Cu")
		(net "GND")
	)
	(gr_poly
		(pts
			(arc
				(start 304.652426 -395.938502)
				(mid 304.402998 -395.938502)
				(end 304.652426 -395.938502)
			)
		)
		(stroke
			(width 0)
			(type solid)
		)
		(fill yes)
		(layer "B.Cu")
		(net "GND")
	)
	(gr_poly
		(pts
			(arc
				(start 304.652426 -384.042158)
				(mid 304.402998 -384.042158)
				(end 304.652426 -384.042158)
			)
		)
		(stroke
			(width 0)
			(type solid)
		)
		(fill yes)
		(layer "B.Cu")
		(net "GND")
	)
	(gr_poly
		(pts
			(arc
				(start 304.652426 -382.840484)
				(mid 304.402998 -382.840484)
				(end 304.652426 -382.840484)
			)
		)
		(stroke
			(width 0)
			(type solid)
		)
		(fill yes)
		(layer "B.Cu")
		(net "GND")
	)
	(gr_poly
		(pts
			(arc
				(start 304.652426 -381.63881)
				(mid 304.402998 -381.63881)
				(end 304.652426 -381.63881)
			)
		)
		(stroke
			(width 0)
			(type solid)
		)
		(fill yes)
		(layer "B.Cu")
		(net "GND")
	)
	(gr_poly
		(pts
			(arc
				(start 304.652426 -380.142242)
				(mid 304.402998 -380.142242)
				(end 304.652426 -380.142242)
			)
		)
		(stroke
			(width 0)
			(type solid)
		)
		(fill yes)
		(layer "B.Cu")
		(net "GND")
	)
	(gr_poly
		(pts
			(arc
				(start 304.652426 -378.940568)
				(mid 304.402998 -378.940568)
				(end 304.652426 -378.940568)
			)
		)
		(stroke
			(width 0)
			(type solid)
		)
		(fill yes)
		(layer "B.Cu")
		(net "GND")
	)
	(gr_poly
		(pts
			(arc
				(start 304.652426 -377.738894)
				(mid 304.402998 -377.738894)
				(end 304.652426 -377.738894)
			)
		)
		(stroke
			(width 0)
			(type solid)
		)
		(fill yes)
		(layer "B.Cu")
		(net "GND")
	)
	(gr_poly
		(pts
			(arc
				(start 304.652426 -376.242072)
				(mid 304.402998 -376.242072)
				(end 304.652426 -376.242072)
			)
		)
		(stroke
			(width 0)
			(type solid)
		)
		(fill yes)
		(layer "B.Cu")
		(net "GND")
	)
	(gr_poly
		(pts
			(arc
				(start 304.652426 -375.040398)
				(mid 304.402998 -375.040398)
				(end 304.652426 -375.040398)
			)
		)
		(stroke
			(width 0)
			(type solid)
		)
		(fill yes)
		(layer "B.Cu")
		(net "GND")
	)
	(gr_poly
		(pts
			(arc
				(start 304.652426 -373.838724)
				(mid 304.402998 -373.838724)
				(end 304.652426 -373.838724)
			)
		)
		(stroke
			(width 0)
			(type solid)
		)
		(fill yes)
		(layer "B.Cu")
		(net "GND")
	)
	(gr_poly
		(pts
			(arc
				(start 304.652426 -372.342156)
				(mid 304.402998 -372.342156)
				(end 304.652426 -372.342156)
			)
		)
		(stroke
			(width 0)
			(type solid)
		)
		(fill yes)
		(layer "B.Cu")
		(net "GND")
	)
	(gr_poly
		(pts
			(arc
				(start 304.652426 -371.140482)
				(mid 304.402998 -371.140482)
				(end 304.652426 -371.140482)
			)
		)
		(stroke
			(width 0)
			(type solid)
		)
		(fill yes)
		(layer "B.Cu")
		(net "GND")
	)
	(gr_poly
		(pts
			(arc
				(start 304.652426 -369.938808)
				(mid 304.402998 -369.938808)
				(end 304.652426 -369.938808)
			)
		)
		(stroke
			(width 0)
			(type solid)
		)
		(fill yes)
		(layer "B.Cu")
		(net "GND")
	)
	(gr_poly
		(pts
			(arc
				(start 312.058558 -351.611438)
				(mid 311.80913 -351.611438)
				(end 312.058558 -351.611438)
			)
		)
		(stroke
			(width 0)
			(type solid)
		)
		(fill yes)
		(layer "B.Cu")
		(net "GND")
	)
	(gr_poly
		(pts
			(arc
				(start 312.058558 -348.58579)
				(mid 311.80913 -348.58579)
				(end 312.058558 -348.58579)
			)
		)
		(stroke
			(width 0)
			(type solid)
		)
		(fill yes)
		(layer "B.Cu")
		(net "GND")
	)
	(gr_poly
		(pts
			(arc
				(start 312.058558 -345.465146)
				(mid 311.80913 -345.465146)
				(end 312.058558 -345.465146)
			)
		)
		(stroke
			(width 0)
			(type solid)
		)
		(fill yes)
		(layer "B.Cu")
		(net "GND")
	)
	(gr_poly
		(pts
			(arc
				(start 312.058558 -342.439498)
				(mid 311.80913 -342.439498)
				(end 312.058558 -342.439498)
			)
		)
		(stroke
			(width 0)
			(type solid)
		)
		(fill yes)
		(layer "B.Cu")
		(net "GND")
	)
	(gr_poly
		(pts
			(arc
				(start 314.060078 -351.611438)
				(mid 313.81065 -351.611438)
				(end 314.060078 -351.611438)
			)
		)
		(stroke
			(width 0)
			(type solid)
		)
		(fill yes)
		(layer "B.Cu")
		(net "GND")
	)
	(gr_poly
		(pts
			(arc
				(start 314.060078 -348.58579)
				(mid 313.81065 -348.58579)
				(end 314.060078 -348.58579)
			)
		)
		(stroke
			(width 0)
			(type solid)
		)
		(fill yes)
		(layer "B.Cu")
		(net "GND")
	)
	(gr_poly
		(pts
			(arc
				(start 314.060078 -345.465146)
				(mid 313.81065 -345.465146)
				(end 314.060078 -345.465146)
			)
		)
		(stroke
			(width 0)
			(type solid)
		)
		(fill yes)
		(layer "B.Cu")
		(net "GND")
	)
	(gr_poly
		(pts
			(arc
				(start 314.060078 -342.439498)
				(mid 313.81065 -342.439498)
				(end 314.060078 -342.439498)
			)
		)
		(stroke
			(width 0)
			(type solid)
		)
		(fill yes)
		(layer "B.Cu")
		(net "GND")
	)
	(gr_poly
		(pts
			(arc
				(start 315.167518 -357.75773)
				(mid 314.91809 -357.75773)
				(end 315.167518 -357.75773)
			)
		)
		(stroke
			(width 0)
			(type solid)
		)
		(fill yes)
		(layer "B.Cu")
		(net "GND")
	)
	(gr_poly
		(pts
			(arc
				(start 315.167518 -354.732082)
				(mid 314.91809 -354.732082)
				(end 315.167518 -354.732082)
			)
		)
		(stroke
			(width 0)
			(type solid)
		)
		(fill yes)
		(layer "B.Cu")
		(net "GND")
	)
	(gr_poly
		(pts
			(arc
				(start 315.167518 -351.611438)
				(mid 314.91809 -351.611438)
				(end 315.167518 -351.611438)
			)
		)
		(stroke
			(width 0)
			(type solid)
		)
		(fill yes)
		(layer "B.Cu")
		(net "GND")
	)
	(gr_poly
		(pts
			(arc
				(start 315.167518 -348.58579)
				(mid 314.91809 -348.58579)
				(end 315.167518 -348.58579)
			)
		)
		(stroke
			(width 0)
			(type solid)
		)
		(fill yes)
		(layer "B.Cu")
		(net "GND")
	)
	(gr_poly
		(pts
			(arc
				(start 315.167518 -345.465146)
				(mid 314.91809 -345.465146)
				(end 315.167518 -345.465146)
			)
		)
		(stroke
			(width 0)
			(type solid)
		)
		(fill yes)
		(layer "B.Cu")
		(net "GND")
	)
	(gr_poly
		(pts
			(arc
				(start 315.167518 -342.439498)
				(mid 314.91809 -342.439498)
				(end 315.167518 -342.439498)
			)
		)
		(stroke
			(width 0)
			(type solid)
		)
		(fill yes)
		(layer "B.Cu")
		(net "GND")
	)
	(gr_poly
		(pts
			(arc
				(start 317.169038 -357.75773)
				(mid 316.91961 -357.75773)
				(end 317.169038 -357.75773)
			)
		)
		(stroke
			(width 0)
			(type solid)
		)
		(fill yes)
		(layer "B.Cu")
		(net "GND")
	)
	(gr_poly
		(pts
			(arc
				(start 317.169038 -354.732082)
				(mid 316.91961 -354.732082)
				(end 317.169038 -354.732082)
			)
		)
		(stroke
			(width 0)
			(type solid)
		)
		(fill yes)
		(layer "B.Cu")
		(net "GND")
	)
	(gr_poly
		(pts
			(arc
				(start 317.169038 -351.611438)
				(mid 316.91961 -351.611438)
				(end 317.169038 -351.611438)
			)
		)
		(stroke
			(width 0)
			(type solid)
		)
		(fill yes)
		(layer "B.Cu")
		(net "GND")
	)
	(gr_poly
		(pts
			(arc
				(start 317.169038 -348.58579)
				(mid 316.91961 -348.58579)
				(end 317.169038 -348.58579)
			)
		)
		(stroke
			(width 0)
			(type solid)
		)
		(fill yes)
		(layer "B.Cu")
		(net "GND")
	)
	(gr_poly
		(pts
			(arc
				(start 317.169038 -345.465146)
				(mid 316.91961 -345.465146)
				(end 317.169038 -345.465146)
			)
		)
		(stroke
			(width 0)
			(type solid)
		)
		(fill yes)
		(layer "B.Cu")
		(net "GND")
	)
	(gr_poly
		(pts
			(arc
				(start 317.169038 -342.439498)
				(mid 316.91961 -342.439498)
				(end 317.169038 -342.439498)
			)
		)
		(stroke
			(width 0)
			(type solid)
		)
		(fill yes)
		(layer "B.Cu")
		(net "GND")
	)
	(gr_poly
		(pts
			(arc
				(start 317.704724 -35.635184)
				(mid 317.451232 -35.635184)
				(end 317.704724 -35.635184)
			)
		)
		(stroke
			(width 0)
			(type solid)
		)
		(fill yes)
		(layer "B.Cu")
		(net "GND")
	)
	(gr_poly
		(pts
			(arc
				(start 318.276478 -357.75773)
				(mid 318.02705 -357.75773)
				(end 318.276478 -357.75773)
			)
		)
		(stroke
			(width 0)
			(type solid)
		)
		(fill yes)
		(layer "B.Cu")
		(net "GND")
	)
	(gr_poly
		(pts
			(arc
				(start 318.276478 -354.732082)
				(mid 318.02705 -354.732082)
				(end 318.276478 -354.732082)
			)
		)
		(stroke
			(width 0)
			(type solid)
		)
		(fill yes)
		(layer "B.Cu")
		(net "GND")
	)
	(gr_poly
		(pts
			(arc
				(start 318.276478 -351.611438)
				(mid 318.02705 -351.611438)
				(end 318.276478 -351.611438)
			)
		)
		(stroke
			(width 0)
			(type solid)
		)
		(fill yes)
		(layer "B.Cu")
		(net "GND")
	)
	(gr_poly
		(pts
			(arc
				(start 318.276478 -348.58579)
				(mid 318.02705 -348.58579)
				(end 318.276478 -348.58579)
			)
		)
		(stroke
			(width 0)
			(type solid)
		)
		(fill yes)
		(layer "B.Cu")
		(net "GND")
	)
	(gr_poly
		(pts
			(arc
				(start 318.276478 -345.465146)
				(mid 318.02705 -345.465146)
				(end 318.276478 -345.465146)
			)
		)
		(stroke
			(width 0)
			(type solid)
		)
		(fill yes)
		(layer "B.Cu")
		(net "GND")
	)
	(gr_poly
		(pts
			(arc
				(start 318.276478 -342.439498)
				(mid 318.02705 -342.439498)
				(end 318.276478 -342.439498)
			)
		)
		(stroke
			(width 0)
			(type solid)
		)
		(fill yes)
		(layer "B.Cu")
		(net "GND")
	)
	(gr_poly
		(pts
			(arc
				(start 320.277998 -357.75773)
				(mid 320.02857 -357.75773)
				(end 320.277998 -357.75773)
			)
		)
		(stroke
			(width 0)
			(type solid)
		)
		(fill yes)
		(layer "B.Cu")
		(net "GND")
	)
	(gr_poly
		(pts
			(arc
				(start 320.277998 -354.732082)
				(mid 320.02857 -354.732082)
				(end 320.277998 -354.732082)
			)
		)
		(stroke
			(width 0)
			(type solid)
		)
		(fill yes)
		(layer "B.Cu")
		(net "GND")
	)
	(gr_poly
		(pts
			(arc
				(start 320.277998 -351.611438)
				(mid 320.02857 -351.611438)
				(end 320.277998 -351.611438)
			)
		)
		(stroke
			(width 0)
			(type solid)
		)
		(fill yes)
		(layer "B.Cu")
		(net "GND")
	)
	(gr_poly
		(pts
			(arc
				(start 320.277998 -348.58579)
				(mid 320.02857 -348.58579)
				(end 320.277998 -348.58579)
			)
		)
		(stroke
			(width 0)
			(type solid)
		)
		(fill yes)
		(layer "B.Cu")
		(net "GND")
	)
	(gr_poly
		(pts
			(arc
				(start 320.277998 -345.465146)
				(mid 320.02857 -345.465146)
				(end 320.277998 -345.465146)
			)
		)
		(stroke
			(width 0)
			(type solid)
		)
		(fill yes)
		(layer "B.Cu")
		(net "GND")
	)
	(gr_poly
		(pts
			(arc
				(start 320.277998 -342.439498)
				(mid 320.02857 -342.439498)
				(end 320.277998 -342.439498)
			)
		)
		(stroke
			(width 0)
			(type solid)
		)
		(fill yes)
		(layer "B.Cu")
		(net "GND")
	)
	(gr_poly
		(pts
			(arc
				(start 321.385438 -357.75773)
				(mid 321.13601 -357.75773)
				(end 321.385438 -357.75773)
			)
		)
		(stroke
			(width 0)
			(type solid)
		)
		(fill yes)
		(layer "B.Cu")
		(net "GND")
	)
	(gr_poly
		(pts
			(arc
				(start 321.385438 -354.732082)
				(mid 321.13601 -354.732082)
				(end 321.385438 -354.732082)
			)
		)
		(stroke
			(width 0)
			(type solid)
		)
		(fill yes)
		(layer "B.Cu")
		(net "GND")
	)
	(gr_poly
		(pts
			(arc
				(start 321.385438 -351.611438)
				(mid 321.13601 -351.611438)
				(end 321.385438 -351.611438)
			)
		)
		(stroke
			(width 0)
			(type solid)
		)
		(fill yes)
		(layer "B.Cu")
		(net "GND")
	)
	(gr_poly
		(pts
			(arc
				(start 321.385438 -348.58579)
				(mid 321.13601 -348.58579)
				(end 321.385438 -348.58579)
			)
		)
		(stroke
			(width 0)
			(type solid)
		)
		(fill yes)
		(layer "B.Cu")
		(net "GND")
	)
	(gr_poly
		(pts
			(arc
				(start 321.385438 -345.465146)
				(mid 321.13601 -345.465146)
				(end 321.385438 -345.465146)
			)
		)
		(stroke
			(width 0)
			(type solid)
		)
		(fill yes)
		(layer "B.Cu")
		(net "GND")
	)
	(gr_poly
		(pts
			(arc
				(start 321.385438 -342.439498)
				(mid 321.13601 -342.439498)
				(end 321.385438 -342.439498)
			)
		)
		(stroke
			(width 0)
			(type solid)
		)
		(fill yes)
		(layer "B.Cu")
		(net "GND")
	)
	(gr_poly
		(pts
			(arc
				(start 323.386958 -357.75773)
				(mid 323.13753 -357.75773)
				(end 323.386958 -357.75773)
			)
		)
		(stroke
			(width 0)
			(type solid)
		)
		(fill yes)
		(layer "B.Cu")
		(net "GND")
	)
	(gr_poly
		(pts
			(arc
				(start 323.386958 -354.732082)
				(mid 323.13753 -354.732082)
				(end 323.386958 -354.732082)
			)
		)
		(stroke
			(width 0)
			(type solid)
		)
		(fill yes)
		(layer "B.Cu")
		(net "GND")
	)
	(gr_poly
		(pts
			(arc
				(start 323.386958 -351.611438)
				(mid 323.13753 -351.611438)
				(end 323.386958 -351.611438)
			)
		)
		(stroke
			(width 0)
			(type solid)
		)
		(fill yes)
		(layer "B.Cu")
		(net "GND")
	)
	(gr_poly
		(pts
			(arc
				(start 323.386958 -348.58579)
				(mid 323.13753 -348.58579)
				(end 323.386958 -348.58579)
			)
		)
		(stroke
			(width 0)
			(type solid)
		)
		(fill yes)
		(layer "B.Cu")
		(net "GND")
	)
	(gr_poly
		(pts
			(arc
				(start 323.386958 -345.465146)
				(mid 323.13753 -345.465146)
				(end 323.386958 -345.465146)
			)
		)
		(stroke
			(width 0)
			(type solid)
		)
		(fill yes)
		(layer "B.Cu")
		(net "GND")
	)
	(gr_poly
		(pts
			(arc
				(start 323.386958 -342.439498)
				(mid 323.13753 -342.439498)
				(end 323.386958 -342.439498)
			)
		)
		(stroke
			(width 0)
			(type solid)
		)
		(fill yes)
		(layer "B.Cu")
		(net "GND")
	)
	(gr_poly
		(pts
			(arc
				(start 324.494398 -357.75773)
				(mid 324.24497 -357.75773)
				(end 324.494398 -357.75773)
			)
		)
		(stroke
			(width 0)
			(type solid)
		)
		(fill yes)
		(layer "B.Cu")
		(net "GND")
	)
	(gr_poly
		(pts
			(arc
				(start 324.494398 -354.732082)
				(mid 324.24497 -354.732082)
				(end 324.494398 -354.732082)
			)
		)
		(stroke
			(width 0)
			(type solid)
		)
		(fill yes)
		(layer "B.Cu")
		(net "GND")
	)
	(gr_poly
		(pts
			(arc
				(start 324.494398 -351.611438)
				(mid 324.24497 -351.611438)
				(end 324.494398 -351.611438)
			)
		)
		(stroke
			(width 0)
			(type solid)
		)
		(fill yes)
		(layer "B.Cu")
		(net "GND")
	)
	(gr_poly
		(pts
			(arc
				(start 324.494398 -348.58579)
				(mid 324.24497 -348.58579)
				(end 324.494398 -348.58579)
			)
		)
		(stroke
			(width 0)
			(type solid)
		)
		(fill yes)
		(layer "B.Cu")
		(net "GND")
	)
	(gr_poly
		(pts
			(arc
				(start 324.494398 -345.465146)
				(mid 324.24497 -345.465146)
				(end 324.494398 -345.465146)
			)
		)
		(stroke
			(width 0)
			(type solid)
		)
		(fill yes)
		(layer "B.Cu")
		(net "GND")
	)
	(gr_poly
		(pts
			(arc
				(start 324.494398 -342.439498)
				(mid 324.24497 -342.439498)
				(end 324.494398 -342.439498)
			)
		)
		(stroke
			(width 0)
			(type solid)
		)
		(fill yes)
		(layer "B.Cu")
		(net "GND")
	)
	(gr_poly
		(pts
			(arc
				(start 326.495918 -357.75773)
				(mid 326.24649 -357.75773)
				(end 326.495918 -357.75773)
			)
		)
		(stroke
			(width 0)
			(type solid)
		)
		(fill yes)
		(layer "B.Cu")
		(net "GND")
	)
	(gr_poly
		(pts
			(arc
				(start 326.495918 -354.732082)
				(mid 326.24649 -354.732082)
				(end 326.495918 -354.732082)
			)
		)
		(stroke
			(width 0)
			(type solid)
		)
		(fill yes)
		(layer "B.Cu")
		(net "GND")
	)
	(gr_poly
		(pts
			(arc
				(start 326.495918 -351.611438)
				(mid 326.24649 -351.611438)
				(end 326.495918 -351.611438)
			)
		)
		(stroke
			(width 0)
			(type solid)
		)
		(fill yes)
		(layer "B.Cu")
		(net "GND")
	)
	(gr_poly
		(pts
			(arc
				(start 326.495918 -348.58579)
				(mid 326.24649 -348.58579)
				(end 326.495918 -348.58579)
			)
		)
		(stroke
			(width 0)
			(type solid)
		)
		(fill yes)
		(layer "B.Cu")
		(net "GND")
	)
	(gr_poly
		(pts
			(arc
				(start 326.495918 -345.465146)
				(mid 326.24649 -345.465146)
				(end 326.495918 -345.465146)
			)
		)
		(stroke
			(width 0)
			(type solid)
		)
		(fill yes)
		(layer "B.Cu")
		(net "GND")
	)
	(gr_poly
		(pts
			(arc
				(start 326.495918 -342.439498)
				(mid 326.24649 -342.439498)
				(end 326.495918 -342.439498)
			)
		)
		(stroke
			(width 0)
			(type solid)
		)
		(fill yes)
		(layer "B.Cu")
		(net "GND")
	)
	(gr_poly
		(pts
			(arc
				(start 327.603358 -357.75773)
				(mid 327.35393 -357.75773)
				(end 327.603358 -357.75773)
			)
		)
		(stroke
			(width 0)
			(type solid)
		)
		(fill yes)
		(layer "B.Cu")
		(net "GND")
	)
	(gr_poly
		(pts
			(arc
				(start 327.603358 -354.732082)
				(mid 327.35393 -354.732082)
				(end 327.603358 -354.732082)
			)
		)
		(stroke
			(width 0)
			(type solid)
		)
		(fill yes)
		(layer "B.Cu")
		(net "GND")
	)
	(gr_poly
		(pts
			(arc
				(start 327.603358 -351.611438)
				(mid 327.35393 -351.611438)
				(end 327.603358 -351.611438)
			)
		)
		(stroke
			(width 0)
			(type solid)
		)
		(fill yes)
		(layer "B.Cu")
		(net "GND")
	)
	(gr_poly
		(pts
			(arc
				(start 327.603358 -348.58579)
				(mid 327.35393 -348.58579)
				(end 327.603358 -348.58579)
			)
		)
		(stroke
			(width 0)
			(type solid)
		)
		(fill yes)
		(layer "B.Cu")
		(net "GND")
	)
	(gr_poly
		(pts
			(arc
				(start 327.603358 -345.465146)
				(mid 327.35393 -345.465146)
				(end 327.603358 -345.465146)
			)
		)
		(stroke
			(width 0)
			(type solid)
		)
		(fill yes)
		(layer "B.Cu")
		(net "GND")
	)
	(gr_poly
		(pts
			(arc
				(start 327.603358 -342.439498)
				(mid 327.35393 -342.439498)
				(end 327.603358 -342.439498)
			)
		)
		(stroke
			(width 0)
			(type solid)
		)
		(fill yes)
		(layer "B.Cu")
		(net "GND")
	)
	(gr_poly
		(pts
			(arc
				(start 329.604878 -357.75773)
				(mid 329.35545 -357.75773)
				(end 329.604878 -357.75773)
			)
		)
		(stroke
			(width 0)
			(type solid)
		)
		(fill yes)
		(layer "B.Cu")
		(net "GND")
	)
	(gr_poly
		(pts
			(arc
				(start 329.604878 -354.732082)
				(mid 329.35545 -354.732082)
				(end 329.604878 -354.732082)
			)
		)
		(stroke
			(width 0)
			(type solid)
		)
		(fill yes)
		(layer "B.Cu")
		(net "GND")
	)
	(gr_poly
		(pts
			(arc
				(start 329.604878 -351.611438)
				(mid 329.35545 -351.611438)
				(end 329.604878 -351.611438)
			)
		)
		(stroke
			(width 0)
			(type solid)
		)
		(fill yes)
		(layer "B.Cu")
		(net "GND")
	)
	(gr_poly
		(pts
			(arc
				(start 329.604878 -348.58579)
				(mid 329.35545 -348.58579)
				(end 329.604878 -348.58579)
			)
		)
		(stroke
			(width 0)
			(type solid)
		)
		(fill yes)
		(layer "B.Cu")
		(net "GND")
	)
	(gr_poly
		(pts
			(arc
				(start 329.604878 -345.465146)
				(mid 329.35545 -345.465146)
				(end 329.604878 -345.465146)
			)
		)
		(stroke
			(width 0)
			(type solid)
		)
		(fill yes)
		(layer "B.Cu")
		(net "GND")
	)
	(gr_poly
		(pts
			(arc
				(start 329.604878 -342.439498)
				(mid 329.35545 -342.439498)
				(end 329.604878 -342.439498)
			)
		)
		(stroke
			(width 0)
			(type solid)
		)
		(fill yes)
		(layer "B.Cu")
		(net "GND")
	)
	(gr_poly
		(pts
			(arc
				(start 330.712318 -357.75773)
				(mid 330.46289 -357.75773)
				(end 330.712318 -357.75773)
			)
		)
		(stroke
			(width 0)
			(type solid)
		)
		(fill yes)
		(layer "B.Cu")
		(net "GND")
	)
	(gr_poly
		(pts
			(arc
				(start 330.712318 -354.732082)
				(mid 330.46289 -354.732082)
				(end 330.712318 -354.732082)
			)
		)
		(stroke
			(width 0)
			(type solid)
		)
		(fill yes)
		(layer "B.Cu")
		(net "GND")
	)
	(gr_poly
		(pts
			(arc
				(start 330.712318 -351.611438)
				(mid 330.46289 -351.611438)
				(end 330.712318 -351.611438)
			)
		)
		(stroke
			(width 0)
			(type solid)
		)
		(fill yes)
		(layer "B.Cu")
		(net "GND")
	)
	(gr_poly
		(pts
			(arc
				(start 330.712318 -348.58579)
				(mid 330.46289 -348.58579)
				(end 330.712318 -348.58579)
			)
		)
		(stroke
			(width 0)
			(type solid)
		)
		(fill yes)
		(layer "B.Cu")
		(net "GND")
	)
	(gr_poly
		(pts
			(arc
				(start 330.712318 -345.465146)
				(mid 330.46289 -345.465146)
				(end 330.712318 -345.465146)
			)
		)
		(stroke
			(width 0)
			(type solid)
		)
		(fill yes)
		(layer "B.Cu")
		(net "GND")
	)
	(gr_poly
		(pts
			(arc
				(start 330.712318 -342.439498)
				(mid 330.46289 -342.439498)
				(end 330.712318 -342.439498)
			)
		)
		(stroke
			(width 0)
			(type solid)
		)
		(fill yes)
		(layer "B.Cu")
		(net "GND")
	)
	(gr_poly
		(pts
			(arc
				(start 331.052678 -410.041852)
				(mid 330.80325 -410.041852)
				(end 331.052678 -410.041852)
			)
		)
		(stroke
			(width 0)
			(type solid)
		)
		(fill yes)
		(layer "B.Cu")
		(net "GND")
	)
	(gr_poly
		(pts
			(arc
				(start 331.052678 -408.840178)
				(mid 330.80325 -408.840178)
				(end 331.052678 -408.840178)
			)
		)
		(stroke
			(width 0)
			(type solid)
		)
		(fill yes)
		(layer "B.Cu")
		(net "GND")
	)
	(gr_poly
		(pts
			(arc
				(start 331.052678 -407.638504)
				(mid 330.80325 -407.638504)
				(end 331.052678 -407.638504)
			)
		)
		(stroke
			(width 0)
			(type solid)
		)
		(fill yes)
		(layer "B.Cu")
		(net "GND")
	)
	(gr_poly
		(pts
			(arc
				(start 331.052678 -406.141936)
				(mid 330.80325 -406.141936)
				(end 331.052678 -406.141936)
			)
		)
		(stroke
			(width 0)
			(type solid)
		)
		(fill yes)
		(layer "B.Cu")
		(net "GND")
	)
	(gr_poly
		(pts
			(arc
				(start 331.052678 -404.940262)
				(mid 330.80325 -404.940262)
				(end 331.052678 -404.940262)
			)
		)
		(stroke
			(width 0)
			(type solid)
		)
		(fill yes)
		(layer "B.Cu")
		(net "GND")
	)
	(gr_poly
		(pts
			(arc
				(start 331.052678 -403.738588)
				(mid 330.80325 -403.738588)
				(end 331.052678 -403.738588)
			)
		)
		(stroke
			(width 0)
			(type solid)
		)
		(fill yes)
		(layer "B.Cu")
		(net "GND")
	)
	(gr_poly
		(pts
			(arc
				(start 331.052678 -402.241766)
				(mid 330.80325 -402.241766)
				(end 331.052678 -402.241766)
			)
		)
		(stroke
			(width 0)
			(type solid)
		)
		(fill yes)
		(layer "B.Cu")
		(net "GND")
	)
	(gr_poly
		(pts
			(arc
				(start 331.052678 -401.040092)
				(mid 330.80325 -401.040092)
				(end 331.052678 -401.040092)
			)
		)
		(stroke
			(width 0)
			(type solid)
		)
		(fill yes)
		(layer "B.Cu")
		(net "GND")
	)
	(gr_poly
		(pts
			(arc
				(start 331.052678 -399.838418)
				(mid 330.80325 -399.838418)
				(end 331.052678 -399.838418)
			)
		)
		(stroke
			(width 0)
			(type solid)
		)
		(fill yes)
		(layer "B.Cu")
		(net "GND")
	)
	(gr_poly
		(pts
			(arc
				(start 331.052678 -398.34185)
				(mid 330.80325 -398.34185)
				(end 331.052678 -398.34185)
			)
		)
		(stroke
			(width 0)
			(type solid)
		)
		(fill yes)
		(layer "B.Cu")
		(net "GND")
	)
	(gr_poly
		(pts
			(arc
				(start 331.052678 -397.140176)
				(mid 330.80325 -397.140176)
				(end 331.052678 -397.140176)
			)
		)
		(stroke
			(width 0)
			(type solid)
		)
		(fill yes)
		(layer "B.Cu")
		(net "GND")
	)
	(gr_poly
		(pts
			(arc
				(start 331.052678 -395.938502)
				(mid 330.80325 -395.938502)
				(end 331.052678 -395.938502)
			)
		)
		(stroke
			(width 0)
			(type solid)
		)
		(fill yes)
		(layer "B.Cu")
		(net "GND")
	)
	(gr_poly
		(pts
			(arc
				(start 331.052678 -384.041904)
				(mid 330.80325 -384.041904)
				(end 331.052678 -384.041904)
			)
		)
		(stroke
			(width 0)
			(type solid)
		)
		(fill yes)
		(layer "B.Cu")
		(net "GND")
	)
	(gr_poly
		(pts
			(arc
				(start 331.052678 -382.84023)
				(mid 330.80325 -382.84023)
				(end 331.052678 -382.84023)
			)
		)
		(stroke
			(width 0)
			(type solid)
		)
		(fill yes)
		(layer "B.Cu")
		(net "GND")
	)
	(gr_poly
		(pts
			(arc
				(start 331.052678 -381.638556)
				(mid 330.80325 -381.638556)
				(end 331.052678 -381.638556)
			)
		)
		(stroke
			(width 0)
			(type solid)
		)
		(fill yes)
		(layer "B.Cu")
		(net "GND")
	)
	(gr_poly
		(pts
			(arc
				(start 331.052678 -380.141988)
				(mid 330.80325 -380.141988)
				(end 331.052678 -380.141988)
			)
		)
		(stroke
			(width 0)
			(type solid)
		)
		(fill yes)
		(layer "B.Cu")
		(net "GND")
	)
	(gr_poly
		(pts
			(arc
				(start 331.052678 -378.940314)
				(mid 330.80325 -378.940314)
				(end 331.052678 -378.940314)
			)
		)
		(stroke
			(width 0)
			(type solid)
		)
		(fill yes)
		(layer "B.Cu")
		(net "GND")
	)
	(gr_poly
		(pts
			(arc
				(start 331.052678 -377.73864)
				(mid 330.80325 -377.73864)
				(end 331.052678 -377.73864)
			)
		)
		(stroke
			(width 0)
			(type solid)
		)
		(fill yes)
		(layer "B.Cu")
		(net "GND")
	)
	(gr_poly
		(pts
			(arc
				(start 331.052678 -376.241818)
				(mid 330.80325 -376.241818)
				(end 331.052678 -376.241818)
			)
		)
		(stroke
			(width 0)
			(type solid)
		)
		(fill yes)
		(layer "B.Cu")
		(net "GND")
	)
	(gr_poly
		(pts
			(arc
				(start 331.052678 -375.040144)
				(mid 330.80325 -375.040144)
				(end 331.052678 -375.040144)
			)
		)
		(stroke
			(width 0)
			(type solid)
		)
		(fill yes)
		(layer "B.Cu")
		(net "GND")
	)
	(gr_poly
		(pts
			(arc
				(start 331.052678 -373.83847)
				(mid 330.80325 -373.83847)
				(end 331.052678 -373.83847)
			)
		)
		(stroke
			(width 0)
			(type solid)
		)
		(fill yes)
		(layer "B.Cu")
		(net "GND")
	)
	(gr_poly
		(pts
			(arc
				(start 331.052678 -372.341902)
				(mid 330.80325 -372.341902)
				(end 331.052678 -372.341902)
			)
		)
		(stroke
			(width 0)
			(type solid)
		)
		(fill yes)
		(layer "B.Cu")
		(net "GND")
	)
	(gr_poly
		(pts
			(arc
				(start 331.052678 -371.140228)
				(mid 330.80325 -371.140228)
				(end 331.052678 -371.140228)
			)
		)
		(stroke
			(width 0)
			(type solid)
		)
		(fill yes)
		(layer "B.Cu")
		(net "GND")
	)
	(gr_poly
		(pts
			(arc
				(start 331.052678 -369.938554)
				(mid 330.80325 -369.938554)
				(end 331.052678 -369.938554)
			)
		)
		(stroke
			(width 0)
			(type solid)
		)
		(fill yes)
		(layer "B.Cu")
		(net "GND")
	)
	(gr_poly
		(pts
			(arc
				(start 332.713838 -357.75773)
				(mid 332.46441 -357.75773)
				(end 332.713838 -357.75773)
			)
		)
		(stroke
			(width 0)
			(type solid)
		)
		(fill yes)
		(layer "B.Cu")
		(net "GND")
	)
	(gr_poly
		(pts
			(arc
				(start 332.713838 -354.732082)
				(mid 332.46441 -354.732082)
				(end 332.713838 -354.732082)
			)
		)
		(stroke
			(width 0)
			(type solid)
		)
		(fill yes)
		(layer "B.Cu")
		(net "GND")
	)
	(gr_poly
		(pts
			(arc
				(start 332.713838 -351.611438)
				(mid 332.46441 -351.611438)
				(end 332.713838 -351.611438)
			)
		)
		(stroke
			(width 0)
			(type solid)
		)
		(fill yes)
		(layer "B.Cu")
		(net "GND")
	)
	(gr_poly
		(pts
			(arc
				(start 332.713838 -348.58579)
				(mid 332.46441 -348.58579)
				(end 332.713838 -348.58579)
			)
		)
		(stroke
			(width 0)
			(type solid)
		)
		(fill yes)
		(layer "B.Cu")
		(net "GND")
	)
	(gr_poly
		(pts
			(arc
				(start 332.713838 -345.465146)
				(mid 332.46441 -345.465146)
				(end 332.713838 -345.465146)
			)
		)
		(stroke
			(width 0)
			(type solid)
		)
		(fill yes)
		(layer "B.Cu")
		(net "GND")
	)
	(gr_poly
		(pts
			(arc
				(start 332.713838 -342.439498)
				(mid 332.46441 -342.439498)
				(end 332.713838 -342.439498)
			)
		)
		(stroke
			(width 0)
			(type solid)
		)
		(fill yes)
		(layer "B.Cu")
		(net "GND")
	)
	(gr_poly
		(pts
			(arc
				(start 333.252572 -411.141926)
				(mid 333.003144 -411.141926)
				(end 333.252572 -411.141926)
			)
		)
		(stroke
			(width 0)
			(type solid)
		)
		(fill yes)
		(layer "B.Cu")
		(net "GND")
	)
	(gr_poly
		(pts
			(arc
				(start 333.252572 -409.940252)
				(mid 333.003144 -409.940252)
				(end 333.252572 -409.940252)
			)
		)
		(stroke
			(width 0)
			(type solid)
		)
		(fill yes)
		(layer "B.Cu")
		(net "GND")
	)
	(gr_poly
		(pts
			(arc
				(start 333.252572 -408.738578)
				(mid 333.003144 -408.738578)
				(end 333.252572 -408.738578)
			)
		)
		(stroke
			(width 0)
			(type solid)
		)
		(fill yes)
		(layer "B.Cu")
		(net "GND")
	)
	(gr_poly
		(pts
			(arc
				(start 333.252572 -407.24201)
				(mid 333.003144 -407.24201)
				(end 333.252572 -407.24201)
			)
		)
		(stroke
			(width 0)
			(type solid)
		)
		(fill yes)
		(layer "B.Cu")
		(net "GND")
	)
	(gr_poly
		(pts
			(arc
				(start 333.252572 -406.040336)
				(mid 333.003144 -406.040336)
				(end 333.252572 -406.040336)
			)
		)
		(stroke
			(width 0)
			(type solid)
		)
		(fill yes)
		(layer "B.Cu")
		(net "GND")
	)
	(gr_poly
		(pts
			(arc
				(start 333.252572 -404.838662)
				(mid 333.003144 -404.838662)
				(end 333.252572 -404.838662)
			)
		)
		(stroke
			(width 0)
			(type solid)
		)
		(fill yes)
		(layer "B.Cu")
		(net "GND")
	)
	(gr_poly
		(pts
			(arc
				(start 333.252572 -403.34184)
				(mid 333.003144 -403.34184)
				(end 333.252572 -403.34184)
			)
		)
		(stroke
			(width 0)
			(type solid)
		)
		(fill yes)
		(layer "B.Cu")
		(net "GND")
	)
	(gr_poly
		(pts
			(arc
				(start 333.252572 -402.140166)
				(mid 333.003144 -402.140166)
				(end 333.252572 -402.140166)
			)
		)
		(stroke
			(width 0)
			(type solid)
		)
		(fill yes)
		(layer "B.Cu")
		(net "GND")
	)
	(gr_poly
		(pts
			(arc
				(start 333.252572 -400.938492)
				(mid 333.003144 -400.938492)
				(end 333.252572 -400.938492)
			)
		)
		(stroke
			(width 0)
			(type solid)
		)
		(fill yes)
		(layer "B.Cu")
		(net "GND")
	)
	(gr_poly
		(pts
			(arc
				(start 333.252572 -399.441924)
				(mid 333.003144 -399.441924)
				(end 333.252572 -399.441924)
			)
		)
		(stroke
			(width 0)
			(type solid)
		)
		(fill yes)
		(layer "B.Cu")
		(net "GND")
	)
	(gr_poly
		(pts
			(arc
				(start 333.252572 -398.24025)
				(mid 333.003144 -398.24025)
				(end 333.252572 -398.24025)
			)
		)
		(stroke
			(width 0)
			(type solid)
		)
		(fill yes)
		(layer "B.Cu")
		(net "GND")
	)
	(gr_poly
		(pts
			(arc
				(start 333.252572 -397.038576)
				(mid 333.003144 -397.038576)
				(end 333.252572 -397.038576)
			)
		)
		(stroke
			(width 0)
			(type solid)
		)
		(fill yes)
		(layer "B.Cu")
		(net "GND")
	)
	(gr_poly
		(pts
			(arc
				(start 333.252572 -385.141978)
				(mid 333.003144 -385.141978)
				(end 333.252572 -385.141978)
			)
		)
		(stroke
			(width 0)
			(type solid)
		)
		(fill yes)
		(layer "B.Cu")
		(net "GND")
	)
	(gr_poly
		(pts
			(arc
				(start 333.252572 -383.940304)
				(mid 333.003144 -383.940304)
				(end 333.252572 -383.940304)
			)
		)
		(stroke
			(width 0)
			(type solid)
		)
		(fill yes)
		(layer "B.Cu")
		(net "GND")
	)
	(gr_poly
		(pts
			(arc
				(start 333.252572 -382.73863)
				(mid 333.003144 -382.73863)
				(end 333.252572 -382.73863)
			)
		)
		(stroke
			(width 0)
			(type solid)
		)
		(fill yes)
		(layer "B.Cu")
		(net "GND")
	)
	(gr_poly
		(pts
			(arc
				(start 333.252572 -381.242062)
				(mid 333.003144 -381.242062)
				(end 333.252572 -381.242062)
			)
		)
		(stroke
			(width 0)
			(type solid)
		)
		(fill yes)
		(layer "B.Cu")
		(net "GND")
	)
	(gr_poly
		(pts
			(arc
				(start 333.252572 -380.040388)
				(mid 333.003144 -380.040388)
				(end 333.252572 -380.040388)
			)
		)
		(stroke
			(width 0)
			(type solid)
		)
		(fill yes)
		(layer "B.Cu")
		(net "GND")
	)
	(gr_poly
		(pts
			(arc
				(start 333.252572 -378.838714)
				(mid 333.003144 -378.838714)
				(end 333.252572 -378.838714)
			)
		)
		(stroke
			(width 0)
			(type solid)
		)
		(fill yes)
		(layer "B.Cu")
		(net "GND")
	)
	(gr_poly
		(pts
			(arc
				(start 333.252572 -377.341892)
				(mid 333.003144 -377.341892)
				(end 333.252572 -377.341892)
			)
		)
		(stroke
			(width 0)
			(type solid)
		)
		(fill yes)
		(layer "B.Cu")
		(net "GND")
	)
	(gr_poly
		(pts
			(arc
				(start 333.252572 -376.140218)
				(mid 333.003144 -376.140218)
				(end 333.252572 -376.140218)
			)
		)
		(stroke
			(width 0)
			(type solid)
		)
		(fill yes)
		(layer "B.Cu")
		(net "GND")
	)
	(gr_poly
		(pts
			(arc
				(start 333.252572 -374.938544)
				(mid 333.003144 -374.938544)
				(end 333.252572 -374.938544)
			)
		)
		(stroke
			(width 0)
			(type solid)
		)
		(fill yes)
		(layer "B.Cu")
		(net "GND")
	)
	(gr_poly
		(pts
			(arc
				(start 333.252572 -373.441976)
				(mid 333.003144 -373.441976)
				(end 333.252572 -373.441976)
			)
		)
		(stroke
			(width 0)
			(type solid)
		)
		(fill yes)
		(layer "B.Cu")
		(net "GND")
	)
	(gr_poly
		(pts
			(arc
				(start 333.252572 -372.240302)
				(mid 333.003144 -372.240302)
				(end 333.252572 -372.240302)
			)
		)
		(stroke
			(width 0)
			(type solid)
		)
		(fill yes)
		(layer "B.Cu")
		(net "GND")
	)
	(gr_poly
		(pts
			(arc
				(start 333.252572 -371.038628)
				(mid 333.003144 -371.038628)
				(end 333.252572 -371.038628)
			)
		)
		(stroke
			(width 0)
			(type solid)
		)
		(fill yes)
		(layer "B.Cu")
		(net "GND")
	)
	(gr_poly
		(pts
			(arc
				(start 333.821278 -357.75773)
				(mid 333.57185 -357.75773)
				(end 333.821278 -357.75773)
			)
		)
		(stroke
			(width 0)
			(type solid)
		)
		(fill yes)
		(layer "B.Cu")
		(net "GND")
	)
	(gr_poly
		(pts
			(arc
				(start 333.821278 -354.732082)
				(mid 333.57185 -354.732082)
				(end 333.821278 -354.732082)
			)
		)
		(stroke
			(width 0)
			(type solid)
		)
		(fill yes)
		(layer "B.Cu")
		(net "GND")
	)
	(gr_poly
		(pts
			(arc
				(start 333.821278 -351.611438)
				(mid 333.57185 -351.611438)
				(end 333.821278 -351.611438)
			)
		)
		(stroke
			(width 0)
			(type solid)
		)
		(fill yes)
		(layer "B.Cu")
		(net "GND")
	)
	(gr_poly
		(pts
			(arc
				(start 333.821278 -348.58579)
				(mid 333.57185 -348.58579)
				(end 333.821278 -348.58579)
			)
		)
		(stroke
			(width 0)
			(type solid)
		)
		(fill yes)
		(layer "B.Cu")
		(net "GND")
	)
	(gr_poly
		(pts
			(arc
				(start 333.821278 -345.465146)
				(mid 333.57185 -345.465146)
				(end 333.821278 -345.465146)
			)
		)
		(stroke
			(width 0)
			(type solid)
		)
		(fill yes)
		(layer "B.Cu")
		(net "GND")
	)
	(gr_poly
		(pts
			(arc
				(start 333.821278 -342.439498)
				(mid 333.57185 -342.439498)
				(end 333.821278 -342.439498)
			)
		)
		(stroke
			(width 0)
			(type solid)
		)
		(fill yes)
		(layer "B.Cu")
		(net "GND")
	)
	(gr_poly
		(pts
			(arc
				(start 335.45272 -410.041852)
				(mid 335.203292 -410.041852)
				(end 335.45272 -410.041852)
			)
		)
		(stroke
			(width 0)
			(type solid)
		)
		(fill yes)
		(layer "B.Cu")
		(net "GND")
	)
	(gr_poly
		(pts
			(arc
				(start 335.45272 -408.840178)
				(mid 335.203292 -408.840178)
				(end 335.45272 -408.840178)
			)
		)
		(stroke
			(width 0)
			(type solid)
		)
		(fill yes)
		(layer "B.Cu")
		(net "GND")
	)
	(gr_poly
		(pts
			(arc
				(start 335.45272 -407.638504)
				(mid 335.203292 -407.638504)
				(end 335.45272 -407.638504)
			)
		)
		(stroke
			(width 0)
			(type solid)
		)
		(fill yes)
		(layer "B.Cu")
		(net "GND")
	)
	(gr_poly
		(pts
			(arc
				(start 335.45272 -406.141936)
				(mid 335.203292 -406.141936)
				(end 335.45272 -406.141936)
			)
		)
		(stroke
			(width 0)
			(type solid)
		)
		(fill yes)
		(layer "B.Cu")
		(net "GND")
	)
	(gr_poly
		(pts
			(arc
				(start 335.45272 -404.940262)
				(mid 335.203292 -404.940262)
				(end 335.45272 -404.940262)
			)
		)
		(stroke
			(width 0)
			(type solid)
		)
		(fill yes)
		(layer "B.Cu")
		(net "GND")
	)
	(gr_poly
		(pts
			(arc
				(start 335.45272 -403.738588)
				(mid 335.203292 -403.738588)
				(end 335.45272 -403.738588)
			)
		)
		(stroke
			(width 0)
			(type solid)
		)
		(fill yes)
		(layer "B.Cu")
		(net "GND")
	)
	(gr_poly
		(pts
			(arc
				(start 335.45272 -402.241766)
				(mid 335.203292 -402.241766)
				(end 335.45272 -402.241766)
			)
		)
		(stroke
			(width 0)
			(type solid)
		)
		(fill yes)
		(layer "B.Cu")
		(net "GND")
	)
	(gr_poly
		(pts
			(arc
				(start 335.45272 -401.040092)
				(mid 335.203292 -401.040092)
				(end 335.45272 -401.040092)
			)
		)
		(stroke
			(width 0)
			(type solid)
		)
		(fill yes)
		(layer "B.Cu")
		(net "GND")
	)
	(gr_poly
		(pts
			(arc
				(start 335.45272 -399.838418)
				(mid 335.203292 -399.838418)
				(end 335.45272 -399.838418)
			)
		)
		(stroke
			(width 0)
			(type solid)
		)
		(fill yes)
		(layer "B.Cu")
		(net "GND")
	)
	(gr_poly
		(pts
			(arc
				(start 335.45272 -398.34185)
				(mid 335.203292 -398.34185)
				(end 335.45272 -398.34185)
			)
		)
		(stroke
			(width 0)
			(type solid)
		)
		(fill yes)
		(layer "B.Cu")
		(net "GND")
	)
	(gr_poly
		(pts
			(arc
				(start 335.45272 -397.140176)
				(mid 335.203292 -397.140176)
				(end 335.45272 -397.140176)
			)
		)
		(stroke
			(width 0)
			(type solid)
		)
		(fill yes)
		(layer "B.Cu")
		(net "GND")
	)
	(gr_poly
		(pts
			(arc
				(start 335.45272 -395.938502)
				(mid 335.203292 -395.938502)
				(end 335.45272 -395.938502)
			)
		)
		(stroke
			(width 0)
			(type solid)
		)
		(fill yes)
		(layer "B.Cu")
		(net "GND")
	)
	(gr_poly
		(pts
			(arc
				(start 335.45272 -384.041904)
				(mid 335.203292 -384.041904)
				(end 335.45272 -384.041904)
			)
		)
		(stroke
			(width 0)
			(type solid)
		)
		(fill yes)
		(layer "B.Cu")
		(net "GND")
	)
	(gr_poly
		(pts
			(arc
				(start 335.45272 -382.84023)
				(mid 335.203292 -382.84023)
				(end 335.45272 -382.84023)
			)
		)
		(stroke
			(width 0)
			(type solid)
		)
		(fill yes)
		(layer "B.Cu")
		(net "GND")
	)
	(gr_poly
		(pts
			(arc
				(start 335.45272 -381.638556)
				(mid 335.203292 -381.638556)
				(end 335.45272 -381.638556)
			)
		)
		(stroke
			(width 0)
			(type solid)
		)
		(fill yes)
		(layer "B.Cu")
		(net "GND")
	)
	(gr_poly
		(pts
			(arc
				(start 335.45272 -380.141988)
				(mid 335.203292 -380.141988)
				(end 335.45272 -380.141988)
			)
		)
		(stroke
			(width 0)
			(type solid)
		)
		(fill yes)
		(layer "B.Cu")
		(net "GND")
	)
	(gr_poly
		(pts
			(arc
				(start 335.45272 -378.940314)
				(mid 335.203292 -378.940314)
				(end 335.45272 -378.940314)
			)
		)
		(stroke
			(width 0)
			(type solid)
		)
		(fill yes)
		(layer "B.Cu")
		(net "GND")
	)
	(gr_poly
		(pts
			(arc
				(start 335.45272 -377.73864)
				(mid 335.203292 -377.73864)
				(end 335.45272 -377.73864)
			)
		)
		(stroke
			(width 0)
			(type solid)
		)
		(fill yes)
		(layer "B.Cu")
		(net "GND")
	)
	(gr_poly
		(pts
			(arc
				(start 335.45272 -376.241818)
				(mid 335.203292 -376.241818)
				(end 335.45272 -376.241818)
			)
		)
		(stroke
			(width 0)
			(type solid)
		)
		(fill yes)
		(layer "B.Cu")
		(net "GND")
	)
	(gr_poly
		(pts
			(arc
				(start 335.45272 -375.040144)
				(mid 335.203292 -375.040144)
				(end 335.45272 -375.040144)
			)
		)
		(stroke
			(width 0)
			(type solid)
		)
		(fill yes)
		(layer "B.Cu")
		(net "GND")
	)
	(gr_poly
		(pts
			(arc
				(start 335.45272 -373.83847)
				(mid 335.203292 -373.83847)
				(end 335.45272 -373.83847)
			)
		)
		(stroke
			(width 0)
			(type solid)
		)
		(fill yes)
		(layer "B.Cu")
		(net "GND")
	)
	(gr_poly
		(pts
			(arc
				(start 335.45272 -372.341902)
				(mid 335.203292 -372.341902)
				(end 335.45272 -372.341902)
			)
		)
		(stroke
			(width 0)
			(type solid)
		)
		(fill yes)
		(layer "B.Cu")
		(net "GND")
	)
	(gr_poly
		(pts
			(arc
				(start 335.45272 -371.140228)
				(mid 335.203292 -371.140228)
				(end 335.45272 -371.140228)
			)
		)
		(stroke
			(width 0)
			(type solid)
		)
		(fill yes)
		(layer "B.Cu")
		(net "GND")
	)
	(gr_poly
		(pts
			(arc
				(start 335.45272 -369.938554)
				(mid 335.203292 -369.938554)
				(end 335.45272 -369.938554)
			)
		)
		(stroke
			(width 0)
			(type solid)
		)
		(fill yes)
		(layer "B.Cu")
		(net "GND")
	)
	(gr_poly
		(pts
			(arc
				(start 335.822798 -357.75773)
				(mid 335.57337 -357.75773)
				(end 335.822798 -357.75773)
			)
		)
		(stroke
			(width 0)
			(type solid)
		)
		(fill yes)
		(layer "B.Cu")
		(net "GND")
	)
	(gr_poly
		(pts
			(arc
				(start 335.822798 -354.732082)
				(mid 335.57337 -354.732082)
				(end 335.822798 -354.732082)
			)
		)
		(stroke
			(width 0)
			(type solid)
		)
		(fill yes)
		(layer "B.Cu")
		(net "GND")
	)
	(gr_poly
		(pts
			(arc
				(start 335.822798 -351.611438)
				(mid 335.57337 -351.611438)
				(end 335.822798 -351.611438)
			)
		)
		(stroke
			(width 0)
			(type solid)
		)
		(fill yes)
		(layer "B.Cu")
		(net "GND")
	)
	(gr_poly
		(pts
			(arc
				(start 335.822798 -348.58579)
				(mid 335.57337 -348.58579)
				(end 335.822798 -348.58579)
			)
		)
		(stroke
			(width 0)
			(type solid)
		)
		(fill yes)
		(layer "B.Cu")
		(net "GND")
	)
	(gr_poly
		(pts
			(arc
				(start 335.822798 -345.465146)
				(mid 335.57337 -345.465146)
				(end 335.822798 -345.465146)
			)
		)
		(stroke
			(width 0)
			(type solid)
		)
		(fill yes)
		(layer "B.Cu")
		(net "GND")
	)
	(gr_poly
		(pts
			(arc
				(start 335.822798 -342.439498)
				(mid 335.57337 -342.439498)
				(end 335.822798 -342.439498)
			)
		)
		(stroke
			(width 0)
			(type solid)
		)
		(fill yes)
		(layer "B.Cu")
		(net "GND")
	)
	(gr_poly
		(pts
			(arc
				(start 336.31251 -245.776242)
				(mid 336.052922 -245.776242)
				(end 336.31251 -245.776242)
			)
		)
		(stroke
			(width 0)
			(type solid)
		)
		(fill yes)
		(layer "B.Cu")
		(net "GND")
	)
	(gr_poly
		(pts
			(arc
				(start 336.930238 -357.75773)
				(mid 336.68081 -357.75773)
				(end 336.930238 -357.75773)
			)
		)
		(stroke
			(width 0)
			(type solid)
		)
		(fill yes)
		(layer "B.Cu")
		(net "GND")
	)
	(gr_poly
		(pts
			(arc
				(start 336.930238 -354.732082)
				(mid 336.68081 -354.732082)
				(end 336.930238 -354.732082)
			)
		)
		(stroke
			(width 0)
			(type solid)
		)
		(fill yes)
		(layer "B.Cu")
		(net "GND")
	)
	(gr_poly
		(pts
			(arc
				(start 336.930238 -351.611438)
				(mid 336.68081 -351.611438)
				(end 336.930238 -351.611438)
			)
		)
		(stroke
			(width 0)
			(type solid)
		)
		(fill yes)
		(layer "B.Cu")
		(net "GND")
	)
	(gr_poly
		(pts
			(arc
				(start 336.930238 -348.58579)
				(mid 336.68081 -348.58579)
				(end 336.930238 -348.58579)
			)
		)
		(stroke
			(width 0)
			(type solid)
		)
		(fill yes)
		(layer "B.Cu")
		(net "GND")
	)
	(gr_poly
		(pts
			(arc
				(start 336.930238 -345.465146)
				(mid 336.68081 -345.465146)
				(end 336.930238 -345.465146)
			)
		)
		(stroke
			(width 0)
			(type solid)
		)
		(fill yes)
		(layer "B.Cu")
		(net "GND")
	)
	(gr_poly
		(pts
			(arc
				(start 336.930238 -342.439498)
				(mid 336.68081 -342.439498)
				(end 336.930238 -342.439498)
			)
		)
		(stroke
			(width 0)
			(type solid)
		)
		(fill yes)
		(layer "B.Cu")
		(net "GND")
	)
	(gr_poly
		(pts
			(arc
				(start 337.652614 -411.141926)
				(mid 337.403186 -411.141926)
				(end 337.652614 -411.141926)
			)
		)
		(stroke
			(width 0)
			(type solid)
		)
		(fill yes)
		(layer "B.Cu")
		(net "GND")
	)
	(gr_poly
		(pts
			(arc
				(start 337.652614 -409.940252)
				(mid 337.403186 -409.940252)
				(end 337.652614 -409.940252)
			)
		)
		(stroke
			(width 0)
			(type solid)
		)
		(fill yes)
		(layer "B.Cu")
		(net "GND")
	)
	(gr_poly
		(pts
			(arc
				(start 337.652614 -408.738578)
				(mid 337.403186 -408.738578)
				(end 337.652614 -408.738578)
			)
		)
		(stroke
			(width 0)
			(type solid)
		)
		(fill yes)
		(layer "B.Cu")
		(net "GND")
	)
	(gr_poly
		(pts
			(arc
				(start 337.652614 -407.24201)
				(mid 337.403186 -407.24201)
				(end 337.652614 -407.24201)
			)
		)
		(stroke
			(width 0)
			(type solid)
		)
		(fill yes)
		(layer "B.Cu")
		(net "GND")
	)
	(gr_poly
		(pts
			(arc
				(start 337.652614 -406.040336)
				(mid 337.403186 -406.040336)
				(end 337.652614 -406.040336)
			)
		)
		(stroke
			(width 0)
			(type solid)
		)
		(fill yes)
		(layer "B.Cu")
		(net "GND")
	)
	(gr_poly
		(pts
			(arc
				(start 337.652614 -404.838662)
				(mid 337.403186 -404.838662)
				(end 337.652614 -404.838662)
			)
		)
		(stroke
			(width 0)
			(type solid)
		)
		(fill yes)
		(layer "B.Cu")
		(net "GND")
	)
	(gr_poly
		(pts
			(arc
				(start 337.652614 -403.34184)
				(mid 337.403186 -403.34184)
				(end 337.652614 -403.34184)
			)
		)
		(stroke
			(width 0)
			(type solid)
		)
		(fill yes)
		(layer "B.Cu")
		(net "GND")
	)
	(gr_poly
		(pts
			(arc
				(start 337.652614 -402.140166)
				(mid 337.403186 -402.140166)
				(end 337.652614 -402.140166)
			)
		)
		(stroke
			(width 0)
			(type solid)
		)
		(fill yes)
		(layer "B.Cu")
		(net "GND")
	)
	(gr_poly
		(pts
			(arc
				(start 337.652614 -400.938492)
				(mid 337.403186 -400.938492)
				(end 337.652614 -400.938492)
			)
		)
		(stroke
			(width 0)
			(type solid)
		)
		(fill yes)
		(layer "B.Cu")
		(net "GND")
	)
	(gr_poly
		(pts
			(arc
				(start 337.652614 -399.441924)
				(mid 337.403186 -399.441924)
				(end 337.652614 -399.441924)
			)
		)
		(stroke
			(width 0)
			(type solid)
		)
		(fill yes)
		(layer "B.Cu")
		(net "GND")
	)
	(gr_poly
		(pts
			(arc
				(start 337.652614 -398.24025)
				(mid 337.403186 -398.24025)
				(end 337.652614 -398.24025)
			)
		)
		(stroke
			(width 0)
			(type solid)
		)
		(fill yes)
		(layer "B.Cu")
		(net "GND")
	)
	(gr_poly
		(pts
			(arc
				(start 337.652614 -397.038576)
				(mid 337.403186 -397.038576)
				(end 337.652614 -397.038576)
			)
		)
		(stroke
			(width 0)
			(type solid)
		)
		(fill yes)
		(layer "B.Cu")
		(net "GND")
	)
	(gr_poly
		(pts
			(arc
				(start 338.931758 -357.75773)
				(mid 338.68233 -357.75773)
				(end 338.931758 -357.75773)
			)
		)
		(stroke
			(width 0)
			(type solid)
		)
		(fill yes)
		(layer "B.Cu")
		(net "GND")
	)
	(gr_poly
		(pts
			(arc
				(start 338.931758 -354.732082)
				(mid 338.68233 -354.732082)
				(end 338.931758 -354.732082)
			)
		)
		(stroke
			(width 0)
			(type solid)
		)
		(fill yes)
		(layer "B.Cu")
		(net "GND")
	)
	(gr_poly
		(pts
			(arc
				(start 338.931758 -351.611438)
				(mid 338.68233 -351.611438)
				(end 338.931758 -351.611438)
			)
		)
		(stroke
			(width 0)
			(type solid)
		)
		(fill yes)
		(layer "B.Cu")
		(net "GND")
	)
	(gr_poly
		(pts
			(arc
				(start 338.931758 -348.58579)
				(mid 338.68233 -348.58579)
				(end 338.931758 -348.58579)
			)
		)
		(stroke
			(width 0)
			(type solid)
		)
		(fill yes)
		(layer "B.Cu")
		(net "GND")
	)
	(gr_poly
		(pts
			(arc
				(start 338.931758 -345.465146)
				(mid 338.68233 -345.465146)
				(end 338.931758 -345.465146)
			)
		)
		(stroke
			(width 0)
			(type solid)
		)
		(fill yes)
		(layer "B.Cu")
		(net "GND")
	)
	(gr_poly
		(pts
			(arc
				(start 338.931758 -342.439498)
				(mid 338.68233 -342.439498)
				(end 338.931758 -342.439498)
			)
		)
		(stroke
			(width 0)
			(type solid)
		)
		(fill yes)
		(layer "B.Cu")
		(net "GND")
	)
	(gr_poly
		(pts
			(arc
				(start 339.852762 -410.041852)
				(mid 339.603334 -410.041852)
				(end 339.852762 -410.041852)
			)
		)
		(stroke
			(width 0)
			(type solid)
		)
		(fill yes)
		(layer "B.Cu")
		(net "GND")
	)
	(gr_poly
		(pts
			(arc
				(start 339.852762 -408.840178)
				(mid 339.603334 -408.840178)
				(end 339.852762 -408.840178)
			)
		)
		(stroke
			(width 0)
			(type solid)
		)
		(fill yes)
		(layer "B.Cu")
		(net "GND")
	)
	(gr_poly
		(pts
			(arc
				(start 339.852762 -407.638504)
				(mid 339.603334 -407.638504)
				(end 339.852762 -407.638504)
			)
		)
		(stroke
			(width 0)
			(type solid)
		)
		(fill yes)
		(layer "B.Cu")
		(net "GND")
	)
	(gr_poly
		(pts
			(arc
				(start 339.852762 -406.141936)
				(mid 339.603334 -406.141936)
				(end 339.852762 -406.141936)
			)
		)
		(stroke
			(width 0)
			(type solid)
		)
		(fill yes)
		(layer "B.Cu")
		(net "GND")
	)
	(gr_poly
		(pts
			(arc
				(start 339.852762 -404.940262)
				(mid 339.603334 -404.940262)
				(end 339.852762 -404.940262)
			)
		)
		(stroke
			(width 0)
			(type solid)
		)
		(fill yes)
		(layer "B.Cu")
		(net "GND")
	)
	(gr_poly
		(pts
			(arc
				(start 339.852762 -403.738588)
				(mid 339.603334 -403.738588)
				(end 339.852762 -403.738588)
			)
		)
		(stroke
			(width 0)
			(type solid)
		)
		(fill yes)
		(layer "B.Cu")
		(net "GND")
	)
	(gr_poly
		(pts
			(arc
				(start 339.852762 -402.241766)
				(mid 339.603334 -402.241766)
				(end 339.852762 -402.241766)
			)
		)
		(stroke
			(width 0)
			(type solid)
		)
		(fill yes)
		(layer "B.Cu")
		(net "GND")
	)
	(gr_poly
		(pts
			(arc
				(start 339.852762 -401.040092)
				(mid 339.603334 -401.040092)
				(end 339.852762 -401.040092)
			)
		)
		(stroke
			(width 0)
			(type solid)
		)
		(fill yes)
		(layer "B.Cu")
		(net "GND")
	)
	(gr_poly
		(pts
			(arc
				(start 339.852762 -399.838418)
				(mid 339.603334 -399.838418)
				(end 339.852762 -399.838418)
			)
		)
		(stroke
			(width 0)
			(type solid)
		)
		(fill yes)
		(layer "B.Cu")
		(net "GND")
	)
	(gr_poly
		(pts
			(arc
				(start 339.852762 -398.34185)
				(mid 339.603334 -398.34185)
				(end 339.852762 -398.34185)
			)
		)
		(stroke
			(width 0)
			(type solid)
		)
		(fill yes)
		(layer "B.Cu")
		(net "GND")
	)
	(gr_poly
		(pts
			(arc
				(start 339.852762 -397.140176)
				(mid 339.603334 -397.140176)
				(end 339.852762 -397.140176)
			)
		)
		(stroke
			(width 0)
			(type solid)
		)
		(fill yes)
		(layer "B.Cu")
		(net "GND")
	)
	(gr_poly
		(pts
			(arc
				(start 339.852762 -395.938502)
				(mid 339.603334 -395.938502)
				(end 339.852762 -395.938502)
			)
		)
		(stroke
			(width 0)
			(type solid)
		)
		(fill yes)
		(layer "B.Cu")
		(net "GND")
	)
	(gr_poly
		(pts
			(arc
				(start 340.039198 -357.75773)
				(mid 339.78977 -357.75773)
				(end 340.039198 -357.75773)
			)
		)
		(stroke
			(width 0)
			(type solid)
		)
		(fill yes)
		(layer "B.Cu")
		(net "GND")
	)
	(gr_poly
		(pts
			(arc
				(start 340.039198 -354.732082)
				(mid 339.78977 -354.732082)
				(end 340.039198 -354.732082)
			)
		)
		(stroke
			(width 0)
			(type solid)
		)
		(fill yes)
		(layer "B.Cu")
		(net "GND")
	)
	(gr_poly
		(pts
			(arc
				(start 340.039198 -351.611438)
				(mid 339.78977 -351.611438)
				(end 340.039198 -351.611438)
			)
		)
		(stroke
			(width 0)
			(type solid)
		)
		(fill yes)
		(layer "B.Cu")
		(net "GND")
	)
	(gr_poly
		(pts
			(arc
				(start 340.039198 -348.58579)
				(mid 339.78977 -348.58579)
				(end 340.039198 -348.58579)
			)
		)
		(stroke
			(width 0)
			(type solid)
		)
		(fill yes)
		(layer "B.Cu")
		(net "GND")
	)
	(gr_poly
		(pts
			(arc
				(start 340.039198 -345.465146)
				(mid 339.78977 -345.465146)
				(end 340.039198 -345.465146)
			)
		)
		(stroke
			(width 0)
			(type solid)
		)
		(fill yes)
		(layer "B.Cu")
		(net "GND")
	)
	(gr_poly
		(pts
			(arc
				(start 340.039198 -342.439498)
				(mid 339.78977 -342.439498)
				(end 340.039198 -342.439498)
			)
		)
		(stroke
			(width 0)
			(type solid)
		)
		(fill yes)
		(layer "B.Cu")
		(net "GND")
	)
	(gr_poly
		(pts
			(arc
				(start 340.949788 -240.641378)
				(mid 340.694772 -240.641378)
				(end 340.949788 -240.641378)
			)
		)
		(stroke
			(width 0)
			(type solid)
		)
		(fill yes)
		(layer "B.Cu")
		(net "GND")
	)
	(gr_poly
		(pts
			(arc
				(start 342.040718 -357.75773)
				(mid 341.79129 -357.75773)
				(end 342.040718 -357.75773)
			)
		)
		(stroke
			(width 0)
			(type solid)
		)
		(fill yes)
		(layer "B.Cu")
		(net "GND")
	)
	(gr_poly
		(pts
			(arc
				(start 342.040718 -354.732082)
				(mid 341.79129 -354.732082)
				(end 342.040718 -354.732082)
			)
		)
		(stroke
			(width 0)
			(type solid)
		)
		(fill yes)
		(layer "B.Cu")
		(net "GND")
	)
	(gr_poly
		(pts
			(arc
				(start 342.040718 -351.611438)
				(mid 341.79129 -351.611438)
				(end 342.040718 -351.611438)
			)
		)
		(stroke
			(width 0)
			(type solid)
		)
		(fill yes)
		(layer "B.Cu")
		(net "GND")
	)
	(gr_poly
		(pts
			(arc
				(start 342.040718 -348.58579)
				(mid 341.79129 -348.58579)
				(end 342.040718 -348.58579)
			)
		)
		(stroke
			(width 0)
			(type solid)
		)
		(fill yes)
		(layer "B.Cu")
		(net "GND")
	)
	(gr_poly
		(pts
			(arc
				(start 342.040718 -345.465146)
				(mid 341.79129 -345.465146)
				(end 342.040718 -345.465146)
			)
		)
		(stroke
			(width 0)
			(type solid)
		)
		(fill yes)
		(layer "B.Cu")
		(net "GND")
	)
	(gr_poly
		(pts
			(arc
				(start 342.040718 -342.439498)
				(mid 341.79129 -342.439498)
				(end 342.040718 -342.439498)
			)
		)
		(stroke
			(width 0)
			(type solid)
		)
		(fill yes)
		(layer "B.Cu")
		(net "GND")
	)
	(gr_poly
		(pts
			(arc
				(start 342.052656 -411.141926)
				(mid 341.803228 -411.141926)
				(end 342.052656 -411.141926)
			)
		)
		(stroke
			(width 0)
			(type solid)
		)
		(fill yes)
		(layer "B.Cu")
		(net "GND")
	)
	(gr_poly
		(pts
			(arc
				(start 342.052656 -409.940252)
				(mid 341.803228 -409.940252)
				(end 342.052656 -409.940252)
			)
		)
		(stroke
			(width 0)
			(type solid)
		)
		(fill yes)
		(layer "B.Cu")
		(net "GND")
	)
	(gr_poly
		(pts
			(arc
				(start 342.052656 -408.738578)
				(mid 341.803228 -408.738578)
				(end 342.052656 -408.738578)
			)
		)
		(stroke
			(width 0)
			(type solid)
		)
		(fill yes)
		(layer "B.Cu")
		(net "GND")
	)
	(gr_poly
		(pts
			(arc
				(start 342.052656 -407.24201)
				(mid 341.803228 -407.24201)
				(end 342.052656 -407.24201)
			)
		)
		(stroke
			(width 0)
			(type solid)
		)
		(fill yes)
		(layer "B.Cu")
		(net "GND")
	)
	(gr_poly
		(pts
			(arc
				(start 342.052656 -406.040336)
				(mid 341.803228 -406.040336)
				(end 342.052656 -406.040336)
			)
		)
		(stroke
			(width 0)
			(type solid)
		)
		(fill yes)
		(layer "B.Cu")
		(net "GND")
	)
	(gr_poly
		(pts
			(arc
				(start 342.052656 -404.838662)
				(mid 341.803228 -404.838662)
				(end 342.052656 -404.838662)
			)
		)
		(stroke
			(width 0)
			(type solid)
		)
		(fill yes)
		(layer "B.Cu")
		(net "GND")
	)
	(gr_poly
		(pts
			(arc
				(start 342.052656 -403.34184)
				(mid 341.803228 -403.34184)
				(end 342.052656 -403.34184)
			)
		)
		(stroke
			(width 0)
			(type solid)
		)
		(fill yes)
		(layer "B.Cu")
		(net "GND")
	)
	(gr_poly
		(pts
			(arc
				(start 342.052656 -402.140166)
				(mid 341.803228 -402.140166)
				(end 342.052656 -402.140166)
			)
		)
		(stroke
			(width 0)
			(type solid)
		)
		(fill yes)
		(layer "B.Cu")
		(net "GND")
	)
	(gr_poly
		(pts
			(arc
				(start 342.052656 -400.938492)
				(mid 341.803228 -400.938492)
				(end 342.052656 -400.938492)
			)
		)
		(stroke
			(width 0)
			(type solid)
		)
		(fill yes)
		(layer "B.Cu")
		(net "GND")
	)
	(gr_poly
		(pts
			(arc
				(start 342.052656 -399.441924)
				(mid 341.803228 -399.441924)
				(end 342.052656 -399.441924)
			)
		)
		(stroke
			(width 0)
			(type solid)
		)
		(fill yes)
		(layer "B.Cu")
		(net "GND")
	)
	(gr_poly
		(pts
			(arc
				(start 342.052656 -398.24025)
				(mid 341.803228 -398.24025)
				(end 342.052656 -398.24025)
			)
		)
		(stroke
			(width 0)
			(type solid)
		)
		(fill yes)
		(layer "B.Cu")
		(net "GND")
	)
	(gr_poly
		(pts
			(arc
				(start 342.052656 -397.038576)
				(mid 341.803228 -397.038576)
				(end 342.052656 -397.038576)
			)
		)
		(stroke
			(width 0)
			(type solid)
		)
		(fill yes)
		(layer "B.Cu")
		(net "GND")
	)
	(gr_poly
		(pts
			(arc
				(start 343.148158 -357.75773)
				(mid 342.89873 -357.75773)
				(end 343.148158 -357.75773)
			)
		)
		(stroke
			(width 0)
			(type solid)
		)
		(fill yes)
		(layer "B.Cu")
		(net "GND")
	)
	(gr_poly
		(pts
			(arc
				(start 343.148158 -354.732082)
				(mid 342.89873 -354.732082)
				(end 343.148158 -354.732082)
			)
		)
		(stroke
			(width 0)
			(type solid)
		)
		(fill yes)
		(layer "B.Cu")
		(net "GND")
	)
	(gr_poly
		(pts
			(arc
				(start 343.148158 -351.611438)
				(mid 342.89873 -351.611438)
				(end 343.148158 -351.611438)
			)
		)
		(stroke
			(width 0)
			(type solid)
		)
		(fill yes)
		(layer "B.Cu")
		(net "GND")
	)
	(gr_poly
		(pts
			(arc
				(start 343.148158 -348.58579)
				(mid 342.89873 -348.58579)
				(end 343.148158 -348.58579)
			)
		)
		(stroke
			(width 0)
			(type solid)
		)
		(fill yes)
		(layer "B.Cu")
		(net "GND")
	)
	(gr_poly
		(pts
			(arc
				(start 343.148158 -345.465146)
				(mid 342.89873 -345.465146)
				(end 343.148158 -345.465146)
			)
		)
		(stroke
			(width 0)
			(type solid)
		)
		(fill yes)
		(layer "B.Cu")
		(net "GND")
	)
	(gr_poly
		(pts
			(arc
				(start 343.148158 -342.439498)
				(mid 342.89873 -342.439498)
				(end 343.148158 -342.439498)
			)
		)
		(stroke
			(width 0)
			(type solid)
		)
		(fill yes)
		(layer "B.Cu")
		(net "GND")
	)
	(gr_poly
		(pts
			(arc
				(start 344.25255 -410.041852)
				(mid 344.003122 -410.041852)
				(end 344.25255 -410.041852)
			)
		)
		(stroke
			(width 0)
			(type solid)
		)
		(fill yes)
		(layer "B.Cu")
		(net "GND")
	)
	(gr_poly
		(pts
			(arc
				(start 344.25255 -408.840178)
				(mid 344.003122 -408.840178)
				(end 344.25255 -408.840178)
			)
		)
		(stroke
			(width 0)
			(type solid)
		)
		(fill yes)
		(layer "B.Cu")
		(net "GND")
	)
	(gr_poly
		(pts
			(arc
				(start 344.25255 -407.638504)
				(mid 344.003122 -407.638504)
				(end 344.25255 -407.638504)
			)
		)
		(stroke
			(width 0)
			(type solid)
		)
		(fill yes)
		(layer "B.Cu")
		(net "GND")
	)
	(gr_poly
		(pts
			(arc
				(start 344.25255 -406.141936)
				(mid 344.003122 -406.141936)
				(end 344.25255 -406.141936)
			)
		)
		(stroke
			(width 0)
			(type solid)
		)
		(fill yes)
		(layer "B.Cu")
		(net "GND")
	)
	(gr_poly
		(pts
			(arc
				(start 344.25255 -404.940262)
				(mid 344.003122 -404.940262)
				(end 344.25255 -404.940262)
			)
		)
		(stroke
			(width 0)
			(type solid)
		)
		(fill yes)
		(layer "B.Cu")
		(net "GND")
	)
	(gr_poly
		(pts
			(arc
				(start 344.25255 -403.738588)
				(mid 344.003122 -403.738588)
				(end 344.25255 -403.738588)
			)
		)
		(stroke
			(width 0)
			(type solid)
		)
		(fill yes)
		(layer "B.Cu")
		(net "GND")
	)
	(gr_poly
		(pts
			(arc
				(start 344.25255 -402.241766)
				(mid 344.003122 -402.241766)
				(end 344.25255 -402.241766)
			)
		)
		(stroke
			(width 0)
			(type solid)
		)
		(fill yes)
		(layer "B.Cu")
		(net "GND")
	)
	(gr_poly
		(pts
			(arc
				(start 344.25255 -401.040092)
				(mid 344.003122 -401.040092)
				(end 344.25255 -401.040092)
			)
		)
		(stroke
			(width 0)
			(type solid)
		)
		(fill yes)
		(layer "B.Cu")
		(net "GND")
	)
	(gr_poly
		(pts
			(arc
				(start 344.25255 -399.838418)
				(mid 344.003122 -399.838418)
				(end 344.25255 -399.838418)
			)
		)
		(stroke
			(width 0)
			(type solid)
		)
		(fill yes)
		(layer "B.Cu")
		(net "GND")
	)
	(gr_poly
		(pts
			(arc
				(start 344.25255 -398.34185)
				(mid 344.003122 -398.34185)
				(end 344.25255 -398.34185)
			)
		)
		(stroke
			(width 0)
			(type solid)
		)
		(fill yes)
		(layer "B.Cu")
		(net "GND")
	)
	(gr_poly
		(pts
			(arc
				(start 344.25255 -397.140176)
				(mid 344.003122 -397.140176)
				(end 344.25255 -397.140176)
			)
		)
		(stroke
			(width 0)
			(type solid)
		)
		(fill yes)
		(layer "B.Cu")
		(net "GND")
	)
	(gr_poly
		(pts
			(arc
				(start 344.25255 -395.938502)
				(mid 344.003122 -395.938502)
				(end 344.25255 -395.938502)
			)
		)
		(stroke
			(width 0)
			(type solid)
		)
		(fill yes)
		(layer "B.Cu")
		(net "GND")
	)
	(gr_poly
		(pts
			(arc
				(start 345.149678 -357.75773)
				(mid 344.90025 -357.75773)
				(end 345.149678 -357.75773)
			)
		)
		(stroke
			(width 0)
			(type solid)
		)
		(fill yes)
		(layer "B.Cu")
		(net "GND")
	)
	(gr_poly
		(pts
			(arc
				(start 345.149678 -354.732082)
				(mid 344.90025 -354.732082)
				(end 345.149678 -354.732082)
			)
		)
		(stroke
			(width 0)
			(type solid)
		)
		(fill yes)
		(layer "B.Cu")
		(net "GND")
	)
	(gr_poly
		(pts
			(arc
				(start 345.149678 -351.611438)
				(mid 344.90025 -351.611438)
				(end 345.149678 -351.611438)
			)
		)
		(stroke
			(width 0)
			(type solid)
		)
		(fill yes)
		(layer "B.Cu")
		(net "GND")
	)
	(gr_poly
		(pts
			(arc
				(start 345.149678 -348.58579)
				(mid 344.90025 -348.58579)
				(end 345.149678 -348.58579)
			)
		)
		(stroke
			(width 0)
			(type solid)
		)
		(fill yes)
		(layer "B.Cu")
		(net "GND")
	)
	(gr_poly
		(pts
			(arc
				(start 345.149678 -345.465146)
				(mid 344.90025 -345.465146)
				(end 345.149678 -345.465146)
			)
		)
		(stroke
			(width 0)
			(type solid)
		)
		(fill yes)
		(layer "B.Cu")
		(net "GND")
	)
	(gr_poly
		(pts
			(arc
				(start 345.149678 -342.439498)
				(mid 344.90025 -342.439498)
				(end 345.149678 -342.439498)
			)
		)
		(stroke
			(width 0)
			(type solid)
		)
		(fill yes)
		(layer "B.Cu")
		(net "GND")
	)
	(gr_poly
		(pts
			(arc
				(start 346.452698 -411.141926)
				(mid 346.20327 -411.141926)
				(end 346.452698 -411.141926)
			)
		)
		(stroke
			(width 0)
			(type solid)
		)
		(fill yes)
		(layer "B.Cu")
		(net "GND")
	)
	(gr_poly
		(pts
			(arc
				(start 346.452698 -409.940252)
				(mid 346.20327 -409.940252)
				(end 346.452698 -409.940252)
			)
		)
		(stroke
			(width 0)
			(type solid)
		)
		(fill yes)
		(layer "B.Cu")
		(net "GND")
	)
	(gr_poly
		(pts
			(arc
				(start 346.452698 -408.738578)
				(mid 346.20327 -408.738578)
				(end 346.452698 -408.738578)
			)
		)
		(stroke
			(width 0)
			(type solid)
		)
		(fill yes)
		(layer "B.Cu")
		(net "GND")
	)
	(gr_poly
		(pts
			(arc
				(start 346.452698 -407.24201)
				(mid 346.20327 -407.24201)
				(end 346.452698 -407.24201)
			)
		)
		(stroke
			(width 0)
			(type solid)
		)
		(fill yes)
		(layer "B.Cu")
		(net "GND")
	)
	(gr_poly
		(pts
			(arc
				(start 346.452698 -406.040336)
				(mid 346.20327 -406.040336)
				(end 346.452698 -406.040336)
			)
		)
		(stroke
			(width 0)
			(type solid)
		)
		(fill yes)
		(layer "B.Cu")
		(net "GND")
	)
	(gr_poly
		(pts
			(arc
				(start 346.452698 -404.838662)
				(mid 346.20327 -404.838662)
				(end 346.452698 -404.838662)
			)
		)
		(stroke
			(width 0)
			(type solid)
		)
		(fill yes)
		(layer "B.Cu")
		(net "GND")
	)
	(gr_poly
		(pts
			(arc
				(start 346.452698 -403.34184)
				(mid 346.20327 -403.34184)
				(end 346.452698 -403.34184)
			)
		)
		(stroke
			(width 0)
			(type solid)
		)
		(fill yes)
		(layer "B.Cu")
		(net "GND")
	)
	(gr_poly
		(pts
			(arc
				(start 346.452698 -402.140166)
				(mid 346.20327 -402.140166)
				(end 346.452698 -402.140166)
			)
		)
		(stroke
			(width 0)
			(type solid)
		)
		(fill yes)
		(layer "B.Cu")
		(net "GND")
	)
	(gr_poly
		(pts
			(arc
				(start 346.452698 -400.938492)
				(mid 346.20327 -400.938492)
				(end 346.452698 -400.938492)
			)
		)
		(stroke
			(width 0)
			(type solid)
		)
		(fill yes)
		(layer "B.Cu")
		(net "GND")
	)
	(gr_poly
		(pts
			(arc
				(start 346.452698 -399.441924)
				(mid 346.20327 -399.441924)
				(end 346.452698 -399.441924)
			)
		)
		(stroke
			(width 0)
			(type solid)
		)
		(fill yes)
		(layer "B.Cu")
		(net "GND")
	)
	(gr_poly
		(pts
			(arc
				(start 346.452698 -398.24025)
				(mid 346.20327 -398.24025)
				(end 346.452698 -398.24025)
			)
		)
		(stroke
			(width 0)
			(type solid)
		)
		(fill yes)
		(layer "B.Cu")
		(net "GND")
	)
	(gr_poly
		(pts
			(arc
				(start 346.452698 -397.038576)
				(mid 346.20327 -397.038576)
				(end 346.452698 -397.038576)
			)
		)
		(stroke
			(width 0)
			(type solid)
		)
		(fill yes)
		(layer "B.Cu")
		(net "GND")
	)
	(gr_poly
		(pts
			(arc
				(start 348.652592 -410.041852)
				(mid 348.403164 -410.041852)
				(end 348.652592 -410.041852)
			)
		)
		(stroke
			(width 0)
			(type solid)
		)
		(fill yes)
		(layer "B.Cu")
		(net "GND")
	)
	(gr_poly
		(pts
			(arc
				(start 348.652592 -408.840178)
				(mid 348.403164 -408.840178)
				(end 348.652592 -408.840178)
			)
		)
		(stroke
			(width 0)
			(type solid)
		)
		(fill yes)
		(layer "B.Cu")
		(net "GND")
	)
	(gr_poly
		(pts
			(arc
				(start 348.652592 -407.638504)
				(mid 348.403164 -407.638504)
				(end 348.652592 -407.638504)
			)
		)
		(stroke
			(width 0)
			(type solid)
		)
		(fill yes)
		(layer "B.Cu")
		(net "GND")
	)
	(gr_poly
		(pts
			(arc
				(start 348.652592 -406.141936)
				(mid 348.403164 -406.141936)
				(end 348.652592 -406.141936)
			)
		)
		(stroke
			(width 0)
			(type solid)
		)
		(fill yes)
		(layer "B.Cu")
		(net "GND")
	)
	(gr_poly
		(pts
			(arc
				(start 348.652592 -404.940262)
				(mid 348.403164 -404.940262)
				(end 348.652592 -404.940262)
			)
		)
		(stroke
			(width 0)
			(type solid)
		)
		(fill yes)
		(layer "B.Cu")
		(net "GND")
	)
	(gr_poly
		(pts
			(arc
				(start 348.652592 -403.738588)
				(mid 348.403164 -403.738588)
				(end 348.652592 -403.738588)
			)
		)
		(stroke
			(width 0)
			(type solid)
		)
		(fill yes)
		(layer "B.Cu")
		(net "GND")
	)
	(gr_poly
		(pts
			(arc
				(start 348.652592 -402.241766)
				(mid 348.403164 -402.241766)
				(end 348.652592 -402.241766)
			)
		)
		(stroke
			(width 0)
			(type solid)
		)
		(fill yes)
		(layer "B.Cu")
		(net "GND")
	)
	(gr_poly
		(pts
			(arc
				(start 348.652592 -401.040092)
				(mid 348.403164 -401.040092)
				(end 348.652592 -401.040092)
			)
		)
		(stroke
			(width 0)
			(type solid)
		)
		(fill yes)
		(layer "B.Cu")
		(net "GND")
	)
	(gr_poly
		(pts
			(arc
				(start 348.652592 -399.838418)
				(mid 348.403164 -399.838418)
				(end 348.652592 -399.838418)
			)
		)
		(stroke
			(width 0)
			(type solid)
		)
		(fill yes)
		(layer "B.Cu")
		(net "GND")
	)
	(gr_poly
		(pts
			(arc
				(start 348.652592 -398.34185)
				(mid 348.403164 -398.34185)
				(end 348.652592 -398.34185)
			)
		)
		(stroke
			(width 0)
			(type solid)
		)
		(fill yes)
		(layer "B.Cu")
		(net "GND")
	)
	(gr_poly
		(pts
			(arc
				(start 348.652592 -397.140176)
				(mid 348.403164 -397.140176)
				(end 348.652592 -397.140176)
			)
		)
		(stroke
			(width 0)
			(type solid)
		)
		(fill yes)
		(layer "B.Cu")
		(net "GND")
	)
	(gr_poly
		(pts
			(arc
				(start 348.652592 -395.938502)
				(mid 348.403164 -395.938502)
				(end 348.652592 -395.938502)
			)
		)
		(stroke
			(width 0)
			(type solid)
		)
		(fill yes)
		(layer "B.Cu")
		(net "GND")
	)
	(gr_poly
		(pts
			(arc
				(start 375.05259 -410.041852)
				(mid 374.803162 -410.041852)
				(end 375.05259 -410.041852)
			)
		)
		(stroke
			(width 0)
			(type solid)
		)
		(fill yes)
		(layer "B.Cu")
		(net "GND")
	)
	(gr_poly
		(pts
			(arc
				(start 375.05259 -408.840178)
				(mid 374.803162 -408.840178)
				(end 375.05259 -408.840178)
			)
		)
		(stroke
			(width 0)
			(type solid)
		)
		(fill yes)
		(layer "B.Cu")
		(net "GND")
	)
	(gr_poly
		(pts
			(arc
				(start 375.05259 -407.638504)
				(mid 374.803162 -407.638504)
				(end 375.05259 -407.638504)
			)
		)
		(stroke
			(width 0)
			(type solid)
		)
		(fill yes)
		(layer "B.Cu")
		(net "GND")
	)
	(gr_poly
		(pts
			(arc
				(start 375.05259 -406.141936)
				(mid 374.803162 -406.141936)
				(end 375.05259 -406.141936)
			)
		)
		(stroke
			(width 0)
			(type solid)
		)
		(fill yes)
		(layer "B.Cu")
		(net "GND")
	)
	(gr_poly
		(pts
			(arc
				(start 375.05259 -404.940262)
				(mid 374.803162 -404.940262)
				(end 375.05259 -404.940262)
			)
		)
		(stroke
			(width 0)
			(type solid)
		)
		(fill yes)
		(layer "B.Cu")
		(net "GND")
	)
	(gr_poly
		(pts
			(arc
				(start 375.05259 -403.738588)
				(mid 374.803162 -403.738588)
				(end 375.05259 -403.738588)
			)
		)
		(stroke
			(width 0)
			(type solid)
		)
		(fill yes)
		(layer "B.Cu")
		(net "GND")
	)
	(gr_poly
		(pts
			(arc
				(start 375.05259 -402.241766)
				(mid 374.803162 -402.241766)
				(end 375.05259 -402.241766)
			)
		)
		(stroke
			(width 0)
			(type solid)
		)
		(fill yes)
		(layer "B.Cu")
		(net "GND")
	)
	(gr_poly
		(pts
			(arc
				(start 375.05259 -401.040092)
				(mid 374.803162 -401.040092)
				(end 375.05259 -401.040092)
			)
		)
		(stroke
			(width 0)
			(type solid)
		)
		(fill yes)
		(layer "B.Cu")
		(net "GND")
	)
	(gr_poly
		(pts
			(arc
				(start 375.05259 -399.838418)
				(mid 374.803162 -399.838418)
				(end 375.05259 -399.838418)
			)
		)
		(stroke
			(width 0)
			(type solid)
		)
		(fill yes)
		(layer "B.Cu")
		(net "GND")
	)
	(gr_poly
		(pts
			(arc
				(start 375.05259 -398.34185)
				(mid 374.803162 -398.34185)
				(end 375.05259 -398.34185)
			)
		)
		(stroke
			(width 0)
			(type solid)
		)
		(fill yes)
		(layer "B.Cu")
		(net "GND")
	)
	(gr_poly
		(pts
			(arc
				(start 375.05259 -397.140176)
				(mid 374.803162 -397.140176)
				(end 375.05259 -397.140176)
			)
		)
		(stroke
			(width 0)
			(type solid)
		)
		(fill yes)
		(layer "B.Cu")
		(net "GND")
	)
	(gr_poly
		(pts
			(arc
				(start 375.05259 -395.938502)
				(mid 374.803162 -395.938502)
				(end 375.05259 -395.938502)
			)
		)
		(stroke
			(width 0)
			(type solid)
		)
		(fill yes)
		(layer "B.Cu")
		(net "GND")
	)
	(gr_poly
		(pts
			(arc
				(start 375.05259 -384.041904)
				(mid 374.803162 -384.041904)
				(end 375.05259 -384.041904)
			)
		)
		(stroke
			(width 0)
			(type solid)
		)
		(fill yes)
		(layer "B.Cu")
		(net "GND")
	)
	(gr_poly
		(pts
			(arc
				(start 375.05259 -382.84023)
				(mid 374.803162 -382.84023)
				(end 375.05259 -382.84023)
			)
		)
		(stroke
			(width 0)
			(type solid)
		)
		(fill yes)
		(layer "B.Cu")
		(net "GND")
	)
	(gr_poly
		(pts
			(arc
				(start 375.05259 -381.638556)
				(mid 374.803162 -381.638556)
				(end 375.05259 -381.638556)
			)
		)
		(stroke
			(width 0)
			(type solid)
		)
		(fill yes)
		(layer "B.Cu")
		(net "GND")
	)
	(gr_poly
		(pts
			(arc
				(start 375.05259 -380.141988)
				(mid 374.803162 -380.141988)
				(end 375.05259 -380.141988)
			)
		)
		(stroke
			(width 0)
			(type solid)
		)
		(fill yes)
		(layer "B.Cu")
		(net "GND")
	)
	(gr_poly
		(pts
			(arc
				(start 375.05259 -378.940314)
				(mid 374.803162 -378.940314)
				(end 375.05259 -378.940314)
			)
		)
		(stroke
			(width 0)
			(type solid)
		)
		(fill yes)
		(layer "B.Cu")
		(net "GND")
	)
	(gr_poly
		(pts
			(arc
				(start 375.05259 -377.73864)
				(mid 374.803162 -377.73864)
				(end 375.05259 -377.73864)
			)
		)
		(stroke
			(width 0)
			(type solid)
		)
		(fill yes)
		(layer "B.Cu")
		(net "GND")
	)
	(gr_poly
		(pts
			(arc
				(start 375.05259 -376.241818)
				(mid 374.803162 -376.241818)
				(end 375.05259 -376.241818)
			)
		)
		(stroke
			(width 0)
			(type solid)
		)
		(fill yes)
		(layer "B.Cu")
		(net "GND")
	)
	(gr_poly
		(pts
			(arc
				(start 375.05259 -375.040144)
				(mid 374.803162 -375.040144)
				(end 375.05259 -375.040144)
			)
		)
		(stroke
			(width 0)
			(type solid)
		)
		(fill yes)
		(layer "B.Cu")
		(net "GND")
	)
	(gr_poly
		(pts
			(arc
				(start 375.05259 -373.83847)
				(mid 374.803162 -373.83847)
				(end 375.05259 -373.83847)
			)
		)
		(stroke
			(width 0)
			(type solid)
		)
		(fill yes)
		(layer "B.Cu")
		(net "GND")
	)
	(gr_poly
		(pts
			(arc
				(start 375.05259 -372.341902)
				(mid 374.803162 -372.341902)
				(end 375.05259 -372.341902)
			)
		)
		(stroke
			(width 0)
			(type solid)
		)
		(fill yes)
		(layer "B.Cu")
		(net "GND")
	)
	(gr_poly
		(pts
			(arc
				(start 375.05259 -371.140228)
				(mid 374.803162 -371.140228)
				(end 375.05259 -371.140228)
			)
		)
		(stroke
			(width 0)
			(type solid)
		)
		(fill yes)
		(layer "B.Cu")
		(net "GND")
	)
	(gr_poly
		(pts
			(arc
				(start 375.05259 -369.938554)
				(mid 374.803162 -369.938554)
				(end 375.05259 -369.938554)
			)
		)
		(stroke
			(width 0)
			(type solid)
		)
		(fill yes)
		(layer "B.Cu")
		(net "GND")
	)
	(gr_poly
		(pts
			(arc
				(start 377.252484 -411.141926)
				(mid 377.003056 -411.141926)
				(end 377.252484 -411.141926)
			)
		)
		(stroke
			(width 0)
			(type solid)
		)
		(fill yes)
		(layer "B.Cu")
		(net "GND")
	)
	(gr_poly
		(pts
			(arc
				(start 377.252484 -409.940252)
				(mid 377.003056 -409.940252)
				(end 377.252484 -409.940252)
			)
		)
		(stroke
			(width 0)
			(type solid)
		)
		(fill yes)
		(layer "B.Cu")
		(net "GND")
	)
	(gr_poly
		(pts
			(arc
				(start 377.252484 -408.738578)
				(mid 377.003056 -408.738578)
				(end 377.252484 -408.738578)
			)
		)
		(stroke
			(width 0)
			(type solid)
		)
		(fill yes)
		(layer "B.Cu")
		(net "GND")
	)
	(gr_poly
		(pts
			(arc
				(start 377.252484 -407.24201)
				(mid 377.003056 -407.24201)
				(end 377.252484 -407.24201)
			)
		)
		(stroke
			(width 0)
			(type solid)
		)
		(fill yes)
		(layer "B.Cu")
		(net "GND")
	)
	(gr_poly
		(pts
			(arc
				(start 377.252484 -406.040336)
				(mid 377.003056 -406.040336)
				(end 377.252484 -406.040336)
			)
		)
		(stroke
			(width 0)
			(type solid)
		)
		(fill yes)
		(layer "B.Cu")
		(net "GND")
	)
	(gr_poly
		(pts
			(arc
				(start 377.252484 -404.838662)
				(mid 377.003056 -404.838662)
				(end 377.252484 -404.838662)
			)
		)
		(stroke
			(width 0)
			(type solid)
		)
		(fill yes)
		(layer "B.Cu")
		(net "GND")
	)
	(gr_poly
		(pts
			(arc
				(start 377.252484 -403.34184)
				(mid 377.003056 -403.34184)
				(end 377.252484 -403.34184)
			)
		)
		(stroke
			(width 0)
			(type solid)
		)
		(fill yes)
		(layer "B.Cu")
		(net "GND")
	)
	(gr_poly
		(pts
			(arc
				(start 377.252484 -402.140166)
				(mid 377.003056 -402.140166)
				(end 377.252484 -402.140166)
			)
		)
		(stroke
			(width 0)
			(type solid)
		)
		(fill yes)
		(layer "B.Cu")
		(net "GND")
	)
	(gr_poly
		(pts
			(arc
				(start 377.252484 -400.938492)
				(mid 377.003056 -400.938492)
				(end 377.252484 -400.938492)
			)
		)
		(stroke
			(width 0)
			(type solid)
		)
		(fill yes)
		(layer "B.Cu")
		(net "GND")
	)
	(gr_poly
		(pts
			(arc
				(start 377.252484 -399.441924)
				(mid 377.003056 -399.441924)
				(end 377.252484 -399.441924)
			)
		)
		(stroke
			(width 0)
			(type solid)
		)
		(fill yes)
		(layer "B.Cu")
		(net "GND")
	)
	(gr_poly
		(pts
			(arc
				(start 377.252484 -398.24025)
				(mid 377.003056 -398.24025)
				(end 377.252484 -398.24025)
			)
		)
		(stroke
			(width 0)
			(type solid)
		)
		(fill yes)
		(layer "B.Cu")
		(net "GND")
	)
	(gr_poly
		(pts
			(arc
				(start 377.252484 -397.038576)
				(mid 377.003056 -397.038576)
				(end 377.252484 -397.038576)
			)
		)
		(stroke
			(width 0)
			(type solid)
		)
		(fill yes)
		(layer "B.Cu")
		(net "GND")
	)
	(gr_poly
		(pts
			(arc
				(start 377.252484 -385.141978)
				(mid 377.003056 -385.141978)
				(end 377.252484 -385.141978)
			)
		)
		(stroke
			(width 0)
			(type solid)
		)
		(fill yes)
		(layer "B.Cu")
		(net "GND")
	)
	(gr_poly
		(pts
			(arc
				(start 377.252484 -383.940304)
				(mid 377.003056 -383.940304)
				(end 377.252484 -383.940304)
			)
		)
		(stroke
			(width 0)
			(type solid)
		)
		(fill yes)
		(layer "B.Cu")
		(net "GND")
	)
	(gr_poly
		(pts
			(arc
				(start 377.252484 -382.73863)
				(mid 377.003056 -382.73863)
				(end 377.252484 -382.73863)
			)
		)
		(stroke
			(width 0)
			(type solid)
		)
		(fill yes)
		(layer "B.Cu")
		(net "GND")
	)
	(gr_poly
		(pts
			(arc
				(start 377.252484 -381.242062)
				(mid 377.003056 -381.242062)
				(end 377.252484 -381.242062)
			)
		)
		(stroke
			(width 0)
			(type solid)
		)
		(fill yes)
		(layer "B.Cu")
		(net "GND")
	)
	(gr_poly
		(pts
			(arc
				(start 377.252484 -380.040388)
				(mid 377.003056 -380.040388)
				(end 377.252484 -380.040388)
			)
		)
		(stroke
			(width 0)
			(type solid)
		)
		(fill yes)
		(layer "B.Cu")
		(net "GND")
	)
	(gr_poly
		(pts
			(arc
				(start 377.252484 -378.838714)
				(mid 377.003056 -378.838714)
				(end 377.252484 -378.838714)
			)
		)
		(stroke
			(width 0)
			(type solid)
		)
		(fill yes)
		(layer "B.Cu")
		(net "GND")
	)
	(gr_poly
		(pts
			(arc
				(start 377.252484 -377.341892)
				(mid 377.003056 -377.341892)
				(end 377.252484 -377.341892)
			)
		)
		(stroke
			(width 0)
			(type solid)
		)
		(fill yes)
		(layer "B.Cu")
		(net "GND")
	)
	(gr_poly
		(pts
			(arc
				(start 377.252484 -376.140218)
				(mid 377.003056 -376.140218)
				(end 377.252484 -376.140218)
			)
		)
		(stroke
			(width 0)
			(type solid)
		)
		(fill yes)
		(layer "B.Cu")
		(net "GND")
	)
	(gr_poly
		(pts
			(arc
				(start 377.252484 -374.938544)
				(mid 377.003056 -374.938544)
				(end 377.252484 -374.938544)
			)
		)
		(stroke
			(width 0)
			(type solid)
		)
		(fill yes)
		(layer "B.Cu")
		(net "GND")
	)
	(gr_poly
		(pts
			(arc
				(start 377.252484 -373.441976)
				(mid 377.003056 -373.441976)
				(end 377.252484 -373.441976)
			)
		)
		(stroke
			(width 0)
			(type solid)
		)
		(fill yes)
		(layer "B.Cu")
		(net "GND")
	)
	(gr_poly
		(pts
			(arc
				(start 377.252484 -372.240302)
				(mid 377.003056 -372.240302)
				(end 377.252484 -372.240302)
			)
		)
		(stroke
			(width 0)
			(type solid)
		)
		(fill yes)
		(layer "B.Cu")
		(net "GND")
	)
	(gr_poly
		(pts
			(arc
				(start 377.252484 -371.038628)
				(mid 377.003056 -371.038628)
				(end 377.252484 -371.038628)
			)
		)
		(stroke
			(width 0)
			(type solid)
		)
		(fill yes)
		(layer "B.Cu")
		(net "GND")
	)
	(gr_poly
		(pts
			(arc
				(start 379.452632 -410.041852)
				(mid 379.203204 -410.041852)
				(end 379.452632 -410.041852)
			)
		)
		(stroke
			(width 0)
			(type solid)
		)
		(fill yes)
		(layer "B.Cu")
		(net "GND")
	)
	(gr_poly
		(pts
			(arc
				(start 379.452632 -408.840178)
				(mid 379.203204 -408.840178)
				(end 379.452632 -408.840178)
			)
		)
		(stroke
			(width 0)
			(type solid)
		)
		(fill yes)
		(layer "B.Cu")
		(net "GND")
	)
	(gr_poly
		(pts
			(arc
				(start 379.452632 -407.638504)
				(mid 379.203204 -407.638504)
				(end 379.452632 -407.638504)
			)
		)
		(stroke
			(width 0)
			(type solid)
		)
		(fill yes)
		(layer "B.Cu")
		(net "GND")
	)
	(gr_poly
		(pts
			(arc
				(start 379.452632 -406.141936)
				(mid 379.203204 -406.141936)
				(end 379.452632 -406.141936)
			)
		)
		(stroke
			(width 0)
			(type solid)
		)
		(fill yes)
		(layer "B.Cu")
		(net "GND")
	)
	(gr_poly
		(pts
			(arc
				(start 379.452632 -404.940262)
				(mid 379.203204 -404.940262)
				(end 379.452632 -404.940262)
			)
		)
		(stroke
			(width 0)
			(type solid)
		)
		(fill yes)
		(layer "B.Cu")
		(net "GND")
	)
	(gr_poly
		(pts
			(arc
				(start 379.452632 -403.738588)
				(mid 379.203204 -403.738588)
				(end 379.452632 -403.738588)
			)
		)
		(stroke
			(width 0)
			(type solid)
		)
		(fill yes)
		(layer "B.Cu")
		(net "GND")
	)
	(gr_poly
		(pts
			(arc
				(start 379.452632 -402.241766)
				(mid 379.203204 -402.241766)
				(end 379.452632 -402.241766)
			)
		)
		(stroke
			(width 0)
			(type solid)
		)
		(fill yes)
		(layer "B.Cu")
		(net "GND")
	)
	(gr_poly
		(pts
			(arc
				(start 379.452632 -401.040092)
				(mid 379.203204 -401.040092)
				(end 379.452632 -401.040092)
			)
		)
		(stroke
			(width 0)
			(type solid)
		)
		(fill yes)
		(layer "B.Cu")
		(net "GND")
	)
	(gr_poly
		(pts
			(arc
				(start 379.452632 -399.838418)
				(mid 379.203204 -399.838418)
				(end 379.452632 -399.838418)
			)
		)
		(stroke
			(width 0)
			(type solid)
		)
		(fill yes)
		(layer "B.Cu")
		(net "GND")
	)
	(gr_poly
		(pts
			(arc
				(start 379.452632 -398.34185)
				(mid 379.203204 -398.34185)
				(end 379.452632 -398.34185)
			)
		)
		(stroke
			(width 0)
			(type solid)
		)
		(fill yes)
		(layer "B.Cu")
		(net "GND")
	)
	(gr_poly
		(pts
			(arc
				(start 379.452632 -397.140176)
				(mid 379.203204 -397.140176)
				(end 379.452632 -397.140176)
			)
		)
		(stroke
			(width 0)
			(type solid)
		)
		(fill yes)
		(layer "B.Cu")
		(net "GND")
	)
	(gr_poly
		(pts
			(arc
				(start 379.452632 -395.938502)
				(mid 379.203204 -395.938502)
				(end 379.452632 -395.938502)
			)
		)
		(stroke
			(width 0)
			(type solid)
		)
		(fill yes)
		(layer "B.Cu")
		(net "GND")
	)
	(gr_poly
		(pts
			(arc
				(start 379.452632 -384.041904)
				(mid 379.203204 -384.041904)
				(end 379.452632 -384.041904)
			)
		)
		(stroke
			(width 0)
			(type solid)
		)
		(fill yes)
		(layer "B.Cu")
		(net "GND")
	)
	(gr_poly
		(pts
			(arc
				(start 379.452632 -382.84023)
				(mid 379.203204 -382.84023)
				(end 379.452632 -382.84023)
			)
		)
		(stroke
			(width 0)
			(type solid)
		)
		(fill yes)
		(layer "B.Cu")
		(net "GND")
	)
	(gr_poly
		(pts
			(arc
				(start 379.452632 -381.638556)
				(mid 379.203204 -381.638556)
				(end 379.452632 -381.638556)
			)
		)
		(stroke
			(width 0)
			(type solid)
		)
		(fill yes)
		(layer "B.Cu")
		(net "GND")
	)
	(gr_poly
		(pts
			(arc
				(start 379.452632 -380.141988)
				(mid 379.203204 -380.141988)
				(end 379.452632 -380.141988)
			)
		)
		(stroke
			(width 0)
			(type solid)
		)
		(fill yes)
		(layer "B.Cu")
		(net "GND")
	)
	(gr_poly
		(pts
			(arc
				(start 379.452632 -378.940314)
				(mid 379.203204 -378.940314)
				(end 379.452632 -378.940314)
			)
		)
		(stroke
			(width 0)
			(type solid)
		)
		(fill yes)
		(layer "B.Cu")
		(net "GND")
	)
	(gr_poly
		(pts
			(arc
				(start 379.452632 -377.73864)
				(mid 379.203204 -377.73864)
				(end 379.452632 -377.73864)
			)
		)
		(stroke
			(width 0)
			(type solid)
		)
		(fill yes)
		(layer "B.Cu")
		(net "GND")
	)
	(gr_poly
		(pts
			(arc
				(start 379.452632 -376.241818)
				(mid 379.203204 -376.241818)
				(end 379.452632 -376.241818)
			)
		)
		(stroke
			(width 0)
			(type solid)
		)
		(fill yes)
		(layer "B.Cu")
		(net "GND")
	)
	(gr_poly
		(pts
			(arc
				(start 379.452632 -375.040144)
				(mid 379.203204 -375.040144)
				(end 379.452632 -375.040144)
			)
		)
		(stroke
			(width 0)
			(type solid)
		)
		(fill yes)
		(layer "B.Cu")
		(net "GND")
	)
	(gr_poly
		(pts
			(arc
				(start 379.452632 -373.83847)
				(mid 379.203204 -373.83847)
				(end 379.452632 -373.83847)
			)
		)
		(stroke
			(width 0)
			(type solid)
		)
		(fill yes)
		(layer "B.Cu")
		(net "GND")
	)
	(gr_poly
		(pts
			(arc
				(start 379.452632 -372.341902)
				(mid 379.203204 -372.341902)
				(end 379.452632 -372.341902)
			)
		)
		(stroke
			(width 0)
			(type solid)
		)
		(fill yes)
		(layer "B.Cu")
		(net "GND")
	)
	(gr_poly
		(pts
			(arc
				(start 379.452632 -371.140228)
				(mid 379.203204 -371.140228)
				(end 379.452632 -371.140228)
			)
		)
		(stroke
			(width 0)
			(type solid)
		)
		(fill yes)
		(layer "B.Cu")
		(net "GND")
	)
	(gr_poly
		(pts
			(arc
				(start 379.452632 -369.938554)
				(mid 379.203204 -369.938554)
				(end 379.452632 -369.938554)
			)
		)
		(stroke
			(width 0)
			(type solid)
		)
		(fill yes)
		(layer "B.Cu")
		(net "GND")
	)
	(gr_poly
		(pts
			(arc
				(start 381.652526 -411.141926)
				(mid 381.403098 -411.141926)
				(end 381.652526 -411.141926)
			)
		)
		(stroke
			(width 0)
			(type solid)
		)
		(fill yes)
		(layer "B.Cu")
		(net "GND")
	)
	(gr_poly
		(pts
			(arc
				(start 381.652526 -409.940252)
				(mid 381.403098 -409.940252)
				(end 381.652526 -409.940252)
			)
		)
		(stroke
			(width 0)
			(type solid)
		)
		(fill yes)
		(layer "B.Cu")
		(net "GND")
	)
	(gr_poly
		(pts
			(arc
				(start 381.652526 -408.738578)
				(mid 381.403098 -408.738578)
				(end 381.652526 -408.738578)
			)
		)
		(stroke
			(width 0)
			(type solid)
		)
		(fill yes)
		(layer "B.Cu")
		(net "GND")
	)
	(gr_poly
		(pts
			(arc
				(start 381.652526 -407.24201)
				(mid 381.403098 -407.24201)
				(end 381.652526 -407.24201)
			)
		)
		(stroke
			(width 0)
			(type solid)
		)
		(fill yes)
		(layer "B.Cu")
		(net "GND")
	)
	(gr_poly
		(pts
			(arc
				(start 381.652526 -406.040336)
				(mid 381.403098 -406.040336)
				(end 381.652526 -406.040336)
			)
		)
		(stroke
			(width 0)
			(type solid)
		)
		(fill yes)
		(layer "B.Cu")
		(net "GND")
	)
	(gr_poly
		(pts
			(arc
				(start 381.652526 -404.838662)
				(mid 381.403098 -404.838662)
				(end 381.652526 -404.838662)
			)
		)
		(stroke
			(width 0)
			(type solid)
		)
		(fill yes)
		(layer "B.Cu")
		(net "GND")
	)
	(gr_poly
		(pts
			(arc
				(start 381.652526 -403.34184)
				(mid 381.403098 -403.34184)
				(end 381.652526 -403.34184)
			)
		)
		(stroke
			(width 0)
			(type solid)
		)
		(fill yes)
		(layer "B.Cu")
		(net "GND")
	)
	(gr_poly
		(pts
			(arc
				(start 381.652526 -402.140166)
				(mid 381.403098 -402.140166)
				(end 381.652526 -402.140166)
			)
		)
		(stroke
			(width 0)
			(type solid)
		)
		(fill yes)
		(layer "B.Cu")
		(net "GND")
	)
	(gr_poly
		(pts
			(arc
				(start 381.652526 -400.938492)
				(mid 381.403098 -400.938492)
				(end 381.652526 -400.938492)
			)
		)
		(stroke
			(width 0)
			(type solid)
		)
		(fill yes)
		(layer "B.Cu")
		(net "GND")
	)
	(gr_poly
		(pts
			(arc
				(start 381.652526 -399.441924)
				(mid 381.403098 -399.441924)
				(end 381.652526 -399.441924)
			)
		)
		(stroke
			(width 0)
			(type solid)
		)
		(fill yes)
		(layer "B.Cu")
		(net "GND")
	)
	(gr_poly
		(pts
			(arc
				(start 381.652526 -398.24025)
				(mid 381.403098 -398.24025)
				(end 381.652526 -398.24025)
			)
		)
		(stroke
			(width 0)
			(type solid)
		)
		(fill yes)
		(layer "B.Cu")
		(net "GND")
	)
	(gr_poly
		(pts
			(arc
				(start 381.652526 -397.038576)
				(mid 381.403098 -397.038576)
				(end 381.652526 -397.038576)
			)
		)
		(stroke
			(width 0)
			(type solid)
		)
		(fill yes)
		(layer "B.Cu")
		(net "GND")
	)
	(gr_poly
		(pts
			(arc
				(start 381.652526 -385.141978)
				(mid 381.403098 -385.141978)
				(end 381.652526 -385.141978)
			)
		)
		(stroke
			(width 0)
			(type solid)
		)
		(fill yes)
		(layer "B.Cu")
		(net "GND")
	)
	(gr_poly
		(pts
			(arc
				(start 381.652526 -383.940304)
				(mid 381.403098 -383.940304)
				(end 381.652526 -383.940304)
			)
		)
		(stroke
			(width 0)
			(type solid)
		)
		(fill yes)
		(layer "B.Cu")
		(net "GND")
	)
	(gr_poly
		(pts
			(arc
				(start 381.652526 -382.73863)
				(mid 381.403098 -382.73863)
				(end 381.652526 -382.73863)
			)
		)
		(stroke
			(width 0)
			(type solid)
		)
		(fill yes)
		(layer "B.Cu")
		(net "GND")
	)
	(gr_poly
		(pts
			(arc
				(start 381.652526 -381.242062)
				(mid 381.403098 -381.242062)
				(end 381.652526 -381.242062)
			)
		)
		(stroke
			(width 0)
			(type solid)
		)
		(fill yes)
		(layer "B.Cu")
		(net "GND")
	)
	(gr_poly
		(pts
			(arc
				(start 381.652526 -380.040388)
				(mid 381.403098 -380.040388)
				(end 381.652526 -380.040388)
			)
		)
		(stroke
			(width 0)
			(type solid)
		)
		(fill yes)
		(layer "B.Cu")
		(net "GND")
	)
	(gr_poly
		(pts
			(arc
				(start 381.652526 -378.838714)
				(mid 381.403098 -378.838714)
				(end 381.652526 -378.838714)
			)
		)
		(stroke
			(width 0)
			(type solid)
		)
		(fill yes)
		(layer "B.Cu")
		(net "GND")
	)
	(gr_poly
		(pts
			(arc
				(start 381.652526 -377.341892)
				(mid 381.403098 -377.341892)
				(end 381.652526 -377.341892)
			)
		)
		(stroke
			(width 0)
			(type solid)
		)
		(fill yes)
		(layer "B.Cu")
		(net "GND")
	)
	(gr_poly
		(pts
			(arc
				(start 381.652526 -376.140218)
				(mid 381.403098 -376.140218)
				(end 381.652526 -376.140218)
			)
		)
		(stroke
			(width 0)
			(type solid)
		)
		(fill yes)
		(layer "B.Cu")
		(net "GND")
	)
	(gr_poly
		(pts
			(arc
				(start 381.652526 -374.938544)
				(mid 381.403098 -374.938544)
				(end 381.652526 -374.938544)
			)
		)
		(stroke
			(width 0)
			(type solid)
		)
		(fill yes)
		(layer "B.Cu")
		(net "GND")
	)
	(gr_poly
		(pts
			(arc
				(start 381.652526 -373.441976)
				(mid 381.403098 -373.441976)
				(end 381.652526 -373.441976)
			)
		)
		(stroke
			(width 0)
			(type solid)
		)
		(fill yes)
		(layer "B.Cu")
		(net "GND")
	)
	(gr_poly
		(pts
			(arc
				(start 381.652526 -372.240302)
				(mid 381.403098 -372.240302)
				(end 381.652526 -372.240302)
			)
		)
		(stroke
			(width 0)
			(type solid)
		)
		(fill yes)
		(layer "B.Cu")
		(net "GND")
	)
	(gr_poly
		(pts
			(arc
				(start 381.652526 -371.038628)
				(mid 381.403098 -371.038628)
				(end 381.652526 -371.038628)
			)
		)
		(stroke
			(width 0)
			(type solid)
		)
		(fill yes)
		(layer "B.Cu")
		(net "GND")
	)
	(gr_poly
		(pts
			(arc
				(start 383.852674 -410.041852)
				(mid 383.603246 -410.041852)
				(end 383.852674 -410.041852)
			)
		)
		(stroke
			(width 0)
			(type solid)
		)
		(fill yes)
		(layer "B.Cu")
		(net "GND")
	)
	(gr_poly
		(pts
			(arc
				(start 383.852674 -408.840178)
				(mid 383.603246 -408.840178)
				(end 383.852674 -408.840178)
			)
		)
		(stroke
			(width 0)
			(type solid)
		)
		(fill yes)
		(layer "B.Cu")
		(net "GND")
	)
	(gr_poly
		(pts
			(arc
				(start 383.852674 -407.638504)
				(mid 383.603246 -407.638504)
				(end 383.852674 -407.638504)
			)
		)
		(stroke
			(width 0)
			(type solid)
		)
		(fill yes)
		(layer "B.Cu")
		(net "GND")
	)
	(gr_poly
		(pts
			(arc
				(start 383.852674 -406.141936)
				(mid 383.603246 -406.141936)
				(end 383.852674 -406.141936)
			)
		)
		(stroke
			(width 0)
			(type solid)
		)
		(fill yes)
		(layer "B.Cu")
		(net "GND")
	)
	(gr_poly
		(pts
			(arc
				(start 383.852674 -404.940262)
				(mid 383.603246 -404.940262)
				(end 383.852674 -404.940262)
			)
		)
		(stroke
			(width 0)
			(type solid)
		)
		(fill yes)
		(layer "B.Cu")
		(net "GND")
	)
	(gr_poly
		(pts
			(arc
				(start 383.852674 -403.738588)
				(mid 383.603246 -403.738588)
				(end 383.852674 -403.738588)
			)
		)
		(stroke
			(width 0)
			(type solid)
		)
		(fill yes)
		(layer "B.Cu")
		(net "GND")
	)
	(gr_poly
		(pts
			(arc
				(start 383.852674 -402.241766)
				(mid 383.603246 -402.241766)
				(end 383.852674 -402.241766)
			)
		)
		(stroke
			(width 0)
			(type solid)
		)
		(fill yes)
		(layer "B.Cu")
		(net "GND")
	)
	(gr_poly
		(pts
			(arc
				(start 383.852674 -401.040092)
				(mid 383.603246 -401.040092)
				(end 383.852674 -401.040092)
			)
		)
		(stroke
			(width 0)
			(type solid)
		)
		(fill yes)
		(layer "B.Cu")
		(net "GND")
	)
	(gr_poly
		(pts
			(arc
				(start 383.852674 -399.838418)
				(mid 383.603246 -399.838418)
				(end 383.852674 -399.838418)
			)
		)
		(stroke
			(width 0)
			(type solid)
		)
		(fill yes)
		(layer "B.Cu")
		(net "GND")
	)
	(gr_poly
		(pts
			(arc
				(start 383.852674 -398.34185)
				(mid 383.603246 -398.34185)
				(end 383.852674 -398.34185)
			)
		)
		(stroke
			(width 0)
			(type solid)
		)
		(fill yes)
		(layer "B.Cu")
		(net "GND")
	)
	(gr_poly
		(pts
			(arc
				(start 383.852674 -397.140176)
				(mid 383.603246 -397.140176)
				(end 383.852674 -397.140176)
			)
		)
		(stroke
			(width 0)
			(type solid)
		)
		(fill yes)
		(layer "B.Cu")
		(net "GND")
	)
	(gr_poly
		(pts
			(arc
				(start 383.852674 -395.938502)
				(mid 383.603246 -395.938502)
				(end 383.852674 -395.938502)
			)
		)
		(stroke
			(width 0)
			(type solid)
		)
		(fill yes)
		(layer "B.Cu")
		(net "GND")
	)
	(gr_poly
		(pts
			(arc
				(start 383.852674 -384.041904)
				(mid 383.603246 -384.041904)
				(end 383.852674 -384.041904)
			)
		)
		(stroke
			(width 0)
			(type solid)
		)
		(fill yes)
		(layer "B.Cu")
		(net "GND")
	)
	(gr_poly
		(pts
			(arc
				(start 383.852674 -382.84023)
				(mid 383.603246 -382.84023)
				(end 383.852674 -382.84023)
			)
		)
		(stroke
			(width 0)
			(type solid)
		)
		(fill yes)
		(layer "B.Cu")
		(net "GND")
	)
	(gr_poly
		(pts
			(arc
				(start 383.852674 -381.638556)
				(mid 383.603246 -381.638556)
				(end 383.852674 -381.638556)
			)
		)
		(stroke
			(width 0)
			(type solid)
		)
		(fill yes)
		(layer "B.Cu")
		(net "GND")
	)
	(gr_poly
		(pts
			(arc
				(start 383.852674 -380.141988)
				(mid 383.603246 -380.141988)
				(end 383.852674 -380.141988)
			)
		)
		(stroke
			(width 0)
			(type solid)
		)
		(fill yes)
		(layer "B.Cu")
		(net "GND")
	)
	(gr_poly
		(pts
			(arc
				(start 383.852674 -378.940314)
				(mid 383.603246 -378.940314)
				(end 383.852674 -378.940314)
			)
		)
		(stroke
			(width 0)
			(type solid)
		)
		(fill yes)
		(layer "B.Cu")
		(net "GND")
	)
	(gr_poly
		(pts
			(arc
				(start 383.852674 -377.73864)
				(mid 383.603246 -377.73864)
				(end 383.852674 -377.73864)
			)
		)
		(stroke
			(width 0)
			(type solid)
		)
		(fill yes)
		(layer "B.Cu")
		(net "GND")
	)
	(gr_poly
		(pts
			(arc
				(start 383.852674 -376.241818)
				(mid 383.603246 -376.241818)
				(end 383.852674 -376.241818)
			)
		)
		(stroke
			(width 0)
			(type solid)
		)
		(fill yes)
		(layer "B.Cu")
		(net "GND")
	)
	(gr_poly
		(pts
			(arc
				(start 383.852674 -375.040144)
				(mid 383.603246 -375.040144)
				(end 383.852674 -375.040144)
			)
		)
		(stroke
			(width 0)
			(type solid)
		)
		(fill yes)
		(layer "B.Cu")
		(net "GND")
	)
	(gr_poly
		(pts
			(arc
				(start 383.852674 -373.83847)
				(mid 383.603246 -373.83847)
				(end 383.852674 -373.83847)
			)
		)
		(stroke
			(width 0)
			(type solid)
		)
		(fill yes)
		(layer "B.Cu")
		(net "GND")
	)
	(gr_poly
		(pts
			(arc
				(start 383.852674 -372.341902)
				(mid 383.603246 -372.341902)
				(end 383.852674 -372.341902)
			)
		)
		(stroke
			(width 0)
			(type solid)
		)
		(fill yes)
		(layer "B.Cu")
		(net "GND")
	)
	(gr_poly
		(pts
			(arc
				(start 383.852674 -371.140228)
				(mid 383.603246 -371.140228)
				(end 383.852674 -371.140228)
			)
		)
		(stroke
			(width 0)
			(type solid)
		)
		(fill yes)
		(layer "B.Cu")
		(net "GND")
	)
	(gr_poly
		(pts
			(arc
				(start 383.852674 -369.938554)
				(mid 383.603246 -369.938554)
				(end 383.852674 -369.938554)
			)
		)
		(stroke
			(width 0)
			(type solid)
		)
		(fill yes)
		(layer "B.Cu")
		(net "GND")
	)
	(gr_poly
		(pts
			(arc
				(start 386.052568 -411.141926)
				(mid 385.80314 -411.141926)
				(end 386.052568 -411.141926)
			)
		)
		(stroke
			(width 0)
			(type solid)
		)
		(fill yes)
		(layer "B.Cu")
		(net "GND")
	)
	(gr_poly
		(pts
			(arc
				(start 386.052568 -409.940252)
				(mid 385.80314 -409.940252)
				(end 386.052568 -409.940252)
			)
		)
		(stroke
			(width 0)
			(type solid)
		)
		(fill yes)
		(layer "B.Cu")
		(net "GND")
	)
	(gr_poly
		(pts
			(arc
				(start 386.052568 -408.738578)
				(mid 385.80314 -408.738578)
				(end 386.052568 -408.738578)
			)
		)
		(stroke
			(width 0)
			(type solid)
		)
		(fill yes)
		(layer "B.Cu")
		(net "GND")
	)
	(gr_poly
		(pts
			(arc
				(start 386.052568 -407.24201)
				(mid 385.80314 -407.24201)
				(end 386.052568 -407.24201)
			)
		)
		(stroke
			(width 0)
			(type solid)
		)
		(fill yes)
		(layer "B.Cu")
		(net "GND")
	)
	(gr_poly
		(pts
			(arc
				(start 386.052568 -406.040336)
				(mid 385.80314 -406.040336)
				(end 386.052568 -406.040336)
			)
		)
		(stroke
			(width 0)
			(type solid)
		)
		(fill yes)
		(layer "B.Cu")
		(net "GND")
	)
	(gr_poly
		(pts
			(arc
				(start 386.052568 -404.838662)
				(mid 385.80314 -404.838662)
				(end 386.052568 -404.838662)
			)
		)
		(stroke
			(width 0)
			(type solid)
		)
		(fill yes)
		(layer "B.Cu")
		(net "GND")
	)
	(gr_poly
		(pts
			(arc
				(start 386.052568 -403.34184)
				(mid 385.80314 -403.34184)
				(end 386.052568 -403.34184)
			)
		)
		(stroke
			(width 0)
			(type solid)
		)
		(fill yes)
		(layer "B.Cu")
		(net "GND")
	)
	(gr_poly
		(pts
			(arc
				(start 386.052568 -402.140166)
				(mid 385.80314 -402.140166)
				(end 386.052568 -402.140166)
			)
		)
		(stroke
			(width 0)
			(type solid)
		)
		(fill yes)
		(layer "B.Cu")
		(net "GND")
	)
	(gr_poly
		(pts
			(arc
				(start 386.052568 -400.938492)
				(mid 385.80314 -400.938492)
				(end 386.052568 -400.938492)
			)
		)
		(stroke
			(width 0)
			(type solid)
		)
		(fill yes)
		(layer "B.Cu")
		(net "GND")
	)
	(gr_poly
		(pts
			(arc
				(start 386.052568 -399.441924)
				(mid 385.80314 -399.441924)
				(end 386.052568 -399.441924)
			)
		)
		(stroke
			(width 0)
			(type solid)
		)
		(fill yes)
		(layer "B.Cu")
		(net "GND")
	)
	(gr_poly
		(pts
			(arc
				(start 386.052568 -398.24025)
				(mid 385.80314 -398.24025)
				(end 386.052568 -398.24025)
			)
		)
		(stroke
			(width 0)
			(type solid)
		)
		(fill yes)
		(layer "B.Cu")
		(net "GND")
	)
	(gr_poly
		(pts
			(arc
				(start 386.052568 -397.038576)
				(mid 385.80314 -397.038576)
				(end 386.052568 -397.038576)
			)
		)
		(stroke
			(width 0)
			(type solid)
		)
		(fill yes)
		(layer "B.Cu")
		(net "GND")
	)
	(gr_poly
		(pts
			(arc
				(start 386.052568 -385.141978)
				(mid 385.80314 -385.141978)
				(end 386.052568 -385.141978)
			)
		)
		(stroke
			(width 0)
			(type solid)
		)
		(fill yes)
		(layer "B.Cu")
		(net "GND")
	)
	(gr_poly
		(pts
			(arc
				(start 386.052568 -383.940304)
				(mid 385.80314 -383.940304)
				(end 386.052568 -383.940304)
			)
		)
		(stroke
			(width 0)
			(type solid)
		)
		(fill yes)
		(layer "B.Cu")
		(net "GND")
	)
	(gr_poly
		(pts
			(arc
				(start 386.052568 -382.73863)
				(mid 385.80314 -382.73863)
				(end 386.052568 -382.73863)
			)
		)
		(stroke
			(width 0)
			(type solid)
		)
		(fill yes)
		(layer "B.Cu")
		(net "GND")
	)
	(gr_poly
		(pts
			(arc
				(start 386.052568 -381.242062)
				(mid 385.80314 -381.242062)
				(end 386.052568 -381.242062)
			)
		)
		(stroke
			(width 0)
			(type solid)
		)
		(fill yes)
		(layer "B.Cu")
		(net "GND")
	)
	(gr_poly
		(pts
			(arc
				(start 386.052568 -380.040388)
				(mid 385.80314 -380.040388)
				(end 386.052568 -380.040388)
			)
		)
		(stroke
			(width 0)
			(type solid)
		)
		(fill yes)
		(layer "B.Cu")
		(net "GND")
	)
	(gr_poly
		(pts
			(arc
				(start 386.052568 -378.838714)
				(mid 385.80314 -378.838714)
				(end 386.052568 -378.838714)
			)
		)
		(stroke
			(width 0)
			(type solid)
		)
		(fill yes)
		(layer "B.Cu")
		(net "GND")
	)
	(gr_poly
		(pts
			(arc
				(start 386.052568 -377.341892)
				(mid 385.80314 -377.341892)
				(end 386.052568 -377.341892)
			)
		)
		(stroke
			(width 0)
			(type solid)
		)
		(fill yes)
		(layer "B.Cu")
		(net "GND")
	)
	(gr_poly
		(pts
			(arc
				(start 386.052568 -376.140218)
				(mid 385.80314 -376.140218)
				(end 386.052568 -376.140218)
			)
		)
		(stroke
			(width 0)
			(type solid)
		)
		(fill yes)
		(layer "B.Cu")
		(net "GND")
	)
	(gr_poly
		(pts
			(arc
				(start 386.052568 -374.938544)
				(mid 385.80314 -374.938544)
				(end 386.052568 -374.938544)
			)
		)
		(stroke
			(width 0)
			(type solid)
		)
		(fill yes)
		(layer "B.Cu")
		(net "GND")
	)
	(gr_poly
		(pts
			(arc
				(start 386.052568 -373.441976)
				(mid 385.80314 -373.441976)
				(end 386.052568 -373.441976)
			)
		)
		(stroke
			(width 0)
			(type solid)
		)
		(fill yes)
		(layer "B.Cu")
		(net "GND")
	)
	(gr_poly
		(pts
			(arc
				(start 386.052568 -372.240302)
				(mid 385.80314 -372.240302)
				(end 386.052568 -372.240302)
			)
		)
		(stroke
			(width 0)
			(type solid)
		)
		(fill yes)
		(layer "B.Cu")
		(net "GND")
	)
	(gr_poly
		(pts
			(arc
				(start 386.052568 -371.038628)
				(mid 385.80314 -371.038628)
				(end 386.052568 -371.038628)
			)
		)
		(stroke
			(width 0)
			(type solid)
		)
		(fill yes)
		(layer "B.Cu")
		(net "GND")
	)
	(gr_poly
		(pts
			(arc
				(start 388.252462 -410.041852)
				(mid 388.003034 -410.041852)
				(end 388.252462 -410.041852)
			)
		)
		(stroke
			(width 0)
			(type solid)
		)
		(fill yes)
		(layer "B.Cu")
		(net "GND")
	)
	(gr_poly
		(pts
			(arc
				(start 388.252462 -408.840178)
				(mid 388.003034 -408.840178)
				(end 388.252462 -408.840178)
			)
		)
		(stroke
			(width 0)
			(type solid)
		)
		(fill yes)
		(layer "B.Cu")
		(net "GND")
	)
	(gr_poly
		(pts
			(arc
				(start 388.252462 -407.638504)
				(mid 388.003034 -407.638504)
				(end 388.252462 -407.638504)
			)
		)
		(stroke
			(width 0)
			(type solid)
		)
		(fill yes)
		(layer "B.Cu")
		(net "GND")
	)
	(gr_poly
		(pts
			(arc
				(start 388.252462 -406.141936)
				(mid 388.003034 -406.141936)
				(end 388.252462 -406.141936)
			)
		)
		(stroke
			(width 0)
			(type solid)
		)
		(fill yes)
		(layer "B.Cu")
		(net "GND")
	)
	(gr_poly
		(pts
			(arc
				(start 388.252462 -404.940262)
				(mid 388.003034 -404.940262)
				(end 388.252462 -404.940262)
			)
		)
		(stroke
			(width 0)
			(type solid)
		)
		(fill yes)
		(layer "B.Cu")
		(net "GND")
	)
	(gr_poly
		(pts
			(arc
				(start 388.252462 -403.738588)
				(mid 388.003034 -403.738588)
				(end 388.252462 -403.738588)
			)
		)
		(stroke
			(width 0)
			(type solid)
		)
		(fill yes)
		(layer "B.Cu")
		(net "GND")
	)
	(gr_poly
		(pts
			(arc
				(start 388.252462 -402.241766)
				(mid 388.003034 -402.241766)
				(end 388.252462 -402.241766)
			)
		)
		(stroke
			(width 0)
			(type solid)
		)
		(fill yes)
		(layer "B.Cu")
		(net "GND")
	)
	(gr_poly
		(pts
			(arc
				(start 388.252462 -401.040092)
				(mid 388.003034 -401.040092)
				(end 388.252462 -401.040092)
			)
		)
		(stroke
			(width 0)
			(type solid)
		)
		(fill yes)
		(layer "B.Cu")
		(net "GND")
	)
	(gr_poly
		(pts
			(arc
				(start 388.252462 -399.838418)
				(mid 388.003034 -399.838418)
				(end 388.252462 -399.838418)
			)
		)
		(stroke
			(width 0)
			(type solid)
		)
		(fill yes)
		(layer "B.Cu")
		(net "GND")
	)
	(gr_poly
		(pts
			(arc
				(start 388.252462 -398.34185)
				(mid 388.003034 -398.34185)
				(end 388.252462 -398.34185)
			)
		)
		(stroke
			(width 0)
			(type solid)
		)
		(fill yes)
		(layer "B.Cu")
		(net "GND")
	)
	(gr_poly
		(pts
			(arc
				(start 388.252462 -397.140176)
				(mid 388.003034 -397.140176)
				(end 388.252462 -397.140176)
			)
		)
		(stroke
			(width 0)
			(type solid)
		)
		(fill yes)
		(layer "B.Cu")
		(net "GND")
	)
	(gr_poly
		(pts
			(arc
				(start 388.252462 -395.938502)
				(mid 388.003034 -395.938502)
				(end 388.252462 -395.938502)
			)
		)
		(stroke
			(width 0)
			(type solid)
		)
		(fill yes)
		(layer "B.Cu")
		(net "GND")
	)
	(gr_poly
		(pts
			(arc
				(start 388.252462 -384.041904)
				(mid 388.003034 -384.041904)
				(end 388.252462 -384.041904)
			)
		)
		(stroke
			(width 0)
			(type solid)
		)
		(fill yes)
		(layer "B.Cu")
		(net "GND")
	)
	(gr_poly
		(pts
			(arc
				(start 388.252462 -382.84023)
				(mid 388.003034 -382.84023)
				(end 388.252462 -382.84023)
			)
		)
		(stroke
			(width 0)
			(type solid)
		)
		(fill yes)
		(layer "B.Cu")
		(net "GND")
	)
	(gr_poly
		(pts
			(arc
				(start 388.252462 -381.638556)
				(mid 388.003034 -381.638556)
				(end 388.252462 -381.638556)
			)
		)
		(stroke
			(width 0)
			(type solid)
		)
		(fill yes)
		(layer "B.Cu")
		(net "GND")
	)
	(gr_poly
		(pts
			(arc
				(start 388.252462 -380.141988)
				(mid 388.003034 -380.141988)
				(end 388.252462 -380.141988)
			)
		)
		(stroke
			(width 0)
			(type solid)
		)
		(fill yes)
		(layer "B.Cu")
		(net "GND")
	)
	(gr_poly
		(pts
			(arc
				(start 388.252462 -378.940314)
				(mid 388.003034 -378.940314)
				(end 388.252462 -378.940314)
			)
		)
		(stroke
			(width 0)
			(type solid)
		)
		(fill yes)
		(layer "B.Cu")
		(net "GND")
	)
	(gr_poly
		(pts
			(arc
				(start 388.252462 -377.73864)
				(mid 388.003034 -377.73864)
				(end 388.252462 -377.73864)
			)
		)
		(stroke
			(width 0)
			(type solid)
		)
		(fill yes)
		(layer "B.Cu")
		(net "GND")
	)
	(gr_poly
		(pts
			(arc
				(start 388.252462 -376.241818)
				(mid 388.003034 -376.241818)
				(end 388.252462 -376.241818)
			)
		)
		(stroke
			(width 0)
			(type solid)
		)
		(fill yes)
		(layer "B.Cu")
		(net "GND")
	)
	(gr_poly
		(pts
			(arc
				(start 388.252462 -375.040144)
				(mid 388.003034 -375.040144)
				(end 388.252462 -375.040144)
			)
		)
		(stroke
			(width 0)
			(type solid)
		)
		(fill yes)
		(layer "B.Cu")
		(net "GND")
	)
	(gr_poly
		(pts
			(arc
				(start 388.252462 -373.83847)
				(mid 388.003034 -373.83847)
				(end 388.252462 -373.83847)
			)
		)
		(stroke
			(width 0)
			(type solid)
		)
		(fill yes)
		(layer "B.Cu")
		(net "GND")
	)
	(gr_poly
		(pts
			(arc
				(start 388.252462 -372.341902)
				(mid 388.003034 -372.341902)
				(end 388.252462 -372.341902)
			)
		)
		(stroke
			(width 0)
			(type solid)
		)
		(fill yes)
		(layer "B.Cu")
		(net "GND")
	)
	(gr_poly
		(pts
			(arc
				(start 388.252462 -371.140228)
				(mid 388.003034 -371.140228)
				(end 388.252462 -371.140228)
			)
		)
		(stroke
			(width 0)
			(type solid)
		)
		(fill yes)
		(layer "B.Cu")
		(net "GND")
	)
	(gr_poly
		(pts
			(arc
				(start 388.252462 -369.938554)
				(mid 388.003034 -369.938554)
				(end 388.252462 -369.938554)
			)
		)
		(stroke
			(width 0)
			(type solid)
		)
		(fill yes)
		(layer "B.Cu")
		(net "GND")
	)
	(gr_poly
		(pts
			(arc
				(start 390.45261 -411.141926)
				(mid 390.203182 -411.141926)
				(end 390.45261 -411.141926)
			)
		)
		(stroke
			(width 0)
			(type solid)
		)
		(fill yes)
		(layer "B.Cu")
		(net "GND")
	)
	(gr_poly
		(pts
			(arc
				(start 390.45261 -409.940252)
				(mid 390.203182 -409.940252)
				(end 390.45261 -409.940252)
			)
		)
		(stroke
			(width 0)
			(type solid)
		)
		(fill yes)
		(layer "B.Cu")
		(net "GND")
	)
	(gr_poly
		(pts
			(arc
				(start 390.45261 -408.738578)
				(mid 390.203182 -408.738578)
				(end 390.45261 -408.738578)
			)
		)
		(stroke
			(width 0)
			(type solid)
		)
		(fill yes)
		(layer "B.Cu")
		(net "GND")
	)
	(gr_poly
		(pts
			(arc
				(start 390.45261 -407.24201)
				(mid 390.203182 -407.24201)
				(end 390.45261 -407.24201)
			)
		)
		(stroke
			(width 0)
			(type solid)
		)
		(fill yes)
		(layer "B.Cu")
		(net "GND")
	)
	(gr_poly
		(pts
			(arc
				(start 390.45261 -406.040336)
				(mid 390.203182 -406.040336)
				(end 390.45261 -406.040336)
			)
		)
		(stroke
			(width 0)
			(type solid)
		)
		(fill yes)
		(layer "B.Cu")
		(net "GND")
	)
	(gr_poly
		(pts
			(arc
				(start 390.45261 -404.838662)
				(mid 390.203182 -404.838662)
				(end 390.45261 -404.838662)
			)
		)
		(stroke
			(width 0)
			(type solid)
		)
		(fill yes)
		(layer "B.Cu")
		(net "GND")
	)
	(gr_poly
		(pts
			(arc
				(start 390.45261 -403.34184)
				(mid 390.203182 -403.34184)
				(end 390.45261 -403.34184)
			)
		)
		(stroke
			(width 0)
			(type solid)
		)
		(fill yes)
		(layer "B.Cu")
		(net "GND")
	)
	(gr_poly
		(pts
			(arc
				(start 390.45261 -402.140166)
				(mid 390.203182 -402.140166)
				(end 390.45261 -402.140166)
			)
		)
		(stroke
			(width 0)
			(type solid)
		)
		(fill yes)
		(layer "B.Cu")
		(net "GND")
	)
	(gr_poly
		(pts
			(arc
				(start 390.45261 -400.938492)
				(mid 390.203182 -400.938492)
				(end 390.45261 -400.938492)
			)
		)
		(stroke
			(width 0)
			(type solid)
		)
		(fill yes)
		(layer "B.Cu")
		(net "GND")
	)
	(gr_poly
		(pts
			(arc
				(start 390.45261 -399.441924)
				(mid 390.203182 -399.441924)
				(end 390.45261 -399.441924)
			)
		)
		(stroke
			(width 0)
			(type solid)
		)
		(fill yes)
		(layer "B.Cu")
		(net "GND")
	)
	(gr_poly
		(pts
			(arc
				(start 390.45261 -398.24025)
				(mid 390.203182 -398.24025)
				(end 390.45261 -398.24025)
			)
		)
		(stroke
			(width 0)
			(type solid)
		)
		(fill yes)
		(layer "B.Cu")
		(net "GND")
	)
	(gr_poly
		(pts
			(arc
				(start 390.45261 -397.038576)
				(mid 390.203182 -397.038576)
				(end 390.45261 -397.038576)
			)
		)
		(stroke
			(width 0)
			(type solid)
		)
		(fill yes)
		(layer "B.Cu")
		(net "GND")
	)
	(gr_poly
		(pts
			(arc
				(start 390.45261 -385.141978)
				(mid 390.203182 -385.141978)
				(end 390.45261 -385.141978)
			)
		)
		(stroke
			(width 0)
			(type solid)
		)
		(fill yes)
		(layer "B.Cu")
		(net "GND")
	)
	(gr_poly
		(pts
			(arc
				(start 390.45261 -383.940304)
				(mid 390.203182 -383.940304)
				(end 390.45261 -383.940304)
			)
		)
		(stroke
			(width 0)
			(type solid)
		)
		(fill yes)
		(layer "B.Cu")
		(net "GND")
	)
	(gr_poly
		(pts
			(arc
				(start 390.45261 -382.73863)
				(mid 390.203182 -382.73863)
				(end 390.45261 -382.73863)
			)
		)
		(stroke
			(width 0)
			(type solid)
		)
		(fill yes)
		(layer "B.Cu")
		(net "GND")
	)
	(gr_poly
		(pts
			(arc
				(start 390.45261 -381.242062)
				(mid 390.203182 -381.242062)
				(end 390.45261 -381.242062)
			)
		)
		(stroke
			(width 0)
			(type solid)
		)
		(fill yes)
		(layer "B.Cu")
		(net "GND")
	)
	(gr_poly
		(pts
			(arc
				(start 390.45261 -380.040388)
				(mid 390.203182 -380.040388)
				(end 390.45261 -380.040388)
			)
		)
		(stroke
			(width 0)
			(type solid)
		)
		(fill yes)
		(layer "B.Cu")
		(net "GND")
	)
	(gr_poly
		(pts
			(arc
				(start 390.45261 -378.838714)
				(mid 390.203182 -378.838714)
				(end 390.45261 -378.838714)
			)
		)
		(stroke
			(width 0)
			(type solid)
		)
		(fill yes)
		(layer "B.Cu")
		(net "GND")
	)
	(gr_poly
		(pts
			(arc
				(start 390.45261 -377.341892)
				(mid 390.203182 -377.341892)
				(end 390.45261 -377.341892)
			)
		)
		(stroke
			(width 0)
			(type solid)
		)
		(fill yes)
		(layer "B.Cu")
		(net "GND")
	)
	(gr_poly
		(pts
			(arc
				(start 390.45261 -376.140218)
				(mid 390.203182 -376.140218)
				(end 390.45261 -376.140218)
			)
		)
		(stroke
			(width 0)
			(type solid)
		)
		(fill yes)
		(layer "B.Cu")
		(net "GND")
	)
	(gr_poly
		(pts
			(arc
				(start 390.45261 -374.938544)
				(mid 390.203182 -374.938544)
				(end 390.45261 -374.938544)
			)
		)
		(stroke
			(width 0)
			(type solid)
		)
		(fill yes)
		(layer "B.Cu")
		(net "GND")
	)
	(gr_poly
		(pts
			(arc
				(start 390.45261 -373.441976)
				(mid 390.203182 -373.441976)
				(end 390.45261 -373.441976)
			)
		)
		(stroke
			(width 0)
			(type solid)
		)
		(fill yes)
		(layer "B.Cu")
		(net "GND")
	)
	(gr_poly
		(pts
			(arc
				(start 390.45261 -372.240302)
				(mid 390.203182 -372.240302)
				(end 390.45261 -372.240302)
			)
		)
		(stroke
			(width 0)
			(type solid)
		)
		(fill yes)
		(layer "B.Cu")
		(net "GND")
	)
	(gr_poly
		(pts
			(arc
				(start 390.45261 -371.038628)
				(mid 390.203182 -371.038628)
				(end 390.45261 -371.038628)
			)
		)
		(stroke
			(width 0)
			(type solid)
		)
		(fill yes)
		(layer "B.Cu")
		(net "GND")
	)
	(gr_poly
		(pts
			(arc
				(start 392.652504 -410.041852)
				(mid 392.403076 -410.041852)
				(end 392.652504 -410.041852)
			)
		)
		(stroke
			(width 0)
			(type solid)
		)
		(fill yes)
		(layer "B.Cu")
		(net "GND")
	)
	(gr_poly
		(pts
			(arc
				(start 392.652504 -408.840178)
				(mid 392.403076 -408.840178)
				(end 392.652504 -408.840178)
			)
		)
		(stroke
			(width 0)
			(type solid)
		)
		(fill yes)
		(layer "B.Cu")
		(net "GND")
	)
	(gr_poly
		(pts
			(arc
				(start 392.652504 -407.638504)
				(mid 392.403076 -407.638504)
				(end 392.652504 -407.638504)
			)
		)
		(stroke
			(width 0)
			(type solid)
		)
		(fill yes)
		(layer "B.Cu")
		(net "GND")
	)
	(gr_poly
		(pts
			(arc
				(start 392.652504 -406.141936)
				(mid 392.403076 -406.141936)
				(end 392.652504 -406.141936)
			)
		)
		(stroke
			(width 0)
			(type solid)
		)
		(fill yes)
		(layer "B.Cu")
		(net "GND")
	)
	(gr_poly
		(pts
			(arc
				(start 392.652504 -404.940262)
				(mid 392.403076 -404.940262)
				(end 392.652504 -404.940262)
			)
		)
		(stroke
			(width 0)
			(type solid)
		)
		(fill yes)
		(layer "B.Cu")
		(net "GND")
	)
	(gr_poly
		(pts
			(arc
				(start 392.652504 -403.738588)
				(mid 392.403076 -403.738588)
				(end 392.652504 -403.738588)
			)
		)
		(stroke
			(width 0)
			(type solid)
		)
		(fill yes)
		(layer "B.Cu")
		(net "GND")
	)
	(gr_poly
		(pts
			(arc
				(start 392.652504 -402.241766)
				(mid 392.403076 -402.241766)
				(end 392.652504 -402.241766)
			)
		)
		(stroke
			(width 0)
			(type solid)
		)
		(fill yes)
		(layer "B.Cu")
		(net "GND")
	)
	(gr_poly
		(pts
			(arc
				(start 392.652504 -401.040092)
				(mid 392.403076 -401.040092)
				(end 392.652504 -401.040092)
			)
		)
		(stroke
			(width 0)
			(type solid)
		)
		(fill yes)
		(layer "B.Cu")
		(net "GND")
	)
	(gr_poly
		(pts
			(arc
				(start 392.652504 -399.838418)
				(mid 392.403076 -399.838418)
				(end 392.652504 -399.838418)
			)
		)
		(stroke
			(width 0)
			(type solid)
		)
		(fill yes)
		(layer "B.Cu")
		(net "GND")
	)
	(gr_poly
		(pts
			(arc
				(start 392.652504 -398.34185)
				(mid 392.403076 -398.34185)
				(end 392.652504 -398.34185)
			)
		)
		(stroke
			(width 0)
			(type solid)
		)
		(fill yes)
		(layer "B.Cu")
		(net "GND")
	)
	(gr_poly
		(pts
			(arc
				(start 392.652504 -397.140176)
				(mid 392.403076 -397.140176)
				(end 392.652504 -397.140176)
			)
		)
		(stroke
			(width 0)
			(type solid)
		)
		(fill yes)
		(layer "B.Cu")
		(net "GND")
	)
	(gr_poly
		(pts
			(arc
				(start 392.652504 -395.938502)
				(mid 392.403076 -395.938502)
				(end 392.652504 -395.938502)
			)
		)
		(stroke
			(width 0)
			(type solid)
		)
		(fill yes)
		(layer "B.Cu")
		(net "GND")
	)
	(gr_poly
		(pts
			(arc
				(start 392.652504 -384.042158)
				(mid 392.403076 -384.042158)
				(end 392.652504 -384.042158)
			)
		)
		(stroke
			(width 0)
			(type solid)
		)
		(fill yes)
		(layer "B.Cu")
		(net "GND")
	)
	(gr_poly
		(pts
			(arc
				(start 392.652504 -382.840484)
				(mid 392.403076 -382.840484)
				(end 392.652504 -382.840484)
			)
		)
		(stroke
			(width 0)
			(type solid)
		)
		(fill yes)
		(layer "B.Cu")
		(net "GND")
	)
	(gr_poly
		(pts
			(arc
				(start 392.652504 -381.63881)
				(mid 392.403076 -381.63881)
				(end 392.652504 -381.63881)
			)
		)
		(stroke
			(width 0)
			(type solid)
		)
		(fill yes)
		(layer "B.Cu")
		(net "GND")
	)
	(gr_poly
		(pts
			(arc
				(start 392.652504 -380.142242)
				(mid 392.403076 -380.142242)
				(end 392.652504 -380.142242)
			)
		)
		(stroke
			(width 0)
			(type solid)
		)
		(fill yes)
		(layer "B.Cu")
		(net "GND")
	)
	(gr_poly
		(pts
			(arc
				(start 392.652504 -378.940568)
				(mid 392.403076 -378.940568)
				(end 392.652504 -378.940568)
			)
		)
		(stroke
			(width 0)
			(type solid)
		)
		(fill yes)
		(layer "B.Cu")
		(net "GND")
	)
	(gr_poly
		(pts
			(arc
				(start 392.652504 -377.738894)
				(mid 392.403076 -377.738894)
				(end 392.652504 -377.738894)
			)
		)
		(stroke
			(width 0)
			(type solid)
		)
		(fill yes)
		(layer "B.Cu")
		(net "GND")
	)
	(gr_poly
		(pts
			(arc
				(start 392.652504 -376.242072)
				(mid 392.403076 -376.242072)
				(end 392.652504 -376.242072)
			)
		)
		(stroke
			(width 0)
			(type solid)
		)
		(fill yes)
		(layer "B.Cu")
		(net "GND")
	)
	(gr_poly
		(pts
			(arc
				(start 392.652504 -375.040398)
				(mid 392.403076 -375.040398)
				(end 392.652504 -375.040398)
			)
		)
		(stroke
			(width 0)
			(type solid)
		)
		(fill yes)
		(layer "B.Cu")
		(net "GND")
	)
	(gr_poly
		(pts
			(arc
				(start 392.652504 -373.838724)
				(mid 392.403076 -373.838724)
				(end 392.652504 -373.838724)
			)
		)
		(stroke
			(width 0)
			(type solid)
		)
		(fill yes)
		(layer "B.Cu")
		(net "GND")
	)
	(gr_poly
		(pts
			(arc
				(start 392.652504 -372.342156)
				(mid 392.403076 -372.342156)
				(end 392.652504 -372.342156)
			)
		)
		(stroke
			(width 0)
			(type solid)
		)
		(fill yes)
		(layer "B.Cu")
		(net "GND")
	)
	(gr_poly
		(pts
			(arc
				(start 392.652504 -371.140482)
				(mid 392.403076 -371.140482)
				(end 392.652504 -371.140482)
			)
		)
		(stroke
			(width 0)
			(type solid)
		)
		(fill yes)
		(layer "B.Cu")
		(net "GND")
	)
	(gr_poly
		(pts
			(arc
				(start 392.652504 -369.938808)
				(mid 392.403076 -369.938808)
				(end 392.652504 -369.938808)
			)
		)
		(stroke
			(width 0)
			(type solid)
		)
		(fill yes)
		(layer "B.Cu")
		(net "GND")
	)
	(gr_poly
		(pts
			(arc
				(start 395.44752 -85.576918)
				(mid 395.19352 -85.576918)
				(end 395.44752 -85.576918)
			)
		)
		(stroke
			(width 0)
			(type solid)
		)
		(fill yes)
		(layer "B.Cu")
		(net "GND")
	)
	(gr_poly
		(pts
			(arc
				(start 395.477492 -86.603332)
				(mid 395.223492 -86.603332)
				(end 395.477492 -86.603332)
			)
		)
		(stroke
			(width 0)
			(type solid)
		)
		(fill yes)
		(layer "B.Cu")
		(net "GND")
	)
	(gr_poly
		(pts
			(arc
				(start 416.262566 -290.066984)
				(mid 416.281953 -290.063034)
				(end 416.29838 -290.051998)
			)
			(xy 416.30092 -290.049458) (xy 416.30854 -290.030916)
			(arc
				(start 416.30854 -289.559492)
				(mid 416.293661 -289.523571)
				(end 416.25774 -289.508692)
			)
			(arc
				(start 398.828514 -289.508692)
				(mid 398.809127 -289.512642)
				(end 398.7927 -289.523678)
			)
			(arc
				(start 398.721326 -289.595052)
				(mid 398.710215 -289.611586)
				(end 398.70634 -289.63112)
			)
			(xy 398.70634 -290.030916) (xy 398.71396 -290.049458)
			(arc
				(start 398.7165 -290.051998)
				(mid 398.732917 -290.06306)
				(end 398.752314 -290.066984)
			)
		)
		(stroke
			(width 0)
			(type solid)
		)
		(fill yes)
		(layer "B.Cu")
		(net "GND")
	)
	(gr_poly
		(pts
			(arc
				(start 419.052502 -410.041852)
				(mid 418.803074 -410.041852)
				(end 419.052502 -410.041852)
			)
		)
		(stroke
			(width 0)
			(type solid)
		)
		(fill yes)
		(layer "B.Cu")
		(net "GND")
	)
	(gr_poly
		(pts
			(arc
				(start 419.052502 -408.840178)
				(mid 418.803074 -408.840178)
				(end 419.052502 -408.840178)
			)
		)
		(stroke
			(width 0)
			(type solid)
		)
		(fill yes)
		(layer "B.Cu")
		(net "GND")
	)
	(gr_poly
		(pts
			(arc
				(start 419.052502 -407.638504)
				(mid 418.803074 -407.638504)
				(end 419.052502 -407.638504)
			)
		)
		(stroke
			(width 0)
			(type solid)
		)
		(fill yes)
		(layer "B.Cu")
		(net "GND")
	)
	(gr_poly
		(pts
			(arc
				(start 419.052502 -406.141936)
				(mid 418.803074 -406.141936)
				(end 419.052502 -406.141936)
			)
		)
		(stroke
			(width 0)
			(type solid)
		)
		(fill yes)
		(layer "B.Cu")
		(net "GND")
	)
	(gr_poly
		(pts
			(arc
				(start 419.052502 -404.940262)
				(mid 418.803074 -404.940262)
				(end 419.052502 -404.940262)
			)
		)
		(stroke
			(width 0)
			(type solid)
		)
		(fill yes)
		(layer "B.Cu")
		(net "GND")
	)
	(gr_poly
		(pts
			(arc
				(start 419.052502 -403.738588)
				(mid 418.803074 -403.738588)
				(end 419.052502 -403.738588)
			)
		)
		(stroke
			(width 0)
			(type solid)
		)
		(fill yes)
		(layer "B.Cu")
		(net "GND")
	)
	(gr_poly
		(pts
			(arc
				(start 419.052502 -402.241766)
				(mid 418.803074 -402.241766)
				(end 419.052502 -402.241766)
			)
		)
		(stroke
			(width 0)
			(type solid)
		)
		(fill yes)
		(layer "B.Cu")
		(net "GND")
	)
	(gr_poly
		(pts
			(arc
				(start 419.052502 -401.040092)
				(mid 418.803074 -401.040092)
				(end 419.052502 -401.040092)
			)
		)
		(stroke
			(width 0)
			(type solid)
		)
		(fill yes)
		(layer "B.Cu")
		(net "GND")
	)
	(gr_poly
		(pts
			(arc
				(start 419.052502 -399.838418)
				(mid 418.803074 -399.838418)
				(end 419.052502 -399.838418)
			)
		)
		(stroke
			(width 0)
			(type solid)
		)
		(fill yes)
		(layer "B.Cu")
		(net "GND")
	)
	(gr_poly
		(pts
			(arc
				(start 419.052502 -398.34185)
				(mid 418.803074 -398.34185)
				(end 419.052502 -398.34185)
			)
		)
		(stroke
			(width 0)
			(type solid)
		)
		(fill yes)
		(layer "B.Cu")
		(net "GND")
	)
	(gr_poly
		(pts
			(arc
				(start 419.052502 -397.140176)
				(mid 418.803074 -397.140176)
				(end 419.052502 -397.140176)
			)
		)
		(stroke
			(width 0)
			(type solid)
		)
		(fill yes)
		(layer "B.Cu")
		(net "GND")
	)
	(gr_poly
		(pts
			(arc
				(start 419.052502 -395.938502)
				(mid 418.803074 -395.938502)
				(end 419.052502 -395.938502)
			)
		)
		(stroke
			(width 0)
			(type solid)
		)
		(fill yes)
		(layer "B.Cu")
		(net "GND")
	)
	(gr_poly
		(pts
			(arc
				(start 419.052502 -384.041904)
				(mid 418.803074 -384.041904)
				(end 419.052502 -384.041904)
			)
		)
		(stroke
			(width 0)
			(type solid)
		)
		(fill yes)
		(layer "B.Cu")
		(net "GND")
	)
	(gr_poly
		(pts
			(arc
				(start 419.052502 -382.84023)
				(mid 418.803074 -382.84023)
				(end 419.052502 -382.84023)
			)
		)
		(stroke
			(width 0)
			(type solid)
		)
		(fill yes)
		(layer "B.Cu")
		(net "GND")
	)
	(gr_poly
		(pts
			(arc
				(start 419.052502 -381.638556)
				(mid 418.803074 -381.638556)
				(end 419.052502 -381.638556)
			)
		)
		(stroke
			(width 0)
			(type solid)
		)
		(fill yes)
		(layer "B.Cu")
		(net "GND")
	)
	(gr_poly
		(pts
			(arc
				(start 419.052502 -380.141988)
				(mid 418.803074 -380.141988)
				(end 419.052502 -380.141988)
			)
		)
		(stroke
			(width 0)
			(type solid)
		)
		(fill yes)
		(layer "B.Cu")
		(net "GND")
	)
	(gr_poly
		(pts
			(arc
				(start 419.052502 -378.940314)
				(mid 418.803074 -378.940314)
				(end 419.052502 -378.940314)
			)
		)
		(stroke
			(width 0)
			(type solid)
		)
		(fill yes)
		(layer "B.Cu")
		(net "GND")
	)
	(gr_poly
		(pts
			(arc
				(start 419.052502 -377.73864)
				(mid 418.803074 -377.73864)
				(end 419.052502 -377.73864)
			)
		)
		(stroke
			(width 0)
			(type solid)
		)
		(fill yes)
		(layer "B.Cu")
		(net "GND")
	)
	(gr_poly
		(pts
			(arc
				(start 419.052502 -376.241818)
				(mid 418.803074 -376.241818)
				(end 419.052502 -376.241818)
			)
		)
		(stroke
			(width 0)
			(type solid)
		)
		(fill yes)
		(layer "B.Cu")
		(net "GND")
	)
	(gr_poly
		(pts
			(arc
				(start 419.052502 -375.040144)
				(mid 418.803074 -375.040144)
				(end 419.052502 -375.040144)
			)
		)
		(stroke
			(width 0)
			(type solid)
		)
		(fill yes)
		(layer "B.Cu")
		(net "GND")
	)
	(gr_poly
		(pts
			(arc
				(start 419.052502 -373.83847)
				(mid 418.803074 -373.83847)
				(end 419.052502 -373.83847)
			)
		)
		(stroke
			(width 0)
			(type solid)
		)
		(fill yes)
		(layer "B.Cu")
		(net "GND")
	)
	(gr_poly
		(pts
			(arc
				(start 419.052502 -372.341902)
				(mid 418.803074 -372.341902)
				(end 419.052502 -372.341902)
			)
		)
		(stroke
			(width 0)
			(type solid)
		)
		(fill yes)
		(layer "B.Cu")
		(net "GND")
	)
	(gr_poly
		(pts
			(arc
				(start 419.052502 -371.140228)
				(mid 418.803074 -371.140228)
				(end 419.052502 -371.140228)
			)
		)
		(stroke
			(width 0)
			(type solid)
		)
		(fill yes)
		(layer "B.Cu")
		(net "GND")
	)
	(gr_poly
		(pts
			(arc
				(start 419.052502 -369.938554)
				(mid 418.803074 -369.938554)
				(end 419.052502 -369.938554)
			)
		)
		(stroke
			(width 0)
			(type solid)
		)
		(fill yes)
		(layer "B.Cu")
		(net "GND")
	)
	(gr_poly
		(pts
			(arc
				(start 421.252396 -411.141926)
				(mid 421.002968 -411.141926)
				(end 421.252396 -411.141926)
			)
		)
		(stroke
			(width 0)
			(type solid)
		)
		(fill yes)
		(layer "B.Cu")
		(net "GND")
	)
	(gr_poly
		(pts
			(arc
				(start 421.252396 -409.940252)
				(mid 421.002968 -409.940252)
				(end 421.252396 -409.940252)
			)
		)
		(stroke
			(width 0)
			(type solid)
		)
		(fill yes)
		(layer "B.Cu")
		(net "GND")
	)
	(gr_poly
		(pts
			(arc
				(start 421.252396 -408.738578)
				(mid 421.002968 -408.738578)
				(end 421.252396 -408.738578)
			)
		)
		(stroke
			(width 0)
			(type solid)
		)
		(fill yes)
		(layer "B.Cu")
		(net "GND")
	)
	(gr_poly
		(pts
			(arc
				(start 421.252396 -407.24201)
				(mid 421.002968 -407.24201)
				(end 421.252396 -407.24201)
			)
		)
		(stroke
			(width 0)
			(type solid)
		)
		(fill yes)
		(layer "B.Cu")
		(net "GND")
	)
	(gr_poly
		(pts
			(arc
				(start 421.252396 -406.040336)
				(mid 421.002968 -406.040336)
				(end 421.252396 -406.040336)
			)
		)
		(stroke
			(width 0)
			(type solid)
		)
		(fill yes)
		(layer "B.Cu")
		(net "GND")
	)
	(gr_poly
		(pts
			(arc
				(start 421.252396 -404.838662)
				(mid 421.002968 -404.838662)
				(end 421.252396 -404.838662)
			)
		)
		(stroke
			(width 0)
			(type solid)
		)
		(fill yes)
		(layer "B.Cu")
		(net "GND")
	)
	(gr_poly
		(pts
			(arc
				(start 421.252396 -403.34184)
				(mid 421.002968 -403.34184)
				(end 421.252396 -403.34184)
			)
		)
		(stroke
			(width 0)
			(type solid)
		)
		(fill yes)
		(layer "B.Cu")
		(net "GND")
	)
	(gr_poly
		(pts
			(arc
				(start 421.252396 -402.140166)
				(mid 421.002968 -402.140166)
				(end 421.252396 -402.140166)
			)
		)
		(stroke
			(width 0)
			(type solid)
		)
		(fill yes)
		(layer "B.Cu")
		(net "GND")
	)
	(gr_poly
		(pts
			(arc
				(start 421.252396 -400.938492)
				(mid 421.002968 -400.938492)
				(end 421.252396 -400.938492)
			)
		)
		(stroke
			(width 0)
			(type solid)
		)
		(fill yes)
		(layer "B.Cu")
		(net "GND")
	)
	(gr_poly
		(pts
			(arc
				(start 421.252396 -399.441924)
				(mid 421.002968 -399.441924)
				(end 421.252396 -399.441924)
			)
		)
		(stroke
			(width 0)
			(type solid)
		)
		(fill yes)
		(layer "B.Cu")
		(net "GND")
	)
	(gr_poly
		(pts
			(arc
				(start 421.252396 -398.24025)
				(mid 421.002968 -398.24025)
				(end 421.252396 -398.24025)
			)
		)
		(stroke
			(width 0)
			(type solid)
		)
		(fill yes)
		(layer "B.Cu")
		(net "GND")
	)
	(gr_poly
		(pts
			(arc
				(start 421.252396 -397.038576)
				(mid 421.002968 -397.038576)
				(end 421.252396 -397.038576)
			)
		)
		(stroke
			(width 0)
			(type solid)
		)
		(fill yes)
		(layer "B.Cu")
		(net "GND")
	)
	(gr_poly
		(pts
			(arc
				(start 421.252396 -385.141978)
				(mid 421.002968 -385.141978)
				(end 421.252396 -385.141978)
			)
		)
		(stroke
			(width 0)
			(type solid)
		)
		(fill yes)
		(layer "B.Cu")
		(net "GND")
	)
	(gr_poly
		(pts
			(arc
				(start 421.252396 -383.940304)
				(mid 421.002968 -383.940304)
				(end 421.252396 -383.940304)
			)
		)
		(stroke
			(width 0)
			(type solid)
		)
		(fill yes)
		(layer "B.Cu")
		(net "GND")
	)
	(gr_poly
		(pts
			(arc
				(start 421.252396 -382.73863)
				(mid 421.002968 -382.73863)
				(end 421.252396 -382.73863)
			)
		)
		(stroke
			(width 0)
			(type solid)
		)
		(fill yes)
		(layer "B.Cu")
		(net "GND")
	)
	(gr_poly
		(pts
			(arc
				(start 421.252396 -381.242062)
				(mid 421.002968 -381.242062)
				(end 421.252396 -381.242062)
			)
		)
		(stroke
			(width 0)
			(type solid)
		)
		(fill yes)
		(layer "B.Cu")
		(net "GND")
	)
	(gr_poly
		(pts
			(arc
				(start 421.252396 -380.040388)
				(mid 421.002968 -380.040388)
				(end 421.252396 -380.040388)
			)
		)
		(stroke
			(width 0)
			(type solid)
		)
		(fill yes)
		(layer "B.Cu")
		(net "GND")
	)
	(gr_poly
		(pts
			(arc
				(start 421.252396 -378.838714)
				(mid 421.002968 -378.838714)
				(end 421.252396 -378.838714)
			)
		)
		(stroke
			(width 0)
			(type solid)
		)
		(fill yes)
		(layer "B.Cu")
		(net "GND")
	)
	(gr_poly
		(pts
			(arc
				(start 421.252396 -377.341892)
				(mid 421.002968 -377.341892)
				(end 421.252396 -377.341892)
			)
		)
		(stroke
			(width 0)
			(type solid)
		)
		(fill yes)
		(layer "B.Cu")
		(net "GND")
	)
	(gr_poly
		(pts
			(arc
				(start 421.252396 -376.140218)
				(mid 421.002968 -376.140218)
				(end 421.252396 -376.140218)
			)
		)
		(stroke
			(width 0)
			(type solid)
		)
		(fill yes)
		(layer "B.Cu")
		(net "GND")
	)
	(gr_poly
		(pts
			(arc
				(start 421.252396 -374.938544)
				(mid 421.002968 -374.938544)
				(end 421.252396 -374.938544)
			)
		)
		(stroke
			(width 0)
			(type solid)
		)
		(fill yes)
		(layer "B.Cu")
		(net "GND")
	)
	(gr_poly
		(pts
			(arc
				(start 421.252396 -373.441976)
				(mid 421.002968 -373.441976)
				(end 421.252396 -373.441976)
			)
		)
		(stroke
			(width 0)
			(type solid)
		)
		(fill yes)
		(layer "B.Cu")
		(net "GND")
	)
	(gr_poly
		(pts
			(arc
				(start 421.252396 -372.240302)
				(mid 421.002968 -372.240302)
				(end 421.252396 -372.240302)
			)
		)
		(stroke
			(width 0)
			(type solid)
		)
		(fill yes)
		(layer "B.Cu")
		(net "GND")
	)
	(gr_poly
		(pts
			(arc
				(start 421.252396 -371.038628)
				(mid 421.002968 -371.038628)
				(end 421.252396 -371.038628)
			)
		)
		(stroke
			(width 0)
			(type solid)
		)
		(fill yes)
		(layer "B.Cu")
		(net "GND")
	)
	(gr_poly
		(pts
			(arc
				(start 423.452544 -410.041852)
				(mid 423.203116 -410.041852)
				(end 423.452544 -410.041852)
			)
		)
		(stroke
			(width 0)
			(type solid)
		)
		(fill yes)
		(layer "B.Cu")
		(net "GND")
	)
	(gr_poly
		(pts
			(arc
				(start 423.452544 -408.840178)
				(mid 423.203116 -408.840178)
				(end 423.452544 -408.840178)
			)
		)
		(stroke
			(width 0)
			(type solid)
		)
		(fill yes)
		(layer "B.Cu")
		(net "GND")
	)
	(gr_poly
		(pts
			(arc
				(start 423.452544 -407.638504)
				(mid 423.203116 -407.638504)
				(end 423.452544 -407.638504)
			)
		)
		(stroke
			(width 0)
			(type solid)
		)
		(fill yes)
		(layer "B.Cu")
		(net "GND")
	)
	(gr_poly
		(pts
			(arc
				(start 423.452544 -406.141936)
				(mid 423.203116 -406.141936)
				(end 423.452544 -406.141936)
			)
		)
		(stroke
			(width 0)
			(type solid)
		)
		(fill yes)
		(layer "B.Cu")
		(net "GND")
	)
	(gr_poly
		(pts
			(arc
				(start 423.452544 -404.940262)
				(mid 423.203116 -404.940262)
				(end 423.452544 -404.940262)
			)
		)
		(stroke
			(width 0)
			(type solid)
		)
		(fill yes)
		(layer "B.Cu")
		(net "GND")
	)
	(gr_poly
		(pts
			(arc
				(start 423.452544 -403.738588)
				(mid 423.203116 -403.738588)
				(end 423.452544 -403.738588)
			)
		)
		(stroke
			(width 0)
			(type solid)
		)
		(fill yes)
		(layer "B.Cu")
		(net "GND")
	)
	(gr_poly
		(pts
			(arc
				(start 423.452544 -402.241766)
				(mid 423.203116 -402.241766)
				(end 423.452544 -402.241766)
			)
		)
		(stroke
			(width 0)
			(type solid)
		)
		(fill yes)
		(layer "B.Cu")
		(net "GND")
	)
	(gr_poly
		(pts
			(arc
				(start 423.452544 -401.040092)
				(mid 423.203116 -401.040092)
				(end 423.452544 -401.040092)
			)
		)
		(stroke
			(width 0)
			(type solid)
		)
		(fill yes)
		(layer "B.Cu")
		(net "GND")
	)
	(gr_poly
		(pts
			(arc
				(start 423.452544 -399.838418)
				(mid 423.203116 -399.838418)
				(end 423.452544 -399.838418)
			)
		)
		(stroke
			(width 0)
			(type solid)
		)
		(fill yes)
		(layer "B.Cu")
		(net "GND")
	)
	(gr_poly
		(pts
			(arc
				(start 423.452544 -398.34185)
				(mid 423.203116 -398.34185)
				(end 423.452544 -398.34185)
			)
		)
		(stroke
			(width 0)
			(type solid)
		)
		(fill yes)
		(layer "B.Cu")
		(net "GND")
	)
	(gr_poly
		(pts
			(arc
				(start 423.452544 -397.140176)
				(mid 423.203116 -397.140176)
				(end 423.452544 -397.140176)
			)
		)
		(stroke
			(width 0)
			(type solid)
		)
		(fill yes)
		(layer "B.Cu")
		(net "GND")
	)
	(gr_poly
		(pts
			(arc
				(start 423.452544 -395.938502)
				(mid 423.203116 -395.938502)
				(end 423.452544 -395.938502)
			)
		)
		(stroke
			(width 0)
			(type solid)
		)
		(fill yes)
		(layer "B.Cu")
		(net "GND")
	)
	(gr_poly
		(pts
			(arc
				(start 423.452544 -384.041904)
				(mid 423.203116 -384.041904)
				(end 423.452544 -384.041904)
			)
		)
		(stroke
			(width 0)
			(type solid)
		)
		(fill yes)
		(layer "B.Cu")
		(net "GND")
	)
	(gr_poly
		(pts
			(arc
				(start 423.452544 -382.84023)
				(mid 423.203116 -382.84023)
				(end 423.452544 -382.84023)
			)
		)
		(stroke
			(width 0)
			(type solid)
		)
		(fill yes)
		(layer "B.Cu")
		(net "GND")
	)
	(gr_poly
		(pts
			(arc
				(start 423.452544 -381.638556)
				(mid 423.203116 -381.638556)
				(end 423.452544 -381.638556)
			)
		)
		(stroke
			(width 0)
			(type solid)
		)
		(fill yes)
		(layer "B.Cu")
		(net "GND")
	)
	(gr_poly
		(pts
			(arc
				(start 423.452544 -380.141988)
				(mid 423.203116 -380.141988)
				(end 423.452544 -380.141988)
			)
		)
		(stroke
			(width 0)
			(type solid)
		)
		(fill yes)
		(layer "B.Cu")
		(net "GND")
	)
	(gr_poly
		(pts
			(arc
				(start 423.452544 -378.940314)
				(mid 423.203116 -378.940314)
				(end 423.452544 -378.940314)
			)
		)
		(stroke
			(width 0)
			(type solid)
		)
		(fill yes)
		(layer "B.Cu")
		(net "GND")
	)
	(gr_poly
		(pts
			(arc
				(start 423.452544 -377.73864)
				(mid 423.203116 -377.73864)
				(end 423.452544 -377.73864)
			)
		)
		(stroke
			(width 0)
			(type solid)
		)
		(fill yes)
		(layer "B.Cu")
		(net "GND")
	)
	(gr_poly
		(pts
			(arc
				(start 423.452544 -376.241818)
				(mid 423.203116 -376.241818)
				(end 423.452544 -376.241818)
			)
		)
		(stroke
			(width 0)
			(type solid)
		)
		(fill yes)
		(layer "B.Cu")
		(net "GND")
	)
	(gr_poly
		(pts
			(arc
				(start 423.452544 -375.040144)
				(mid 423.203116 -375.040144)
				(end 423.452544 -375.040144)
			)
		)
		(stroke
			(width 0)
			(type solid)
		)
		(fill yes)
		(layer "B.Cu")
		(net "GND")
	)
	(gr_poly
		(pts
			(arc
				(start 423.452544 -373.83847)
				(mid 423.203116 -373.83847)
				(end 423.452544 -373.83847)
			)
		)
		(stroke
			(width 0)
			(type solid)
		)
		(fill yes)
		(layer "B.Cu")
		(net "GND")
	)
	(gr_poly
		(pts
			(arc
				(start 423.452544 -372.341902)
				(mid 423.203116 -372.341902)
				(end 423.452544 -372.341902)
			)
		)
		(stroke
			(width 0)
			(type solid)
		)
		(fill yes)
		(layer "B.Cu")
		(net "GND")
	)
	(gr_poly
		(pts
			(arc
				(start 423.452544 -371.140228)
				(mid 423.203116 -371.140228)
				(end 423.452544 -371.140228)
			)
		)
		(stroke
			(width 0)
			(type solid)
		)
		(fill yes)
		(layer "B.Cu")
		(net "GND")
	)
	(gr_poly
		(pts
			(arc
				(start 423.452544 -369.938554)
				(mid 423.203116 -369.938554)
				(end 423.452544 -369.938554)
			)
		)
		(stroke
			(width 0)
			(type solid)
		)
		(fill yes)
		(layer "B.Cu")
		(net "GND")
	)
	(gr_poly
		(pts
			(arc
				(start 425.652438 -411.141926)
				(mid 425.40301 -411.141926)
				(end 425.652438 -411.141926)
			)
		)
		(stroke
			(width 0)
			(type solid)
		)
		(fill yes)
		(layer "B.Cu")
		(net "GND")
	)
	(gr_poly
		(pts
			(arc
				(start 425.652438 -409.940252)
				(mid 425.40301 -409.940252)
				(end 425.652438 -409.940252)
			)
		)
		(stroke
			(width 0)
			(type solid)
		)
		(fill yes)
		(layer "B.Cu")
		(net "GND")
	)
	(gr_poly
		(pts
			(arc
				(start 425.652438 -408.738578)
				(mid 425.40301 -408.738578)
				(end 425.652438 -408.738578)
			)
		)
		(stroke
			(width 0)
			(type solid)
		)
		(fill yes)
		(layer "B.Cu")
		(net "GND")
	)
	(gr_poly
		(pts
			(arc
				(start 425.652438 -407.24201)
				(mid 425.40301 -407.24201)
				(end 425.652438 -407.24201)
			)
		)
		(stroke
			(width 0)
			(type solid)
		)
		(fill yes)
		(layer "B.Cu")
		(net "GND")
	)
	(gr_poly
		(pts
			(arc
				(start 425.652438 -406.040336)
				(mid 425.40301 -406.040336)
				(end 425.652438 -406.040336)
			)
		)
		(stroke
			(width 0)
			(type solid)
		)
		(fill yes)
		(layer "B.Cu")
		(net "GND")
	)
	(gr_poly
		(pts
			(arc
				(start 425.652438 -404.838662)
				(mid 425.40301 -404.838662)
				(end 425.652438 -404.838662)
			)
		)
		(stroke
			(width 0)
			(type solid)
		)
		(fill yes)
		(layer "B.Cu")
		(net "GND")
	)
	(gr_poly
		(pts
			(arc
				(start 425.652438 -403.34184)
				(mid 425.40301 -403.34184)
				(end 425.652438 -403.34184)
			)
		)
		(stroke
			(width 0)
			(type solid)
		)
		(fill yes)
		(layer "B.Cu")
		(net "GND")
	)
	(gr_poly
		(pts
			(arc
				(start 425.652438 -402.140166)
				(mid 425.40301 -402.140166)
				(end 425.652438 -402.140166)
			)
		)
		(stroke
			(width 0)
			(type solid)
		)
		(fill yes)
		(layer "B.Cu")
		(net "GND")
	)
	(gr_poly
		(pts
			(arc
				(start 425.652438 -400.938492)
				(mid 425.40301 -400.938492)
				(end 425.652438 -400.938492)
			)
		)
		(stroke
			(width 0)
			(type solid)
		)
		(fill yes)
		(layer "B.Cu")
		(net "GND")
	)
	(gr_poly
		(pts
			(arc
				(start 425.652438 -399.441924)
				(mid 425.40301 -399.441924)
				(end 425.652438 -399.441924)
			)
		)
		(stroke
			(width 0)
			(type solid)
		)
		(fill yes)
		(layer "B.Cu")
		(net "GND")
	)
	(gr_poly
		(pts
			(arc
				(start 425.652438 -398.24025)
				(mid 425.40301 -398.24025)
				(end 425.652438 -398.24025)
			)
		)
		(stroke
			(width 0)
			(type solid)
		)
		(fill yes)
		(layer "B.Cu")
		(net "GND")
	)
	(gr_poly
		(pts
			(arc
				(start 425.652438 -397.038576)
				(mid 425.40301 -397.038576)
				(end 425.652438 -397.038576)
			)
		)
		(stroke
			(width 0)
			(type solid)
		)
		(fill yes)
		(layer "B.Cu")
		(net "GND")
	)
	(gr_poly
		(pts
			(arc
				(start 425.652438 -385.141978)
				(mid 425.40301 -385.141978)
				(end 425.652438 -385.141978)
			)
		)
		(stroke
			(width 0)
			(type solid)
		)
		(fill yes)
		(layer "B.Cu")
		(net "GND")
	)
	(gr_poly
		(pts
			(arc
				(start 425.652438 -383.940304)
				(mid 425.40301 -383.940304)
				(end 425.652438 -383.940304)
			)
		)
		(stroke
			(width 0)
			(type solid)
		)
		(fill yes)
		(layer "B.Cu")
		(net "GND")
	)
	(gr_poly
		(pts
			(arc
				(start 425.652438 -382.73863)
				(mid 425.40301 -382.73863)
				(end 425.652438 -382.73863)
			)
		)
		(stroke
			(width 0)
			(type solid)
		)
		(fill yes)
		(layer "B.Cu")
		(net "GND")
	)
	(gr_poly
		(pts
			(arc
				(start 425.652438 -381.242062)
				(mid 425.40301 -381.242062)
				(end 425.652438 -381.242062)
			)
		)
		(stroke
			(width 0)
			(type solid)
		)
		(fill yes)
		(layer "B.Cu")
		(net "GND")
	)
	(gr_poly
		(pts
			(arc
				(start 425.652438 -380.040388)
				(mid 425.40301 -380.040388)
				(end 425.652438 -380.040388)
			)
		)
		(stroke
			(width 0)
			(type solid)
		)
		(fill yes)
		(layer "B.Cu")
		(net "GND")
	)
	(gr_poly
		(pts
			(arc
				(start 425.652438 -378.838714)
				(mid 425.40301 -378.838714)
				(end 425.652438 -378.838714)
			)
		)
		(stroke
			(width 0)
			(type solid)
		)
		(fill yes)
		(layer "B.Cu")
		(net "GND")
	)
	(gr_poly
		(pts
			(arc
				(start 425.652438 -377.341892)
				(mid 425.40301 -377.341892)
				(end 425.652438 -377.341892)
			)
		)
		(stroke
			(width 0)
			(type solid)
		)
		(fill yes)
		(layer "B.Cu")
		(net "GND")
	)
	(gr_poly
		(pts
			(arc
				(start 425.652438 -376.140218)
				(mid 425.40301 -376.140218)
				(end 425.652438 -376.140218)
			)
		)
		(stroke
			(width 0)
			(type solid)
		)
		(fill yes)
		(layer "B.Cu")
		(net "GND")
	)
	(gr_poly
		(pts
			(arc
				(start 425.652438 -374.938544)
				(mid 425.40301 -374.938544)
				(end 425.652438 -374.938544)
			)
		)
		(stroke
			(width 0)
			(type solid)
		)
		(fill yes)
		(layer "B.Cu")
		(net "GND")
	)
	(gr_poly
		(pts
			(arc
				(start 425.652438 -373.441976)
				(mid 425.40301 -373.441976)
				(end 425.652438 -373.441976)
			)
		)
		(stroke
			(width 0)
			(type solid)
		)
		(fill yes)
		(layer "B.Cu")
		(net "GND")
	)
	(gr_poly
		(pts
			(arc
				(start 425.652438 -372.240302)
				(mid 425.40301 -372.240302)
				(end 425.652438 -372.240302)
			)
		)
		(stroke
			(width 0)
			(type solid)
		)
		(fill yes)
		(layer "B.Cu")
		(net "GND")
	)
	(gr_poly
		(pts
			(arc
				(start 425.652438 -371.038628)
				(mid 425.40301 -371.038628)
				(end 425.652438 -371.038628)
			)
		)
		(stroke
			(width 0)
			(type solid)
		)
		(fill yes)
		(layer "B.Cu")
		(net "GND")
	)
	(gr_poly
		(pts
			(arc
				(start 427.852586 -410.041852)
				(mid 427.603158 -410.041852)
				(end 427.852586 -410.041852)
			)
		)
		(stroke
			(width 0)
			(type solid)
		)
		(fill yes)
		(layer "B.Cu")
		(net "GND")
	)
	(gr_poly
		(pts
			(arc
				(start 427.852586 -408.840178)
				(mid 427.603158 -408.840178)
				(end 427.852586 -408.840178)
			)
		)
		(stroke
			(width 0)
			(type solid)
		)
		(fill yes)
		(layer "B.Cu")
		(net "GND")
	)
	(gr_poly
		(pts
			(arc
				(start 427.852586 -407.638504)
				(mid 427.603158 -407.638504)
				(end 427.852586 -407.638504)
			)
		)
		(stroke
			(width 0)
			(type solid)
		)
		(fill yes)
		(layer "B.Cu")
		(net "GND")
	)
	(gr_poly
		(pts
			(arc
				(start 427.852586 -406.141936)
				(mid 427.603158 -406.141936)
				(end 427.852586 -406.141936)
			)
		)
		(stroke
			(width 0)
			(type solid)
		)
		(fill yes)
		(layer "B.Cu")
		(net "GND")
	)
	(gr_poly
		(pts
			(arc
				(start 427.852586 -404.940262)
				(mid 427.603158 -404.940262)
				(end 427.852586 -404.940262)
			)
		)
		(stroke
			(width 0)
			(type solid)
		)
		(fill yes)
		(layer "B.Cu")
		(net "GND")
	)
	(gr_poly
		(pts
			(arc
				(start 427.852586 -403.738588)
				(mid 427.603158 -403.738588)
				(end 427.852586 -403.738588)
			)
		)
		(stroke
			(width 0)
			(type solid)
		)
		(fill yes)
		(layer "B.Cu")
		(net "GND")
	)
	(gr_poly
		(pts
			(arc
				(start 427.852586 -402.241766)
				(mid 427.603158 -402.241766)
				(end 427.852586 -402.241766)
			)
		)
		(stroke
			(width 0)
			(type solid)
		)
		(fill yes)
		(layer "B.Cu")
		(net "GND")
	)
	(gr_poly
		(pts
			(arc
				(start 427.852586 -401.040092)
				(mid 427.603158 -401.040092)
				(end 427.852586 -401.040092)
			)
		)
		(stroke
			(width 0)
			(type solid)
		)
		(fill yes)
		(layer "B.Cu")
		(net "GND")
	)
	(gr_poly
		(pts
			(arc
				(start 427.852586 -399.838418)
				(mid 427.603158 -399.838418)
				(end 427.852586 -399.838418)
			)
		)
		(stroke
			(width 0)
			(type solid)
		)
		(fill yes)
		(layer "B.Cu")
		(net "GND")
	)
	(gr_poly
		(pts
			(arc
				(start 427.852586 -398.34185)
				(mid 427.603158 -398.34185)
				(end 427.852586 -398.34185)
			)
		)
		(stroke
			(width 0)
			(type solid)
		)
		(fill yes)
		(layer "B.Cu")
		(net "GND")
	)
	(gr_poly
		(pts
			(arc
				(start 427.852586 -397.140176)
				(mid 427.603158 -397.140176)
				(end 427.852586 -397.140176)
			)
		)
		(stroke
			(width 0)
			(type solid)
		)
		(fill yes)
		(layer "B.Cu")
		(net "GND")
	)
	(gr_poly
		(pts
			(arc
				(start 427.852586 -395.938502)
				(mid 427.603158 -395.938502)
				(end 427.852586 -395.938502)
			)
		)
		(stroke
			(width 0)
			(type solid)
		)
		(fill yes)
		(layer "B.Cu")
		(net "GND")
	)
	(gr_poly
		(pts
			(arc
				(start 427.852586 -384.041904)
				(mid 427.603158 -384.041904)
				(end 427.852586 -384.041904)
			)
		)
		(stroke
			(width 0)
			(type solid)
		)
		(fill yes)
		(layer "B.Cu")
		(net "GND")
	)
	(gr_poly
		(pts
			(arc
				(start 427.852586 -382.84023)
				(mid 427.603158 -382.84023)
				(end 427.852586 -382.84023)
			)
		)
		(stroke
			(width 0)
			(type solid)
		)
		(fill yes)
		(layer "B.Cu")
		(net "GND")
	)
	(gr_poly
		(pts
			(arc
				(start 427.852586 -381.638556)
				(mid 427.603158 -381.638556)
				(end 427.852586 -381.638556)
			)
		)
		(stroke
			(width 0)
			(type solid)
		)
		(fill yes)
		(layer "B.Cu")
		(net "GND")
	)
	(gr_poly
		(pts
			(arc
				(start 427.852586 -380.141988)
				(mid 427.603158 -380.141988)
				(end 427.852586 -380.141988)
			)
		)
		(stroke
			(width 0)
			(type solid)
		)
		(fill yes)
		(layer "B.Cu")
		(net "GND")
	)
	(gr_poly
		(pts
			(arc
				(start 427.852586 -378.940314)
				(mid 427.603158 -378.940314)
				(end 427.852586 -378.940314)
			)
		)
		(stroke
			(width 0)
			(type solid)
		)
		(fill yes)
		(layer "B.Cu")
		(net "GND")
	)
	(gr_poly
		(pts
			(arc
				(start 427.852586 -377.73864)
				(mid 427.603158 -377.73864)
				(end 427.852586 -377.73864)
			)
		)
		(stroke
			(width 0)
			(type solid)
		)
		(fill yes)
		(layer "B.Cu")
		(net "GND")
	)
	(gr_poly
		(pts
			(arc
				(start 427.852586 -376.241818)
				(mid 427.603158 -376.241818)
				(end 427.852586 -376.241818)
			)
		)
		(stroke
			(width 0)
			(type solid)
		)
		(fill yes)
		(layer "B.Cu")
		(net "GND")
	)
	(gr_poly
		(pts
			(arc
				(start 427.852586 -375.040144)
				(mid 427.603158 -375.040144)
				(end 427.852586 -375.040144)
			)
		)
		(stroke
			(width 0)
			(type solid)
		)
		(fill yes)
		(layer "B.Cu")
		(net "GND")
	)
	(gr_poly
		(pts
			(arc
				(start 427.852586 -373.83847)
				(mid 427.603158 -373.83847)
				(end 427.852586 -373.83847)
			)
		)
		(stroke
			(width 0)
			(type solid)
		)
		(fill yes)
		(layer "B.Cu")
		(net "GND")
	)
	(gr_poly
		(pts
			(arc
				(start 427.852586 -372.341902)
				(mid 427.603158 -372.341902)
				(end 427.852586 -372.341902)
			)
		)
		(stroke
			(width 0)
			(type solid)
		)
		(fill yes)
		(layer "B.Cu")
		(net "GND")
	)
	(gr_poly
		(pts
			(arc
				(start 427.852586 -371.140228)
				(mid 427.603158 -371.140228)
				(end 427.852586 -371.140228)
			)
		)
		(stroke
			(width 0)
			(type solid)
		)
		(fill yes)
		(layer "B.Cu")
		(net "GND")
	)
	(gr_poly
		(pts
			(arc
				(start 427.852586 -369.938554)
				(mid 427.603158 -369.938554)
				(end 427.852586 -369.938554)
			)
		)
		(stroke
			(width 0)
			(type solid)
		)
		(fill yes)
		(layer "B.Cu")
		(net "GND")
	)
	(gr_poly
		(pts
			(arc
				(start 430.05248 -411.141926)
				(mid 429.803052 -411.141926)
				(end 430.05248 -411.141926)
			)
		)
		(stroke
			(width 0)
			(type solid)
		)
		(fill yes)
		(layer "B.Cu")
		(net "GND")
	)
	(gr_poly
		(pts
			(arc
				(start 430.05248 -409.940252)
				(mid 429.803052 -409.940252)
				(end 430.05248 -409.940252)
			)
		)
		(stroke
			(width 0)
			(type solid)
		)
		(fill yes)
		(layer "B.Cu")
		(net "GND")
	)
	(gr_poly
		(pts
			(arc
				(start 430.05248 -408.738578)
				(mid 429.803052 -408.738578)
				(end 430.05248 -408.738578)
			)
		)
		(stroke
			(width 0)
			(type solid)
		)
		(fill yes)
		(layer "B.Cu")
		(net "GND")
	)
	(gr_poly
		(pts
			(arc
				(start 430.05248 -407.24201)
				(mid 429.803052 -407.24201)
				(end 430.05248 -407.24201)
			)
		)
		(stroke
			(width 0)
			(type solid)
		)
		(fill yes)
		(layer "B.Cu")
		(net "GND")
	)
	(gr_poly
		(pts
			(arc
				(start 430.05248 -406.040336)
				(mid 429.803052 -406.040336)
				(end 430.05248 -406.040336)
			)
		)
		(stroke
			(width 0)
			(type solid)
		)
		(fill yes)
		(layer "B.Cu")
		(net "GND")
	)
	(gr_poly
		(pts
			(arc
				(start 430.05248 -404.838662)
				(mid 429.803052 -404.838662)
				(end 430.05248 -404.838662)
			)
		)
		(stroke
			(width 0)
			(type solid)
		)
		(fill yes)
		(layer "B.Cu")
		(net "GND")
	)
	(gr_poly
		(pts
			(arc
				(start 430.05248 -403.34184)
				(mid 429.803052 -403.34184)
				(end 430.05248 -403.34184)
			)
		)
		(stroke
			(width 0)
			(type solid)
		)
		(fill yes)
		(layer "B.Cu")
		(net "GND")
	)
	(gr_poly
		(pts
			(arc
				(start 430.05248 -402.140166)
				(mid 429.803052 -402.140166)
				(end 430.05248 -402.140166)
			)
		)
		(stroke
			(width 0)
			(type solid)
		)
		(fill yes)
		(layer "B.Cu")
		(net "GND")
	)
	(gr_poly
		(pts
			(arc
				(start 430.05248 -400.938492)
				(mid 429.803052 -400.938492)
				(end 430.05248 -400.938492)
			)
		)
		(stroke
			(width 0)
			(type solid)
		)
		(fill yes)
		(layer "B.Cu")
		(net "GND")
	)
	(gr_poly
		(pts
			(arc
				(start 430.05248 -399.441924)
				(mid 429.803052 -399.441924)
				(end 430.05248 -399.441924)
			)
		)
		(stroke
			(width 0)
			(type solid)
		)
		(fill yes)
		(layer "B.Cu")
		(net "GND")
	)
	(gr_poly
		(pts
			(arc
				(start 430.05248 -398.24025)
				(mid 429.803052 -398.24025)
				(end 430.05248 -398.24025)
			)
		)
		(stroke
			(width 0)
			(type solid)
		)
		(fill yes)
		(layer "B.Cu")
		(net "GND")
	)
	(gr_poly
		(pts
			(arc
				(start 430.05248 -397.038576)
				(mid 429.803052 -397.038576)
				(end 430.05248 -397.038576)
			)
		)
		(stroke
			(width 0)
			(type solid)
		)
		(fill yes)
		(layer "B.Cu")
		(net "GND")
	)
	(gr_poly
		(pts
			(arc
				(start 430.05248 -385.141978)
				(mid 429.803052 -385.141978)
				(end 430.05248 -385.141978)
			)
		)
		(stroke
			(width 0)
			(type solid)
		)
		(fill yes)
		(layer "B.Cu")
		(net "GND")
	)
	(gr_poly
		(pts
			(arc
				(start 430.05248 -383.940304)
				(mid 429.803052 -383.940304)
				(end 430.05248 -383.940304)
			)
		)
		(stroke
			(width 0)
			(type solid)
		)
		(fill yes)
		(layer "B.Cu")
		(net "GND")
	)
	(gr_poly
		(pts
			(arc
				(start 430.05248 -382.73863)
				(mid 429.803052 -382.73863)
				(end 430.05248 -382.73863)
			)
		)
		(stroke
			(width 0)
			(type solid)
		)
		(fill yes)
		(layer "B.Cu")
		(net "GND")
	)
	(gr_poly
		(pts
			(arc
				(start 430.05248 -381.242062)
				(mid 429.803052 -381.242062)
				(end 430.05248 -381.242062)
			)
		)
		(stroke
			(width 0)
			(type solid)
		)
		(fill yes)
		(layer "B.Cu")
		(net "GND")
	)
	(gr_poly
		(pts
			(arc
				(start 430.05248 -380.040388)
				(mid 429.803052 -380.040388)
				(end 430.05248 -380.040388)
			)
		)
		(stroke
			(width 0)
			(type solid)
		)
		(fill yes)
		(layer "B.Cu")
		(net "GND")
	)
	(gr_poly
		(pts
			(arc
				(start 430.05248 -378.838714)
				(mid 429.803052 -378.838714)
				(end 430.05248 -378.838714)
			)
		)
		(stroke
			(width 0)
			(type solid)
		)
		(fill yes)
		(layer "B.Cu")
		(net "GND")
	)
	(gr_poly
		(pts
			(arc
				(start 430.05248 -377.341892)
				(mid 429.803052 -377.341892)
				(end 430.05248 -377.341892)
			)
		)
		(stroke
			(width 0)
			(type solid)
		)
		(fill yes)
		(layer "B.Cu")
		(net "GND")
	)
	(gr_poly
		(pts
			(arc
				(start 430.05248 -376.140218)
				(mid 429.803052 -376.140218)
				(end 430.05248 -376.140218)
			)
		)
		(stroke
			(width 0)
			(type solid)
		)
		(fill yes)
		(layer "B.Cu")
		(net "GND")
	)
	(gr_poly
		(pts
			(arc
				(start 430.05248 -374.938544)
				(mid 429.803052 -374.938544)
				(end 430.05248 -374.938544)
			)
		)
		(stroke
			(width 0)
			(type solid)
		)
		(fill yes)
		(layer "B.Cu")
		(net "GND")
	)
	(gr_poly
		(pts
			(arc
				(start 430.05248 -373.441976)
				(mid 429.803052 -373.441976)
				(end 430.05248 -373.441976)
			)
		)
		(stroke
			(width 0)
			(type solid)
		)
		(fill yes)
		(layer "B.Cu")
		(net "GND")
	)
	(gr_poly
		(pts
			(arc
				(start 430.05248 -372.240302)
				(mid 429.803052 -372.240302)
				(end 430.05248 -372.240302)
			)
		)
		(stroke
			(width 0)
			(type solid)
		)
		(fill yes)
		(layer "B.Cu")
		(net "GND")
	)
	(gr_poly
		(pts
			(arc
				(start 430.05248 -371.038628)
				(mid 429.803052 -371.038628)
				(end 430.05248 -371.038628)
			)
		)
		(stroke
			(width 0)
			(type solid)
		)
		(fill yes)
		(layer "B.Cu")
		(net "GND")
	)
	(gr_poly
		(pts
			(arc
				(start 432.252374 -410.041852)
				(mid 432.002946 -410.041852)
				(end 432.252374 -410.041852)
			)
		)
		(stroke
			(width 0)
			(type solid)
		)
		(fill yes)
		(layer "B.Cu")
		(net "GND")
	)
	(gr_poly
		(pts
			(arc
				(start 432.252374 -408.840178)
				(mid 432.002946 -408.840178)
				(end 432.252374 -408.840178)
			)
		)
		(stroke
			(width 0)
			(type solid)
		)
		(fill yes)
		(layer "B.Cu")
		(net "GND")
	)
	(gr_poly
		(pts
			(arc
				(start 432.252374 -407.638504)
				(mid 432.002946 -407.638504)
				(end 432.252374 -407.638504)
			)
		)
		(stroke
			(width 0)
			(type solid)
		)
		(fill yes)
		(layer "B.Cu")
		(net "GND")
	)
	(gr_poly
		(pts
			(arc
				(start 432.252374 -406.141936)
				(mid 432.002946 -406.141936)
				(end 432.252374 -406.141936)
			)
		)
		(stroke
			(width 0)
			(type solid)
		)
		(fill yes)
		(layer "B.Cu")
		(net "GND")
	)
	(gr_poly
		(pts
			(arc
				(start 432.252374 -404.940262)
				(mid 432.002946 -404.940262)
				(end 432.252374 -404.940262)
			)
		)
		(stroke
			(width 0)
			(type solid)
		)
		(fill yes)
		(layer "B.Cu")
		(net "GND")
	)
	(gr_poly
		(pts
			(arc
				(start 432.252374 -403.738588)
				(mid 432.002946 -403.738588)
				(end 432.252374 -403.738588)
			)
		)
		(stroke
			(width 0)
			(type solid)
		)
		(fill yes)
		(layer "B.Cu")
		(net "GND")
	)
	(gr_poly
		(pts
			(arc
				(start 432.252374 -402.241766)
				(mid 432.002946 -402.241766)
				(end 432.252374 -402.241766)
			)
		)
		(stroke
			(width 0)
			(type solid)
		)
		(fill yes)
		(layer "B.Cu")
		(net "GND")
	)
	(gr_poly
		(pts
			(arc
				(start 432.252374 -401.040092)
				(mid 432.002946 -401.040092)
				(end 432.252374 -401.040092)
			)
		)
		(stroke
			(width 0)
			(type solid)
		)
		(fill yes)
		(layer "B.Cu")
		(net "GND")
	)
	(gr_poly
		(pts
			(arc
				(start 432.252374 -399.838418)
				(mid 432.002946 -399.838418)
				(end 432.252374 -399.838418)
			)
		)
		(stroke
			(width 0)
			(type solid)
		)
		(fill yes)
		(layer "B.Cu")
		(net "GND")
	)
	(gr_poly
		(pts
			(arc
				(start 432.252374 -398.34185)
				(mid 432.002946 -398.34185)
				(end 432.252374 -398.34185)
			)
		)
		(stroke
			(width 0)
			(type solid)
		)
		(fill yes)
		(layer "B.Cu")
		(net "GND")
	)
	(gr_poly
		(pts
			(arc
				(start 432.252374 -397.140176)
				(mid 432.002946 -397.140176)
				(end 432.252374 -397.140176)
			)
		)
		(stroke
			(width 0)
			(type solid)
		)
		(fill yes)
		(layer "B.Cu")
		(net "GND")
	)
	(gr_poly
		(pts
			(arc
				(start 432.252374 -395.938502)
				(mid 432.002946 -395.938502)
				(end 432.252374 -395.938502)
			)
		)
		(stroke
			(width 0)
			(type solid)
		)
		(fill yes)
		(layer "B.Cu")
		(net "GND")
	)
	(gr_poly
		(pts
			(arc
				(start 432.252374 -384.041904)
				(mid 432.002946 -384.041904)
				(end 432.252374 -384.041904)
			)
		)
		(stroke
			(width 0)
			(type solid)
		)
		(fill yes)
		(layer "B.Cu")
		(net "GND")
	)
	(gr_poly
		(pts
			(arc
				(start 432.252374 -382.84023)
				(mid 432.002946 -382.84023)
				(end 432.252374 -382.84023)
			)
		)
		(stroke
			(width 0)
			(type solid)
		)
		(fill yes)
		(layer "B.Cu")
		(net "GND")
	)
	(gr_poly
		(pts
			(arc
				(start 432.252374 -381.638556)
				(mid 432.002946 -381.638556)
				(end 432.252374 -381.638556)
			)
		)
		(stroke
			(width 0)
			(type solid)
		)
		(fill yes)
		(layer "B.Cu")
		(net "GND")
	)
	(gr_poly
		(pts
			(arc
				(start 432.252374 -380.141988)
				(mid 432.002946 -380.141988)
				(end 432.252374 -380.141988)
			)
		)
		(stroke
			(width 0)
			(type solid)
		)
		(fill yes)
		(layer "B.Cu")
		(net "GND")
	)
	(gr_poly
		(pts
			(arc
				(start 432.252374 -378.940314)
				(mid 432.002946 -378.940314)
				(end 432.252374 -378.940314)
			)
		)
		(stroke
			(width 0)
			(type solid)
		)
		(fill yes)
		(layer "B.Cu")
		(net "GND")
	)
	(gr_poly
		(pts
			(arc
				(start 432.252374 -377.73864)
				(mid 432.002946 -377.73864)
				(end 432.252374 -377.73864)
			)
		)
		(stroke
			(width 0)
			(type solid)
		)
		(fill yes)
		(layer "B.Cu")
		(net "GND")
	)
	(gr_poly
		(pts
			(arc
				(start 432.252374 -376.241818)
				(mid 432.002946 -376.241818)
				(end 432.252374 -376.241818)
			)
		)
		(stroke
			(width 0)
			(type solid)
		)
		(fill yes)
		(layer "B.Cu")
		(net "GND")
	)
	(gr_poly
		(pts
			(arc
				(start 432.252374 -375.040144)
				(mid 432.002946 -375.040144)
				(end 432.252374 -375.040144)
			)
		)
		(stroke
			(width 0)
			(type solid)
		)
		(fill yes)
		(layer "B.Cu")
		(net "GND")
	)
	(gr_poly
		(pts
			(arc
				(start 432.252374 -373.83847)
				(mid 432.002946 -373.83847)
				(end 432.252374 -373.83847)
			)
		)
		(stroke
			(width 0)
			(type solid)
		)
		(fill yes)
		(layer "B.Cu")
		(net "GND")
	)
	(gr_poly
		(pts
			(arc
				(start 432.252374 -372.341902)
				(mid 432.002946 -372.341902)
				(end 432.252374 -372.341902)
			)
		)
		(stroke
			(width 0)
			(type solid)
		)
		(fill yes)
		(layer "B.Cu")
		(net "GND")
	)
	(gr_poly
		(pts
			(arc
				(start 432.252374 -371.140228)
				(mid 432.002946 -371.140228)
				(end 432.252374 -371.140228)
			)
		)
		(stroke
			(width 0)
			(type solid)
		)
		(fill yes)
		(layer "B.Cu")
		(net "GND")
	)
	(gr_poly
		(pts
			(arc
				(start 432.252374 -369.938554)
				(mid 432.002946 -369.938554)
				(end 432.252374 -369.938554)
			)
		)
		(stroke
			(width 0)
			(type solid)
		)
		(fill yes)
		(layer "B.Cu")
		(net "GND")
	)
	(gr_poly
		(pts
			(arc
				(start 434.452522 -411.141926)
				(mid 434.203094 -411.141926)
				(end 434.452522 -411.141926)
			)
		)
		(stroke
			(width 0)
			(type solid)
		)
		(fill yes)
		(layer "B.Cu")
		(net "GND")
	)
	(gr_poly
		(pts
			(arc
				(start 434.452522 -409.940252)
				(mid 434.203094 -409.940252)
				(end 434.452522 -409.940252)
			)
		)
		(stroke
			(width 0)
			(type solid)
		)
		(fill yes)
		(layer "B.Cu")
		(net "GND")
	)
	(gr_poly
		(pts
			(arc
				(start 434.452522 -408.738578)
				(mid 434.203094 -408.738578)
				(end 434.452522 -408.738578)
			)
		)
		(stroke
			(width 0)
			(type solid)
		)
		(fill yes)
		(layer "B.Cu")
		(net "GND")
	)
	(gr_poly
		(pts
			(arc
				(start 434.452522 -407.24201)
				(mid 434.203094 -407.24201)
				(end 434.452522 -407.24201)
			)
		)
		(stroke
			(width 0)
			(type solid)
		)
		(fill yes)
		(layer "B.Cu")
		(net "GND")
	)
	(gr_poly
		(pts
			(arc
				(start 434.452522 -406.040336)
				(mid 434.203094 -406.040336)
				(end 434.452522 -406.040336)
			)
		)
		(stroke
			(width 0)
			(type solid)
		)
		(fill yes)
		(layer "B.Cu")
		(net "GND")
	)
	(gr_poly
		(pts
			(arc
				(start 434.452522 -404.838662)
				(mid 434.203094 -404.838662)
				(end 434.452522 -404.838662)
			)
		)
		(stroke
			(width 0)
			(type solid)
		)
		(fill yes)
		(layer "B.Cu")
		(net "GND")
	)
	(gr_poly
		(pts
			(arc
				(start 434.452522 -403.34184)
				(mid 434.203094 -403.34184)
				(end 434.452522 -403.34184)
			)
		)
		(stroke
			(width 0)
			(type solid)
		)
		(fill yes)
		(layer "B.Cu")
		(net "GND")
	)
	(gr_poly
		(pts
			(arc
				(start 434.452522 -402.140166)
				(mid 434.203094 -402.140166)
				(end 434.452522 -402.140166)
			)
		)
		(stroke
			(width 0)
			(type solid)
		)
		(fill yes)
		(layer "B.Cu")
		(net "GND")
	)
	(gr_poly
		(pts
			(arc
				(start 434.452522 -400.938492)
				(mid 434.203094 -400.938492)
				(end 434.452522 -400.938492)
			)
		)
		(stroke
			(width 0)
			(type solid)
		)
		(fill yes)
		(layer "B.Cu")
		(net "GND")
	)
	(gr_poly
		(pts
			(arc
				(start 434.452522 -399.441924)
				(mid 434.203094 -399.441924)
				(end 434.452522 -399.441924)
			)
		)
		(stroke
			(width 0)
			(type solid)
		)
		(fill yes)
		(layer "B.Cu")
		(net "GND")
	)
	(gr_poly
		(pts
			(arc
				(start 434.452522 -398.24025)
				(mid 434.203094 -398.24025)
				(end 434.452522 -398.24025)
			)
		)
		(stroke
			(width 0)
			(type solid)
		)
		(fill yes)
		(layer "B.Cu")
		(net "GND")
	)
	(gr_poly
		(pts
			(arc
				(start 434.452522 -397.038576)
				(mid 434.203094 -397.038576)
				(end 434.452522 -397.038576)
			)
		)
		(stroke
			(width 0)
			(type solid)
		)
		(fill yes)
		(layer "B.Cu")
		(net "GND")
	)
	(gr_poly
		(pts
			(arc
				(start 434.452522 -385.141978)
				(mid 434.203094 -385.141978)
				(end 434.452522 -385.141978)
			)
		)
		(stroke
			(width 0)
			(type solid)
		)
		(fill yes)
		(layer "B.Cu")
		(net "GND")
	)
	(gr_poly
		(pts
			(arc
				(start 434.452522 -383.940304)
				(mid 434.203094 -383.940304)
				(end 434.452522 -383.940304)
			)
		)
		(stroke
			(width 0)
			(type solid)
		)
		(fill yes)
		(layer "B.Cu")
		(net "GND")
	)
	(gr_poly
		(pts
			(arc
				(start 434.452522 -382.73863)
				(mid 434.203094 -382.73863)
				(end 434.452522 -382.73863)
			)
		)
		(stroke
			(width 0)
			(type solid)
		)
		(fill yes)
		(layer "B.Cu")
		(net "GND")
	)
	(gr_poly
		(pts
			(arc
				(start 434.452522 -381.242062)
				(mid 434.203094 -381.242062)
				(end 434.452522 -381.242062)
			)
		)
		(stroke
			(width 0)
			(type solid)
		)
		(fill yes)
		(layer "B.Cu")
		(net "GND")
	)
	(gr_poly
		(pts
			(arc
				(start 434.452522 -380.040388)
				(mid 434.203094 -380.040388)
				(end 434.452522 -380.040388)
			)
		)
		(stroke
			(width 0)
			(type solid)
		)
		(fill yes)
		(layer "B.Cu")
		(net "GND")
	)
	(gr_poly
		(pts
			(arc
				(start 434.452522 -378.838714)
				(mid 434.203094 -378.838714)
				(end 434.452522 -378.838714)
			)
		)
		(stroke
			(width 0)
			(type solid)
		)
		(fill yes)
		(layer "B.Cu")
		(net "GND")
	)
	(gr_poly
		(pts
			(arc
				(start 434.452522 -377.341892)
				(mid 434.203094 -377.341892)
				(end 434.452522 -377.341892)
			)
		)
		(stroke
			(width 0)
			(type solid)
		)
		(fill yes)
		(layer "B.Cu")
		(net "GND")
	)
	(gr_poly
		(pts
			(arc
				(start 434.452522 -376.140218)
				(mid 434.203094 -376.140218)
				(end 434.452522 -376.140218)
			)
		)
		(stroke
			(width 0)
			(type solid)
		)
		(fill yes)
		(layer "B.Cu")
		(net "GND")
	)
	(gr_poly
		(pts
			(arc
				(start 434.452522 -374.938544)
				(mid 434.203094 -374.938544)
				(end 434.452522 -374.938544)
			)
		)
		(stroke
			(width 0)
			(type solid)
		)
		(fill yes)
		(layer "B.Cu")
		(net "GND")
	)
	(gr_poly
		(pts
			(arc
				(start 434.452522 -373.441976)
				(mid 434.203094 -373.441976)
				(end 434.452522 -373.441976)
			)
		)
		(stroke
			(width 0)
			(type solid)
		)
		(fill yes)
		(layer "B.Cu")
		(net "GND")
	)
	(gr_poly
		(pts
			(arc
				(start 434.452522 -372.240302)
				(mid 434.203094 -372.240302)
				(end 434.452522 -372.240302)
			)
		)
		(stroke
			(width 0)
			(type solid)
		)
		(fill yes)
		(layer "B.Cu")
		(net "GND")
	)
	(gr_poly
		(pts
			(arc
				(start 434.452522 -371.038628)
				(mid 434.203094 -371.038628)
				(end 434.452522 -371.038628)
			)
		)
		(stroke
			(width 0)
			(type solid)
		)
		(fill yes)
		(layer "B.Cu")
		(net "GND")
	)
	(gr_poly
		(pts
			(arc
				(start 436.652416 -410.041852)
				(mid 436.402988 -410.041852)
				(end 436.652416 -410.041852)
			)
		)
		(stroke
			(width 0)
			(type solid)
		)
		(fill yes)
		(layer "B.Cu")
		(net "GND")
	)
	(gr_poly
		(pts
			(arc
				(start 436.652416 -408.840178)
				(mid 436.402988 -408.840178)
				(end 436.652416 -408.840178)
			)
		)
		(stroke
			(width 0)
			(type solid)
		)
		(fill yes)
		(layer "B.Cu")
		(net "GND")
	)
	(gr_poly
		(pts
			(arc
				(start 436.652416 -407.638504)
				(mid 436.402988 -407.638504)
				(end 436.652416 -407.638504)
			)
		)
		(stroke
			(width 0)
			(type solid)
		)
		(fill yes)
		(layer "B.Cu")
		(net "GND")
	)
	(gr_poly
		(pts
			(arc
				(start 436.652416 -406.141936)
				(mid 436.402988 -406.141936)
				(end 436.652416 -406.141936)
			)
		)
		(stroke
			(width 0)
			(type solid)
		)
		(fill yes)
		(layer "B.Cu")
		(net "GND")
	)
	(gr_poly
		(pts
			(arc
				(start 436.652416 -404.940262)
				(mid 436.402988 -404.940262)
				(end 436.652416 -404.940262)
			)
		)
		(stroke
			(width 0)
			(type solid)
		)
		(fill yes)
		(layer "B.Cu")
		(net "GND")
	)
	(gr_poly
		(pts
			(arc
				(start 436.652416 -403.738588)
				(mid 436.402988 -403.738588)
				(end 436.652416 -403.738588)
			)
		)
		(stroke
			(width 0)
			(type solid)
		)
		(fill yes)
		(layer "B.Cu")
		(net "GND")
	)
	(gr_poly
		(pts
			(arc
				(start 436.652416 -402.241766)
				(mid 436.402988 -402.241766)
				(end 436.652416 -402.241766)
			)
		)
		(stroke
			(width 0)
			(type solid)
		)
		(fill yes)
		(layer "B.Cu")
		(net "GND")
	)
	(gr_poly
		(pts
			(arc
				(start 436.652416 -401.040092)
				(mid 436.402988 -401.040092)
				(end 436.652416 -401.040092)
			)
		)
		(stroke
			(width 0)
			(type solid)
		)
		(fill yes)
		(layer "B.Cu")
		(net "GND")
	)
	(gr_poly
		(pts
			(arc
				(start 436.652416 -399.838418)
				(mid 436.402988 -399.838418)
				(end 436.652416 -399.838418)
			)
		)
		(stroke
			(width 0)
			(type solid)
		)
		(fill yes)
		(layer "B.Cu")
		(net "GND")
	)
	(gr_poly
		(pts
			(arc
				(start 436.652416 -398.34185)
				(mid 436.402988 -398.34185)
				(end 436.652416 -398.34185)
			)
		)
		(stroke
			(width 0)
			(type solid)
		)
		(fill yes)
		(layer "B.Cu")
		(net "GND")
	)
	(gr_poly
		(pts
			(arc
				(start 436.652416 -397.140176)
				(mid 436.402988 -397.140176)
				(end 436.652416 -397.140176)
			)
		)
		(stroke
			(width 0)
			(type solid)
		)
		(fill yes)
		(layer "B.Cu")
		(net "GND")
	)
	(gr_poly
		(pts
			(arc
				(start 436.652416 -395.938502)
				(mid 436.402988 -395.938502)
				(end 436.652416 -395.938502)
			)
		)
		(stroke
			(width 0)
			(type solid)
		)
		(fill yes)
		(layer "B.Cu")
		(net "GND")
	)
	(gr_poly
		(pts
			(arc
				(start 436.652416 -384.042158)
				(mid 436.402988 -384.042158)
				(end 436.652416 -384.042158)
			)
		)
		(stroke
			(width 0)
			(type solid)
		)
		(fill yes)
		(layer "B.Cu")
		(net "GND")
	)
	(gr_poly
		(pts
			(arc
				(start 436.652416 -382.840484)
				(mid 436.402988 -382.840484)
				(end 436.652416 -382.840484)
			)
		)
		(stroke
			(width 0)
			(type solid)
		)
		(fill yes)
		(layer "B.Cu")
		(net "GND")
	)
	(gr_poly
		(pts
			(arc
				(start 436.652416 -381.63881)
				(mid 436.402988 -381.63881)
				(end 436.652416 -381.63881)
			)
		)
		(stroke
			(width 0)
			(type solid)
		)
		(fill yes)
		(layer "B.Cu")
		(net "GND")
	)
	(gr_poly
		(pts
			(arc
				(start 436.652416 -380.142242)
				(mid 436.402988 -380.142242)
				(end 436.652416 -380.142242)
			)
		)
		(stroke
			(width 0)
			(type solid)
		)
		(fill yes)
		(layer "B.Cu")
		(net "GND")
	)
	(gr_poly
		(pts
			(arc
				(start 436.652416 -378.940568)
				(mid 436.402988 -378.940568)
				(end 436.652416 -378.940568)
			)
		)
		(stroke
			(width 0)
			(type solid)
		)
		(fill yes)
		(layer "B.Cu")
		(net "GND")
	)
	(gr_poly
		(pts
			(arc
				(start 436.652416 -377.738894)
				(mid 436.402988 -377.738894)
				(end 436.652416 -377.738894)
			)
		)
		(stroke
			(width 0)
			(type solid)
		)
		(fill yes)
		(layer "B.Cu")
		(net "GND")
	)
	(gr_poly
		(pts
			(arc
				(start 436.652416 -376.242072)
				(mid 436.402988 -376.242072)
				(end 436.652416 -376.242072)
			)
		)
		(stroke
			(width 0)
			(type solid)
		)
		(fill yes)
		(layer "B.Cu")
		(net "GND")
	)
	(gr_poly
		(pts
			(arc
				(start 436.652416 -375.040398)
				(mid 436.402988 -375.040398)
				(end 436.652416 -375.040398)
			)
		)
		(stroke
			(width 0)
			(type solid)
		)
		(fill yes)
		(layer "B.Cu")
		(net "GND")
	)
	(gr_poly
		(pts
			(arc
				(start 436.652416 -373.838724)
				(mid 436.402988 -373.838724)
				(end 436.652416 -373.838724)
			)
		)
		(stroke
			(width 0)
			(type solid)
		)
		(fill yes)
		(layer "B.Cu")
		(net "GND")
	)
	(gr_poly
		(pts
			(arc
				(start 436.652416 -372.342156)
				(mid 436.402988 -372.342156)
				(end 436.652416 -372.342156)
			)
		)
		(stroke
			(width 0)
			(type solid)
		)
		(fill yes)
		(layer "B.Cu")
		(net "GND")
	)
	(gr_poly
		(pts
			(arc
				(start 436.652416 -371.140482)
				(mid 436.402988 -371.140482)
				(end 436.652416 -371.140482)
			)
		)
		(stroke
			(width 0)
			(type solid)
		)
		(fill yes)
		(layer "B.Cu")
		(net "GND")
	)
	(gr_poly
		(pts
			(arc
				(start 436.652416 -369.938808)
				(mid 436.402988 -369.938808)
				(end 436.652416 -369.938808)
			)
		)
		(stroke
			(width 0)
			(type solid)
		)
		(fill yes)
		(layer "B.Cu")
		(net "GND")
	)
	(gr_poly
		(pts
			(arc
				(start 224.32264 -252.53823)
				(mid 224.042732 -252.53823)
				(end 224.32264 -252.53823)
			)
		)
		(stroke
			(width 0)
			(type solid)
		)
		(fill yes)
		(layer "B.Cu")
		(net "GND")
	)
	(gr_poly
		(pts
			(xy 237.036864 -223.746822) (xy 237.11281 -223.670876) (xy 237.212886 -223.5708) (xy 239.806988 -223.5708)
			(xy 239.832388 -223.5454) (xy 239.832388 -222.598234) (xy 239.789462 -222.555308)
			(arc
				(start 238.923068 -222.555308)
				(mid 238.906534 -222.544197)
				(end 238.887 -222.540322)
			)
			(arc
				(start 238.26724 -222.540322)
				(mid 238.247853 -222.544272)
				(end 238.231426 -222.555308)
			)
			(arc
				(start 238.20882 -222.57766)
				(mid 238.192374 -222.588586)
				(end 238.173006 -222.592392)
			)
			(xy 236.69117 -222.592392) (xy 236.595666 -222.592392) (xy 236.342428 -222.84563) (xy 236.332776 -222.855282)
			(xy 236.332776 -223.915478) (xy 236.357414 -223.940116) (xy 236.417358 -223.940116) (xy 236.84357 -223.940116)
		)
		(stroke
			(width 0)
			(type solid)
		)
		(fill yes)
		(layer "B.Cu")
		(net "P3V3_AUX")
	)
	(gr_poly
		(pts
			(xy 333.707232 -323.047614) (xy 348.086934 -323.047614) (xy 349.437706 -323.047614) (xy 349.719138 -322.766182)
			(xy 349.719138 -320.406522) (xy 349.146368 -319.833752) (xy 349.146368 -319.304924) (xy 348.85503 -319.013586)
			(xy 348.85503 -316.097666) (xy 349.719138 -315.233558) (xy 349.719138 -308.74335) (xy 349.669354 -308.693566)
			(xy 349.273114 -308.693566) (xy 348.873826 -308.693566) (xy 346.107258 -308.693566) (xy 346.049092 -308.751732)
			(xy 346.049092 -318.744092) (xy 345.682316 -319.110868) (xy 344.366088 -319.110868) (xy 333.023718 -319.110868)
			(xy 332.07071 -319.110868) (xy 331.911706 -319.269872) (xy 331.911706 -322.136262) (xy 331.911706 -322.851272)
			(xy 331.911706 -323.379338) (xy 332.169262 -323.636894) (xy 333.117952 -323.636894)
		)
		(stroke
			(width 0)
			(type solid)
		)
		(fill yes)
		(layer "B.Cu")
		(net "P0V8_SERDES_VDDA_PEX2")
	)
	(gr_poly
		(pts
			(arc
				(start 334.42021 -82.282284)
				(mid 334.439733 -82.278383)
				(end 334.456278 -82.267298)
			)
			(arc
				(start 334.51673 -82.206846)
				(mid 334.527841 -82.190312)
				(end 334.531716 -82.170778)
			)
			(arc
				(start 334.531716 -80.40497)
				(mid 334.527815 -80.385447)
				(end 334.51673 -80.368902)
			)
			(arc
				(start 334.448658 -80.30083)
				(mid 334.432124 -80.289719)
				(end 334.41259 -80.285844)
			)
			(arc
				(start 333.101696 -80.285844)
				(mid 333.082173 -80.289745)
				(end 333.065628 -80.30083)
			)
			(xy 332.999842 -80.366616)
			(arc
				(start 332.999842 -82.231484)
				(mid 333.014721 -82.267405)
				(end 333.050642 -82.282284)
			)
		)
		(stroke
			(width 0)
			(type solid)
		)
		(fill yes)
		(layer "B.Cu")
		(net "GND")
	)
	(gr_poly
		(pts
			(xy 19.492214 -174.010828) (xy 19.492214 -173.85792) (xy 19.492214 -173.092364) (xy 19.492214 -173.077378)
			(xy 19.746214 -172.823378) (xy 19.992594 -172.576998) (xy 20.35175 -172.217842) (xy 21.642324 -172.217842)
			(xy 22.00148 -172.576998) (xy 23.48611 -172.576998) (xy 23.755096 -172.308012) (xy 23.755096 -171.600368)
			(xy 23.755096 -169.523918) (xy 23.625556 -169.394378) (xy 22.609556 -169.394378) (xy 22.355556 -169.648378)
			(xy 22.355556 -169.961814) (xy 21.565108 -170.752262) (xy 21.26615 -171.05122) (xy 20.325842 -171.05122)
			(xy 18.953734 -171.05122) (xy 18.285714 -171.05122) (xy 17.961864 -171.37507) (xy 17.961864 -172.802804)
			(xy 17.961864 -173.895258) (xy 17.961864 -174.058072) (xy 18.048986 -174.145194) (xy 19.357848 -174.145194)
		)
		(stroke
			(width 0)
			(type solid)
		)
		(fill yes)
		(layer "B.Cu")
		(net "GND")
	)
	(gr_poly
		(pts
			(arc
				(start 37.877496 -265.804904)
				(mid 37.577776 -265.804904)
				(end 37.877496 -265.804904)
			)
		)
		(stroke
			(width 0)
			(type solid)
		)
		(fill yes)
		(layer "B.Cu")
		(net "GND")
	)
	(gr_poly
		(pts
			(arc
				(start 39.650162 -270.547592)
				(mid 39.350442 -270.547592)
				(end 39.650162 -270.547592)
			)
		)
		(stroke
			(width 0)
			(type solid)
		)
		(fill yes)
		(layer "B.Cu")
		(net "GND")
	)
	(gr_poly
		(pts
			(arc
				(start 41.812972 -264.532872)
				(mid 41.513252 -264.532872)
				(end 41.812972 -264.532872)
			)
		)
		(stroke
			(width 0)
			(type solid)
		)
		(fill yes)
		(layer "B.Cu")
		(net "GND")
	)
	(gr_poly
		(pts
			(arc
				(start 67.860418 -303.402238)
				(mid 67.879941 -303.398337)
				(end 67.896486 -303.387252)
			)
			(arc
				(start 68.120514 -303.163224)
				(mid 68.131625 -303.14669)
				(end 68.1355 -303.127156)
			)
			(arc
				(start 68.1355 -302.61052)
				(mid 68.131599 -302.590997)
				(end 68.120514 -302.574452)
			)
			(arc
				(start 68.096892 -302.55083)
				(mid 68.080358 -302.539719)
				(end 68.060824 -302.535844)
			)
			(xy 50.2158 -302.535844) (xy 50.1396 -302.612044) (xy 50.1396 -303.313592) (xy 50.1904 -303.364392)
			(arc
				(start 67.744848 -303.364392)
				(mid 67.764205 -303.368225)
				(end 67.780662 -303.379124)
			)
			(arc
				(start 67.789044 -303.387252)
				(mid 67.805461 -303.398314)
				(end 67.824858 -303.402238)
			)
		)
		(stroke
			(width 0)
			(type solid)
		)
		(fill yes)
		(layer "B.Cu")
		(net "P1V25_PEX0")
	)
	(gr_poly
		(pts
			(arc
				(start 122.563382 -234.856782)
				(mid 122.263662 -234.856782)
				(end 122.563382 -234.856782)
			)
		)
		(stroke
			(width 0)
			(type solid)
		)
		(fill yes)
		(layer "B.Cu")
		(net "GND")
	)
	(gr_poly
		(pts
			(arc
				(start 124.200412 -238.481362)
				(mid 123.900692 -238.481362)
				(end 124.200412 -238.481362)
			)
		)
		(stroke
			(width 0)
			(type solid)
		)
		(fill yes)
		(layer "B.Cu")
		(net "GND")
	)
	(gr_poly
		(pts
			(arc
				(start 124.64288 -251.338334)
				(mid 124.349764 -251.338334)
				(end 124.64288 -251.338334)
			)
		)
		(stroke
			(width 0)
			(type solid)
		)
		(fill yes)
		(layer "B.Cu")
		(net "GND")
	)
	(gr_poly
		(pts
			(arc
				(start 125.381512 -247.923812)
				(mid 125.088396 -247.923812)
				(end 125.381512 -247.923812)
			)
		)
		(stroke
			(width 0)
			(type solid)
		)
		(fill yes)
		(layer "B.Cu")
		(net "GND")
	)
	(gr_poly
		(pts
			(arc
				(start 132.177028 -261.942834)
				(mid 131.877308 -261.942834)
				(end 132.177028 -261.942834)
			)
		)
		(stroke
			(width 0)
			(type solid)
		)
		(fill yes)
		(layer "B.Cu")
		(net "GND")
	)
	(gr_poly
		(pts
			(arc
				(start 134.095744 -231.510332)
				(mid 133.796024 -231.510332)
				(end 134.095744 -231.510332)
			)
		)
		(stroke
			(width 0)
			(type solid)
		)
		(fill yes)
		(layer "B.Cu")
		(net "GND")
	)
	(gr_poly
		(pts
			(arc
				(start 147.279614 -229.454456)
				(mid 146.979894 -229.454456)
				(end 147.279614 -229.454456)
			)
		)
		(stroke
			(width 0)
			(type solid)
		)
		(fill yes)
		(layer "B.Cu")
		(net "GND")
	)
	(gr_poly
		(pts
			(arc
				(start 148.157184 -230.875586)
				(mid 147.857464 -230.875586)
				(end 148.157184 -230.875586)
			)
		)
		(stroke
			(width 0)
			(type solid)
		)
		(fill yes)
		(layer "B.Cu")
		(net "GND")
	)
	(gr_poly
		(pts
			(arc
				(start 150.491952 -262.892794)
				(mid 150.192232 -262.892794)
				(end 150.491952 -262.892794)
			)
		)
		(stroke
			(width 0)
			(type solid)
		)
		(fill yes)
		(layer "B.Cu")
		(net "GND")
	)
	(gr_poly
		(pts
			(arc
				(start 151.820626 -232.000044)
				(mid 151.520906 -232.000044)
				(end 151.820626 -232.000044)
			)
		)
		(stroke
			(width 0)
			(type solid)
		)
		(fill yes)
		(layer "B.Cu")
		(net "GND")
	)
	(gr_poly
		(pts
			(arc
				(start 153.66873 -262.85698)
				(mid 153.36901 -262.85698)
				(end 153.66873 -262.85698)
			)
		)
		(stroke
			(width 0)
			(type solid)
		)
		(fill yes)
		(layer "B.Cu")
		(net "GND")
	)
	(gr_poly
		(pts
			(arc
				(start 157.397704 -268.339062)
				(mid 157.097984 -268.339062)
				(end 157.397704 -268.339062)
			)
		)
		(stroke
			(width 0)
			(type solid)
		)
		(fill yes)
		(layer "B.Cu")
		(net "GND")
	)
	(gr_poly
		(pts
			(arc
				(start 157.668214 -264.252202)
				(mid 157.368494 -264.252202)
				(end 157.668214 -264.252202)
			)
		)
		(stroke
			(width 0)
			(type solid)
		)
		(fill yes)
		(layer "B.Cu")
		(net "GND")
	)
	(gr_poly
		(pts
			(arc
				(start 157.81147 -265.88339)
				(mid 157.51175 -265.88339)
				(end 157.81147 -265.88339)
			)
		)
		(stroke
			(width 0)
			(type solid)
		)
		(fill yes)
		(layer "B.Cu")
		(net "GND")
	)
	(gr_poly
		(pts
			(arc
				(start 183.124602 -238.83874)
				(mid 182.824882 -238.83874)
				(end 183.124602 -238.83874)
			)
		)
		(stroke
			(width 0)
			(type solid)
		)
		(fill yes)
		(layer "B.Cu")
		(net "GND")
	)
	(gr_poly
		(pts
			(arc
				(start 184.184798 -243.404898)
				(mid 183.885078 -243.404898)
				(end 184.184798 -243.404898)
			)
		)
		(stroke
			(width 0)
			(type solid)
		)
		(fill yes)
		(layer "B.Cu")
		(net "GND")
	)
	(gr_poly
		(pts
			(arc
				(start 208.209896 -219.356178)
				(mid 207.910176 -219.356178)
				(end 208.209896 -219.356178)
			)
		)
		(stroke
			(width 0)
			(type solid)
		)
		(fill yes)
		(layer "B.Cu")
		(net "GND")
	)
	(gr_poly
		(pts
			(arc
				(start 208.428082 -191.543686)
				(mid 208.128362 -191.543686)
				(end 208.428082 -191.543686)
			)
		)
		(stroke
			(width 0)
			(type solid)
		)
		(fill yes)
		(layer "B.Cu")
		(net "GND")
	)
	(gr_poly
		(pts
			(arc
				(start 210.156298 -224.474024)
				(mid 209.856578 -224.474024)
				(end 210.156298 -224.474024)
			)
		)
		(stroke
			(width 0)
			(type solid)
		)
		(fill yes)
		(layer "B.Cu")
		(net "GND")
	)
	(gr_poly
		(pts
			(arc
				(start 210.71586 -216.408)
				(mid 210.41614 -216.408)
				(end 210.71586 -216.408)
			)
		)
		(stroke
			(width 0)
			(type solid)
		)
		(fill yes)
		(layer "B.Cu")
		(net "GND")
	)
	(gr_poly
		(pts
			(arc
				(start 221.972632 -189.127638)
				(mid 221.672912 -189.127638)
				(end 221.972632 -189.127638)
			)
		)
		(stroke
			(width 0)
			(type solid)
		)
		(fill yes)
		(layer "B.Cu")
		(net "GND")
	)
	(gr_poly
		(pts
			(arc
				(start 225.976942 -198.214234)
				(mid 225.677222 -198.214234)
				(end 225.976942 -198.214234)
			)
		)
		(stroke
			(width 0)
			(type solid)
		)
		(fill yes)
		(layer "B.Cu")
		(net "GND")
	)
	(gr_poly
		(pts
			(arc
				(start 239.125252 -332.785974)
				(mid 238.825532 -332.785974)
				(end 239.125252 -332.785974)
			)
		)
		(stroke
			(width 0)
			(type solid)
		)
		(fill yes)
		(layer "B.Cu")
		(net "GND")
	)
	(gr_poly
		(pts
			(arc
				(start 240.331752 -208.70037)
				(mid 240.367673 -208.685491)
				(end 240.382552 -208.64957)
			)
			(arc
				(start 240.382552 -207.70596)
				(mid 240.367673 -207.670039)
				(end 240.331752 -207.65516)
			)
			(arc
				(start 238.304324 -207.65516)
				(mid 238.284801 -207.659061)
				(end 238.268256 -207.670146)
			)
			(arc
				(start 238.136938 -207.801464)
				(mid 238.125827 -207.817998)
				(end 238.121952 -207.837532)
			)
			(arc
				(start 238.121952 -208.458308)
				(mid 238.125853 -208.477831)
				(end 238.136938 -208.494376)
			)
			(arc
				(start 238.327946 -208.685384)
				(mid 238.34448 -208.696495)
				(end 238.364014 -208.70037)
			)
		)
		(stroke
			(width 0)
			(type solid)
		)
		(fill yes)
		(layer "B.Cu")
		(net "P3V3_AUX")
	)
	(gr_poly
		(pts
			(arc
				(start 246.989092 -216.215468)
				(mid 246.689372 -216.215468)
				(end 246.989092 -216.215468)
			)
		)
		(stroke
			(width 0)
			(type solid)
		)
		(fill yes)
		(layer "B.Cu")
		(net "GND")
	)
	(gr_poly
		(pts
			(arc
				(start 248.746518 -326.366632)
				(mid 248.446798 -326.366632)
				(end 248.746518 -326.366632)
			)
		)
		(stroke
			(width 0)
			(type solid)
		)
		(fill yes)
		(layer "B.Cu")
		(net "GND")
	)
	(gr_poly
		(pts
			(arc
				(start 248.895362 -206.836264)
				(mid 248.595642 -206.836264)
				(end 248.895362 -206.836264)
			)
		)
		(stroke
			(width 0)
			(type solid)
		)
		(fill yes)
		(layer "B.Cu")
		(net "GND")
	)
	(gr_poly
		(pts
			(arc
				(start 250.330462 -199.488298)
				(mid 250.030742 -199.488298)
				(end 250.330462 -199.488298)
			)
		)
		(stroke
			(width 0)
			(type solid)
		)
		(fill yes)
		(layer "B.Cu")
		(net "GND")
	)
	(gr_poly
		(pts
			(arc
				(start 250.34748 -198.425816)
				(mid 250.04776 -198.425816)
				(end 250.34748 -198.425816)
			)
		)
		(stroke
			(width 0)
			(type solid)
		)
		(fill yes)
		(layer "B.Cu")
		(net "GND")
	)
	(gr_poly
		(pts
			(arc
				(start 251.185426 -198.48703)
				(mid 250.885706 -198.48703)
				(end 251.185426 -198.48703)
			)
		)
		(stroke
			(width 0)
			(type solid)
		)
		(fill yes)
		(layer "B.Cu")
		(net "GND")
	)
	(gr_poly
		(pts
			(arc
				(start 251.31014 -218.161362)
				(mid 251.01042 -218.161362)
				(end 251.31014 -218.161362)
			)
		)
		(stroke
			(width 0)
			(type solid)
		)
		(fill yes)
		(layer "B.Cu")
		(net "GND")
	)
	(gr_poly
		(pts
			(arc
				(start 254.10541 -208.149952)
				(mid 253.80569 -208.149952)
				(end 254.10541 -208.149952)
			)
		)
		(stroke
			(width 0)
			(type solid)
		)
		(fill yes)
		(layer "B.Cu")
		(net "GND")
	)
	(gr_poly
		(pts
			(arc
				(start 257.854958 -203.908152)
				(mid 257.555238 -203.908152)
				(end 257.854958 -203.908152)
			)
		)
		(stroke
			(width 0)
			(type solid)
		)
		(fill yes)
		(layer "B.Cu")
		(net "GND")
	)
	(gr_poly
		(pts
			(arc
				(start 258.16306 -205.11389)
				(mid 257.86334 -205.11389)
				(end 258.16306 -205.11389)
			)
		)
		(stroke
			(width 0)
			(type solid)
		)
		(fill yes)
		(layer "B.Cu")
		(net "GND")
	)
	(gr_poly
		(pts
			(arc
				(start 258.733036 -201.572368)
				(mid 258.433316 -201.572368)
				(end 258.733036 -201.572368)
			)
		)
		(stroke
			(width 0)
			(type solid)
		)
		(fill yes)
		(layer "B.Cu")
		(net "GND")
	)
	(gr_poly
		(pts
			(arc
				(start 259.07111 -198.896224)
				(mid 258.77139 -198.896224)
				(end 259.07111 -198.896224)
			)
		)
		(stroke
			(width 0)
			(type solid)
		)
		(fill yes)
		(layer "B.Cu")
		(net "GND")
	)
	(gr_poly
		(pts
			(arc
				(start 260.718046 -203.77785)
				(mid 260.418326 -203.77785)
				(end 260.718046 -203.77785)
			)
		)
		(stroke
			(width 0)
			(type solid)
		)
		(fill yes)
		(layer "B.Cu")
		(net "GND")
	)
	(gr_poly
		(pts
			(arc
				(start 261.30123 -223.370902)
				(mid 261.00151 -223.370902)
				(end 261.30123 -223.370902)
			)
		)
		(stroke
			(width 0)
			(type solid)
		)
		(fill yes)
		(layer "B.Cu")
		(net "GND")
	)
	(gr_poly
		(pts
			(arc
				(start 265.04138 -201.910696)
				(mid 264.74166 -201.910696)
				(end 265.04138 -201.910696)
			)
		)
		(stroke
			(width 0)
			(type solid)
		)
		(fill yes)
		(layer "B.Cu")
		(net "GND")
	)
	(gr_poly
		(pts
			(arc
				(start 265.212322 -262.987536)
				(mid 264.912602 -262.987536)
				(end 265.212322 -262.987536)
			)
		)
		(stroke
			(width 0)
			(type solid)
		)
		(fill yes)
		(layer "B.Cu")
		(net "GND")
	)
	(gr_poly
		(pts
			(arc
				(start 265.768836 -203.41209)
				(mid 265.469116 -203.41209)
				(end 265.768836 -203.41209)
			)
		)
		(stroke
			(width 0)
			(type solid)
		)
		(fill yes)
		(layer "B.Cu")
		(net "GND")
	)
	(gr_poly
		(pts
			(arc
				(start 268.871954 -236.707426)
				(mid 268.572234 -236.707426)
				(end 268.871954 -236.707426)
			)
		)
		(stroke
			(width 0)
			(type solid)
		)
		(fill yes)
		(layer "B.Cu")
		(net "GND")
	)
	(gr_poly
		(pts
			(arc
				(start 269.433548 -266.822174)
				(mid 269.133828 -266.822174)
				(end 269.433548 -266.822174)
			)
		)
		(stroke
			(width 0)
			(type solid)
		)
		(fill yes)
		(layer "B.Cu")
		(net "GND")
	)
	(gr_poly
		(pts
			(arc
				(start 271.150842 -264.304018)
				(mid 270.851122 -264.304018)
				(end 271.150842 -264.304018)
			)
		)
		(stroke
			(width 0)
			(type solid)
		)
		(fill yes)
		(layer "B.Cu")
		(net "GND")
	)
	(gr_poly
		(pts
			(arc
				(start 272.127472 -257.112008)
				(mid 271.827752 -257.112008)
				(end 272.127472 -257.112008)
			)
		)
		(stroke
			(width 0)
			(type solid)
		)
		(fill yes)
		(layer "B.Cu")
		(net "GND")
	)
	(gr_poly
		(pts
			(arc
				(start 292.155118 -206.584042)
				(mid 291.855398 -206.584042)
				(end 292.155118 -206.584042)
			)
		)
		(stroke
			(width 0)
			(type solid)
		)
		(fill yes)
		(layer "B.Cu")
		(net "GND")
	)
	(gr_poly
		(pts
			(arc
				(start 292.8874 -214.539068)
				(mid 292.58768 -214.539068)
				(end 292.8874 -214.539068)
			)
		)
		(stroke
			(width 0)
			(type solid)
		)
		(fill yes)
		(layer "B.Cu")
		(net "GND")
	)
	(gr_poly
		(pts
			(arc
				(start 294.920924 -203.4286)
				(mid 294.621204 -203.4286)
				(end 294.920924 -203.4286)
			)
		)
		(stroke
			(width 0)
			(type solid)
		)
		(fill yes)
		(layer "B.Cu")
		(net "GND")
	)
	(gr_poly
		(pts
			(arc
				(start 299.30471 -227.089462)
				(mid 299.00499 -227.089462)
				(end 299.30471 -227.089462)
			)
		)
		(stroke
			(width 0)
			(type solid)
		)
		(fill yes)
		(layer "B.Cu")
		(net "GND")
	)
	(gr_poly
		(pts
			(arc
				(start 299.48378 -232.46588)
				(mid 299.18406 -232.46588)
				(end 299.48378 -232.46588)
			)
		)
		(stroke
			(width 0)
			(type solid)
		)
		(fill yes)
		(layer "B.Cu")
		(net "GND")
	)
	(gr_poly
		(pts
			(arc
				(start 301.582328 -217.288364)
				(mid 301.282608 -217.288364)
				(end 301.582328 -217.288364)
			)
		)
		(stroke
			(width 0)
			(type solid)
		)
		(fill yes)
		(layer "B.Cu")
		(net "GND")
	)
	(gr_poly
		(pts
			(arc
				(start 301.826422 -215.832436)
				(mid 301.526702 -215.832436)
				(end 301.826422 -215.832436)
			)
		)
		(stroke
			(width 0)
			(type solid)
		)
		(fill yes)
		(layer "B.Cu")
		(net "GND")
	)
	(gr_poly
		(pts
			(arc
				(start 330.727558 -83.566)
				(mid 330.434442 -83.566)
				(end 330.727558 -83.566)
			)
		)
		(stroke
			(width 0)
			(type solid)
		)
		(fill yes)
		(layer "B.Cu")
		(net "GND")
	)
	(gr_poly
		(pts
			(arc
				(start 352.17608 -82.098388)
				(mid 351.882964 -82.098388)
				(end 352.17608 -82.098388)
			)
		)
		(stroke
			(width 0)
			(type solid)
		)
		(fill yes)
		(layer "B.Cu")
		(net "GND")
	)
	(gr_poly
		(pts
			(arc
				(start 359.393744 -330.96708)
				(mid 359.094024 -330.96708)
				(end 359.393744 -330.96708)
			)
		)
		(stroke
			(width 0)
			(type solid)
		)
		(fill yes)
		(layer "B.Cu")
		(net "GND")
	)
	(gr_poly
		(pts
			(arc
				(start 364.229904 -341.200486)
				(mid 363.930184 -341.200486)
				(end 364.229904 -341.200486)
			)
		)
		(stroke
			(width 0)
			(type solid)
		)
		(fill yes)
		(layer "B.Cu")
		(net "GND")
	)
	(gr_poly
		(pts
			(arc
				(start 366.236504 -339.287104)
				(mid 365.936784 -339.287104)
				(end 366.236504 -339.287104)
			)
		)
		(stroke
			(width 0)
			(type solid)
		)
		(fill yes)
		(layer "B.Cu")
		(net "GND")
	)
	(gr_poly
		(pts
			(arc
				(start 371.705886 -241.298984)
				(mid 371.406166 -241.298984)
				(end 371.705886 -241.298984)
			)
		)
		(stroke
			(width 0)
			(type solid)
		)
		(fill yes)
		(layer "B.Cu")
		(net "GND")
	)
	(gr_poly
		(pts
			(arc
				(start 377.03506 -93.603064)
				(mid 376.741944 -93.603064)
				(end 377.03506 -93.603064)
			)
		)
		(stroke
			(width 0)
			(type solid)
		)
		(fill yes)
		(layer "B.Cu")
		(net "GND")
	)
	(gr_poly
		(pts
			(arc
				(start 378.079762 -88.236298)
				(mid 377.786646 -88.236298)
				(end 378.079762 -88.236298)
			)
		)
		(stroke
			(width 0)
			(type solid)
		)
		(fill yes)
		(layer "B.Cu")
		(net "GND")
	)
	(gr_poly
		(pts
			(arc
				(start 384.69443 -241.400584)
				(mid 384.39471 -241.400584)
				(end 384.69443 -241.400584)
			)
		)
		(stroke
			(width 0)
			(type solid)
		)
		(fill yes)
		(layer "B.Cu")
		(net "GND")
	)
	(gr_poly
		(pts
			(arc
				(start 384.795776 -238.457994)
				(mid 384.496056 -238.457994)
				(end 384.795776 -238.457994)
			)
		)
		(stroke
			(width 0)
			(type solid)
		)
		(fill yes)
		(layer "B.Cu")
		(net "GND")
	)
	(gr_poly
		(pts
			(arc
				(start 395.46022 -87.791544)
				(mid 395.167104 -87.791544)
				(end 395.46022 -87.791544)
			)
		)
		(stroke
			(width 0)
			(type solid)
		)
		(fill yes)
		(layer "B.Cu")
		(net "GND")
	)
	(gr_poly
		(pts
			(arc
				(start 416.160458 -303.402238)
				(mid 416.179981 -303.398337)
				(end 416.196526 -303.387252)
			)
			(arc
				(start 416.420554 -303.163224)
				(mid 416.431665 -303.14669)
				(end 416.43554 -303.127156)
			)
			(arc
				(start 416.43554 -302.61052)
				(mid 416.431639 -302.590997)
				(end 416.420554 -302.574452)
			)
			(arc
				(start 416.396932 -302.55083)
				(mid 416.380398 -302.539719)
				(end 416.360864 -302.535844)
			)
			(xy 398.51584 -302.535844) (xy 398.43964 -302.612044) (xy 398.43964 -303.313592) (xy 398.49044 -303.364392)
			(arc
				(start 416.044888 -303.364392)
				(mid 416.064245 -303.368225)
				(end 416.080702 -303.379124)
			)
			(arc
				(start 416.089084 -303.387252)
				(mid 416.105501 -303.398314)
				(end 416.124898 -303.402238)
			)
		)
		(stroke
			(width 0)
			(type solid)
		)
		(fill yes)
		(layer "B.Cu")
		(net "P1V25_PEX3")
	)
	(gr_poly
		(pts
			(arc
				(start 91.073478 -294.50157)
				(mid 90.763598 -294.50157)
				(end 91.073478 -294.50157)
			)
		)
		(stroke
			(width 0)
			(type solid)
		)
		(fill yes)
		(layer "B.Cu")
		(net "GND")
	)
	(gr_poly
		(pts
			(arc
				(start 99.82073 -87.00897)
				(mid 99.511866 -87.00897)
				(end 99.82073 -87.00897)
			)
		)
		(stroke
			(width 0)
			(type solid)
		)
		(fill yes)
		(layer "B.Cu")
		(net "GND")
	)
	(gr_poly
		(pts
			(arc
				(start 99.82073 -85.750146)
				(mid 99.511866 -85.750146)
				(end 99.82073 -85.750146)
			)
		)
		(stroke
			(width 0)
			(type solid)
		)
		(fill yes)
		(layer "B.Cu")
		(net "GND")
	)
	(gr_poly
		(pts
			(arc
				(start 188.872876 -298.599606)
				(mid 188.892399 -298.595705)
				(end 188.908944 -298.58462)
			)
			(xy 188.91504 -298.578524)
			(arc
				(start 188.91504 -293.18077)
				(mid 188.91109 -293.161383)
				(end 188.900054 -293.144956)
			)
			(arc
				(start 188.89472 -293.139622)
				(mid 188.878186 -293.128511)
				(end 188.858652 -293.124636)
			)
			(arc
				(start 188.173614 -293.124636)
				(mid 188.154091 -293.128537)
				(end 188.137546 -293.139622)
			)
			(arc
				(start 188.11748 -293.159688)
				(mid 188.106369 -293.176222)
				(end 188.102494 -293.195756)
			)
			(arc
				(start 188.102494 -298.506134)
				(mid 188.106395 -298.525657)
				(end 188.11748 -298.542202)
			)
			(arc
				(start 188.159898 -298.58462)
				(mid 188.176432 -298.595731)
				(end 188.195966 -298.599606)
			)
		)
		(stroke
			(width 0)
			(type solid)
		)
		(fill yes)
		(layer "B.Cu")
		(net "P1V25_SERDES_VDDPLL_PEX1")
	)
	(gr_poly
		(pts
			(arc
				(start 207.173576 -294.50157)
				(mid 206.863696 -294.50157)
				(end 207.173576 -294.50157)
			)
		)
		(stroke
			(width 0)
			(type solid)
		)
		(fill yes)
		(layer "B.Cu")
		(net "GND")
	)
	(gr_poly
		(pts
			(arc
				(start 244.377972 -235.621322)
				(mid 244.05336 -235.621322)
				(end 244.377972 -235.621322)
			)
		)
		(stroke
			(width 0)
			(type solid)
		)
		(fill yes)
		(layer "B.Cu")
		(net "GND")
	)
	(gr_poly
		(pts
			(arc
				(start 317.32982 -260.569456)
				(mid 317.020448 -260.569456)
				(end 317.32982 -260.569456)
			)
		)
		(stroke
			(width 0)
			(type solid)
		)
		(fill yes)
		(layer "B.Cu")
		(net "GND")
	)
	(gr_poly
		(pts
			(arc
				(start 323.27342 -294.50157)
				(mid 322.96354 -294.50157)
				(end 323.27342 -294.50157)
			)
		)
		(stroke
			(width 0)
			(type solid)
		)
		(fill yes)
		(layer "B.Cu")
		(net "GND")
	)
	(gr_poly
		(pts
			(arc
				(start 439.373518 -294.50157)
				(mid 439.063638 -294.50157)
				(end 439.373518 -294.50157)
			)
		)
		(stroke
			(width 0)
			(type solid)
		)
		(fill yes)
		(layer "B.Cu")
		(net "GND")
	)
	(gr_poly
		(pts
			(arc
				(start 27.087068 -260.891528)
				(mid 27.106591 -260.887627)
				(end 27.123136 -260.876542)
			)
			(arc
				(start 27.257756 -260.741922)
				(mid 27.268867 -260.725388)
				(end 27.272742 -260.705854)
			)
			(arc
				(start 27.272742 -260.089142)
				(mid 27.268841 -260.069619)
				(end 27.257756 -260.053074)
			)
			(arc
				(start 26.370534 -259.165852)
				(mid 26.354 -259.154741)
				(end 26.334466 -259.150866)
			)
			(arc
				(start 25.27427 -259.150866)
				(mid 25.238349 -259.165745)
				(end 25.22347 -259.201666)
			)
			(arc
				(start 25.22347 -260.65226)
				(mid 25.227371 -260.671783)
				(end 25.238456 -260.688328)
			)
			(arc
				(start 25.42667 -260.876542)
				(mid 25.443204 -260.887653)
				(end 25.462738 -260.891528)
			)
		)
		(stroke
			(width 0)
			(type solid)
		)
		(fill yes)
		(layer "B.Cu")
		(net "P1V8_VDDA_PEX0")
	)
	(gr_poly
		(pts
			(arc
				(start 59.542172 -306.722018)
				(mid 59.561695 -306.718117)
				(end 59.57824 -306.707032)
			)
			(arc
				(start 60.098686 -306.186586)
				(mid 60.11522 -306.175475)
				(end 60.134754 -306.1716)
			)
			(xy 68.781168 -306.1716) (xy 68.9102 -306.1716) (xy 68.961 -306.1208) (xy 68.961 -305.562) (xy 68.916296 -305.517296)
			(xy 68.775326 -305.517296) (xy 68.65112 -305.517296) (xy 51.07178 -305.517296) (xy 49.489868 -305.517296)
			(xy 49.468024 -305.53914) (xy 49.468024 -306.058316) (xy 49.566322 -306.156614) (xy 51.058826 -306.156614)
			(xy 51.326288 -306.156614)
			(arc
				(start 58.223404 -306.156614)
				(mid 58.242927 -306.160515)
				(end 58.259472 -306.1716)
			)
			(arc
				(start 58.794904 -306.707032)
				(mid 58.811438 -306.718143)
				(end 58.830972 -306.722018)
			)
		)
		(stroke
			(width 0)
			(type solid)
		)
		(fill yes)
		(layer "B.Cu")
		(net "GND")
	)
	(gr_poly
		(pts
			(arc
				(start 67.936618 -289.254438)
				(mid 67.956141 -289.250537)
				(end 67.972686 -289.239452)
			)
			(arc
				(start 68.044314 -289.167824)
				(mid 68.055425 -289.15129)
				(end 68.0593 -289.131756)
			)
			(arc
				(start 68.0593 -288.53892)
				(mid 68.055399 -288.519397)
				(end 68.044314 -288.502852)
			)
			(arc
				(start 68.02374 -288.482278)
				(mid 68.007323 -288.471216)
				(end 67.987926 -288.467292)
			)
			(arc
				(start 50.4063 -288.467292)
				(mid 50.370379 -288.482171)
				(end 50.3555 -288.518092)
			)
			(arc
				(start 50.3555 -289.131756)
				(mid 50.359401 -289.151279)
				(end 50.370486 -289.167824)
			)
			(arc
				(start 50.442114 -289.239452)
				(mid 50.458648 -289.250563)
				(end 50.478182 -289.254438)
			)
		)
		(stroke
			(width 0)
			(type solid)
		)
		(fill yes)
		(layer "B.Cu")
		(net "P1V25_PEX0")
	)
	(gr_poly
		(pts
			(xy 73.8886 -299.1358) (xy 74.3204 -299.1358) (xy 74.6252 -298.831) (xy 74.6252 -298.1198) (xy 74.4982 -297.9928)
			(xy 73.974198 -297.9928) (xy 73.669398 -297.688)
			(arc
				(start 73.669398 -292.456616)
				(mid 73.665497 -292.437093)
				(end 73.654412 -292.420548)
			)
			(arc
				(start 73.615296 -292.381432)
				(mid 73.598762 -292.370321)
				(end 73.579228 -292.366446)
			)
			(arc
				(start 73.35139 -292.366446)
				(mid 73.331867 -292.370347)
				(end 73.315322 -292.381432)
			)
			(xy 73.279254 -292.4175) (xy 73.278746 -292.418008) (xy 73.267824 -292.42893) (xy 73.267316 -292.429438)
			(xy 73.069196 -292.627558) (xy 73.069196 -299.247814)
			(arc
				(start 73.21296 -299.391578)
				(mid 73.229494 -299.402689)
				(end 73.249028 -299.406564)
			)
			(xy 73.617836 -299.406564)
		)
		(stroke
			(width 0)
			(type solid)
		)
		(fill yes)
		(layer "B.Cu")
		(net "GND")
	)
	(gr_poly
		(pts
			(arc
				(start 159.044386 -287.488884)
				(mid 159.063909 -287.484983)
				(end 159.080454 -287.473898)
			)
			(arc
				(start 159.123634 -287.430718)
				(mid 159.13456 -287.414272)
				(end 159.138366 -287.394904)
			)
			(arc
				(start 159.138366 -285.687008)
				(mid 159.123487 -285.651087)
				(end 159.087566 -285.636208)
			)
			(arc
				(start 158.251906 -285.636208)
				(mid 158.232383 -285.640109)
				(end 158.215838 -285.651194)
			)
			(arc
				(start 157.935676 -285.931356)
				(mid 157.924565 -285.94789)
				(end 157.92069 -285.967424)
			)
			(arc
				(start 157.92069 -287.361122)
				(mid 157.924591 -287.380645)
				(end 157.935676 -287.39719)
			)
			(arc
				(start 158.012384 -287.473898)
				(mid 158.028918 -287.485009)
				(end 158.048452 -287.488884)
			)
		)
		(stroke
			(width 0)
			(type solid)
		)
		(fill yes)
		(layer "B.Cu")
		(net "GND")
	)
	(gr_poly
		(pts
			(arc
				(start 184.036716 -289.254438)
				(mid 184.056239 -289.250537)
				(end 184.072784 -289.239452)
			)
			(arc
				(start 184.144412 -289.167824)
				(mid 184.155523 -289.15129)
				(end 184.159398 -289.131756)
			)
			(arc
				(start 184.159398 -288.53892)
				(mid 184.155497 -288.519397)
				(end 184.144412 -288.502852)
			)
			(arc
				(start 184.123838 -288.482278)
				(mid 184.107421 -288.471216)
				(end 184.088024 -288.467292)
			)
			(arc
				(start 166.506398 -288.467292)
				(mid 166.470477 -288.482171)
				(end 166.455598 -288.518092)
			)
			(arc
				(start 166.455598 -289.131756)
				(mid 166.459499 -289.151279)
				(end 166.470584 -289.167824)
			)
			(arc
				(start 166.542212 -289.239452)
				(mid 166.558746 -289.250563)
				(end 166.57828 -289.254438)
			)
		)
		(stroke
			(width 0)
			(type solid)
		)
		(fill yes)
		(layer "B.Cu")
		(net "P1V25_PEX1")
	)
	(gr_poly
		(pts
			(arc
				(start 247.400318 -87.634572)
				(mid 247.055386 -87.634572)
				(end 247.400318 -87.634572)
			)
		)
		(stroke
			(width 0)
			(type solid)
		)
		(fill yes)
		(layer "B.Cu")
		(net "GND")
	)
	(gr_poly
		(pts
			(arc
				(start 300.034452 -300.39691)
				(mid 300.053975 -300.393009)
				(end 300.07052 -300.381924)
			)
			(arc
				(start 300.117256 -300.335188)
				(mid 300.128367 -300.318654)
				(end 300.132242 -300.29912)
			)
			(arc
				(start 300.132242 -300.111668)
				(mid 300.128341 -300.092145)
				(end 300.117256 -300.0756)
			)
			(xy 299.875448 -299.833792) (xy 299.868336 -299.826426) (xy 299.84954 -299.818806)
			(arc
				(start 282.87472 -299.818806)
				(mid 282.855197 -299.822707)
				(end 282.838652 -299.833792)
			)
			(xy 282.658312 -300.014132) (xy 282.650946 -300.021244) (xy 282.643326 -300.04004)
			(arc
				(start 282.643326 -300.290738)
				(mid 282.647227 -300.310261)
				(end 282.658312 -300.326806)
			)
			(arc
				(start 282.71343 -300.381924)
				(mid 282.729964 -300.393035)
				(end 282.749498 -300.39691)
			)
		)
		(stroke
			(width 0)
			(type solid)
		)
		(fill yes)
		(layer "B.Cu")
		(net "GND")
	)
	(gr_poly
		(pts
			(arc
				(start 300.13656 -289.254438)
				(mid 300.156083 -289.250537)
				(end 300.172628 -289.239452)
			)
			(arc
				(start 300.244256 -289.167824)
				(mid 300.255367 -289.15129)
				(end 300.259242 -289.131756)
			)
			(arc
				(start 300.259242 -288.53892)
				(mid 300.255341 -288.519397)
				(end 300.244256 -288.502852)
			)
			(arc
				(start 300.223682 -288.482278)
				(mid 300.207265 -288.471216)
				(end 300.187868 -288.467292)
			)
			(arc
				(start 282.606242 -288.467292)
				(mid 282.570321 -288.482171)
				(end 282.555442 -288.518092)
			)
			(arc
				(start 282.555442 -289.131756)
				(mid 282.559343 -289.151279)
				(end 282.570428 -289.167824)
			)
			(arc
				(start 282.642056 -289.239452)
				(mid 282.65859 -289.250563)
				(end 282.678124 -289.254438)
			)
		)
		(stroke
			(width 0)
			(type solid)
		)
		(fill yes)
		(layer "B.Cu")
		(net "P1V25_PEX2")
	)
	(gr_poly
		(pts
			(arc
				(start 356.963726 -231.367838)
				(mid 356.618286 -231.367838)
				(end 356.963726 -231.367838)
			)
		)
		(stroke
			(width 0)
			(type solid)
		)
		(fill yes)
		(layer "B.Cu")
		(net "GND")
	)
	(gr_poly
		(pts
			(arc
				(start 361.567222 -231.15651)
				(mid 361.221782 -231.15651)
				(end 361.567222 -231.15651)
			)
		)
		(stroke
			(width 0)
			(type solid)
		)
		(fill yes)
		(layer "B.Cu")
		(net "GND")
	)
	(gr_poly
		(pts
			(xy 364.380018 -321.771264) (xy 364.44047 -321.710812) (xy 367.83518 -321.710812) (xy 368.035332 -321.51066)
			(xy 368.035332 -319.269872) (xy 367.876328 -319.110868) (xy 366.92332 -319.110868) (xy 355.58095 -319.110868)
			(xy 355.378258 -318.908176) (xy 355.378258 -308.800754) (xy 355.27107 -308.693566) (xy 354.306378 -308.693566)
			(xy 351.073212 -308.693566) (xy 350.391476 -308.693566) (xy 350.260158 -308.824884) (xy 350.260158 -315.233558)
			(xy 350.803464 -315.776864) (xy 350.803464 -319.828672) (xy 350.795844 -319.836292) (xy 350.795844 -320.249296)
			(xy 350.666304 -320.378836) (xy 350.486472 -320.378836) (xy 350.260158 -320.60515) (xy 350.260158 -321.00139)
			(xy 350.301306 -321.042538) (xy 356.50932 -321.042538) (xy 357.189278 -321.722496) (xy 361.226862 -321.722496)
			(xy 361.584494 -322.080128) (xy 364.071154 -322.080128)
		)
		(stroke
			(width 0)
			(type solid)
		)
		(fill yes)
		(layer "B.Cu")
		(net "P0V8_SERDES_VDDA_PEX3")
	)
	(gr_poly
		(pts
			(arc
				(start 364.723934 -150.824184)
				(mid 364.378494 -150.824184)
				(end 364.723934 -150.824184)
			)
		)
		(stroke
			(width 0)
			(type solid)
		)
		(fill yes)
		(layer "B.Cu")
		(net "GND")
	)
	(gr_poly
		(pts
			(arc
				(start 365.472472 -220.378782)
				(mid 365.127032 -220.378782)
				(end 365.472472 -220.378782)
			)
		)
		(stroke
			(width 0)
			(type solid)
		)
		(fill yes)
		(layer "B.Cu")
		(net "GND")
	)
	(gr_poly
		(pts
			(arc
				(start 368.237008 -226.715574)
				(mid 367.891568 -226.715574)
				(end 368.237008 -226.715574)
			)
		)
		(stroke
			(width 0)
			(type solid)
		)
		(fill yes)
		(layer "B.Cu")
		(net "GND")
	)
	(gr_poly
		(pts
			(arc
				(start 371.132608 -225.04019)
				(mid 370.787168 -225.04019)
				(end 371.132608 -225.04019)
			)
		)
		(stroke
			(width 0)
			(type solid)
		)
		(fill yes)
		(layer "B.Cu")
		(net "GND")
	)
	(gr_poly
		(pts
			(arc
				(start 371.327934 -220.33865)
				(mid 370.982494 -220.33865)
				(end 371.327934 -220.33865)
			)
		)
		(stroke
			(width 0)
			(type solid)
		)
		(fill yes)
		(layer "B.Cu")
		(net "GND")
	)
	(gr_poly
		(pts
			(arc
				(start 372.556024 -248.855484)
				(mid 372.210584 -248.855484)
				(end 372.556024 -248.855484)
			)
		)
		(stroke
			(width 0)
			(type solid)
		)
		(fill yes)
		(layer "B.Cu")
		(net "GND")
	)
	(gr_poly
		(pts
			(arc
				(start 373.91213 -190.151766)
				(mid 373.56669 -190.151766)
				(end 373.91213 -190.151766)
			)
		)
		(stroke
			(width 0)
			(type solid)
		)
		(fill yes)
		(layer "B.Cu")
		(net "GND")
	)
	(gr_poly
		(pts
			(arc
				(start 374.44807 -180.353208)
				(mid 374.10263 -180.353208)
				(end 374.44807 -180.353208)
			)
		)
		(stroke
			(width 0)
			(type solid)
		)
		(fill yes)
		(layer "B.Cu")
		(net "GND")
	)
	(gr_poly
		(pts
			(arc
				(start 374.475756 -219.541598)
				(mid 374.130316 -219.541598)
				(end 374.475756 -219.541598)
			)
		)
		(stroke
			(width 0)
			(type solid)
		)
		(fill yes)
		(layer "B.Cu")
		(net "GND")
	)
	(gr_poly
		(pts
			(arc
				(start 376.462036 -231.53878)
				(mid 376.116596 -231.53878)
				(end 376.462036 -231.53878)
			)
		)
		(stroke
			(width 0)
			(type solid)
		)
		(fill yes)
		(layer "B.Cu")
		(net "GND")
	)
	(gr_poly
		(pts
			(arc
				(start 377.420124 -247.367044)
				(mid 377.074684 -247.367044)
				(end 377.420124 -247.367044)
			)
		)
		(stroke
			(width 0)
			(type solid)
		)
		(fill yes)
		(layer "B.Cu")
		(net "GND")
	)
	(gr_poly
		(pts
			(arc
				(start 378.54382 -212.59419)
				(mid 378.19838 -212.59419)
				(end 378.54382 -212.59419)
			)
		)
		(stroke
			(width 0)
			(type solid)
		)
		(fill yes)
		(layer "B.Cu")
		(net "GND")
	)
	(gr_poly
		(pts
			(arc
				(start 378.58319 -220.062044)
				(mid 378.23775 -220.062044)
				(end 378.58319 -220.062044)
			)
		)
		(stroke
			(width 0)
			(type solid)
		)
		(fill yes)
		(layer "B.Cu")
		(net "GND")
	)
	(gr_poly
		(pts
			(arc
				(start 378.902468 -201.422762)
				(mid 378.557028 -201.422762)
				(end 378.902468 -201.422762)
			)
		)
		(stroke
			(width 0)
			(type solid)
		)
		(fill yes)
		(layer "B.Cu")
		(net "GND")
	)
	(gr_poly
		(pts
			(arc
				(start 378.991876 -222.347282)
				(mid 378.646436 -222.347282)
				(end 378.991876 -222.347282)
			)
		)
		(stroke
			(width 0)
			(type solid)
		)
		(fill yes)
		(layer "B.Cu")
		(net "GND")
	)
	(gr_poly
		(pts
			(arc
				(start 379.166374 -227.29444)
				(mid 378.820934 -227.29444)
				(end 379.166374 -227.29444)
			)
		)
		(stroke
			(width 0)
			(type solid)
		)
		(fill yes)
		(layer "B.Cu")
		(net "GND")
	)
	(gr_poly
		(pts
			(arc
				(start 379.28296 -247.562116)
				(mid 378.93752 -247.562116)
				(end 379.28296 -247.562116)
			)
		)
		(stroke
			(width 0)
			(type solid)
		)
		(fill yes)
		(layer "B.Cu")
		(net "GND")
	)
	(gr_poly
		(pts
			(arc
				(start 382.502918 -237.109)
				(mid 382.522441 -237.105099)
				(end 382.538986 -237.094014)
			)
			(arc
				(start 382.763014 -236.869986)
				(mid 382.774125 -236.853452)
				(end 382.778 -236.833918)
			)
			(xy 382.778 -233.78541) (xy 382.39573 -233.40314) (xy 382.22301 -233.23042) (xy 381.9144 -232.92181)
			(xy 381.9144 -232.50779) (xy 381.56261 -232.156) (xy 381.529082 -232.156) (xy 381.492252 -232.11917)
			(xy 380.883922 -232.11917) (xy 380.544578 -232.458514) (xy 380.544578 -232.699306) (xy 380.748032 -232.90276)
			(xy 380.98857 -232.90276) (xy 381.254 -233.16819)
			(arc
				(start 381.254 -236.960918)
				(mid 381.257901 -236.980441)
				(end 381.268986 -236.996986)
			)
			(arc
				(start 381.366014 -237.094014)
				(mid 381.382548 -237.105125)
				(end 381.402082 -237.109)
			)
		)
		(stroke
			(width 0)
			(type solid)
		)
		(fill yes)
		(layer "B.Cu")
		(net "P3V3_SDB_VPHY")
	)
	(gr_poly
		(pts
			(xy 385.70154 -228.068632) (xy 385.70154 -225.132138) (xy 385.354068 -224.784666) (xy 384.458972 -224.784666)
			(arc
				(start 381.029718 -224.784666)
				(mid 381.010195 -224.788567)
				(end 380.99365 -224.799652)
			)
			(arc
				(start 380.769622 -225.02368)
				(mid 380.758511 -225.040214)
				(end 380.754636 -225.059748)
			)
			(arc
				(start 380.754636 -226.96678)
				(mid 380.758961 -226.987292)
				(end 380.771146 -227.004372)
			)
			(arc
				(start 380.771146 -227.004372)
				(mid 380.869134 -227.147945)
				(end 380.89332 -227.320094)
			)
			(xy 381.002286 -227.42906) (xy 381.002286 -227.553266) (xy 381.159766 -227.710746) (xy 381.871728 -227.710746)
			(xy 382.247648 -228.086666) (xy 384.670554 -228.086666) (xy 385.683506 -228.086666)
		)
		(stroke
			(width 0)
			(type solid)
		)
		(fill yes)
		(layer "B.Cu")
		(net "GND")
	)
	(gr_poly
		(pts
			(arc
				(start 387.260084 -248.991374)
				(mid 386.914644 -248.991374)
				(end 387.260084 -248.991374)
			)
		)
		(stroke
			(width 0)
			(type solid)
		)
		(fill yes)
		(layer "B.Cu")
		(net "GND")
	)
	(gr_poly
		(pts
			(arc
				(start 407.842212 -306.722018)
				(mid 407.861735 -306.718117)
				(end 407.87828 -306.707032)
			)
			(arc
				(start 408.398726 -306.186586)
				(mid 408.41526 -306.175475)
				(end 408.434794 -306.1716)
			)
			(xy 417.081208 -306.1716) (xy 417.21024 -306.1716) (xy 417.26104 -306.1208) (xy 417.26104 -305.562)
			(xy 417.216336 -305.517296) (xy 417.075366 -305.517296) (xy 416.95116 -305.517296) (xy 399.37182 -305.517296)
			(xy 397.789908 -305.517296) (xy 397.768064 -305.53914) (xy 397.768064 -306.058316) (xy 397.866362 -306.156614)
			(xy 399.358866 -306.156614) (xy 399.626328 -306.156614)
			(arc
				(start 406.523444 -306.156614)
				(mid 406.542967 -306.160515)
				(end 406.559512 -306.1716)
			)
			(arc
				(start 407.094944 -306.707032)
				(mid 407.111478 -306.718143)
				(end 407.131012 -306.722018)
			)
		)
		(stroke
			(width 0)
			(type solid)
		)
		(fill yes)
		(layer "B.Cu")
		(net "GND")
	)
	(gr_poly
		(pts
			(arc
				(start 416.236658 -289.254438)
				(mid 416.256181 -289.250537)
				(end 416.272726 -289.239452)
			)
			(arc
				(start 416.344354 -289.167824)
				(mid 416.355465 -289.15129)
				(end 416.35934 -289.131756)
			)
			(arc
				(start 416.35934 -288.53892)
				(mid 416.355439 -288.519397)
				(end 416.344354 -288.502852)
			)
			(arc
				(start 416.32378 -288.482278)
				(mid 416.307363 -288.471216)
				(end 416.287966 -288.467292)
			)
			(arc
				(start 398.70634 -288.467292)
				(mid 398.670419 -288.482171)
				(end 398.65554 -288.518092)
			)
			(arc
				(start 398.65554 -289.131756)
				(mid 398.659441 -289.151279)
				(end 398.670526 -289.167824)
			)
			(arc
				(start 398.742154 -289.239452)
				(mid 398.758688 -289.250563)
				(end 398.778222 -289.254438)
			)
		)
		(stroke
			(width 0)
			(type solid)
		)
		(fill yes)
		(layer "B.Cu")
		(net "P1V25_PEX3")
	)
	(gr_poly
		(pts
			(arc
				(start 421.073834 -251.669042)
				(mid 420.728394 -251.669042)
				(end 421.073834 -251.669042)
			)
		)
		(stroke
			(width 0)
			(type solid)
		)
		(fill yes)
		(layer "B.Cu")
		(net "GND")
	)
	(gr_poly
		(pts
			(arc
				(start 423.780966 -296.629328)
				(mid 423.800489 -296.625427)
				(end 423.817034 -296.614342)
			)
			(arc
				(start 423.874438 -296.556938)
				(mid 423.885549 -296.540404)
				(end 423.889424 -296.52087)
			)
			(arc
				(start 423.889424 -294.378888)
				(mid 423.885523 -294.359365)
				(end 423.874438 -294.34282)
			)
			(xy 423.777156 -294.245538) (xy 423.770044 -294.238172) (xy 423.751248 -294.230552)
			(arc
				(start 422.559988 -294.230552)
				(mid 422.540465 -294.234453)
				(end 422.52392 -294.245538)
			)
			(xy 422.450768 -294.31869) (xy 422.443402 -294.325802) (xy 422.435782 -294.344598)
			(arc
				(start 422.435782 -296.528744)
				(mid 422.439683 -296.548267)
				(end 422.450768 -296.564812)
			)
			(arc
				(start 422.500298 -296.614342)
				(mid 422.516832 -296.625453)
				(end 422.536366 -296.629328)
			)
		)
		(stroke
			(width 0)
			(type solid)
		)
		(fill yes)
		(layer "B.Cu")
		(net "GND")
	)
	(gr_poly
		(pts
			(arc
				(start 444.185294 -250.032266)
				(mid 443.839854 -250.032266)
				(end 444.185294 -250.032266)
			)
		)
		(stroke
			(width 0)
			(type solid)
		)
		(fill yes)
		(layer "B.Cu")
		(net "GND")
	)
	(gr_poly
		(pts
			(arc
				(start 242.907058 -208.840578)
				(mid 242.926249 -208.836813)
				(end 242.942618 -208.8261)
			)
			(xy 242.942872 -208.825846) (xy 243.05768 -208.711038)
			(arc
				(start 243.058188 -208.71053)
				(mid 243.06893 -208.694173)
				(end 243.072666 -208.67497)
			)
			(arc
				(start 243.072666 -204.901546)
				(mid 243.068765 -204.882023)
				(end 243.05768 -204.865478)
			)
			(xy 242.960144 -204.767942) (xy 242.953032 -204.760576) (xy 242.934236 -204.752956)
			(arc
				(start 241.58194 -204.752956)
				(mid 241.546019 -204.767835)
				(end 241.53114 -204.803756)
			)
			(arc
				(start 241.53114 -208.541874)
				(mid 241.534973 -208.561231)
				(end 241.545872 -208.577688)
			)
			(arc
				(start 241.793776 -208.825592)
				(mid 241.81031 -208.836703)
				(end 241.829844 -208.840578)
			)
		)
		(stroke
			(width 0)
			(type solid)
		)
		(fill yes)
		(layer "B.Cu")
		(net "P1V2_AUX")
	)
	(gr_poly
		(pts
			(arc
				(start 14.818614 -383.03708)
				(mid 14.837971 -383.033247)
				(end 14.854428 -383.022348)
			)
			(xy 14.859762 -383.017014) (xy 14.867636 -382.998472)
			(arc
				(start 14.867636 -381.579374)
				(mid 14.863735 -381.559851)
				(end 14.85265 -381.543306)
			)
			(arc
				(start 14.478762 -381.169418)
				(mid 14.462228 -381.158307)
				(end 14.442694 -381.154432)
			)
			(xy 14.324838 -381.154432) (xy 14.322552 -381.1524)
			(arc
				(start 12.879578 -381.1524)
				(mid 12.860221 -381.156233)
				(end 12.843764 -381.167132)
			)
			(arc
				(start 12.83335 -381.177546)
				(mid 12.822239 -381.19408)
				(end 12.818364 -381.213614)
			)
			(arc
				(start 12.818364 -381.593344)
				(mid 12.822265 -381.612867)
				(end 12.83335 -381.629412)
			)
			(arc
				(start 14.226286 -383.022348)
				(mid 14.242732 -383.033274)
				(end 14.2621 -383.03708)
			)
		)
		(stroke
			(width 0)
			(type solid)
		)
		(fill yes)
		(layer "B.Cu")
		(net "P3V3_USB_8042")
	)
	(gr_poly
		(pts
			(arc
				(start 16.950436 -392.653774)
				(mid 16.969959 -392.649873)
				(end 16.986504 -392.638788)
			)
			(arc
				(start 17.129252 -392.49604)
				(mid 17.140363 -392.479506)
				(end 17.144238 -392.459972)
			)
			(arc
				(start 17.144238 -391.466578)
				(mid 17.140337 -391.447055)
				(end 17.129252 -391.43051)
			)
			(arc
				(start 17.063466 -391.364724)
				(mid 17.046932 -391.353613)
				(end 17.027398 -391.349738)
			)
			(arc
				(start 14.021308 -391.349738)
				(mid 14.001785 -391.353639)
				(end 13.98524 -391.364724)
			)
			(arc
				(start 13.868146 -391.481818)
				(mid 13.857035 -391.498352)
				(end 13.85316 -391.517886)
			)
			(arc
				(start 13.85316 -392.45667)
				(mid 13.857061 -392.476193)
				(end 13.868146 -392.492738)
			)
			(arc
				(start 14.014196 -392.638788)
				(mid 14.03073 -392.649899)
				(end 14.050264 -392.653774)
			)
		)
		(stroke
			(width 0)
			(type solid)
		)
		(fill yes)
		(layer "B.Cu")
		(net "P3V3_USB_8042")
	)
	(gr_poly
		(pts
			(arc
				(start 42.55008 -287.18129)
				(mid 42.569603 -287.177389)
				(end 42.586148 -287.166304)
			)
			(arc
				(start 42.62501 -287.127442)
				(mid 42.636121 -287.110908)
				(end 42.639996 -287.091374)
			)
			(arc
				(start 42.639996 -285.545022)
				(mid 42.636095 -285.525499)
				(end 42.62501 -285.508954)
			)
			(arc
				(start 42.614342 -285.498286)
				(mid 42.597925 -285.487224)
				(end 42.578528 -285.4833)
			)
			(arc
				(start 40.956738 -285.4833)
				(mid 40.937351 -285.48725)
				(end 40.920924 -285.498286)
			)
			(arc
				(start 40.869362 -285.549848)
				(mid 40.858251 -285.566382)
				(end 40.854376 -285.585916)
			)
			(arc
				(start 40.854376 -286.977074)
				(mid 40.858277 -286.996597)
				(end 40.869362 -287.013142)
			)
			(arc
				(start 41.022524 -287.166304)
				(mid 41.039058 -287.177415)
				(end 41.058592 -287.18129)
			)
		)
		(stroke
			(width 0)
			(type solid)
		)
		(fill yes)
		(layer "B.Cu")
		(net "GND")
	)
	(gr_poly
		(pts
			(arc
				(start 49.709578 -304.19675)
				(mid 49.729101 -304.192849)
				(end 49.745646 -304.181764)
			)
			(arc
				(start 49.778666 -304.14849)
				(mid 49.7952 -304.137379)
				(end 49.814734 -304.133504)
			)
			(arc
				(start 67.8815 -304.133504)
				(mid 67.917421 -304.118625)
				(end 67.9323 -304.082704)
			)
			(arc
				(start 67.9323 -303.911508)
				(mid 67.928399 -303.891985)
				(end 67.917314 -303.87544)
			)
			(xy 67.675506 -303.633632) (xy 67.668394 -303.626266) (xy 67.649598 -303.618646)
			(arc
				(start 48.193452 -303.618646)
				(mid 48.173929 -303.622547)
				(end 48.157384 -303.633632)
			)
			(xy 48.12284 -303.668176) (xy 48.12284 -304.13198) (xy 48.172624 -304.181764)
			(arc
				(start 49.523142 -304.181764)
				(mid 49.539676 -304.192875)
				(end 49.55921 -304.19675)
			)
		)
		(stroke
			(width 0)
			(type solid)
		)
		(fill yes)
		(layer "B.Cu")
		(net "GND")
	)
	(gr_poly
		(pts
			(arc
				(start 67.83451 -300.39691)
				(mid 67.854033 -300.393009)
				(end 67.870578 -300.381924)
			)
			(arc
				(start 67.917314 -300.335188)
				(mid 67.928425 -300.318654)
				(end 67.9323 -300.29912)
			)
			(arc
				(start 67.9323 -300.111668)
				(mid 67.928399 -300.092145)
				(end 67.917314 -300.0756)
			)
			(arc
				(start 67.675506 -299.833792)
				(mid 67.658972 -299.822681)
				(end 67.639438 -299.818806)
			)
			(arc
				(start 50.674778 -299.818806)
				(mid 50.655255 -299.822707)
				(end 50.63871 -299.833792)
			)
			(arc
				(start 50.45837 -300.014132)
				(mid 50.447259 -300.030666)
				(end 50.443384 -300.0502)
			)
			(arc
				(start 50.443384 -300.290738)
				(mid 50.447285 -300.310261)
				(end 50.45837 -300.326806)
			)
			(arc
				(start 50.513488 -300.381924)
				(mid 50.530022 -300.393035)
				(end 50.549556 -300.39691)
			)
		)
		(stroke
			(width 0)
			(type solid)
		)
		(fill yes)
		(layer "B.Cu")
		(net "GND")
	)
	(gr_poly
		(pts
			(arc
				(start 67.885818 -288.213038)
				(mid 67.905341 -288.209137)
				(end 67.921886 -288.198052)
			)
			(arc
				(start 67.993514 -288.126424)
				(mid 68.004625 -288.10989)
				(end 68.0085 -288.090356)
			)
			(arc
				(start 68.0085 -287.77692)
				(mid 68.004599 -287.757397)
				(end 67.993514 -287.740852)
			)
			(arc
				(start 67.89674 -287.644078)
				(mid 67.880323 -287.633016)
				(end 67.860926 -287.629092)
			)
			(arc
				(start 50.503074 -287.629092)
				(mid 50.483687 -287.633042)
				(end 50.46726 -287.644078)
			)
			(arc
				(start 50.395886 -287.715452)
				(mid 50.384775 -287.731986)
				(end 50.3809 -287.75152)
			)
			(arc
				(start 50.3809 -288.115756)
				(mid 50.384801 -288.135279)
				(end 50.395886 -288.151824)
			)
			(arc
				(start 50.442114 -288.198052)
				(mid 50.458648 -288.209163)
				(end 50.478182 -288.213038)
			)
		)
		(stroke
			(width 0)
			(type solid)
		)
		(fill yes)
		(layer "B.Cu")
		(net "GND")
	)
	(gr_poly
		(pts
			(arc
				(start 75.480926 -296.629328)
				(mid 75.500449 -296.625427)
				(end 75.516994 -296.614342)
			)
			(arc
				(start 75.574398 -296.556938)
				(mid 75.585509 -296.540404)
				(end 75.589384 -296.52087)
			)
			(arc
				(start 75.589384 -294.378888)
				(mid 75.585483 -294.359365)
				(end 75.574398 -294.34282)
			)
			(arc
				(start 75.477116 -294.245538)
				(mid 75.460582 -294.234427)
				(end 75.441048 -294.230552)
			)
			(arc
				(start 74.259948 -294.230552)
				(mid 74.240425 -294.234453)
				(end 74.22388 -294.245538)
			)
			(arc
				(start 74.150728 -294.31869)
				(mid 74.139617 -294.335224)
				(end 74.135742 -294.354758)
			)
			(arc
				(start 74.135742 -296.528744)
				(mid 74.139643 -296.548267)
				(end 74.150728 -296.564812)
			)
			(arc
				(start 74.200258 -296.614342)
				(mid 74.216792 -296.625453)
				(end 74.236326 -296.629328)
			)
		)
		(stroke
			(width 0)
			(type solid)
		)
		(fill yes)
		(layer "B.Cu")
		(net "GND")
	)
	(gr_poly
		(pts
			(arc
				(start 80.246474 -296.605452)
				(mid 80.265997 -296.601551)
				(end 80.282542 -296.590466)
			)
			(arc
				(start 80.332072 -296.540936)
				(mid 80.343183 -296.524402)
				(end 80.347058 -296.504868)
			)
			(arc
				(start 80.347058 -294.37076)
				(mid 80.343157 -294.351237)
				(end 80.332072 -294.334692)
			)
			(arc
				(start 80.266794 -294.269414)
				(mid 80.25026 -294.258303)
				(end 80.230726 -294.254428)
			)
			(arc
				(start 79.010002 -294.254428)
				(mid 78.990479 -294.258329)
				(end 78.973934 -294.269414)
			)
			(arc
				(start 78.837028 -294.40632)
				(mid 78.825917 -294.422854)
				(end 78.822042 -294.442388)
			)
			(arc
				(start 78.822042 -296.441368)
				(mid 78.825943 -296.460891)
				(end 78.837028 -296.477436)
			)
			(arc
				(start 78.950058 -296.590466)
				(mid 78.966592 -296.601577)
				(end 78.986126 -296.605452)
			)
		)
		(stroke
			(width 0)
			(type solid)
		)
		(fill yes)
		(layer "B.Cu")
		(net "GND")
	)
	(gr_poly
		(pts
			(arc
				(start 133.971538 -203.851256)
				(mid 133.991061 -203.847355)
				(end 134.007606 -203.83627)
			)
			(arc
				(start 134.101332 -203.742544)
				(mid 134.112443 -203.72601)
				(end 134.116318 -203.706476)
			)
			(arc
				(start 134.116318 -202.203304)
				(mid 134.112417 -202.183781)
				(end 134.101332 -202.167236)
			)
			(arc
				(start 134.052564 -202.118468)
				(mid 134.03603 -202.107357)
				(end 134.016496 -202.103482)
			)
			(arc
				(start 132.813806 -202.103482)
				(mid 132.794283 -202.107383)
				(end 132.777738 -202.118468)
			)
			(arc
				(start 132.575046 -202.32116)
				(mid 132.563935 -202.337694)
				(end 132.56006 -202.357228)
			)
			(arc
				(start 132.56006 -203.05014)
				(mid 132.563961 -203.069663)
				(end 132.575046 -203.086208)
			)
			(arc
				(start 133.325108 -203.83627)
				(mid 133.341642 -203.847381)
				(end 133.361176 -203.851256)
			)
		)
		(stroke
			(width 0)
			(type solid)
		)
		(fill yes)
		(layer "B.Cu")
		(net "P1V8_CLI_VCORE")
	)
	(gr_poly
		(pts
			(arc
				(start 165.809676 -304.19675)
				(mid 165.829199 -304.192849)
				(end 165.845744 -304.181764)
			)
			(arc
				(start 165.878764 -304.14849)
				(mid 165.895298 -304.137379)
				(end 165.914832 -304.133504)
			)
			(arc
				(start 183.981598 -304.133504)
				(mid 184.017519 -304.118625)
				(end 184.032398 -304.082704)
			)
			(arc
				(start 184.032398 -303.911508)
				(mid 184.028497 -303.891985)
				(end 184.017412 -303.87544)
			)
			(xy 183.775604 -303.633632) (xy 183.768492 -303.626266) (xy 183.749696 -303.618646)
			(arc
				(start 164.29355 -303.618646)
				(mid 164.274027 -303.622547)
				(end 164.257482 -303.633632)
			)
			(xy 164.222938 -303.668176) (xy 164.222938 -304.13198) (xy 164.272722 -304.181764)
			(arc
				(start 165.62324 -304.181764)
				(mid 165.639774 -304.192875)
				(end 165.659308 -304.19675)
			)
		)
		(stroke
			(width 0)
			(type solid)
		)
		(fill yes)
		(layer "B.Cu")
		(net "GND")
	)
	(gr_poly
		(pts
			(arc
				(start 183.985916 -288.213038)
				(mid 184.005439 -288.209137)
				(end 184.021984 -288.198052)
			)
			(arc
				(start 184.093612 -288.126424)
				(mid 184.104723 -288.10989)
				(end 184.108598 -288.090356)
			)
			(arc
				(start 184.108598 -287.77692)
				(mid 184.104697 -287.757397)
				(end 184.093612 -287.740852)
			)
			(arc
				(start 183.996838 -287.644078)
				(mid 183.980421 -287.633016)
				(end 183.961024 -287.629092)
			)
			(arc
				(start 166.603172 -287.629092)
				(mid 166.583785 -287.633042)
				(end 166.567358 -287.644078)
			)
			(arc
				(start 166.495984 -287.715452)
				(mid 166.484873 -287.731986)
				(end 166.480998 -287.75152)
			)
			(arc
				(start 166.480998 -288.115756)
				(mid 166.484899 -288.135279)
				(end 166.495984 -288.151824)
			)
			(arc
				(start 166.542212 -288.198052)
				(mid 166.558746 -288.209163)
				(end 166.57828 -288.213038)
			)
		)
		(stroke
			(width 0)
			(type solid)
		)
		(fill yes)
		(layer "B.Cu")
		(net "GND")
	)
	(gr_poly
		(pts
			(arc
				(start 187.738258 -299.389038)
				(mid 187.757781 -299.385137)
				(end 187.774326 -299.374052)
			)
			(arc
				(start 187.808362 -299.340016)
				(mid 187.819473 -299.323482)
				(end 187.823348 -299.303948)
			)
			(arc
				(start 187.823348 -292.50894)
				(mid 187.819447 -292.489417)
				(end 187.808362 -292.472872)
			)
			(xy 187.704222 -292.368732) (xy 187.69711 -292.361366) (xy 187.678314 -292.353746)
			(arc
				(start 187.431426 -292.353746)
				(mid 187.411903 -292.357647)
				(end 187.395358 -292.368732)
			)
			(xy 187.277756 -292.486334) (xy 187.27039 -292.493446) (xy 187.26277 -292.512242) (xy 187.26277 -298.804838)
			(xy 187.263278 -298.8056)
			(arc
				(start 187.263278 -299.142912)
				(mid 187.267179 -299.162435)
				(end 187.278264 -299.17898)
			)
			(arc
				(start 187.473336 -299.374052)
				(mid 187.48987 -299.385163)
				(end 187.509404 -299.389038)
			)
		)
		(stroke
			(width 0)
			(type solid)
		)
		(fill yes)
		(layer "B.Cu")
		(net "GND")
	)
	(gr_poly
		(pts
			(arc
				(start 191.581024 -296.629328)
				(mid 191.600547 -296.625427)
				(end 191.617092 -296.614342)
			)
			(arc
				(start 191.674496 -296.556938)
				(mid 191.685607 -296.540404)
				(end 191.689482 -296.52087)
			)
			(arc
				(start 191.689482 -294.378888)
				(mid 191.685581 -294.359365)
				(end 191.674496 -294.34282)
			)
			(arc
				(start 191.577214 -294.245538)
				(mid 191.56068 -294.234427)
				(end 191.541146 -294.230552)
			)
			(arc
				(start 190.360046 -294.230552)
				(mid 190.340523 -294.234453)
				(end 190.323978 -294.245538)
			)
			(arc
				(start 190.250826 -294.31869)
				(mid 190.239715 -294.335224)
				(end 190.23584 -294.354758)
			)
			(arc
				(start 190.23584 -296.528744)
				(mid 190.239741 -296.548267)
				(end 190.250826 -296.564812)
			)
			(arc
				(start 190.300356 -296.614342)
				(mid 190.31689 -296.625453)
				(end 190.336424 -296.629328)
			)
		)
		(stroke
			(width 0)
			(type solid)
		)
		(fill yes)
		(layer "B.Cu")
		(net "GND")
	)
	(gr_poly
		(pts
			(arc
				(start 196.346572 -296.605452)
				(mid 196.366095 -296.601551)
				(end 196.38264 -296.590466)
			)
			(arc
				(start 196.43217 -296.540936)
				(mid 196.443281 -296.524402)
				(end 196.447156 -296.504868)
			)
			(arc
				(start 196.447156 -294.37076)
				(mid 196.443255 -294.351237)
				(end 196.43217 -294.334692)
			)
			(arc
				(start 196.366892 -294.269414)
				(mid 196.350358 -294.258303)
				(end 196.330824 -294.254428)
			)
			(arc
				(start 195.1101 -294.254428)
				(mid 195.090577 -294.258329)
				(end 195.074032 -294.269414)
			)
			(arc
				(start 194.937126 -294.40632)
				(mid 194.926015 -294.422854)
				(end 194.92214 -294.442388)
			)
			(arc
				(start 194.92214 -296.441368)
				(mid 194.926041 -296.460891)
				(end 194.937126 -296.477436)
			)
			(arc
				(start 195.050156 -296.590466)
				(mid 195.06669 -296.601577)
				(end 195.086224 -296.605452)
			)
		)
		(stroke
			(width 0)
			(type solid)
		)
		(fill yes)
		(layer "B.Cu")
		(net "GND")
	)
	(gr_poly
		(pts
			(arc
				(start 202.002136 -358.471978)
				(mid 201.606912 -358.471978)
				(end 202.002136 -358.471978)
			)
		)
		(stroke
			(width 0)
			(type solid)
		)
		(fill yes)
		(layer "B.Cu")
		(net "GND")
	)
	(gr_poly
		(pts
			(arc
				(start 224.501964 -155.032202)
				(mid 224.521487 -155.028301)
				(end 224.538032 -155.017216)
			)
			(arc
				(start 224.63506 -154.920188)
				(mid 224.646171 -154.903654)
				(end 224.650046 -154.88412)
			)
			(arc
				(start 224.650046 -153.529284)
				(mid 224.646145 -153.509761)
				(end 224.63506 -153.493216)
			)
			(arc
				(start 224.538032 -153.396188)
				(mid 224.521498 -153.385077)
				(end 224.501964 -153.381202)
			)
			(arc
				(start 222.004128 -153.381202)
				(mid 221.984605 -153.385103)
				(end 221.96806 -153.396188)
			)
			(arc
				(start 221.871032 -153.493216)
				(mid 221.859921 -153.50975)
				(end 221.856046 -153.529284)
			)
			(arc
				(start 221.856046 -154.88412)
				(mid 221.859947 -154.903643)
				(end 221.871032 -154.920188)
			)
			(arc
				(start 221.96806 -155.017216)
				(mid 221.984594 -155.028327)
				(end 222.004128 -155.032202)
			)
		)
		(stroke
			(width 0)
			(type solid)
		)
		(fill yes)
		(layer "B.Cu")
		(net "P3V3")
	)
	(gr_poly
		(pts
			(arc
				(start 235.804964 -155.794202)
				(mid 235.824487 -155.790301)
				(end 235.841032 -155.779216)
			)
			(arc
				(start 235.93806 -155.682188)
				(mid 235.949171 -155.665654)
				(end 235.953046 -155.64612)
			)
			(arc
				(start 235.953046 -154.545284)
				(mid 235.949145 -154.525761)
				(end 235.93806 -154.509216)
			)
			(arc
				(start 235.841032 -154.412188)
				(mid 235.824498 -154.401077)
				(end 235.804964 -154.397202)
			)
			(arc
				(start 233.434128 -154.397202)
				(mid 233.414605 -154.401103)
				(end 233.39806 -154.412188)
			)
			(arc
				(start 233.301032 -154.509216)
				(mid 233.289921 -154.52575)
				(end 233.286046 -154.545284)
			)
			(arc
				(start 233.286046 -155.64612)
				(mid 233.289947 -155.665643)
				(end 233.301032 -155.682188)
			)
			(arc
				(start 233.39806 -155.779216)
				(mid 233.414594 -155.790327)
				(end 233.434128 -155.794202)
			)
		)
		(stroke
			(width 0)
			(type solid)
		)
		(fill yes)
		(layer "B.Cu")
		(net "P3V3")
	)
	(gr_poly
		(pts
			(arc
				(start 241.827304 -376.462798)
				(mid 241.846827 -376.458897)
				(end 241.863372 -376.447812)
			)
			(arc
				(start 242.299744 -376.01144)
				(mid 242.310855 -375.994906)
				(end 242.31473 -375.975372)
			)
			(arc
				(start 242.31473 -368.741706)
				(mid 242.310829 -368.722183)
				(end 242.299744 -368.705638)
			)
			(arc
				(start 242.15979 -368.565684)
				(mid 242.143256 -368.554573)
				(end 242.123722 -368.550698)
			)
			(arc
				(start 236.230668 -368.550698)
				(mid 236.211145 -368.554599)
				(end 236.1946 -368.565684)
			)
			(arc
				(start 236.10189 -368.658394)
				(mid 236.090779 -368.674928)
				(end 236.086904 -368.694462)
			)
			(arc
				(start 236.086904 -376.102118)
				(mid 236.090805 -376.121641)
				(end 236.10189 -376.138186)
			)
			(arc
				(start 236.411516 -376.447812)
				(mid 236.42805 -376.458923)
				(end 236.447584 -376.462798)
			)
		)
		(stroke
			(width 0)
			(type solid)
		)
		(fill yes)
		(layer "B.Cu")
		(net "P12V_STBY_R1")
	)
	(gr_poly
		(pts
			(arc
				(start 252.431042 -397.963136)
				(mid 252.450565 -397.959235)
				(end 252.46711 -397.94815)
			)
			(arc
				(start 252.932438 -397.482822)
				(mid 252.943549 -397.466288)
				(end 252.947424 -397.446754)
			)
			(arc
				(start 252.947424 -392.961114)
				(mid 252.943523 -392.941591)
				(end 252.932438 -392.925046)
			)
			(arc
				(start 252.451362 -392.44397)
				(mid 252.434828 -392.432859)
				(end 252.415294 -392.428984)
			)
			(arc
				(start 246.598694 -392.428984)
				(mid 246.579171 -392.432885)
				(end 246.562626 -392.44397)
			)
			(arc
				(start 246.380762 -392.625834)
				(mid 246.369651 -392.642368)
				(end 246.365776 -392.661902)
			)
			(arc
				(start 246.365776 -397.327628)
				(mid 246.369677 -397.347151)
				(end 246.380762 -397.363696)
			)
			(arc
				(start 246.965216 -397.94815)
				(mid 246.98175 -397.959261)
				(end 247.001284 -397.963136)
			)
		)
		(stroke
			(width 0)
			(type solid)
		)
		(fill yes)
		(layer "B.Cu")
		(net "P12V_STBY_FUSE")
	)
	(gr_poly
		(pts
			(arc
				(start 255.101598 -87.364316)
				(mid 255.121121 -87.360415)
				(end 255.137666 -87.34933)
			)
			(arc
				(start 255.234694 -87.252302)
				(mid 255.245805 -87.235768)
				(end 255.24968 -87.216234)
			)
			(arc
				(start 255.24968 -84.210398)
				(mid 255.245779 -84.190875)
				(end 255.234694 -84.17433)
			)
			(arc
				(start 255.010666 -83.950302)
				(mid 254.994132 -83.939191)
				(end 254.974598 -83.935316)
			)
			(xy 254.712216 -83.935316) (xy 254.543814 -84.103718) (xy 254.543814 -84.703412) (xy 254.248666 -84.99856)
			(arc
				(start 254.248666 -85.19033)
				(mid 254.237555 -85.206864)
				(end 254.23368 -85.226398)
			)
			(arc
				(start 254.23368 -87.216234)
				(mid 254.237581 -87.235757)
				(end 254.248666 -87.252302)
			)
			(arc
				(start 254.345694 -87.34933)
				(mid 254.362228 -87.360441)
				(end 254.381762 -87.364316)
			)
		)
		(stroke
			(width 0)
			(type solid)
		)
		(fill yes)
		(layer "B.Cu")
		(net "P3V3_CLK_GEN_VDDPT_CK440")
	)
	(gr_poly
		(pts
			(arc
				(start 300.08576 -288.213038)
				(mid 300.105283 -288.209137)
				(end 300.121828 -288.198052)
			)
			(arc
				(start 300.193456 -288.126424)
				(mid 300.204567 -288.10989)
				(end 300.208442 -288.090356)
			)
			(arc
				(start 300.208442 -287.77692)
				(mid 300.204541 -287.757397)
				(end 300.193456 -287.740852)
			)
			(arc
				(start 300.096682 -287.644078)
				(mid 300.080265 -287.633016)
				(end 300.060868 -287.629092)
			)
			(arc
				(start 282.703016 -287.629092)
				(mid 282.683629 -287.633042)
				(end 282.667202 -287.644078)
			)
			(arc
				(start 282.595828 -287.715452)
				(mid 282.584717 -287.731986)
				(end 282.580842 -287.75152)
			)
			(arc
				(start 282.580842 -288.115756)
				(mid 282.584743 -288.135279)
				(end 282.595828 -288.151824)
			)
			(arc
				(start 282.642056 -288.198052)
				(mid 282.65859 -288.209163)
				(end 282.678124 -288.213038)
			)
		)
		(stroke
			(width 0)
			(type solid)
		)
		(fill yes)
		(layer "B.Cu")
		(net "GND")
	)
	(gr_poly
		(pts
			(arc
				(start 307.680868 -296.629328)
				(mid 307.700391 -296.625427)
				(end 307.716936 -296.614342)
			)
			(arc
				(start 307.77434 -296.556938)
				(mid 307.785451 -296.540404)
				(end 307.789326 -296.52087)
			)
			(arc
				(start 307.789326 -294.378888)
				(mid 307.785425 -294.359365)
				(end 307.77434 -294.34282)
			)
			(arc
				(start 307.677058 -294.245538)
				(mid 307.660524 -294.234427)
				(end 307.64099 -294.230552)
			)
			(arc
				(start 306.45989 -294.230552)
				(mid 306.440367 -294.234453)
				(end 306.423822 -294.245538)
			)
			(arc
				(start 306.35067 -294.31869)
				(mid 306.339559 -294.335224)
				(end 306.335684 -294.354758)
			)
			(arc
				(start 306.335684 -296.528744)
				(mid 306.339585 -296.548267)
				(end 306.35067 -296.564812)
			)
			(arc
				(start 306.4002 -296.614342)
				(mid 306.416734 -296.625453)
				(end 306.436268 -296.629328)
			)
		)
		(stroke
			(width 0)
			(type solid)
		)
		(fill yes)
		(layer "B.Cu")
		(net "GND")
	)
	(gr_poly
		(pts
			(arc
				(start 312.446416 -296.605452)
				(mid 312.465939 -296.601551)
				(end 312.482484 -296.590466)
			)
			(arc
				(start 312.532014 -296.540936)
				(mid 312.543125 -296.524402)
				(end 312.547 -296.504868)
			)
			(arc
				(start 312.547 -294.37076)
				(mid 312.543099 -294.351237)
				(end 312.532014 -294.334692)
			)
			(arc
				(start 312.466736 -294.269414)
				(mid 312.450202 -294.258303)
				(end 312.430668 -294.254428)
			)
			(arc
				(start 311.209944 -294.254428)
				(mid 311.190421 -294.258329)
				(end 311.173876 -294.269414)
			)
			(arc
				(start 311.03697 -294.40632)
				(mid 311.025859 -294.422854)
				(end 311.021984 -294.442388)
			)
			(arc
				(start 311.021984 -296.441368)
				(mid 311.025885 -296.460891)
				(end 311.03697 -296.477436)
			)
			(arc
				(start 311.15 -296.590466)
				(mid 311.166534 -296.601577)
				(end 311.186068 -296.605452)
			)
		)
		(stroke
			(width 0)
			(type solid)
		)
		(fill yes)
		(layer "B.Cu")
		(net "GND")
	)
	(gr_poly
		(pts
			(arc
				(start 332.615032 -82.3087)
				(mid 332.634555 -82.304799)
				(end 332.6511 -82.293714)
			)
			(arc
				(start 332.730602 -82.214212)
				(mid 332.741713 -82.197678)
				(end 332.745588 -82.178144)
			)
			(arc
				(start 332.745588 -80.517492)
				(mid 332.741687 -80.497969)
				(end 332.730602 -80.481424)
			)
			(arc
				(start 332.719172 -80.469994)
				(mid 332.702638 -80.458883)
				(end 332.683104 -80.455008)
			)
			(arc
				(start 330.817728 -80.455008)
				(mid 330.798205 -80.458909)
				(end 330.78166 -80.469994)
			)
			(arc
				(start 330.421234 -80.83042)
				(mid 330.410123 -80.846954)
				(end 330.406248 -80.866488)
			)
			(arc
				(start 330.406248 -82.19059)
				(mid 330.410149 -82.210113)
				(end 330.421234 -82.226658)
			)
			(arc
				(start 330.48829 -82.293714)
				(mid 330.504824 -82.304825)
				(end 330.524358 -82.3087)
			)
		)
		(stroke
			(width 0)
			(type solid)
		)
		(fill yes)
		(layer "B.Cu")
		(net "P3V3")
	)
	(gr_poly
		(pts
			(arc
				(start 398.009618 -304.19675)
				(mid 398.029141 -304.192849)
				(end 398.045686 -304.181764)
			)
			(arc
				(start 398.078706 -304.14849)
				(mid 398.09524 -304.137379)
				(end 398.114774 -304.133504)
			)
			(arc
				(start 416.18154 -304.133504)
				(mid 416.217461 -304.118625)
				(end 416.23234 -304.082704)
			)
			(arc
				(start 416.23234 -303.911508)
				(mid 416.228439 -303.891985)
				(end 416.217354 -303.87544)
			)
			(xy 415.975546 -303.633632) (xy 415.968434 -303.626266) (xy 415.949638 -303.618646)
			(arc
				(start 396.493492 -303.618646)
				(mid 396.473969 -303.622547)
				(end 396.457424 -303.633632)
			)
			(xy 396.42288 -303.668176) (xy 396.42288 -304.13198) (xy 396.472664 -304.181764)
			(arc
				(start 397.823182 -304.181764)
				(mid 397.839716 -304.192875)
				(end 397.85925 -304.19675)
			)
		)
		(stroke
			(width 0)
			(type solid)
		)
		(fill yes)
		(layer "B.Cu")
		(net "GND")
	)
	(gr_poly
		(pts
			(arc
				(start 416.13455 -300.39691)
				(mid 416.154073 -300.393009)
				(end 416.170618 -300.381924)
			)
			(arc
				(start 416.217354 -300.335188)
				(mid 416.228465 -300.318654)
				(end 416.23234 -300.29912)
			)
			(arc
				(start 416.23234 -300.111668)
				(mid 416.228439 -300.092145)
				(end 416.217354 -300.0756)
			)
			(arc
				(start 415.975546 -299.833792)
				(mid 415.959012 -299.822681)
				(end 415.939478 -299.818806)
			)
			(arc
				(start 398.974818 -299.818806)
				(mid 398.955295 -299.822707)
				(end 398.93875 -299.833792)
			)
			(arc
				(start 398.75841 -300.014132)
				(mid 398.747299 -300.030666)
				(end 398.743424 -300.0502)
			)
			(arc
				(start 398.743424 -300.290738)
				(mid 398.747325 -300.310261)
				(end 398.75841 -300.326806)
			)
			(arc
				(start 398.813528 -300.381924)
				(mid 398.830062 -300.393035)
				(end 398.849596 -300.39691)
			)
		)
		(stroke
			(width 0)
			(type solid)
		)
		(fill yes)
		(layer "B.Cu")
		(net "GND")
	)
	(gr_poly
		(pts
			(arc
				(start 416.185858 -288.213038)
				(mid 416.205381 -288.209137)
				(end 416.221926 -288.198052)
			)
			(arc
				(start 416.293554 -288.126424)
				(mid 416.304665 -288.10989)
				(end 416.30854 -288.090356)
			)
			(arc
				(start 416.30854 -287.77692)
				(mid 416.304639 -287.757397)
				(end 416.293554 -287.740852)
			)
			(arc
				(start 416.19678 -287.644078)
				(mid 416.180363 -287.633016)
				(end 416.160966 -287.629092)
			)
			(arc
				(start 398.803114 -287.629092)
				(mid 398.783727 -287.633042)
				(end 398.7673 -287.644078)
			)
			(arc
				(start 398.695926 -287.715452)
				(mid 398.684815 -287.731986)
				(end 398.68094 -287.75152)
			)
			(arc
				(start 398.68094 -288.115756)
				(mid 398.684841 -288.135279)
				(end 398.695926 -288.151824)
			)
			(arc
				(start 398.742154 -288.198052)
				(mid 398.758688 -288.209163)
				(end 398.778222 -288.213038)
			)
		)
		(stroke
			(width 0)
			(type solid)
		)
		(fill yes)
		(layer "B.Cu")
		(net "GND")
	)
	(gr_poly
		(pts
			(arc
				(start 421.072818 -298.599606)
				(mid 421.092341 -298.595705)
				(end 421.108886 -298.58462)
			)
			(arc
				(start 421.123618 -298.569888)
				(mid 421.134729 -298.553354)
				(end 421.138604 -298.53382)
			)
			(arc
				(start 421.138604 -293.204646)
				(mid 421.134703 -293.185123)
				(end 421.123618 -293.168578)
			)
			(arc
				(start 421.094662 -293.139622)
				(mid 421.078128 -293.128511)
				(end 421.058594 -293.124636)
			)
			(arc
				(start 420.373556 -293.124636)
				(mid 420.354033 -293.128537)
				(end 420.337488 -293.139622)
			)
			(arc
				(start 420.317422 -293.159688)
				(mid 420.306311 -293.176222)
				(end 420.302436 -293.195756)
			)
			(arc
				(start 420.302436 -298.506134)
				(mid 420.306337 -298.525657)
				(end 420.317422 -298.542202)
			)
			(arc
				(start 420.35984 -298.58462)
				(mid 420.376374 -298.595731)
				(end 420.395908 -298.599606)
			)
		)
		(stroke
			(width 0)
			(type solid)
		)
		(fill yes)
		(layer "B.Cu")
		(net "P1V25_SERDES_VDDPLL_PEX3")
	)
	(gr_poly
		(pts
			(arc
				(start 428.546514 -296.605452)
				(mid 428.566037 -296.601551)
				(end 428.582582 -296.590466)
			)
			(arc
				(start 428.632112 -296.540936)
				(mid 428.643223 -296.524402)
				(end 428.647098 -296.504868)
			)
			(arc
				(start 428.647098 -294.37076)
				(mid 428.643197 -294.351237)
				(end 428.632112 -294.334692)
			)
			(arc
				(start 428.566834 -294.269414)
				(mid 428.5503 -294.258303)
				(end 428.530766 -294.254428)
			)
			(arc
				(start 427.310042 -294.254428)
				(mid 427.290519 -294.258329)
				(end 427.273974 -294.269414)
			)
			(arc
				(start 427.137068 -294.40632)
				(mid 427.125957 -294.422854)
				(end 427.122082 -294.442388)
			)
			(arc
				(start 427.122082 -296.441368)
				(mid 427.125983 -296.460891)
				(end 427.137068 -296.477436)
			)
			(arc
				(start 427.250098 -296.590466)
				(mid 427.266632 -296.601577)
				(end 427.286166 -296.605452)
			)
		)
		(stroke
			(width 0)
			(type solid)
		)
		(fill yes)
		(layer "B.Cu")
		(net "GND")
	)
	(gr_poly
		(pts
			(arc
				(start 72.920098 -285.714186)
				(mid 72.939621 -285.710285)
				(end 72.956166 -285.6992)
			)
			(arc
				(start 73.080372 -285.574994)
				(mid 73.091483 -285.55846)
				(end 73.095358 -285.538926)
			)
			(xy 73.095358 -285.006796) (xy 73.095104 -285.002732) (xy 73.094088 -284.975046) (xy 73.094088 -284.974538)
			(xy 73.095104 -284.946852) (xy 73.095358 -284.942788) (xy 73.095358 -284.056836) (xy 73.095104 -284.052772)
			(xy 73.094088 -284.025086) (xy 73.094088 -284.024578) (xy 73.095104 -283.996892) (xy 73.095358 -283.992828)
			(xy 73.095358 -283.908246) (xy 73.095358 -283.595826) (xy 72.98817 -283.488638) (xy 71.750682 -283.488638)
			(arc
				(start 71.351648 -283.488638)
				(mid 71.315727 -283.503517)
				(end 71.300848 -283.539438)
			)
			(xy 71.300848 -285.09468) (xy 71.300848 -285.660592) (xy 71.354442 -285.714186)
		)
		(stroke
			(width 0)
			(type solid)
		)
		(fill yes)
		(layer "B.Cu")
		(net "P1V8_PEX")
	)
	(gr_poly
		(pts
			(xy 166.06139 -302.281336)
			(arc
				(start 183.915812 -302.281336)
				(mid 183.935169 -302.277503)
				(end 183.951626 -302.266604)
			)
			(arc
				(start 184.02554 -302.19269)
				(mid 184.036651 -302.176156)
				(end 184.040526 -302.156622)
			)
			(arc
				(start 184.040526 -301.857156)
				(mid 184.036625 -301.837633)
				(end 184.02554 -301.821088)
			)
			(xy 183.938164 -301.733712) (xy 183.931052 -301.726346) (xy 183.912256 -301.718726)
			(arc
				(start 165.6461 -301.718726)
				(mid 165.626577 -301.722627)
				(end 165.610032 -301.733712)
			)
			(arc
				(start 165.585394 -301.75835)
				(mid 165.574468 -301.774796)
				(end 165.570662 -301.794164)
			)
			(arc
				(start 165.570662 -302.231298)
				(mid 165.574563 -302.250821)
				(end 165.585648 -302.267366)
			)
			(arc
				(start 165.586156 -302.267874)
				(mid 165.60269 -302.278985)
				(end 165.622224 -302.28286)
			)
			(xy 166.06012 -302.28286)
		)
		(stroke
			(width 0)
			(type solid)
		)
		(fill yes)
		(layer "B.Cu")
		(net "GND")
	)
	(gr_poly
		(pts
			(arc
				(start 189.020196 -285.714186)
				(mid 189.039719 -285.710285)
				(end 189.056264 -285.6992)
			)
			(arc
				(start 189.18047 -285.574994)
				(mid 189.191581 -285.55846)
				(end 189.195456 -285.538926)
			)
			(xy 189.195456 -285.006796) (xy 189.195202 -285.002732) (xy 189.194186 -284.975046) (xy 189.194186 -284.974538)
			(xy 189.195202 -284.946852) (xy 189.195456 -284.942788) (xy 189.195456 -284.056836) (xy 189.195202 -284.052772)
			(xy 189.194186 -284.025086) (xy 189.194186 -284.024578) (xy 189.195202 -283.996892) (xy 189.195456 -283.992828)
			(xy 189.195456 -283.908246) (xy 189.195456 -283.65196) (xy 189.032134 -283.488638) (xy 187.85078 -283.488638)
			(arc
				(start 187.451746 -283.488638)
				(mid 187.415825 -283.503517)
				(end 187.400946 -283.539438)
			)
			(xy 187.400946 -285.09468) (xy 187.400946 -285.660592) (xy 187.45454 -285.714186)
		)
		(stroke
			(width 0)
			(type solid)
		)
		(fill yes)
		(layer "B.Cu")
		(net "P1V8_PEX")
	)
	(gr_poly
		(pts
			(xy 227.743004 -143.69288) (xy 228.797612 -143.69288) (xy 228.968046 -143.522446) (xy 228.968046 -142.43812)
			(arc
				(start 228.968046 -142.099284)
				(mid 228.964145 -142.079761)
				(end 228.95306 -142.063216)
			)
			(arc
				(start 228.729032 -141.839188)
				(mid 228.712498 -141.828077)
				(end 228.692964 -141.824202)
			)
			(arc
				(start 227.846128 -141.824202)
				(mid 227.826605 -141.820301)
				(end 227.81006 -141.809216)
			)
			(arc
				(start 227.713032 -141.712188)
				(mid 227.696498 -141.701077)
				(end 227.676964 -141.697202)
			)
			(arc
				(start 225.687128 -141.697202)
				(mid 225.667605 -141.701103)
				(end 225.65106 -141.712188)
			)
			(arc
				(start 225.554032 -141.809216)
				(mid 225.542921 -141.82575)
				(end 225.539046 -141.845284)
			)
			(xy 225.539046 -142.56512) (xy 225.539046 -143.358108) (xy 226.018852 -143.837914) (xy 227.383848 -143.837914)
			(xy 227.59797 -143.837914)
		)
		(stroke
			(width 0)
			(type solid)
		)
		(fill yes)
		(layer "B.Cu")
		(net "P3V3_CLK_GEN_VDDPT_CK440_PEX")
	)
	(gr_poly
		(pts
			(arc
				(start 421.220138 -285.714186)
				(mid 421.239661 -285.710285)
				(end 421.256206 -285.6992)
			)
			(arc
				(start 421.380412 -285.574994)
				(mid 421.391523 -285.55846)
				(end 421.395398 -285.538926)
			)
			(xy 421.395398 -285.006796) (xy 421.395144 -285.002732) (xy 421.394128 -284.975046) (xy 421.394128 -284.974538)
			(xy 421.395144 -284.946852) (xy 421.395398 -284.942788) (xy 421.395398 -284.056836) (xy 421.395144 -284.052772)
			(xy 421.394128 -284.025086) (xy 421.394128 -284.024578) (xy 421.395144 -283.996892) (xy 421.395398 -283.992828)
			(xy 421.395398 -283.908246) (xy 421.395398 -283.603192) (xy 421.280844 -283.488638) (xy 420.050722 -283.488638)
			(arc
				(start 419.651688 -283.488638)
				(mid 419.615767 -283.503517)
				(end 419.600888 -283.539438)
			)
			(xy 419.600888 -285.09468) (xy 419.600888 -285.660592) (xy 419.654482 -285.714186)
		)
		(stroke
			(width 0)
			(type solid)
		)
		(fill yes)
		(layer "B.Cu")
		(net "P1V8_PEX")
	)
	(gr_poly
		(pts
			(xy 49.961292 -302.281336)
			(arc
				(start 67.815714 -302.281336)
				(mid 67.835071 -302.277503)
				(end 67.851528 -302.266604)
			)
			(arc
				(start 67.925442 -302.19269)
				(mid 67.936553 -302.176156)
				(end 67.940428 -302.156622)
			)
			(arc
				(start 67.940428 -301.857156)
				(mid 67.936527 -301.837633)
				(end 67.925442 -301.821088)
			)
			(arc
				(start 67.838066 -301.733712)
				(mid 67.821532 -301.722601)
				(end 67.801998 -301.718726)
			)
			(arc
				(start 49.546002 -301.718726)
				(mid 49.526479 -301.722627)
				(end 49.509934 -301.733712)
			)
			(arc
				(start 49.485296 -301.75835)
				(mid 49.47437 -301.774796)
				(end 49.470564 -301.794164)
			)
			(arc
				(start 49.470564 -302.231044)
				(mid 49.474348 -302.250538)
				(end 49.485296 -302.267112)
			)
			(arc
				(start 49.486058 -302.267874)
				(mid 49.502592 -302.278985)
				(end 49.522126 -302.28286)
			)
			(xy 49.960022 -302.28286)
		)
		(stroke
			(width 0)
			(type solid)
		)
		(fill yes)
		(layer "B.Cu")
		(net "GND")
	)
	(gr_poly
		(pts
			(arc
				(start 221.818962 -366.358424)
				(mid 221.838485 -366.354523)
				(end 221.85503 -366.343438)
			)
			(arc
				(start 221.972124 -366.226344)
				(mid 221.983235 -366.20981)
				(end 221.98711 -366.190276)
			)
			(arc
				(start 221.98711 -362.196126)
				(mid 221.983209 -362.176603)
				(end 221.972124 -362.160058)
			)
			(arc
				(start 221.872048 -362.059982)
				(mid 221.855514 -362.048871)
				(end 221.83598 -362.044996)
			)
			(arc
				(start 217.821764 -362.044996)
				(mid 217.802241 -362.048897)
				(end 217.785696 -362.059982)
			)
			(arc
				(start 217.678 -362.167678)
				(mid 217.666889 -362.184212)
				(end 217.663014 -362.203746)
			)
			(arc
				(start 217.663014 -366.210088)
				(mid 217.666915 -366.229611)
				(end 217.678 -366.246156)
			)
			(arc
				(start 217.767662 -366.335818)
				(mid 217.784079 -366.34688)
				(end 217.803476 -366.350804)
			)
			(xy 221.650052 -366.350804) (xy 221.668848 -366.358424)
		)
		(stroke
			(width 0)
			(type solid)
		)
		(fill yes)
		(layer "B.Cu")
		(net "P12V_AUX")
	)
	(gr_poly
		(pts
			(arc
				(start 222.825818 -212.03666)
				(mid 222.845341 -212.032759)
				(end 222.861886 -212.021674)
			)
			(arc
				(start 223.639126 -211.244434)
				(mid 223.650237 -211.2279)
				(end 223.654112 -211.208366)
			)
			(xy 223.654112 -210.851242) (xy 223.653604 -210.837018)
			(arc
				(start 223.653604 -209.336894)
				(mid 223.649771 -209.317537)
				(end 223.638872 -209.30108)
			)
			(arc
				(start 222.666306 -208.328514)
				(mid 222.649772 -208.317403)
				(end 222.630238 -208.313528)
			)
			(arc
				(start 221.720664 -208.313528)
				(mid 221.701141 -208.317429)
				(end 221.684596 -208.328514)
			)
			(arc
				(start 221.578424 -208.434686)
				(mid 221.567313 -208.45122)
				(end 221.563438 -208.470754)
			)
			(arc
				(start 221.563438 -211.964524)
				(mid 221.567339 -211.984047)
				(end 221.578424 -212.000592)
			)
			(arc
				(start 221.599506 -212.021674)
				(mid 221.61604 -212.032785)
				(end 221.635574 -212.03666)
			)
		)
		(stroke
			(width 0)
			(type solid)
		)
		(fill yes)
		(layer "B.Cu")
		(net "P3V3_AUX")
	)
	(gr_poly
		(pts
			(arc
				(start 232.664 -366.184688)
				(mid 232.675111 -366.168154)
				(end 232.678986 -366.14862)
			)
			(arc
				(start 232.678986 -362.185712)
				(mid 232.675085 -362.166189)
				(end 232.664 -362.149644)
			)
			(arc
				(start 232.503472 -361.989116)
				(mid 232.486938 -361.978005)
				(end 232.467404 -361.97413)
			)
			(arc
				(start 228.579172 -361.97413)
				(mid 228.559649 -361.978031)
				(end 228.543104 -361.989116)
			)
			(arc
				(start 228.34854 -362.18368)
				(mid 228.337429 -362.200214)
				(end 228.333554 -362.219748)
			)
			(arc
				(start 228.333554 -366.220248)
				(mid 228.337455 -366.239771)
				(end 228.34854 -366.256316)
			)
			(arc
				(start 228.387148 -366.294924)
				(mid 228.403594 -366.30585)
				(end 228.422962 -366.309656)
			)
			(arc
				(start 232.341674 -366.309656)
				(mid 232.361061 -366.313606)
				(end 232.377488 -366.324642)
			)
			(xy 232.44429 -366.391444) (xy 232.457244 -366.391444)
		)
		(stroke
			(width 0)
			(type solid)
		)
		(fill yes)
		(layer "B.Cu")
		(net "P12V_AUX")
	)
	(gr_poly
		(pts
			(xy 398.261332 -302.281336)
			(arc
				(start 416.115754 -302.281336)
				(mid 416.135111 -302.277503)
				(end 416.151568 -302.266604)
			)
			(arc
				(start 416.225482 -302.19269)
				(mid 416.236593 -302.176156)
				(end 416.240468 -302.156622)
			)
			(arc
				(start 416.240468 -301.857156)
				(mid 416.236567 -301.837633)
				(end 416.225482 -301.821088)
			)
			(arc
				(start 416.138106 -301.733712)
				(mid 416.121572 -301.722601)
				(end 416.102038 -301.718726)
			)
			(arc
				(start 397.846042 -301.718726)
				(mid 397.826519 -301.722627)
				(end 397.809974 -301.733712)
			)
			(arc
				(start 397.785336 -301.75835)
				(mid 397.77441 -301.774796)
				(end 397.770604 -301.794164)
			)
			(arc
				(start 397.770604 -302.231044)
				(mid 397.774388 -302.250538)
				(end 397.785336 -302.267112)
			)
			(arc
				(start 397.786098 -302.267874)
				(mid 397.802632 -302.278985)
				(end 397.822166 -302.28286)
			)
			(xy 398.260062 -302.28286)
		)
		(stroke
			(width 0)
			(type solid)
		)
		(fill yes)
		(layer "B.Cu")
		(net "GND")
	)
	(gr_poly
		(pts
			(arc
				(start 231.326944 -150.310088)
				(mid 231.346467 -150.306187)
				(end 231.363012 -150.295102)
			)
			(arc
				(start 231.766618 -149.891496)
				(mid 231.777729 -149.874962)
				(end 231.781604 -149.855428)
			)
			(arc
				(start 231.781604 -144.802606)
				(mid 231.777703 -144.783083)
				(end 231.766618 -144.766538)
			)
			(arc
				(start 231.398826 -144.398746)
				(mid 231.387715 -144.382212)
				(end 231.38384 -144.362678)
			)
			(xy 231.38384 -144.152874) (xy 231.194356 -143.96339) (xy 227.905818 -143.96339) (xy 227.38207 -144.487138)
			(xy 226.195128 -144.487138) (xy 225.978212 -144.704054) (xy 225.681032 -145.001234) (xy 225.681032 -145.711164)
			(xy 225.978212 -146.008344)
			(arc
				(start 225.978212 -149.855936)
				(mid 225.982113 -149.875459)
				(end 225.993198 -149.892004)
			)
			(arc
				(start 226.393756 -150.292562)
				(mid 226.41029 -150.303673)
				(end 226.429824 -150.307548)
			)
			(xy 226.82962 -150.307548) (xy 226.83216 -150.310088)
		)
		(stroke
			(width 0)
			(type solid)
		)
		(fill yes)
		(layer "B.Cu")
		(net "GND")
	)
	(gr_poly
		(pts
			(arc
				(start 127.802894 -175.353218)
				(mid 127.822417 -175.349317)
				(end 127.838962 -175.338232)
			)
			(arc
				(start 127.966978 -175.210216)
				(mid 127.978089 -175.193682)
				(end 127.981964 -175.174148)
			)
			(arc
				(start 127.981964 -172.925232)
				(mid 127.978014 -172.905845)
				(end 127.966978 -172.889418)
			)
			(arc
				(start 127.508762 -172.430948)
				(mid 127.4977 -172.414531)
				(end 127.493776 -172.395134)
			)
			(xy 127.493776 -172.390308)
			(arc
				(start 127.118872 -172.01515)
				(mid 127.102338 -172.004039)
				(end 127.082804 -172.000164)
			)
			(arc
				(start 126.151894 -172.000164)
				(mid 126.132371 -172.004065)
				(end 126.115826 -172.01515)
			)
			(arc
				(start 125.623828 -172.507148)
				(mid 125.612717 -172.523682)
				(end 125.608842 -172.543216)
			)
			(arc
				(start 125.608842 -175.213264)
				(mid 125.612743 -175.232787)
				(end 125.623828 -175.249332)
			)
			(arc
				(start 125.712728 -175.338232)
				(mid 125.729262 -175.349343)
				(end 125.748796 -175.353218)
			)
		)
		(stroke
			(width 0)
			(type solid)
		)
		(fill yes)
		(layer "B.Cu")
		(net "P3V3_DB2000QL_FB_VDD")
	)
	(gr_poly
		(pts
			(xy 276.441916 -300.397418) (xy 276.449028 -300.390052)
			(arc
				(start 276.495002 -300.344078)
				(mid 276.505928 -300.327632)
				(end 276.509734 -300.308264)
			)
			(arc
				(start 276.509734 -297.55211)
				(mid 276.513069 -297.534007)
				(end 276.522688 -297.518328)
			)
			(xy 276.529038 -297.511216) (xy 276.535642 -297.493944) (xy 276.535642 -297.29176) (xy 276.528022 -297.272964)
			(xy 276.520656 -297.265852)
			(arc
				(start 276.372828 -297.118024)
				(mid 276.356294 -297.106913)
				(end 276.33676 -297.103038)
			)
			(xy 275.860764 -297.103038) (xy 275.841968 -297.110658) (xy 275.834856 -297.118024)
			(arc
				(start 275.737828 -297.215052)
				(mid 275.726717 -297.231586)
				(end 275.722842 -297.25112)
			)
			(xy 275.722842 -300.29404) (xy 275.745702 -300.32198)
			(arc
				(start 275.763736 -300.325536)
				(mid 275.840439 -300.350654)
				(end 275.90877 -300.393608)
			)
			(arc
				(start 275.90877 -300.393608)
				(mid 275.923793 -300.402049)
				(end 275.940774 -300.405038)
			)
			(xy 276.42312 -300.405038)
		)
		(stroke
			(width 0)
			(type solid)
		)
		(fill yes)
		(layer "B.Cu")
		(net "GND")
	)
	(gr_poly
		(pts
			(arc
				(start 449.197984 -280.459688)
				(mid 449.217507 -280.455787)
				(end 449.234052 -280.444702)
			)
			(arc
				(start 449.61556 -280.063194)
				(mid 449.626671 -280.04666)
				(end 449.630546 -280.027126)
			)
			(arc
				(start 449.630546 -273.771614)
				(mid 449.634447 -273.752091)
				(end 449.645532 -273.735546)
			)
			(arc
				(start 449.670678 -273.7104)
				(mid 449.681789 -273.693866)
				(end 449.685664 -273.674332)
			)
			(arc
				(start 449.685664 -272.550382)
				(mid 449.681763 -272.530859)
				(end 449.670678 -272.514314)
			)
			(xy 449.66509 -272.508726)
			(arc
				(start 447.367406 -272.508726)
				(mid 447.347883 -272.512627)
				(end 447.331338 -272.523712)
			)
			(arc
				(start 446.967864 -272.887186)
				(mid 446.956938 -272.903632)
				(end 446.953132 -272.923)
			)
			(arc
				(start 446.953132 -280.251154)
				(mid 446.956965 -280.270511)
				(end 446.967864 -280.286968)
			)
			(arc
				(start 447.125598 -280.444702)
				(mid 447.142132 -280.455813)
				(end 447.161666 -280.459688)
			)
		)
		(stroke
			(width 0)
			(type solid)
		)
		(fill yes)
		(layer "B.Cu")
		(net "GND")
	)
	(gr_poly
		(pts
			(arc
				(start 44.213018 -300.405038)
				(mid 44.232541 -300.401137)
				(end 44.249086 -300.390052)
			)
			(arc
				(start 44.29506 -300.344078)
				(mid 44.305986 -300.327632)
				(end 44.309792 -300.308264)
			)
			(arc
				(start 44.309792 -297.55211)
				(mid 44.313742 -297.532723)
				(end 44.324778 -297.516296)
			)
			(xy 44.32808 -297.512994) (xy 44.3357 -297.494452)
			(arc
				(start 44.3357 -297.30192)
				(mid 44.331799 -297.282397)
				(end 44.320714 -297.265852)
			)
			(arc
				(start 44.172886 -297.118024)
				(mid 44.156352 -297.106913)
				(end 44.136818 -297.103038)
			)
			(arc
				(start 43.670982 -297.103038)
				(mid 43.651459 -297.106939)
				(end 43.634914 -297.118024)
			)
			(arc
				(start 43.537886 -297.215052)
				(mid 43.526775 -297.231586)
				(end 43.5229 -297.25112)
			)
			(arc
				(start 43.5229 -300.307756)
				(mid 43.526801 -300.327279)
				(end 43.537886 -300.343824)
			)
			(arc
				(start 43.584114 -300.390052)
				(mid 43.600648 -300.401163)
				(end 43.620182 -300.405038)
			)
		)
		(stroke
			(width 0)
			(type solid)
		)
		(fill yes)
		(layer "B.Cu")
		(net "GND")
	)
	(gr_poly
		(pts
			(arc
				(start 142.72006 -201.84618)
				(mid 142.739583 -201.842279)
				(end 142.756128 -201.831194)
			)
			(arc
				(start 143.044926 -201.542396)
				(mid 143.056037 -201.525862)
				(end 143.059912 -201.506328)
			)
			(arc
				(start 143.059912 -200.90003)
				(mid 143.056011 -200.880507)
				(end 143.044926 -200.863962)
			)
			(arc
				(start 142.8496 -200.668636)
				(mid 142.833066 -200.657525)
				(end 142.813532 -200.65365)
			)
			(arc
				(start 141.089634 -200.65365)
				(mid 141.070111 -200.657551)
				(end 141.053566 -200.668636)
			)
			(arc
				(start 140.963396 -200.758806)
				(mid 140.952285 -200.77534)
				(end 140.94841 -200.794874)
			)
			(arc
				(start 140.94841 -201.667618)
				(mid 140.952311 -201.687141)
				(end 140.963396 -201.703686)
			)
			(arc
				(start 141.044676 -201.784966)
				(mid 141.061093 -201.796028)
				(end 141.08049 -201.799952)
			)
			(arc
				(start 141.793214 -201.799952)
				(mid 141.893841 -201.810554)
				(end 141.990064 -201.841862)
			)
			(xy 141.99997 -201.84618)
		)
		(stroke
			(width 0)
			(type solid)
		)
		(fill yes)
		(layer "B.Cu")
		(net "P1V8_CLI_VCORE")
	)
	(gr_poly
		(pts
			(xy 282.161234 -302.281336)
			(arc
				(start 300.015656 -302.281336)
				(mid 300.035013 -302.277503)
				(end 300.05147 -302.266604)
			)
			(xy 300.125384 -302.19269)
			(arc
				(start 300.125892 -302.192182)
				(mid 300.136634 -302.175825)
				(end 300.14037 -302.156622)
			)
			(arc
				(start 300.14037 -301.857156)
				(mid 300.136469 -301.837633)
				(end 300.125384 -301.821088)
			)
			(arc
				(start 300.038008 -301.733712)
				(mid 300.021562 -301.722786)
				(end 300.002194 -301.71898)
			)
			(xy 282.029408 -301.71898) (xy 282.029408 -301.718726)
			(arc
				(start 281.745944 -301.718726)
				(mid 281.726421 -301.722627)
				(end 281.709876 -301.733712)
			)
			(arc
				(start 281.685238 -301.75835)
				(mid 281.674312 -301.774796)
				(end 281.670506 -301.794164)
			)
			(arc
				(start 281.670506 -302.231298)
				(mid 281.674407 -302.250821)
				(end 281.685492 -302.267366)
			)
			(xy 281.687016 -302.26889)
			(arc
				(start 281.688286 -302.269906)
				(mid 281.70399 -302.27946)
				(end 281.722068 -302.28286)
			)
			(xy 282.159964 -302.28286)
		)
		(stroke
			(width 0)
			(type solid)
		)
		(fill yes)
		(layer "B.Cu")
		(net "GND")
	)
	(gr_poly
		(pts
			(xy 240.730278 -278.508968) (xy 241.801396 -278.508968) (xy 241.883184 -278.42718) (xy 241.883184 -277.58263)
			(xy 241.012726 -276.712172) (xy 241.012726 -275.346414)
			(arc
				(start 242.931188 -273.427952)
				(mid 242.942299 -273.411418)
				(end 242.946174 -273.391884)
			)
			(arc
				(start 242.946174 -261.900924)
				(mid 242.942273 -261.881401)
				(end 242.931188 -261.864856)
			)
			(arc
				(start 242.778026 -261.711694)
				(mid 242.761492 -261.700583)
				(end 242.741958 -261.696708)
			)
			(arc
				(start 236.546136 -261.696708)
				(mid 236.526613 -261.700609)
				(end 236.510068 -261.711694)
			)
			(arc
				(start 236.26445 -261.957312)
				(mid 236.253388 -261.973729)
				(end 236.249464 -261.993126)
			)
			(xy 236.249464 -271.981422) (xy 236.24921 -271.986502) (xy 235.91774 -272.317972) (xy 235.174536 -272.317972)
			(xy 234.991656 -272.500852) (xy 234.991656 -273.244056) (xy 234.991656 -275.693124) (xy 235.018072 -275.71954)
			(xy 235.018072 -276.008846) (xy 234.333288 -276.69363) (xy 234.333288 -278.159464) (xy 234.688888 -278.515064)
			(xy 240.724182 -278.515064)
		)
		(stroke
			(width 0)
			(type solid)
		)
		(fill yes)
		(layer "B.Cu")
		(net "P1V25_PEX2")
	)
	(gr_poly
		(pts
			(xy 251.94768 -86.66099)
			(arc
				(start 251.94768 -86.154006)
				(mid 251.945216 -86.138376)
				(end 251.938028 -86.124288)
			)
			(arc
				(start 251.938028 -86.124288)
				(mid 251.869306 -85.989626)
				(end 251.845572 -85.840316)
			)
			(arc
				(start 251.845572 -85.840316)
				(mid 251.869306 -85.691006)
				(end 251.938028 -85.556344)
			)
			(arc
				(start 251.938028 -85.556344)
				(mid 251.945175 -85.542243)
				(end 251.94768 -85.526626)
			)
			(arc
				(start 251.94768 -84.337398)
				(mid 251.943779 -84.317875)
				(end 251.932694 -84.30133)
			)
			(arc
				(start 251.835666 -84.204302)
				(mid 251.819132 -84.193191)
				(end 251.799598 -84.189316)
			)
			(arc
				(start 250.317762 -84.189316)
				(mid 250.298239 -84.193217)
				(end 250.281694 -84.204302)
			)
			(arc
				(start 250.057666 -84.42833)
				(mid 250.046555 -84.444864)
				(end 250.04268 -84.464398)
			)
			(xy 250.04268 -85.885782) (xy 250.939808 -86.78291) (xy 251.82576 -86.78291)
		)
		(stroke
			(width 0)
			(type solid)
		)
		(fill yes)
		(layer "B.Cu")
		(net "P3V3")
	)
	(gr_poly
		(pts
			(arc
				(start 393.529058 -300.506638)
				(mid 393.548581 -300.502737)
				(end 393.565126 -300.491652)
			)
			(arc
				(start 393.595098 -300.46168)
				(mid 393.606209 -300.445146)
				(end 393.610084 -300.425612)
			)
			(arc
				(start 393.610084 -297.765724)
				(mid 393.606183 -297.746201)
				(end 393.595098 -297.729656)
			)
			(arc
				(start 393.472162 -297.60672)
				(mid 393.441227 -297.591965)
				(end 393.4079 -297.600116)
			)
			(arc
				(start 393.4079 -297.600116)
				(mid 393.32055 -297.641315)
				(end 393.22502 -297.655488)
			)
			(arc
				(start 393.224766 -297.655488)
				(mid 393.124727 -297.639994)
				(end 393.034012 -297.595036)
			)
			(xy 393.027662 -297.59021) (xy 393.01293 -297.585638)
			(arc
				(start 392.936222 -297.585638)
				(mid 392.916699 -297.589539)
				(end 392.900154 -297.600624)
			)
			(xy 392.879326 -297.621452) (xy 392.87196 -297.628564) (xy 392.86434 -297.64736) (xy 392.86434 -300.285658)
			(xy 393.08532 -300.506638)
		)
		(stroke
			(width 0)
			(type solid)
		)
		(fill yes)
		(layer "B.Cu")
		(net "P1V8_VDDA_PEX3")
	)
	(gr_poly
		(pts
			(arc
				(start 2.287524 -278.305514)
				(mid 2.307047 -278.301613)
				(end 2.323592 -278.290528)
			)
			(arc
				(start 2.636774 -277.977346)
				(mid 2.647885 -277.960812)
				(end 2.65176 -277.941278)
			)
			(arc
				(start 2.65176 -270.039846)
				(mid 2.647859 -270.020323)
				(end 2.636774 -270.003778)
			)
			(arc
				(start 2.59588 -269.962884)
				(mid 2.579434 -269.951958)
				(end 2.560066 -269.948152)
			)
			(arc
				(start 2.24917 -269.948152)
				(mid 2.229783 -269.944202)
				(end 2.213356 -269.933166)
			)
			(arc
				(start 2.189988 -269.910052)
				(mid 2.173571 -269.89899)
				(end 2.154174 -269.895066)
			)
			(arc
				(start 1.50622 -269.895066)
				(mid 1.486697 -269.898967)
				(end 1.470152 -269.910052)
			)
			(arc
				(start 1.332484 -270.04772)
				(mid 1.321373 -270.064254)
				(end 1.317498 -270.083788)
			)
			(arc
				(start 1.317498 -278.226012)
				(mid 1.321282 -278.245506)
				(end 1.33223 -278.26208)
			)
			(arc
				(start 1.360678 -278.290528)
				(mid 1.377212 -278.301639)
				(end 1.396746 -278.305514)
			)
		)
		(stroke
			(width 0)
			(type solid)
		)
		(fill yes)
		(layer "B.Cu")
		(net "GND")
	)
	(gr_poly
		(pts
			(arc
				(start 299.98416 -291.972238)
				(mid 300.003683 -291.968337)
				(end 300.020228 -291.957252)
			)
			(arc
				(start 300.117256 -291.860224)
				(mid 300.128367 -291.84369)
				(end 300.132242 -291.824156)
			)
			(arc
				(start 300.132242 -291.56152)
				(mid 300.128341 -291.541997)
				(end 300.117256 -291.525452)
			)
			(arc
				(start 299.969428 -291.377624)
				(mid 299.952894 -291.366513)
				(end 299.93336 -291.362638)
			)
			(arc
				(start 283.160724 -291.362638)
				(mid 283.141201 -291.366539)
				(end 283.124656 -291.377624)
			)
			(xy 283.088842 -291.413438)
			(arc
				(start 283.088842 -291.425376)
				(mid 283.138501 -291.519624)
				(end 283.155644 -291.624766)
			)
			(arc
				(start 283.155644 -291.624766)
				(mid 283.140835 -291.722621)
				(end 283.097732 -291.81171)
			)
			(xy 283.093414 -291.818314) (xy 283.088842 -291.832538) (xy 283.088842 -291.935916) (xy 283.096462 -291.954458)
			(arc
				(start 283.099256 -291.957252)
				(mid 283.11579 -291.968363)
				(end 283.135324 -291.972238)
			)
		)
		(stroke
			(width 0)
			(type solid)
		)
		(fill yes)
		(layer "B.Cu")
		(net "GND")
	)
	(gr_poly
		(pts
			(arc
				(start 44.213018 -296.595038)
				(mid 44.232541 -296.591137)
				(end 44.249086 -296.580052)
			)
			(arc
				(start 44.29506 -296.534078)
				(mid 44.305986 -296.517632)
				(end 44.309792 -296.498264)
			)
			(arc
				(start 44.309792 -291.611812)
				(mid 44.305959 -291.592455)
				(end 44.29506 -291.575998)
			)
			(arc
				(start 44.237656 -291.518594)
				(mid 44.221239 -291.507532)
				(end 44.201842 -291.503608)
			)
			(arc
				(start 43.656758 -291.503608)
				(mid 43.637371 -291.507558)
				(end 43.620944 -291.518594)
			)
			(arc
				(start 43.487086 -291.652452)
				(mid 43.475975 -291.668986)
				(end 43.4721 -291.68852)
			)
			(xy 43.4721 -293.427658)
			(arc
				(start 43.473116 -293.432738)
				(mid 43.480147 -293.478601)
				(end 43.482514 -293.52494)
			)
			(arc
				(start 43.482514 -293.52494)
				(mid 43.480162 -293.571281)
				(end 43.473116 -293.617142)
			)
			(xy 43.4721 -293.622222)
			(arc
				(start 43.4721 -296.421556)
				(mid 43.476001 -296.441079)
				(end 43.487086 -296.457624)
			)
			(arc
				(start 43.609514 -296.580052)
				(mid 43.626048 -296.591163)
				(end 43.645582 -296.595038)
			)
		)
		(stroke
			(width 0)
			(type solid)
		)
		(fill yes)
		(layer "B.Cu")
		(net "GND")
	)
	(gr_poly
		(pts
			(arc
				(start 100.56749 -356.263448)
				(mid 100.587013 -356.259547)
				(end 100.603558 -356.248462)
			)
			(arc
				(start 100.795074 -356.056946)
				(mid 100.806185 -356.040412)
				(end 100.81006 -356.020878)
			)
			(xy 100.81006 -355.64318)
			(arc
				(start 100.808536 -355.637084)
				(mid 100.79981 -355.590836)
				(end 100.796852 -355.543866)
			)
			(arc
				(start 100.796852 -355.543866)
				(mid 100.799817 -355.496897)
				(end 100.808536 -355.450648)
			)
			(xy 100.81006 -355.444552)
			(arc
				(start 100.81006 -354.539042)
				(mid 100.806159 -354.519519)
				(end 100.795074 -354.502974)
			)
			(arc
				(start 100.533454 -354.241608)
				(mid 100.51692 -354.230497)
				(end 100.497386 -354.226622)
			)
			(xy 99.530408 -354.226622) (xy 99.50196 -354.22586)
			(arc
				(start 99.501706 -354.22586)
				(mid 99.463859 -354.239525)
				(end 99.447858 -354.276406)
			)
			(arc
				(start 99.447858 -356.140258)
				(mid 99.451759 -356.159781)
				(end 99.462844 -356.176326)
			)
			(arc
				(start 99.53498 -356.248462)
				(mid 99.551514 -356.259573)
				(end 99.571048 -356.263448)
			)
		)
		(stroke
			(width 0)
			(type solid)
		)
		(fill yes)
		(layer "B.Cu")
		(net "P3V3_CLK_BUFFER_9ZXL0451E_S3_VZX3P3")
	)
	(gr_poly
		(pts
			(arc
				(start 102.440994 -328.66838)
				(mid 102.487242 -328.659654)
				(end 102.534212 -328.656696)
			)
			(arc
				(start 102.534212 -328.656696)
				(mid 102.581181 -328.659661)
				(end 102.62743 -328.66838)
			)
			(xy 102.633526 -328.669904)
			(arc
				(start 103.539036 -328.669904)
				(mid 103.558559 -328.666003)
				(end 103.575104 -328.654918)
			)
			(arc
				(start 103.83647 -328.393298)
				(mid 103.847581 -328.376764)
				(end 103.851456 -328.35723)
			)
			(xy 103.851456 -327.390252) (xy 103.852218 -327.361804)
			(arc
				(start 103.852218 -327.36155)
				(mid 103.838553 -327.323703)
				(end 103.801672 -327.307702)
			)
			(arc
				(start 101.93782 -327.307702)
				(mid 101.918297 -327.311603)
				(end 101.901752 -327.322688)
			)
			(arc
				(start 101.829616 -327.394824)
				(mid 101.818505 -327.411358)
				(end 101.81463 -327.430892)
			)
			(arc
				(start 101.81463 -328.427334)
				(mid 101.818531 -328.446857)
				(end 101.829616 -328.463402)
			)
			(arc
				(start 102.021132 -328.654918)
				(mid 102.037666 -328.666029)
				(end 102.0572 -328.669904)
			)
			(xy 102.434898 -328.669904)
		)
		(stroke
			(width 0)
			(type solid)
		)
		(fill yes)
		(layer "B.Cu")
		(net "P3V3_CLK_BUFFER_9ZXL0451E_VZX3P3")
	)
	(gr_poly
		(pts
			(arc
				(start 160.313116 -296.595038)
				(mid 160.332639 -296.591137)
				(end 160.349184 -296.580052)
			)
			(arc
				(start 160.395158 -296.534078)
				(mid 160.406084 -296.517632)
				(end 160.40989 -296.498264)
			)
			(arc
				(start 160.40989 -291.611812)
				(mid 160.406057 -291.592455)
				(end 160.395158 -291.575998)
			)
			(arc
				(start 160.337754 -291.518594)
				(mid 160.321337 -291.507532)
				(end 160.30194 -291.503608)
			)
			(arc
				(start 159.756856 -291.503608)
				(mid 159.737469 -291.507558)
				(end 159.721042 -291.518594)
			)
			(arc
				(start 159.587184 -291.652452)
				(mid 159.576073 -291.668986)
				(end 159.572198 -291.68852)
			)
			(xy 159.572198 -293.427658)
			(arc
				(start 159.573214 -293.432738)
				(mid 159.580245 -293.478601)
				(end 159.582612 -293.52494)
			)
			(arc
				(start 159.582612 -293.52494)
				(mid 159.58026 -293.571281)
				(end 159.573214 -293.617142)
			)
			(xy 159.572198 -293.622222)
			(arc
				(start 159.572198 -296.421556)
				(mid 159.576099 -296.441079)
				(end 159.587184 -296.457624)
			)
			(arc
				(start 159.709612 -296.580052)
				(mid 159.726146 -296.591163)
				(end 159.74568 -296.595038)
			)
		)
		(stroke
			(width 0)
			(type solid)
		)
		(fill yes)
		(layer "B.Cu")
		(net "GND")
	)
	(gr_poly
		(pts
			(arc
				(start 392.513058 -296.595038)
				(mid 392.532581 -296.591137)
				(end 392.549126 -296.580052)
			)
			(arc
				(start 392.5951 -296.534078)
				(mid 392.606026 -296.517632)
				(end 392.609832 -296.498264)
			)
			(arc
				(start 392.609832 -291.611812)
				(mid 392.605999 -291.592455)
				(end 392.5951 -291.575998)
			)
			(arc
				(start 392.537696 -291.518594)
				(mid 392.521279 -291.507532)
				(end 392.501882 -291.503608)
			)
			(arc
				(start 391.956798 -291.503608)
				(mid 391.937411 -291.507558)
				(end 391.920984 -291.518594)
			)
			(arc
				(start 391.787126 -291.652452)
				(mid 391.776015 -291.668986)
				(end 391.77214 -291.68852)
			)
			(xy 391.77214 -293.427658)
			(arc
				(start 391.773156 -293.432738)
				(mid 391.780187 -293.478601)
				(end 391.782554 -293.52494)
			)
			(arc
				(start 391.782554 -293.52494)
				(mid 391.780202 -293.571281)
				(end 391.773156 -293.617142)
			)
			(xy 391.77214 -293.622222)
			(arc
				(start 391.77214 -296.421556)
				(mid 391.776041 -296.441079)
				(end 391.787126 -296.457624)
			)
			(arc
				(start 391.909554 -296.580052)
				(mid 391.926088 -296.591163)
				(end 391.945622 -296.595038)
			)
		)
		(stroke
			(width 0)
			(type solid)
		)
		(fill yes)
		(layer "B.Cu")
		(net "GND")
	)
	(gr_poly
		(pts
			(xy 68.339716 -305.173126) (xy 68.339716 -304.608484) (xy 68.133976 -304.402998) (xy 68.126864 -304.395632)
			(xy 68.108068 -304.388012)
			(arc
				(start 49.920398 -304.388012)
				(mid 49.900875 -304.391913)
				(end 49.88433 -304.402998)
			)
			(xy 49.846738 -304.44059)
			(arc
				(start 49.841658 -304.446432)
				(mid 49.834254 -304.460746)
				(end 49.831752 -304.476658)
			)
			(arc
				(start 49.831752 -304.604674)
				(mid 49.837913 -304.628923)
				(end 49.854866 -304.647346)
			)
			(arc
				(start 49.854866 -304.647346)
				(mid 49.965399 -304.766902)
				(end 50.005488 -304.924714)
			)
			(arc
				(start 50.005488 -304.924714)
				(mid 49.991591 -305.019069)
				(end 49.951386 -305.105562)
			)
			(xy 49.947576 -305.111404) (xy 49.943512 -305.124612)
			(arc
				(start 49.943258 -305.131724)
				(mid 49.944565 -305.14509)
				(end 49.949354 -305.157632)
			)
			(arc
				(start 49.991772 -305.236372)
				(mid 50.010448 -305.255868)
				(end 50.036476 -305.263042)
			)
			(xy 68.2498 -305.263042)
		)
		(stroke
			(width 0)
			(type solid)
		)
		(fill yes)
		(layer "B.Cu")
		(net "P1V25_SERDES_VDDPLL_PEX0")
	)
	(gr_poly
		(pts
			(arc
				(start 161.329116 -300.506638)
				(mid 161.348639 -300.502737)
				(end 161.365184 -300.491652)
			)
			(arc
				(start 161.395156 -300.46168)
				(mid 161.406267 -300.445146)
				(end 161.410142 -300.425612)
			)
			(arc
				(start 161.410142 -297.765724)
				(mid 161.406241 -297.746201)
				(end 161.395156 -297.729656)
			)
			(xy 161.259266 -297.593766) (xy 161.223198 -297.59021)
			(arc
				(start 161.207958 -297.600116)
				(mid 161.120608 -297.641315)
				(end 161.025078 -297.655488)
			)
			(arc
				(start 161.024824 -297.655488)
				(mid 160.924785 -297.639994)
				(end 160.83407 -297.595036)
			)
			(xy 160.82772 -297.59021) (xy 160.812988 -297.585638)
			(arc
				(start 160.73628 -297.585638)
				(mid 160.716757 -297.589539)
				(end 160.700212 -297.600624)
			)
			(xy 160.679384 -297.621452) (xy 160.672018 -297.628564) (xy 160.664398 -297.64736)
			(arc
				(start 160.664398 -300.434756)
				(mid 160.668299 -300.454279)
				(end 160.679384 -300.470824)
			)
			(xy 160.700212 -300.491652) (xy 160.707324 -300.499018) (xy 160.72612 -300.506638)
		)
		(stroke
			(width 0)
			(type solid)
		)
		(fill yes)
		(layer "B.Cu")
		(net "P1V8_VDDA_PEX1")
	)
	(gr_poly
		(pts
			(arc
				(start 256.752598 -90.539316)
				(mid 256.772121 -90.535415)
				(end 256.788666 -90.52433)
			)
			(arc
				(start 256.885694 -90.427302)
				(mid 256.896805 -90.410768)
				(end 256.90068 -90.391234)
			)
			(xy 256.90068 -88.229694) (xy 257.151632 -87.978742) (xy 257.87477 -87.978742) (xy 258.004056 -87.849456)
			(xy 258.004056 -87.298784) (xy 257.899662 -87.19439)
			(arc
				(start 256.730754 -87.19439)
				(mid 256.714337 -87.183328)
				(end 256.69494 -87.179404)
			)
			(arc
				(start 256.498852 -87.179404)
				(mid 256.479495 -87.175571)
				(end 256.463038 -87.164672)
			)
			(arc
				(start 256.423414 -87.125302)
				(mid 256.406997 -87.11424)
				(end 256.3876 -87.110316)
			)
			(arc
				(start 256.159762 -87.110316)
				(mid 256.140239 -87.114217)
				(end 256.123694 -87.125302)
			)
			(arc
				(start 255.899666 -87.34933)
				(mid 255.888555 -87.365864)
				(end 255.88468 -87.385398)
			)
			(arc
				(start 255.88468 -90.264234)
				(mid 255.888581 -90.283757)
				(end 255.899666 -90.300302)
			)
			(arc
				(start 256.123694 -90.52433)
				(mid 256.140228 -90.535441)
				(end 256.159762 -90.539316)
			)
		)
		(stroke
			(width 0)
			(type solid)
		)
		(fill yes)
		(layer "B.Cu")
		(net "P3V3_CLK_GEN_VDDA25M_CK440")
	)
	(gr_poly
		(pts
			(arc
				(start 276.41296 -296.595038)
				(mid 276.432483 -296.591137)
				(end 276.449028 -296.580052)
			)
			(arc
				(start 276.495002 -296.534078)
				(mid 276.505928 -296.517632)
				(end 276.509734 -296.498264)
			)
			(arc
				(start 276.509734 -291.611812)
				(mid 276.505833 -291.592289)
				(end 276.494748 -291.575744)
			)
			(arc
				(start 276.437598 -291.518594)
				(mid 276.424776 -291.509135)
				(end 276.409658 -291.504116)
			)
			(xy 276.40153 -291.503608) (xy 275.856954 -291.503608)
			(arc
				(start 275.848826 -291.504116)
				(mid 275.833718 -291.509156)
				(end 275.820886 -291.518594)
			)
			(xy 275.687028 -291.652452) (xy 275.679662 -291.659564) (xy 275.672042 -291.67836) (xy 275.672042 -293.427658)
			(arc
				(start 275.673058 -293.432738)
				(mid 275.680089 -293.478601)
				(end 275.682456 -293.52494)
			)
			(arc
				(start 275.682456 -293.52494)
				(mid 275.680104 -293.571281)
				(end 275.673058 -293.617142)
			)
			(xy 275.672042 -293.622222)
			(arc
				(start 275.672042 -296.421556)
				(mid 275.675943 -296.441079)
				(end 275.687028 -296.457624)
			)
			(arc
				(start 275.809456 -296.580052)
				(mid 275.82599 -296.591163)
				(end 275.845524 -296.595038)
			)
		)
		(stroke
			(width 0)
			(type solid)
		)
		(fill yes)
		(layer "B.Cu")
		(net "GND")
	)
	(gr_poly
		(pts
			(xy 416.639756 -305.173126) (xy 416.639756 -304.608484) (xy 416.434016 -304.402998) (xy 416.426904 -304.395632)
			(xy 416.408108 -304.388012)
			(arc
				(start 398.220438 -304.388012)
				(mid 398.200915 -304.391913)
				(end 398.18437 -304.402998)
			)
			(xy 398.146778 -304.44059)
			(arc
				(start 398.141698 -304.446432)
				(mid 398.134294 -304.460746)
				(end 398.131792 -304.476658)
			)
			(arc
				(start 398.131792 -304.604674)
				(mid 398.137953 -304.628923)
				(end 398.154906 -304.647346)
			)
			(arc
				(start 398.154906 -304.647346)
				(mid 398.265439 -304.766902)
				(end 398.305528 -304.924714)
			)
			(arc
				(start 398.305528 -304.924714)
				(mid 398.291631 -305.019069)
				(end 398.251426 -305.105562)
			)
			(xy 398.247616 -305.111404) (xy 398.243552 -305.124612)
			(arc
				(start 398.243298 -305.131724)
				(mid 398.244605 -305.14509)
				(end 398.249394 -305.157632)
			)
			(arc
				(start 398.291812 -305.236372)
				(mid 398.310488 -305.255868)
				(end 398.336516 -305.263042)
			)
			(xy 416.54984 -305.263042)
		)
		(stroke
			(width 0)
			(type solid)
		)
		(fill yes)
		(layer "B.Cu")
		(net "P1V25_SERDES_VDDPLL_PEX3")
	)
	(gr_poly
		(pts
			(arc
				(start 104.937052 -394.028422)
				(mid 104.956575 -394.024521)
				(end 104.97312 -394.013436)
			)
			(arc
				(start 105.192068 -393.794488)
				(mid 105.203179 -393.777954)
				(end 105.207054 -393.75842)
			)
			(arc
				(start 105.207054 -390.562846)
				(mid 105.203153 -390.543323)
				(end 105.192068 -390.526778)
			)
			(arc
				(start 104.859582 -390.194292)
				(mid 104.843019 -390.183318)
				(end 104.823514 -390.17956)
			)
			(arc
				(start 102.495096 -390.17956)
				(mid 102.37885 -390.156228)
				(end 102.280212 -390.090406)
			)
			(arc
				(start 101.836982 -389.647176)
				(mid 101.820448 -389.636065)
				(end 101.800914 -389.63219)
			)
			(arc
				(start 101.450902 -389.63219)
				(mid 101.431379 -389.636091)
				(end 101.414834 -389.647176)
			)
			(arc
				(start 101.395276 -389.666734)
				(mid 101.384302 -389.683297)
				(end 101.380544 -389.702802)
			)
			(arc
				(start 101.380544 -393.622022)
				(mid 101.384328 -393.641516)
				(end 101.395276 -393.65809)
			)
			(arc
				(start 101.750622 -394.013436)
				(mid 101.767156 -394.024547)
				(end 101.78669 -394.028422)
			)
		)
		(stroke
			(width 0)
			(type solid)
		)
		(fill yes)
		(layer "B.Cu")
		(net "GND")
	)
	(gr_poly
		(pts
			(arc
				(start 107.878118 -360.426)
				(mid 107.897641 -360.422099)
				(end 107.914186 -360.411014)
			)
			(arc
				(start 108.544614 -359.780586)
				(mid 108.555725 -359.764052)
				(end 108.5596 -359.744518)
			)
			(arc
				(start 108.5596 -358.161082)
				(mid 108.555699 -358.141559)
				(end 108.544614 -358.125014)
			)
			(arc
				(start 108.472986 -358.053386)
				(mid 108.456452 -358.042275)
				(end 108.436918 -358.0384)
			)
			(arc
				(start 107.183682 -358.0384)
				(mid 107.164159 -358.042301)
				(end 107.147614 -358.053386)
			)
			(arc
				(start 106.872786 -358.328214)
				(mid 106.861675 -358.344748)
				(end 106.8578 -358.364282)
			)
			(arc
				(start 106.8578 -359.185718)
				(mid 106.853899 -359.205241)
				(end 106.842814 -359.221786)
			)
			(xy 106.759756 -359.304844)
			(arc
				(start 106.755946 -359.315512)
				(mid 106.736256 -359.36338)
				(end 106.712258 -359.409238)
			)
			(arc
				(start 106.712258 -359.409238)
				(mid 106.707145 -359.421612)
				(end 106.7054 -359.434892)
			)
			(arc
				(start 106.7054 -360.277918)
				(mid 106.709301 -360.297441)
				(end 106.720386 -360.313986)
			)
			(arc
				(start 106.817414 -360.411014)
				(mid 106.833948 -360.422125)
				(end 106.853482 -360.426)
			)
		)
		(stroke
			(width 0)
			(type solid)
		)
		(fill yes)
		(layer "B.Cu")
		(net "P3V3")
	)
	(gr_poly
		(pts
			(arc
				(start 240.083594 -218.953842)
				(mid 240.103117 -218.949941)
				(end 240.119662 -218.938856)
			)
			(arc
				(start 240.24971 -218.808808)
				(mid 240.260821 -218.792274)
				(end 240.264696 -218.77274)
			)
			(xy 240.264696 -217.739214) (xy 240.257076 -217.720418) (xy 240.24971 -217.713306)
			(arc
				(start 240.087658 -217.551)
				(mid 240.078252 -217.543539)
				(end 240.067338 -217.538554)
			)
			(xy 240.056162 -217.534998) (xy 240.044224 -217.536522)
			(arc
				(start 240.043716 -217.536522)
				(mid 240.016611 -217.539531)
				(end 239.98936 -217.540586)
			)
			(arc
				(start 239.98936 -217.540586)
				(mid 239.895382 -217.528765)
				(end 239.807242 -217.494104)
			)
			(arc
				(start 239.807242 -217.494104)
				(mid 239.795433 -217.489524)
				(end 239.782858 -217.488008)
			)
			(arc
				(start 237.988602 -217.488008)
				(mid 237.969079 -217.491909)
				(end 237.952534 -217.502994)
			)
			(arc
				(start 236.845602 -218.609926)
				(mid 236.834491 -218.62646)
				(end 236.830616 -218.645994)
			)
			(arc
				(start 236.830616 -218.666822)
				(mid 236.834566 -218.686209)
				(end 236.845602 -218.702636)
			)
			(arc
				(start 237.081822 -218.938856)
				(mid 237.098239 -218.949918)
				(end 237.117636 -218.953842)
			)
		)
		(stroke
			(width 0)
			(type solid)
		)
		(fill yes)
		(layer "B.Cu")
		(net "P1V2_BIC_ADCVREFREXT0")
	)
	(gr_poly
		(pts
			(arc
				(start 419.9382 -299.389038)
				(mid 419.957723 -299.385137)
				(end 419.974268 -299.374052)
			)
			(arc
				(start 420.008304 -299.340016)
				(mid 420.019415 -299.323482)
				(end 420.02329 -299.303948)
			)
			(arc
				(start 420.02329 -292.50894)
				(mid 420.019389 -292.489417)
				(end 420.008304 -292.472872)
			)
			(arc
				(start 419.904164 -292.368732)
				(mid 419.88763 -292.357621)
				(end 419.868096 -292.353746)
			)
			(arc
				(start 419.631368 -292.353746)
				(mid 419.611845 -292.357647)
				(end 419.5953 -292.368732)
			)
			(arc
				(start 419.477698 -292.486334)
				(mid 419.466587 -292.502868)
				(end 419.462712 -292.522402)
			)
			(arc
				(start 419.462712 -292.716458)
				(mid 419.466662 -292.735845)
				(end 419.477698 -292.752272)
			)
			(xy 419.481254 -292.756082) (xy 419.489128 -292.774624)
			(arc
				(start 419.489128 -298.98213)
				(mid 419.485178 -299.001517)
				(end 419.474142 -299.017944)
			)
			(xy 419.47084 -299.021246) (xy 419.46322 -299.039788)
			(arc
				(start 419.46322 -299.142912)
				(mid 419.467121 -299.162435)
				(end 419.478206 -299.17898)
			)
			(arc
				(start 419.673278 -299.374052)
				(mid 419.689812 -299.385163)
				(end 419.709346 -299.389038)
			)
		)
		(stroke
			(width 0)
			(type solid)
		)
		(fill yes)
		(layer "B.Cu")
		(net "GND")
	)
	(gr_poly
		(pts
			(arc
				(start 45.229018 -300.506638)
				(mid 45.248541 -300.502737)
				(end 45.265086 -300.491652)
			)
			(arc
				(start 45.295058 -300.46168)
				(mid 45.306169 -300.445146)
				(end 45.310044 -300.425612)
			)
			(arc
				(start 45.310044 -297.765724)
				(mid 45.306143 -297.746201)
				(end 45.295058 -297.729656)
			)
			(arc
				(start 45.166026 -297.600624)
				(mid 45.149492 -297.589513)
				(end 45.129958 -297.585638)
			)
			(arc
				(start 45.12818 -297.585638)
				(mid 45.032416 -297.637543)
				(end 44.92498 -297.655488)
			)
			(arc
				(start 44.92498 -297.655488)
				(mid 44.824907 -297.640064)
				(end 44.734226 -297.595036)
			)
			(xy 44.727622 -297.59021) (xy 44.71289 -297.585638)
			(arc
				(start 44.636182 -297.585638)
				(mid 44.616659 -297.589539)
				(end 44.600114 -297.600624)
			)
			(arc
				(start 44.579286 -297.621452)
				(mid 44.568175 -297.637986)
				(end 44.5643 -297.65752)
			)
			(arc
				(start 44.5643 -300.434756)
				(mid 44.568201 -300.454279)
				(end 44.579286 -300.470824)
			)
			(arc
				(start 44.600114 -300.491652)
				(mid 44.616648 -300.502763)
				(end 44.636182 -300.506638)
			)
		)
		(stroke
			(width 0)
			(type solid)
		)
		(fill yes)
		(layer "B.Cu")
		(net "P1V8_VDDA_PEX0")
	)
	(gr_poly
		(pts
			(arc
				(start 111.553498 -338.788502)
				(mid 111.573021 -338.784601)
				(end 111.589566 -338.773516)
			)
			(arc
				(start 111.920274 -338.442808)
				(mid 111.931385 -338.426274)
				(end 111.93526 -338.40674)
			)
			(arc
				(start 111.93526 -336.818732)
				(mid 111.931359 -336.799209)
				(end 111.920274 -336.782664)
			)
			(arc
				(start 111.625888 -336.488278)
				(mid 111.609354 -336.477167)
				(end 111.58982 -336.473292)
			)
			(arc
				(start 109.686852 -336.473292)
				(mid 109.667329 -336.477193)
				(end 109.650784 -336.488278)
			)
			(xy 109.61624 -336.522822) (xy 109.60862 -336.541872) (xy 109.608874 -336.552286) (xy 109.609128 -336.562954)
			(arc
				(start 109.609128 -337.128104)
				(mid 109.570337 -337.322648)
				(end 109.46003 -337.487514)
			)
			(arc
				(start 109.458252 -337.489546)
				(mid 109.453272 -337.537514)
				(end 109.443774 -337.584796)
			)
			(xy 109.442504 -337.590892)
			(arc
				(start 109.442504 -338.67217)
				(mid 109.446337 -338.691527)
				(end 109.457236 -338.707984)
			)
			(arc
				(start 109.522768 -338.773516)
				(mid 109.539302 -338.784627)
				(end 109.558836 -338.788502)
			)
		)
		(stroke
			(width 0)
			(type solid)
		)
		(fill yes)
		(layer "B.Cu")
		(net "GND")
	)
	(gr_poly
		(pts
			(xy 160.342072 -300.397418) (xy 160.349184 -300.390052)
			(arc
				(start 160.395158 -300.344078)
				(mid 160.406084 -300.327632)
				(end 160.40989 -300.308264)
			)
			(arc
				(start 160.40989 -297.55211)
				(mid 160.413225 -297.534007)
				(end 160.422844 -297.518328)
			)
			(xy 160.429194 -297.511216) (xy 160.435798 -297.493944) (xy 160.435798 -297.29176) (xy 160.428178 -297.272964)
			(xy 160.420812 -297.265852)
			(arc
				(start 160.272984 -297.118024)
				(mid 160.25645 -297.106913)
				(end 160.236916 -297.103038)
			)
			(xy 159.76092 -297.103038) (xy 159.742124 -297.110658) (xy 159.735012 -297.118024)
			(arc
				(start 159.637984 -297.215052)
				(mid 159.626873 -297.231586)
				(end 159.622998 -297.25112)
			)
			(arc
				(start 159.622998 -298.03725)
				(mid 159.624584 -298.0501)
				(end 159.629348 -298.062142)
			)
			(arc
				(start 159.629348 -298.062142)
				(mid 159.68354 -298.197327)
				(end 159.701992 -298.341796)
			)
			(xy 159.701992 -300.31563) (xy 159.718756 -300.340776)
			(arc
				(start 159.732472 -300.346872)
				(mid 159.772298 -300.367626)
				(end 159.808926 -300.393608)
			)
			(arc
				(start 159.808926 -300.393608)
				(mid 159.823949 -300.402049)
				(end 159.84093 -300.405038)
			)
			(xy 160.323276 -300.405038)
		)
		(stroke
			(width 0)
			(type solid)
		)
		(fill yes)
		(layer "B.Cu")
		(net "GND")
	)
	(gr_poly
		(pts
			(arc
				(start 269.935706 -91.047316)
				(mid 269.955229 -91.043415)
				(end 269.971774 -91.03233)
			)
			(arc
				(start 270.53032 -90.473784)
				(mid 270.541431 -90.45725)
				(end 270.545306 -90.437716)
			)
			(arc
				(start 270.545306 -87.142828)
				(mid 270.541405 -87.123305)
				(end 270.53032 -87.10676)
			)
			(arc
				(start 270.255746 -86.832186)
				(mid 270.239212 -86.821075)
				(end 270.219678 -86.8172)
			)
			(arc
				(start 268.421612 -86.8172)
				(mid 268.402089 -86.821101)
				(end 268.385544 -86.832186)
			)
			(arc
				(start 266.9794 -88.23833)
				(mid 266.962866 -88.249441)
				(end 266.943332 -88.253316)
			)
			(arc
				(start 266.215368 -88.253316)
				(mid 266.195981 -88.257266)
				(end 266.179554 -88.268302)
			)
			(arc
				(start 266.016994 -88.430862)
				(mid 265.980348 -88.4638)
				(end 265.94054 -88.492838)
			)
			(arc
				(start 265.94054 -88.492838)
				(mid 265.923764 -88.511165)
				(end 265.91768 -88.535256)
			)
			(xy 265.91768 -90.888312) (xy 265.9253 -90.906854)
			(arc
				(start 265.928094 -90.909648)
				(mid 265.931995 -90.929171)
				(end 265.94308 -90.945716)
			)
			(arc
				(start 266.029694 -91.03233)
				(mid 266.046228 -91.043441)
				(end 266.065762 -91.047316)
			)
		)
		(stroke
			(width 0)
			(type solid)
		)
		(fill yes)
		(layer "B.Cu")
		(net "P3V3")
	)
	(gr_poly
		(pts
			(arc
				(start 277.42896 -300.506638)
				(mid 277.448483 -300.502737)
				(end 277.465028 -300.491652)
			)
			(arc
				(start 277.495 -300.46168)
				(mid 277.506111 -300.445146)
				(end 277.509986 -300.425612)
			)
			(arc
				(start 277.509986 -297.765724)
				(mid 277.506085 -297.746201)
				(end 277.495 -297.729656)
			)
			(arc
				(start 277.372064 -297.60672)
				(mid 277.341129 -297.591965)
				(end 277.307802 -297.600116)
			)
			(arc
				(start 277.307802 -297.600116)
				(mid 277.220452 -297.641315)
				(end 277.124922 -297.655488)
			)
			(arc
				(start 277.124668 -297.655488)
				(mid 277.024629 -297.639994)
				(end 276.933914 -297.595036)
			)
			(xy 276.927564 -297.59021) (xy 276.912832 -297.585638)
			(arc
				(start 276.836124 -297.585638)
				(mid 276.816601 -297.589539)
				(end 276.800056 -297.600624)
			)
			(xy 276.779228 -297.621452) (xy 276.771862 -297.628564) (xy 276.764242 -297.64736)
			(arc
				(start 276.764242 -300.434756)
				(mid 276.768143 -300.454279)
				(end 276.779228 -300.470824)
			)
			(arc
				(start 276.800056 -300.491652)
				(mid 276.81659 -300.502763)
				(end 276.836124 -300.506638)
			)
		)
		(stroke
			(width 0)
			(type solid)
		)
		(fill yes)
		(layer "B.Cu")
		(net "P1V8_VDDA_PEX2")
	)
	(gr_poly
		(pts
			(arc
				(start 13.233908 -291.280596)
				(mid 13.253431 -291.276695)
				(end 13.269976 -291.26561)
			)
			(arc
				(start 13.321792 -291.213794)
				(mid 13.332903 -291.19726)
				(end 13.336778 -291.177726)
			)
			(arc
				(start 13.336778 -278.709374)
				(mid 13.332877 -278.689851)
				(end 13.321792 -278.673306)
			)
			(xy 13.10894 -278.460454) (xy 13.101828 -278.453088) (xy 13.083032 -278.445468)
			(arc
				(start 2.874264 -278.445468)
				(mid 2.854741 -278.449369)
				(end 2.838196 -278.460454)
			)
			(xy 2.438146 -278.860504) (xy 2.43078 -278.867616) (xy 2.42316 -278.886412)
			(arc
				(start 2.42316 -280.857706)
				(mid 2.427061 -280.877229)
				(end 2.438146 -280.893774)
			)
			(arc
				(start 2.80289 -281.258518)
				(mid 2.819424 -281.269629)
				(end 2.838958 -281.273504)
			)
			(arc
				(start 4.380484 -281.273504)
				(mid 4.400007 -281.277405)
				(end 4.416552 -281.28849)
			)
			(arc
				(start 4.870958 -281.742896)
				(mid 4.882069 -281.75943)
				(end 4.885944 -281.778964)
			)
			(arc
				(start 4.885944 -290.785804)
				(mid 4.889845 -290.805327)
				(end 4.90093 -290.821872)
			)
			(arc
				(start 5.344668 -291.26561)
				(mid 5.361202 -291.276721)
				(end 5.380736 -291.280596)
			)
		)
		(stroke
			(width 0)
			(type solid)
		)
		(fill yes)
		(layer "B.Cu")
		(net "P1V25_PEX0_R")
	)
	(gr_poly
		(pts
			(arc
				(start 202.832208 -370.717572)
				(mid 202.858066 -370.713018)
				(end 202.884278 -370.711476)
			)
			(xy 203.15174 -370.711476) (xy 203.15174 -370.718842) (xy 203.677012 -370.718842) (xy 203.677012 -370.711476)
			(arc
				(start 203.944474 -370.711476)
				(mid 203.970688 -370.713001)
				(end 203.996544 -370.717572)
			)
			(xy 204.002386 -370.718842)
			(arc
				(start 204.077316 -370.718842)
				(mid 204.096839 -370.714941)
				(end 204.113384 -370.703856)
			)
			(arc
				(start 204.337412 -370.479828)
				(mid 204.348523 -370.463294)
				(end 204.352398 -370.44376)
			)
			(arc
				(start 204.352398 -369.342924)
				(mid 204.348497 -369.323401)
				(end 204.337412 -369.306856)
			)
			(arc
				(start 204.119988 -369.089432)
				(mid 204.103454 -369.078321)
				(end 204.08392 -369.074446)
			)
			(arc
				(start 202.969876 -369.074446)
				(mid 202.950353 -369.078347)
				(end 202.933808 -369.089432)
			)
			(arc
				(start 202.589384 -369.433856)
				(mid 202.578273 -369.45039)
				(end 202.574398 -369.469924)
			)
			(arc
				(start 202.574398 -370.57076)
				(mid 202.578299 -370.590283)
				(end 202.589384 -370.606828)
			)
			(arc
				(start 202.686412 -370.703856)
				(mid 202.702946 -370.714967)
				(end 202.72248 -370.718842)
			)
			(xy 202.826366 -370.718842)
		)
		(stroke
			(width 0)
			(type solid)
		)
		(fill yes)
		(layer "B.Cu")
		(net "AGND_HSC")
	)
	(gr_poly
		(pts
			(xy 218.95181 -279.804622) (xy 223.936052 -279.804622) (xy 223.959928 -279.780746) (xy 223.959928 -278.803862)
			(xy 224.159572 -278.604218) (xy 224.45599 -278.3078) (xy 224.45599 -275.653246) (xy 224.752154 -275.357082)
			(xy 224.787968 -275.321268) (xy 226.68103 -273.427952) (xy 226.797362 -273.31162) (xy 227.403406 -273.31162)
			(xy 227.403406 -272.618708) (xy 226.696016 -271.911318)
			(arc
				(start 226.696016 -261.900924)
				(mid 226.692115 -261.881401)
				(end 226.68103 -261.864856)
			)
			(arc
				(start 226.527868 -261.711694)
				(mid 226.511334 -261.700583)
				(end 226.4918 -261.696708)
			)
			(arc
				(start 220.295978 -261.696708)
				(mid 220.276455 -261.700609)
				(end 220.25991 -261.711694)
			)
			(arc
				(start 220.014292 -261.957312)
				(mid 220.00323 -261.973729)
				(end 219.999306 -261.993126)
			)
			(arc
				(start 219.999306 -271.981422)
				(mid 219.995473 -272.000779)
				(end 219.984574 -272.017236)
			)
			(arc
				(start 219.982034 -272.02003)
				(mid 219.970972 -272.036447)
				(end 219.967048 -272.055844)
			)
			(xy 219.967048 -272.089372) (xy 219.786708 -272.269712) (xy 218.045284 -272.269712) (xy 217.94343 -272.371566)
			(xy 217.94343 -272.515838) (xy 217.94343 -279.910794) (xy 217.96756 -279.934924) (xy 218.821508 -279.934924)
		)
		(stroke
			(width 0)
			(type solid)
		)
		(fill yes)
		(layer "B.Cu")
		(net "P1V25_PEX1")
	)
	(gr_poly
		(pts
			(arc
				(start 183.884316 -291.972238)
				(mid 183.903507 -291.968473)
				(end 183.919876 -291.95776)
			)
			(xy 183.92013 -291.957506) (xy 184.017412 -291.860224)
			(arc
				(start 184.01792 -291.859716)
				(mid 184.028662 -291.843359)
				(end 184.032398 -291.824156)
			)
			(arc
				(start 184.032398 -291.572442)
				(mid 184.028497 -291.552919)
				(end 184.017412 -291.536374)
			)
			(arc
				(start 183.858662 -291.377624)
				(mid 183.842128 -291.366513)
				(end 183.822594 -291.362638)
			)
			(arc
				(start 167.06088 -291.362638)
				(mid 167.041357 -291.366539)
				(end 167.024812 -291.377624)
			)
			(xy 167.001444 -291.400992) (xy 166.997126 -291.436044)
			(arc
				(start 167.006524 -291.45103)
				(mid 167.043238 -291.534473)
				(end 167.0558 -291.624766)
			)
			(arc
				(start 167.0558 -291.624766)
				(mid 167.041043 -291.722452)
				(end 166.998142 -291.811456)
			)
			(xy 166.997888 -291.811964) (xy 166.99357 -291.818314)
			(arc
				(start 166.991538 -291.824918)
				(mid 166.989684 -291.832568)
				(end 166.988998 -291.840412)
			)
			(arc
				(start 166.988998 -291.921438)
				(mid 167.003877 -291.957359)
				(end 167.039798 -291.972238)
			)
		)
		(stroke
			(width 0)
			(type solid)
		)
		(fill yes)
		(layer "B.Cu")
		(net "GND")
	)
	(gr_poly
		(pts
			(xy 453.45858 -280.2128) (xy 453.45858 -279.108408) (xy 453.678036 -278.888952) (xy 454.61936 -278.888952)
			(xy 454.768712 -278.7396) (xy 454.768712 -276.085046) (xy 455.077068 -275.77669) (xy 455.373232 -275.480526)
			(xy 455.409046 -275.444712) (xy 457.302108 -273.551396) (xy 457.876656 -273.551396) (xy 458.226414 -273.201638)
			(xy 458.226414 -272.577306) (xy 458.096112 -272.447004) (xy 457.591414 -272.447004) (xy 457.317094 -272.172684)
			(arc
				(start 457.317094 -262.024368)
				(mid 457.313193 -262.004845)
				(end 457.302108 -261.9883)
			)
			(arc
				(start 457.148946 -261.835138)
				(mid 457.132412 -261.824027)
				(end 457.112878 -261.820152)
			)
			(arc
				(start 450.917056 -261.820152)
				(mid 450.897533 -261.824053)
				(end 450.880988 -261.835138)
			)
			(arc
				(start 450.63537 -262.080756)
				(mid 450.624308 -262.097173)
				(end 450.620384 -262.11657)
			)
			(arc
				(start 450.620384 -272.104866)
				(mid 450.616551 -272.124223)
				(end 450.605652 -272.14068)
			)
			(arc
				(start 450.603112 -272.143474)
				(mid 450.59205 -272.159891)
				(end 450.588126 -272.179288)
			)
			(xy 450.588126 -272.212816) (xy 450.256656 -272.544286) (xy 449.990972 -272.544286) (xy 449.95846 -272.576798)
			(xy 449.95846 -280.139902) (xy 450.165978 -280.34742) (xy 453.32396 -280.34742)
		)
		(stroke
			(width 0)
			(type solid)
		)
		(fill yes)
		(layer "B.Cu")
		(net "P1V25_PEX3")
	)
	(gr_poly
		(pts
			(xy 107.611926 -321.86753) (xy 107.619546 -321.86753) (xy 107.688126 -321.79895) (xy 107.789472 -321.697604)
			(xy 109.798612 -321.697604) (xy 110.253018 -321.243452) (xy 117.380766 -321.243452) (xy 117.518942 -321.105276)
			(xy 117.518942 -319.610994) (xy 116.673884 -318.765936) (xy 116.673884 -315.715142) (xy 117.518942 -314.870084)
			(arc
				(start 117.518942 -308.764432)
				(mid 117.515041 -308.744909)
				(end 117.503956 -308.728364)
			)
			(arc
				(start 117.484144 -308.708552)
				(mid 117.46761 -308.697441)
				(end 117.448076 -308.693566)
			)
			(arc
				(start 113.928144 -308.693566)
				(mid 113.908621 -308.697467)
				(end 113.892076 -308.708552)
			)
			(arc
				(start 113.863882 -308.736746)
				(mid 113.852771 -308.75328)
				(end 113.848896 -308.772814)
			)
			(arc
				(start 113.848896 -318.72301)
				(mid 113.844995 -318.742533)
				(end 113.83391 -318.759078)
			)
			(arc
				(start 113.497106 -319.095882)
				(mid 113.480572 -319.106993)
				(end 113.461038 -319.110868)
			)
			(arc
				(start 99.891596 -319.110868)
				(mid 99.872073 -319.114769)
				(end 99.855528 -319.125854)
			)
			(arc
				(start 99.726496 -319.254886)
				(mid 99.715385 -319.27142)
				(end 99.71151 -319.290954)
			)
			(xy 99.71151 -322.262754) (xy 99.90836 -322.459604) (xy 102.992936 -322.459604) (xy 107.019852 -322.459604)
		)
		(stroke
			(width 0)
			(type solid)
		)
		(fill yes)
		(layer "B.Cu")
		(net "P0V8_SERDES_VDDA_PEX0")
	)
	(gr_poly
		(pts
			(arc
				(start 131.200906 -184.044844)
				(mid 131.220293 -184.040894)
				(end 131.23672 -184.029858)
			)
			(arc
				(start 131.277106 -183.989472)
				(mid 131.288217 -183.972938)
				(end 131.292092 -183.953404)
			)
			(arc
				(start 131.292092 -182.068978)
				(mid 131.288191 -182.049455)
				(end 131.277106 -182.03291)
			)
			(arc
				(start 130.966718 -181.722522)
				(mid 130.950184 -181.711411)
				(end 130.93065 -181.707536)
			)
			(arc
				(start 130.357372 -181.707536)
				(mid 130.337849 -181.711437)
				(end 130.321304 -181.722522)
			)
			(arc
				(start 129.926334 -182.117492)
				(mid 129.915223 -182.134026)
				(end 129.911348 -182.15356)
			)
			(arc
				(start 129.911348 -182.555642)
				(mid 129.915249 -182.575165)
				(end 129.926334 -182.59171)
			)
			(arc
				(start 130.139186 -182.804562)
				(mid 130.150297 -182.821096)
				(end 130.154172 -182.84063)
			)
			(arc
				(start 130.154172 -183.869584)
				(mid 130.169051 -183.905505)
				(end 130.204972 -183.920384)
			)
			(arc
				(start 130.475736 -183.920384)
				(mid 130.656064 -183.949618)
				(end 130.817874 -184.03443)
			)
			(arc
				(start 130.817874 -184.03443)
				(mid 130.832271 -184.042093)
				(end 130.848354 -184.044844)
			)
		)
		(stroke
			(width 0)
			(type solid)
		)
		(fill yes)
		(layer "B.Cu")
		(net "P3V3_DB2000QL_FB_VDD")
	)
	(gr_poly
		(pts
			(arc
				(start 228.293168 -293.567358)
				(mid 228.312691 -293.563457)
				(end 228.329236 -293.552372)
			)
			(arc
				(start 228.381052 -293.500556)
				(mid 228.392163 -293.484022)
				(end 228.396038 -293.464488)
			)
			(arc
				(start 228.396038 -280.996136)
				(mid 228.392137 -280.976613)
				(end 228.381052 -280.960068)
			)
			(arc
				(start 228.1682 -280.747216)
				(mid 228.151666 -280.736105)
				(end 228.132132 -280.73223)
			)
			(arc
				(start 217.933524 -280.73223)
				(mid 217.914001 -280.736131)
				(end 217.897456 -280.747216)
			)
			(arc
				(start 217.497406 -281.147266)
				(mid 217.486295 -281.1638)
				(end 217.48242 -281.183334)
			)
			(arc
				(start 217.48242 -283.144468)
				(mid 217.486321 -283.163991)
				(end 217.497406 -283.180536)
			)
			(arc
				(start 217.86215 -283.54528)
				(mid 217.878684 -283.556391)
				(end 217.898218 -283.560266)
			)
			(arc
				(start 219.439744 -283.560266)
				(mid 219.459267 -283.564167)
				(end 219.475812 -283.575252)
			)
			(arc
				(start 219.930218 -284.029658)
				(mid 219.941329 -284.046192)
				(end 219.945204 -284.065726)
			)
			(arc
				(start 219.945204 -293.072566)
				(mid 219.949105 -293.092089)
				(end 219.96019 -293.108634)
			)
			(arc
				(start 220.403928 -293.552372)
				(mid 220.420462 -293.563483)
				(end 220.439996 -293.567358)
			)
		)
		(stroke
			(width 0)
			(type solid)
		)
		(fill yes)
		(layer "B.Cu")
		(net "P1V25_PEX1_R")
	)
	(gr_poly
		(pts
			(arc
				(start 231.174036 -143.661384)
				(mid 231.193423 -143.657434)
				(end 231.20985 -143.646398)
			)
			(arc
				(start 231.23906 -143.617188)
				(mid 231.250171 -143.600654)
				(end 231.254046 -143.58112)
			)
			(xy 231.254046 -142.174214) (xy 230.570786 -141.490954) (xy 230.570786 -140.92174) (xy 230.604568 -140.887958)
			(xy 230.746046 -140.74648)
			(arc
				(start 230.746046 -139.813284)
				(mid 230.742145 -139.793761)
				(end 230.73106 -139.777216)
			)
			(arc
				(start 230.507032 -139.553188)
				(mid 230.495921 -139.536654)
				(end 230.492046 -139.51712)
			)
			(arc
				(start 230.492046 -138.501374)
				(mid 230.488096 -138.481987)
				(end 230.47706 -138.46556)
			)
			(arc
				(start 230.394002 -138.382248)
				(mid 230.38294 -138.365831)
				(end 230.379016 -138.346434)
			)
			(xy 230.379016 -137.785348) (xy 230.371396 -137.766552) (xy 230.365046 -137.760202)
			(arc
				(start 229.497128 -137.760202)
				(mid 229.477605 -137.764103)
				(end 229.46106 -137.775188)
			)
			(arc
				(start 229.364032 -137.872216)
				(mid 229.352921 -137.88875)
				(end 229.349046 -137.908284)
			)
			(arc
				(start 229.349046 -143.58112)
				(mid 229.352947 -143.600643)
				(end 229.364032 -143.617188)
			)
			(arc
				(start 229.393242 -143.646398)
				(mid 229.409659 -143.65746)
				(end 229.429056 -143.661384)
			)
		)
		(stroke
			(width 0)
			(type solid)
		)
		(fill yes)
		(layer "B.Cu")
		(net "P3V3_CLK_GEN_VDDXTAL_CK440_PEX")
	)
	(gr_poly
		(pts
			(arc
				(start 244.543326 -293.567358)
				(mid 244.562849 -293.563457)
				(end 244.579394 -293.552372)
			)
			(arc
				(start 244.63121 -293.500556)
				(mid 244.642321 -293.484022)
				(end 244.646196 -293.464488)
			)
			(arc
				(start 244.646196 -281.550364)
				(mid 244.642295 -281.530841)
				(end 244.63121 -281.514296)
			)
			(arc
				(start 244.16131 -281.044396)
				(mid 244.144776 -281.033285)
				(end 244.125242 -281.02941)
			)
			(arc
				(start 234.224576 -281.02941)
				(mid 234.205053 -281.033311)
				(end 234.188508 -281.044396)
			)
			(arc
				(start 233.917744 -281.31516)
				(mid 233.906633 -281.331694)
				(end 233.902758 -281.351228)
			)
			(arc
				(start 233.902758 -283.82849)
				(mid 233.906659 -283.848013)
				(end 233.917744 -283.864558)
			)
			(arc
				(start 234.002072 -283.948886)
				(mid 234.018606 -283.959997)
				(end 234.03814 -283.963872)
			)
			(arc
				(start 236.093508 -283.963872)
				(mid 236.113031 -283.967773)
				(end 236.129576 -283.978858)
			)
			(arc
				(start 236.180376 -284.029658)
				(mid 236.191487 -284.046192)
				(end 236.195362 -284.065726)
			)
			(arc
				(start 236.195362 -293.072566)
				(mid 236.199263 -293.092089)
				(end 236.210348 -293.108634)
			)
			(arc
				(start 236.654086 -293.552372)
				(mid 236.67062 -293.563483)
				(end 236.690154 -293.567358)
			)
		)
		(stroke
			(width 0)
			(type solid)
		)
		(fill yes)
		(layer "B.Cu")
		(net "P1V25_PEX2_R")
	)
	(gr_poly
		(pts
			(arc
				(start 129.624582 -173.909736)
				(mid 129.644105 -173.905835)
				(end 129.66065 -173.89475)
			)
			(arc
				(start 129.884678 -173.670722)
				(mid 129.895789 -173.654188)
				(end 129.899664 -173.634654)
			)
			(arc
				(start 129.899664 -173.2153)
				(mid 129.895763 -173.195777)
				(end 129.884678 -173.179232)
			)
			(arc
				(start 129.850642 -173.145196)
				(mid 129.839531 -173.128662)
				(end 129.835656 -173.109128)
			)
			(arc
				(start 129.835656 -172.075602)
				(mid 129.831755 -172.056079)
				(end 129.82067 -172.039534)
			)
			(arc
				(start 129.633472 -171.852336)
				(mid 129.616938 -171.841225)
				(end 129.597404 -171.83735)
			)
			(xy 128.508252 -171.83735) (xy 128.505966 -171.83989)
			(arc
				(start 127.890016 -171.83989)
				(mid 127.870493 -171.843791)
				(end 127.853948 -171.854876)
			)
			(arc
				(start 127.76327 -171.945554)
				(mid 127.752159 -171.962088)
				(end 127.748284 -171.981622)
			)
			(arc
				(start 127.748284 -172.289724)
				(mid 127.752185 -172.309247)
				(end 127.76327 -172.325792)
			)
			(arc
				(start 128.295908 -172.85843)
				(mid 128.307019 -172.874964)
				(end 128.310894 -172.894498)
			)
			(arc
				(start 128.310894 -173.691296)
				(mid 128.314795 -173.710819)
				(end 128.32588 -173.727364)
			)
			(arc
				(start 128.493266 -173.89475)
				(mid 128.5098 -173.905861)
				(end 128.529334 -173.909736)
			)
		)
		(stroke
			(width 0)
			(type solid)
		)
		(fill yes)
		(layer "B.Cu")
		(net "P3V3")
	)
	(gr_poly
		(pts
			(arc
				(start 281.90952 -304.19675)
				(mid 281.929043 -304.192849)
				(end 281.945588 -304.181764)
			)
			(arc
				(start 281.978608 -304.14849)
				(mid 281.995142 -304.137379)
				(end 282.014676 -304.133504)
			)
			(arc
				(start 300.081442 -304.133504)
				(mid 300.117363 -304.118625)
				(end 300.132242 -304.082704)
			)
			(xy 300.132242 -303.901348) (xy 300.124622 -303.882552) (xy 300.117256 -303.87544)
			(arc
				(start 299.875448 -303.633632)
				(mid 299.859002 -303.622706)
				(end 299.839634 -303.6189)
			)
			(xy 282.18257 -303.6189) (xy 282.17495 -303.618646) (xy 280.383234 -303.618646) (xy 280.364438 -303.626266)
			(xy 280.357326 -303.633632)
			(arc
				(start 280.337768 -303.65319)
				(mid 280.326657 -303.669724)
				(end 280.322782 -303.689258)
			)
			(xy 280.322782 -303.869344) (xy 280.341832 -303.89576)
			(arc
				(start 280.35758 -303.901094)
				(mid 280.476721 -303.956839)
				(end 280.57983 -304.038508)
			)
			(arc
				(start 280.708354 -304.166778)
				(mid 280.724888 -304.177889)
				(end 280.744422 -304.181764)
			)
			(arc
				(start 281.702764 -304.181764)
				(mid 281.712732 -304.182701)
				(end 281.722322 -304.185574)
			)
			(arc
				(start 281.739594 -304.19294)
				(mid 281.749184 -304.195813)
				(end 281.759152 -304.19675)
			)
		)
		(stroke
			(width 0)
			(type solid)
		)
		(fill yes)
		(layer "B.Cu")
		(net "GND")
	)
	(gr_poly
		(pts
			(arc
				(start 305.12004 -285.714186)
				(mid 305.139563 -285.710285)
				(end 305.156108 -285.6992)
			)
			(arc
				(start 305.280314 -285.574994)
				(mid 305.291425 -285.55846)
				(end 305.2953 -285.538926)
			)
			(xy 305.2953 -285.006796) (xy 305.295046 -285.002732) (xy 305.29403 -284.975046) (xy 305.29403 -284.974538)
			(xy 305.295046 -284.946852) (xy 305.2953 -284.942788) (xy 305.2953 -284.056836) (xy 305.295046 -284.052772)
			(xy 305.29403 -284.025086) (xy 305.29403 -284.024578) (xy 305.295046 -283.996892) (xy 305.2953 -283.992828)
			(arc
				(start 305.2953 -283.908246)
				(mid 305.291399 -283.888723)
				(end 305.280314 -283.872178)
			)
			(xy 304.91176 -283.503624) (xy 304.904648 -283.496258) (xy 304.885852 -283.488638)
			(arc
				(start 303.55159 -283.488638)
				(mid 303.515669 -283.503517)
				(end 303.50079 -283.539438)
			)
			(arc
				(start 303.50079 -285.09468)
				(mid 303.476892 -285.214821)
				(end 303.408842 -285.316676)
			)
			(arc
				(start 303.21123 -285.514542)
				(mid 303.196216 -285.55052)
				(end 303.21123 -285.586424)
			)
			(arc
				(start 303.324006 -285.6992)
				(mid 303.34054 -285.710311)
				(end 303.360074 -285.714186)
			)
		)
		(stroke
			(width 0)
			(type solid)
		)
		(fill yes)
		(layer "B.Cu")
		(net "P1V8_PEX")
	)
	(gr_poly
		(pts
			(arc
				(start 359.083356 -326.696832)
				(mid 359.102879 -326.692931)
				(end 359.119424 -326.681846)
			)
			(arc
				(start 360.392726 -325.408544)
				(mid 360.40926 -325.397433)
				(end 360.428794 -325.393558)
			)
			(xy 361.03052 -325.393558) (xy 361.061 -325.392796)
			(arc
				(start 367.055654 -325.392796)
				(mid 367.075041 -325.388846)
				(end 367.091468 -325.37781)
			)
			(arc
				(start 367.376456 -325.092822)
				(mid 367.387567 -325.076288)
				(end 367.391442 -325.056754)
			)
			(arc
				(start 367.391442 -324.632574)
				(mid 367.387541 -324.613051)
				(end 367.376456 -324.596506)
			)
			(arc
				(start 367.22812 -324.44817)
				(mid 367.211586 -324.437059)
				(end 367.192052 -324.433184)
			)
			(arc
				(start 359.934764 -324.433184)
				(mid 359.915241 -324.437085)
				(end 359.898696 -324.44817)
			)
			(arc
				(start 359.215436 -325.13143)
				(mid 359.198902 -325.142541)
				(end 359.179368 -325.146416)
			)
			(arc
				(start 350.26219 -325.146416)
				(mid 350.242667 -325.150317)
				(end 350.226122 -325.161402)
			)
			(arc
				(start 349.967804 -325.41972)
				(mid 349.956693 -325.436254)
				(end 349.952818 -325.455788)
			)
			(arc
				(start 349.952818 -326.387714)
				(mid 349.956719 -326.407237)
				(end 349.967804 -326.423782)
			)
			(arc
				(start 350.225868 -326.681846)
				(mid 350.242402 -326.692957)
				(end 350.261936 -326.696832)
			)
		)
		(stroke
			(width 0)
			(type solid)
		)
		(fill yes)
		(layer "B.Cu")
		(net "GND")
	)
	(gr_poly
		(pts
			(xy 15.633446 -390.125712) (xy 15.633446 -385.21513) (xy 15.633446 -384.715512) (xy 15.439898 -384.521964)
			(xy 15.438374 -384.521964) (xy 15.240508 -384.323844) (xy 15.240508 -383.793492) (xy 14.738604 -383.291588)
			(xy 14.131544 -383.291588) (xy 12.492482 -381.652526) (xy 12.492482 -381.193548) (xy 12.450826 -381.151892)
			(xy 12.449048 -381.151892) (xy 12.374372 -381.077216) (xy 11.530584 -381.077216) (xy 11.369548 -381.077216)
			(xy 8.354822 -381.077216) (xy 8.191246 -381.240792) (xy 8.191246 -383.15138) (xy 8.356092 -383.316226)
			(xy 11.049 -383.316226) (xy 11.054588 -383.321814) (xy 12.951206 -383.321814) (xy 13.103352 -383.47396)
			(xy 13.103352 -388.662926) (xy 12.274042 -389.492236) (xy 10.741406 -389.492236) (xy 10.436606 -389.797036)
			(xy 10.436606 -390.070848) (xy 10.29335 -390.214104) (xy 5.644642 -390.214104) (xy 5.382006 -389.951468)
			(xy 4.884674 -389.454136) (xy 4.884674 -389.448802) (xy 4.472178 -389.036306) (xy 4.472178 -387.760464)
			(xy 4.885182 -387.347714) (xy 6.733286 -387.347714) (xy 6.800088 -387.280912) (xy 6.800088 -386.549138)
			(xy 6.241796 -385.990846) (xy 4.997196 -385.990846) (xy 4.93141 -385.990846) (xy 4.46278 -386.459476)
			(xy 3.994912 -386.927344) (xy 3.580638 -387.341618) (xy 3.580638 -389.494268) (xy 3.994912 -389.908542)
			(xy 5.158232 -391.071862) (xy 14.08938 -391.071862) (xy 14.687296 -391.071862)
		)
		(stroke
			(width 0)
			(type solid)
		)
		(fill yes)
		(layer "B.Cu")
		(net "P1V2_USB_8042")
	)
	(gr_poly
		(pts
			(arc
				(start 226.749356 -139.411202)
				(mid 226.764986 -139.408738)
				(end 226.779074 -139.40155)
			)
			(arc
				(start 226.779074 -139.40155)
				(mid 226.913758 -139.33297)
				(end 227.063046 -139.309348)
			)
			(arc
				(start 227.063046 -139.309348)
				(mid 227.212348 -139.332928)
				(end 227.347018 -139.40155)
			)
			(arc
				(start 227.347018 -139.40155)
				(mid 227.361119 -139.408697)
				(end 227.376736 -139.411202)
			)
			(arc
				(start 228.565964 -139.411202)
				(mid 228.585487 -139.407301)
				(end 228.602032 -139.396216)
			)
			(arc
				(start 228.69906 -139.299188)
				(mid 228.710171 -139.282654)
				(end 228.714046 -139.26312)
			)
			(arc
				(start 228.714046 -137.781284)
				(mid 228.710145 -137.761761)
				(end 228.69906 -137.745216)
			)
			(arc
				(start 228.475032 -137.521188)
				(mid 228.458498 -137.510077)
				(end 228.438964 -137.506202)
			)
			(arc
				(start 226.195128 -137.506202)
				(mid 226.175605 -137.510103)
				(end 226.15906 -137.521188)
			)
			(arc
				(start 225.935032 -137.745216)
				(mid 225.923921 -137.76175)
				(end 225.920046 -137.781284)
			)
			(arc
				(start 225.920046 -139.26312)
				(mid 225.923947 -139.282643)
				(end 225.935032 -139.299188)
			)
			(arc
				(start 226.03206 -139.396216)
				(mid 226.048594 -139.407327)
				(end 226.068128 -139.411202)
			)
		)
		(stroke
			(width 0)
			(type solid)
		)
		(fill yes)
		(layer "B.Cu")
		(net "P3V3")
	)
	(gr_poly
		(pts
			(arc
				(start 274.749514 -287.273746)
				(mid 274.769037 -287.269845)
				(end 274.785582 -287.25876)
			)
			(arc
				(start 274.828762 -287.21558)
				(mid 274.839688 -287.199134)
				(end 274.843494 -287.179766)
			)
			(arc
				(start 274.843494 -285.47187)
				(mid 274.828615 -285.435949)
				(end 274.792694 -285.42107)
			)
			(arc
				(start 273.957034 -285.42107)
				(mid 273.937511 -285.424971)
				(end 273.920966 -285.436056)
			)
			(xy 273.640804 -285.716218) (xy 273.633438 -285.72333) (xy 273.625818 -285.742126) (xy 273.625818 -285.787338)
			(arc
				(start 273.629882 -285.796736)
				(mid 273.649099 -285.859464)
				(end 273.655536 -285.924752)
			)
			(arc
				(start 273.655536 -285.924752)
				(mid 273.649079 -285.990036)
				(end 273.629882 -286.052768)
			)
			(xy 273.625818 -286.062166) (xy 273.625818 -286.737552)
			(arc
				(start 273.629882 -286.74695)
				(mid 273.649099 -286.809678)
				(end 273.655536 -286.874966)
			)
			(arc
				(start 273.655536 -286.874966)
				(mid 273.649079 -286.94025)
				(end 273.629882 -287.002982)
			)
			(xy 273.625818 -287.01238)
			(arc
				(start 273.625818 -287.145984)
				(mid 273.629719 -287.165507)
				(end 273.640804 -287.182052)
			)
			(arc
				(start 273.717512 -287.25876)
				(mid 273.734046 -287.269871)
				(end 273.75358 -287.273746)
			)
		)
		(stroke
			(width 0)
			(type solid)
		)
		(fill yes)
		(layer "B.Cu")
		(net "GND")
	)
	(gr_poly
		(pts
			(arc
				(start 390.849612 -287.273746)
				(mid 390.869135 -287.269845)
				(end 390.88568 -287.25876)
			)
			(arc
				(start 390.92886 -287.21558)
				(mid 390.939786 -287.199134)
				(end 390.943592 -287.179766)
			)
			(arc
				(start 390.943592 -285.47187)
				(mid 390.928713 -285.435949)
				(end 390.892792 -285.42107)
			)
			(arc
				(start 390.057132 -285.42107)
				(mid 390.037609 -285.424971)
				(end 390.021064 -285.436056)
			)
			(xy 389.740902 -285.716218) (xy 389.733536 -285.72333) (xy 389.725916 -285.742126) (xy 389.725916 -285.787338)
			(arc
				(start 389.72998 -285.796736)
				(mid 389.749197 -285.859464)
				(end 389.755634 -285.924752)
			)
			(arc
				(start 389.755634 -285.924752)
				(mid 389.749177 -285.990036)
				(end 389.72998 -286.052768)
			)
			(xy 389.725916 -286.062166) (xy 389.725916 -286.737552)
			(arc
				(start 389.72998 -286.74695)
				(mid 389.749197 -286.809678)
				(end 389.755634 -286.874966)
			)
			(arc
				(start 389.755634 -286.874966)
				(mid 389.749177 -286.94025)
				(end 389.72998 -287.002982)
			)
			(xy 389.725916 -287.01238)
			(arc
				(start 389.725916 -287.145984)
				(mid 389.729817 -287.165507)
				(end 389.740902 -287.182052)
			)
			(arc
				(start 389.81761 -287.25876)
				(mid 389.834144 -287.269871)
				(end 389.853678 -287.273746)
			)
		)
		(stroke
			(width 0)
			(type solid)
		)
		(fill yes)
		(layer "B.Cu")
		(net "GND")
	)
	(gr_poly
		(pts
			(arc
				(start 230.411274 -213.317836)
				(mid 230.430797 -213.313935)
				(end 230.447342 -213.30285)
			)
			(arc
				(start 230.542084 -213.208108)
				(mid 230.553195 -213.191574)
				(end 230.55707 -213.17204)
			)
			(xy 230.55707 -212.654896) (xy 230.556308 -212.654134) (xy 230.556308 -212.478112) (xy 230.55707 -212.47735)
			(arc
				(start 230.55707 -212.471254)
				(mid 230.560971 -212.451731)
				(end 230.572056 -212.435186)
			)
			(arc
				(start 230.814372 -212.19287)
				(mid 230.825483 -212.176336)
				(end 230.829358 -212.156802)
			)
			(arc
				(start 230.829358 -211.187538)
				(mid 230.825457 -211.168015)
				(end 230.814372 -211.15147)
			)
			(xy 230.798624 -211.135722) (xy 230.768144 -211.12988)
			(arc
				(start 230.753666 -211.13623)
				(mid 230.679698 -211.159574)
				(end 230.602536 -211.167472)
			)
			(arc
				(start 230.602536 -211.167472)
				(mid 230.513316 -211.156954)
				(end 230.429054 -211.125816)
			)
			(xy 230.42372 -211.123022) (xy 230.412036 -211.120228)
			(arc
				(start 230.047292 -211.120228)
				(mid 230.027769 -211.124129)
				(end 230.011224 -211.135214)
			)
			(arc
				(start 229.98557 -211.160868)
				(mid 229.974459 -211.177402)
				(end 229.970584 -211.196936)
			)
			(arc
				(start 229.970584 -213.158324)
				(mid 229.974485 -213.177847)
				(end 229.98557 -213.194392)
			)
			(arc
				(start 230.094028 -213.30285)
				(mid 230.110562 -213.313961)
				(end 230.130096 -213.317836)
			)
		)
		(stroke
			(width 0)
			(type solid)
		)
		(fill yes)
		(layer "B.Cu")
		(net "P3V3_BIC_SPI")
	)
	(gr_poly
		(pts
			(xy 133.052058 -184.038748) (xy 133.052058 -183.861202) (xy 133.044438 -183.84266) (xy 133.04012 -183.838342)
			(xy 133.04012 -180.90007) (xy 133.04012 -180.888894) (xy 133.302502 -180.626512) (xy 133.302502 -180.23967)
			(xy 132.687314 -179.624482)
			(arc
				(start 132.687314 -179.346098)
				(mid 132.683413 -179.326575)
				(end 132.672328 -179.31003)
			)
			(arc
				(start 132.563616 -179.201318)
				(mid 132.547082 -179.190207)
				(end 132.527548 -179.186332)
			)
			(arc
				(start 132.255006 -179.186332)
				(mid 132.235483 -179.190233)
				(end 132.218938 -179.201318)
			)
			(arc
				(start 132.110226 -179.31003)
				(mid 132.099115 -179.326564)
				(end 132.09524 -179.346098)
			)
			(arc
				(start 132.09524 -179.642008)
				(mid 132.091339 -179.661531)
				(end 132.080254 -179.678076)
			)
			(arc
				(start 131.883912 -179.874418)
				(mid 131.867378 -179.885529)
				(end 131.847844 -179.889404)
			)
			(arc
				(start 131.702048 -179.889404)
				(mid 131.682525 -179.893305)
				(end 131.66598 -179.90439)
			)
			(arc
				(start 131.41833 -180.15204)
				(mid 131.407219 -180.168574)
				(end 131.403344 -180.188108)
			)
			(xy 130.97383 -180.617622) (xy 130.97383 -181.28488) (xy 131.611624 -181.922674) (xy 131.611624 -182.033672)
			(arc
				(start 131.611624 -183.978804)
				(mid 131.615525 -183.998327)
				(end 131.62661 -184.014872)
			)
			(arc
				(start 131.641596 -184.029858)
				(mid 131.658013 -184.04092)
				(end 131.67741 -184.044844)
			)
			(xy 133.046216 -184.044844)
		)
		(stroke
			(width 0)
			(type solid)
		)
		(fill yes)
		(layer "B.Cu")
		(net "P3V3_DB2000QL_VDDA")
	)
	(gr_poly
		(pts
			(arc
				(start 175.64227 -306.722018)
				(mid 175.661793 -306.718117)
				(end 175.678338 -306.707032)
			)
			(arc
				(start 176.198784 -306.186586)
				(mid 176.215318 -306.175475)
				(end 176.234852 -306.1716)
			)
			(arc
				(start 184.881266 -306.1716)
				(mid 184.900789 -306.167699)
				(end 184.917334 -306.156614)
			)
			(arc
				(start 185.01106 -306.062888)
				(mid 185.022171 -306.046354)
				(end 185.026046 -306.02682)
			)
			(arc
				(start 185.026046 -306.02047)
				(mid 185.02116 -305.998732)
				(end 185.007504 -305.9811)
			)
			(arc
				(start 185.007504 -305.9811)
				(mid 184.89768 -305.84061)
				(end 184.858406 -305.666648)
			)
			(arc
				(start 184.858406 -305.666648)
				(mid 184.86281 -305.606946)
				(end 184.875932 -305.548538)
			)
			(arc
				(start 184.875932 -305.548538)
				(mid 184.868146 -305.503609)
				(end 184.827418 -305.483006)
			)
			(xy 184.780936 -305.483006) (xy 184.751218 -305.512724) (xy 184.751218 -305.517296) (xy 167.171878 -305.517296)
			(xy 165.589966 -305.517296) (xy 165.568122 -305.53914) (xy 165.568122 -306.058316) (xy 165.66642 -306.156614)
			(xy 167.158924 -306.156614) (xy 167.426386 -306.156614)
			(arc
				(start 174.323502 -306.156614)
				(mid 174.343025 -306.160515)
				(end 174.35957 -306.1716)
			)
			(arc
				(start 174.895002 -306.707032)
				(mid 174.911536 -306.718143)
				(end 174.93107 -306.722018)
			)
		)
		(stroke
			(width 0)
			(type solid)
		)
		(fill yes)
		(layer "B.Cu")
		(net "GND")
	)
	(gr_poly
		(pts
			(arc
				(start 291.742114 -306.722018)
				(mid 291.761637 -306.718117)
				(end 291.778182 -306.707032)
			)
			(arc
				(start 292.298628 -306.186586)
				(mid 292.315162 -306.175475)
				(end 292.334696 -306.1716)
			)
			(arc
				(start 300.98111 -306.1716)
				(mid 301.000633 -306.167699)
				(end 301.017178 -306.156614)
			)
			(arc
				(start 301.110904 -306.062888)
				(mid 301.122015 -306.046354)
				(end 301.12589 -306.02682)
			)
			(arc
				(start 301.12589 -306.02047)
				(mid 301.121004 -305.998732)
				(end 301.107348 -305.9811)
			)
			(arc
				(start 301.107348 -305.9811)
				(mid 300.997524 -305.84061)
				(end 300.95825 -305.666648)
			)
			(arc
				(start 300.95825 -305.666648)
				(mid 300.962654 -305.606946)
				(end 300.975776 -305.548538)
			)
			(arc
				(start 300.975776 -305.548538)
				(mid 300.96799 -305.503609)
				(end 300.927262 -305.483006)
			)
			(xy 300.88078 -305.483006) (xy 300.851062 -305.512724) (xy 300.851062 -305.517296) (xy 283.271722 -305.517296)
			(xy 281.68981 -305.517296) (xy 281.667966 -305.53914) (xy 281.667966 -306.058316) (xy 281.766264 -306.156614)
			(xy 283.258768 -306.156614) (xy 283.52623 -306.156614)
			(arc
				(start 290.423346 -306.156614)
				(mid 290.442869 -306.160515)
				(end 290.459414 -306.1716)
			)
			(arc
				(start 290.994846 -306.707032)
				(mid 291.01138 -306.718143)
				(end 291.030914 -306.722018)
			)
		)
		(stroke
			(width 0)
			(type solid)
		)
		(fill yes)
		(layer "B.Cu")
		(net "GND")
	)
	(gr_poly
		(pts
			(arc
				(start 100.79736 -358.051354)
				(mid 100.816883 -358.047453)
				(end 100.833428 -358.036368)
			)
			(arc
				(start 100.863146 -358.00665)
				(mid 100.874257 -357.990116)
				(end 100.878132 -357.970582)
			)
			(arc
				(start 100.878132 -356.996238)
				(mid 100.872054 -356.972143)
				(end 100.855272 -356.95382)
			)
			(arc
				(start 100.855272 -356.95382)
				(mid 100.745043 -356.854178)
				(end 100.67036 -356.725728)
			)
			(arc
				(start 100.67036 -356.725728)
				(mid 100.665662 -356.716515)
				(end 100.659184 -356.708456)
			)
			(xy 100.656898 -356.70617)
			(arc
				(start 99.549966 -356.70617)
				(mid 99.530443 -356.702269)
				(end 99.513898 -356.691184)
			)
			(xy 98.968052 -356.145338)
			(arc
				(start 98.968052 -353.493324)
				(mid 98.964151 -353.473801)
				(end 98.953066 -353.457256)
			)
			(arc
				(start 98.939604 -353.443794)
				(mid 98.92307 -353.432683)
				(end 98.903536 -353.428808)
			)
			(arc
				(start 97.790254 -353.428808)
				(mid 97.770731 -353.432709)
				(end 97.754186 -353.443794)
			)
			(arc
				(start 97.602294 -353.595686)
				(mid 97.591183 -353.61222)
				(end 97.587308 -353.631754)
			)
			(arc
				(start 97.587308 -354.152454)
				(mid 97.588245 -354.162422)
				(end 97.591118 -354.172012)
			)
			(arc
				(start 99.108514 -357.834184)
				(mid 99.113174 -357.842967)
				(end 99.119436 -357.850694)
			)
			(arc
				(start 99.30511 -358.036368)
				(mid 99.321644 -358.047479)
				(end 99.341178 -358.051354)
			)
		)
		(stroke
			(width 0)
			(type solid)
		)
		(fill yes)
		(layer "B.Cu")
		(net "GND")
	)
	(gr_poly
		(pts
			(arc
				(start 101.08184 -328.737976)
				(mid 101.105935 -328.731898)
				(end 101.124258 -328.715116)
			)
			(arc
				(start 101.124258 -328.715116)
				(mid 101.2239 -328.604887)
				(end 101.35235 -328.530204)
			)
			(arc
				(start 101.35235 -328.530204)
				(mid 101.361563 -328.525506)
				(end 101.369622 -328.519028)
			)
			(xy 101.371908 -328.516742)
			(arc
				(start 101.371908 -327.40981)
				(mid 101.375809 -327.390287)
				(end 101.386894 -327.373742)
			)
			(xy 101.93274 -326.827896)
			(arc
				(start 104.584754 -326.827896)
				(mid 104.604277 -326.823995)
				(end 104.620822 -326.81291)
			)
			(arc
				(start 104.634284 -326.799448)
				(mid 104.645395 -326.782914)
				(end 104.64927 -326.76338)
			)
			(arc
				(start 104.64927 -325.650098)
				(mid 104.645369 -325.630575)
				(end 104.634284 -325.61403)
			)
			(arc
				(start 104.482392 -325.462138)
				(mid 104.465858 -325.451027)
				(end 104.446324 -325.447152)
			)
			(arc
				(start 103.925624 -325.447152)
				(mid 103.915656 -325.448089)
				(end 103.906066 -325.450962)
			)
			(arc
				(start 100.243894 -326.968358)
				(mid 100.235111 -326.973018)
				(end 100.227384 -326.97928)
			)
			(arc
				(start 100.04171 -327.164954)
				(mid 100.030599 -327.181488)
				(end 100.026724 -327.201022)
			)
			(arc
				(start 100.026724 -328.657204)
				(mid 100.030625 -328.676727)
				(end 100.04171 -328.693272)
			)
			(arc
				(start 100.071428 -328.72299)
				(mid 100.087962 -328.734101)
				(end 100.107496 -328.737976)
			)
		)
		(stroke
			(width 0)
			(type solid)
		)
		(fill yes)
		(layer "B.Cu")
		(net "GND")
	)
	(gr_poly
		(pts
			(arc
				(start 355.131116 -228.074982)
				(mid 355.150639 -228.071081)
				(end 355.167184 -228.059996)
			)
			(arc
				(start 355.205538 -228.021642)
				(mid 355.216649 -228.005108)
				(end 355.220524 -227.985574)
			)
			(arc
				(start 355.220524 -226.754944)
				(mid 355.216623 -226.735421)
				(end 355.205538 -226.718876)
			)
			(arc
				(start 354.537518 -226.050856)
				(mid 354.520984 -226.039745)
				(end 354.50145 -226.03587)
			)
			(arc
				(start 351.7519 -226.03587)
				(mid 351.732377 -226.039771)
				(end 351.715832 -226.050856)
			)
			(xy 351.602548 -226.16414)
			(arc
				(start 351.5995 -226.169474)
				(mid 351.58335 -226.194188)
				(end 351.56521 -226.21748)
			)
			(arc
				(start 351.56521 -226.21748)
				(mid 351.556206 -226.232781)
				(end 351.553018 -226.250246)
			)
			(arc
				(start 351.553018 -226.52355)
				(mid 351.556207 -226.541014)
				(end 351.56521 -226.556316)
			)
			(arc
				(start 351.56521 -226.556316)
				(mid 351.628009 -226.664109)
				(end 351.649792 -226.786948)
			)
			(arc
				(start 351.649792 -226.786948)
				(mid 351.628026 -226.909793)
				(end 351.56521 -227.01758)
			)
			(arc
				(start 351.56521 -227.01758)
				(mid 351.556206 -227.032881)
				(end 351.553018 -227.050346)
			)
			(arc
				(start 351.553018 -227.916994)
				(mid 351.556919 -227.936517)
				(end 351.568004 -227.953062)
			)
			(arc
				(start 351.674938 -228.059996)
				(mid 351.691472 -228.071107)
				(end 351.711006 -228.074982)
			)
		)
		(stroke
			(width 0)
			(type solid)
		)
		(fill yes)
		(layer "B.Cu")
		(net "P3V3_FPGA_VCCIO0")
	)
	(gr_poly
		(pts
			(arc
				(start 385.550918 -237.744)
				(mid 385.570441 -237.740099)
				(end 385.586986 -237.729014)
			)
			(arc
				(start 385.684014 -237.631986)
				(mid 385.695125 -237.615452)
				(end 385.699 -237.595918)
			)
			(arc
				(start 385.699 -234.929934)
				(mid 385.69669 -234.915042)
				(end 385.69011 -234.901486)
			)
			(arc
				(start 385.69011 -234.901486)
				(mid 385.606534 -234.62996)
				(end 385.69011 -234.358434)
			)
			(arc
				(start 385.69011 -234.358434)
				(mid 385.696686 -234.344876)
				(end 385.699 -234.329986)
			)
			(arc
				(start 385.699 -232.812082)
				(mid 385.695099 -232.792559)
				(end 385.684014 -232.776014)
			)
			(arc
				(start 385.332986 -232.424986)
				(mid 385.316452 -232.413875)
				(end 385.296918 -232.41)
			)
			(xy 384.704082 -232.41) (xy 384.450336 -232.156254) (xy 383.210308 -232.156254) (xy 382.605534 -232.156254)
			(xy 382.445514 -232.156254) (xy 382.216914 -232.384854) (xy 382.216914 -232.828846) (xy 382.698244 -233.310176)
			(xy 382.815592 -233.310176) (xy 383.241042 -233.310176) (xy 383.561844 -233.310176) (xy 384.012694 -233.761026)
			(xy 384.012694 -234.88396) (xy 384.429 -235.300266)
			(arc
				(start 384.429 -237.341918)
				(mid 384.432901 -237.361441)
				(end 384.443986 -237.377986)
			)
			(arc
				(start 384.795014 -237.729014)
				(mid 384.811548 -237.740125)
				(end 384.831082 -237.744)
			)
		)
		(stroke
			(width 0)
			(type solid)
		)
		(fill yes)
		(layer "B.Cu")
		(net "P3V3_SDB_VPLL")
	)
	(gr_poly
		(pts
			(arc
				(start 235.740448 -93.97111)
				(mid 235.759971 -93.967209)
				(end 235.776516 -93.956124)
			)
			(arc
				(start 235.879132 -93.853508)
				(mid 235.890243 -93.836974)
				(end 235.894118 -93.81744)
			)
			(arc
				(start 235.894118 -90.866214)
				(mid 235.890217 -90.846691)
				(end 235.879132 -90.830146)
			)
			(arc
				(start 235.644182 -90.595196)
				(mid 235.627648 -90.584085)
				(end 235.608114 -90.58021)
			)
			(arc
				(start 234.25277 -90.58021)
				(mid 234.233247 -90.576309)
				(end 234.216702 -90.565224)
			)
			(arc
				(start 234.170982 -90.519504)
				(mid 234.154536 -90.508578)
				(end 234.135168 -90.504772)
			)
			(arc
				(start 233.877612 -90.504772)
				(mid 233.858255 -90.508605)
				(end 233.841798 -90.519504)
			)
			(arc
				(start 233.743246 -90.618056)
				(mid 233.726712 -90.629167)
				(end 233.707178 -90.633042)
			)
			(arc
				(start 232.987596 -90.633042)
				(mid 232.968073 -90.629141)
				(end 232.951528 -90.618056)
			)
			(arc
				(start 232.776268 -90.442796)
				(mid 232.759734 -90.431685)
				(end 232.7402 -90.42781)
			)
			(arc
				(start 232.55732 -90.42781)
				(mid 232.537797 -90.431711)
				(end 232.521252 -90.442796)
			)
			(arc
				(start 232.259632 -90.704416)
				(mid 232.248521 -90.72095)
				(end 232.244646 -90.740484)
			)
			(arc
				(start 232.244646 -93.691964)
				(mid 232.248547 -93.711487)
				(end 232.259632 -93.728032)
			)
			(arc
				(start 232.487724 -93.956124)
				(mid 232.504258 -93.967235)
				(end 232.523792 -93.97111)
			)
		)
		(stroke
			(width 0)
			(type solid)
		)
		(fill yes)
		(layer "B.Cu")
		(net "GND")
	)
	(gr_poly
		(pts
			(arc
				(start 346.016072 -330.091796)
				(mid 346.035459 -330.087846)
				(end 346.051886 -330.07681)
			)
			(arc
				(start 346.480384 -329.648312)
				(mid 346.491495 -329.631778)
				(end 346.49537 -329.612244)
			)
			(arc
				(start 346.49537 -327.212198)
				(mid 346.491469 -327.192675)
				(end 346.480384 -327.17613)
			)
			(arc
				(start 346.290646 -326.986392)
				(mid 346.274112 -326.975281)
				(end 346.254578 -326.971406)
			)
			(arc
				(start 336.452718 -326.971406)
				(mid 336.433195 -326.967505)
				(end 336.41665 -326.95642)
			)
			(arc
				(start 335.726278 -326.266048)
				(mid 335.709744 -326.254937)
				(end 335.69021 -326.251062)
			)
			(arc
				(start 333.639922 -326.251062)
				(mid 333.620399 -326.254963)
				(end 333.603854 -326.266048)
			)
			(arc
				(start 333.455518 -326.414384)
				(mid 333.444407 -326.430918)
				(end 333.440532 -326.450452)
			)
			(arc
				(start 333.440532 -327.087738)
				(mid 333.444433 -327.107261)
				(end 333.455518 -327.123806)
			)
			(arc
				(start 333.562706 -327.230994)
				(mid 333.57924 -327.242105)
				(end 333.598774 -327.24598)
			)
			(arc
				(start 335.7245 -327.24598)
				(mid 335.744023 -327.249881)
				(end 335.760568 -327.260966)
			)
			(arc
				(start 336.05978 -327.560178)
				(mid 336.070891 -327.576712)
				(end 336.074766 -327.596246)
			)
			(arc
				(start 336.074766 -329.659996)
				(mid 336.078667 -329.679519)
				(end 336.089752 -329.696064)
			)
			(arc
				(start 336.470498 -330.07681)
				(mid 336.486915 -330.087872)
				(end 336.506312 -330.091796)
			)
		)
		(stroke
			(width 0)
			(type solid)
		)
		(fill yes)
		(layer "B.Cu")
		(net "GND")
	)
	(gr_poly
		(pts
			(arc
				(start 227.945696 -152.789128)
				(mid 227.965219 -152.785227)
				(end 227.981764 -152.774142)
			)
			(arc
				(start 228.367844 -152.388062)
				(mid 228.378955 -152.371528)
				(end 228.38283 -152.351994)
			)
			(arc
				(start 228.38283 -150.824184)
				(mid 228.378929 -150.804661)
				(end 228.367844 -150.788116)
			)
			(arc
				(start 228.159056 -150.579328)
				(mid 228.14261 -150.568402)
				(end 228.123242 -150.564596)
			)
			(xy 226.72675 -150.564596) (xy 226.72421 -150.562056)
			(arc
				(start 226.324414 -150.562056)
				(mid 226.305027 -150.558106)
				(end 226.2886 -150.54707)
			)
			(arc
				(start 225.73869 -149.99716)
				(mid 225.727628 -149.980743)
				(end 225.723704 -149.961346)
			)
			(arc
				(start 225.723704 -149.936962)
				(mid 225.719871 -149.917605)
				(end 225.708972 -149.901148)
			)
			(arc
				(start 225.7044 -149.896576)
				(mid 225.693289 -149.880042)
				(end 225.689414 -149.860508)
			)
			(arc
				(start 225.689414 -146.128232)
				(mid 225.685513 -146.108709)
				(end 225.674428 -146.092164)
			)
			(arc
				(start 225.467164 -145.8849)
				(mid 225.45063 -145.873789)
				(end 225.431096 -145.869914)
			)
			(xy 223.163638 -145.869914) (xy 222.804736 -146.228816) (xy 222.804736 -147.165822) (xy 222.59925 -147.371308)
			(xy 222.448374 -147.522184)
			(arc
				(start 222.448374 -152.58669)
				(mid 222.452275 -152.606213)
				(end 222.46336 -152.622758)
			)
			(arc
				(start 222.61449 -152.773888)
				(mid 222.631024 -152.784999)
				(end 222.650558 -152.788874)
			)
			(xy 227.845874 -152.788874) (xy 227.846128 -152.789128)
		)
		(stroke
			(width 0)
			(type solid)
		)
		(fill yes)
		(layer "B.Cu")
		(net "P3V3_CLK_GEN_VDDMXCK_CK440_PEX")
	)
	(gr_poly
		(pts
			(arc
				(start 237.80369 -210.544918)
				(mid 237.823213 -210.541017)
				(end 237.839758 -210.529932)
			)
			(arc
				(start 238.307118 -210.062572)
				(mid 238.323652 -210.051461)
				(end 238.343186 -210.047586)
			)
			(arc
				(start 238.997744 -210.047586)
				(mid 239.017267 -210.043685)
				(end 239.033812 -210.0326)
			)
			(arc
				(start 239.054894 -210.011518)
				(mid 239.066005 -209.994984)
				(end 239.06988 -209.97545)
			)
			(arc
				(start 239.06988 -209.333592)
				(mid 239.065979 -209.314069)
				(end 239.054894 -209.297524)
			)
			(arc
				(start 238.987076 -209.229706)
				(mid 238.970542 -209.218595)
				(end 238.951008 -209.21472)
			)
			(arc
				(start 237.981236 -209.21472)
				(mid 237.961713 -209.210819)
				(end 237.945168 -209.199734)
			)
			(arc
				(start 237.176564 -208.43113)
				(mid 237.16003 -208.420019)
				(end 237.140496 -208.416144)
			)
			(xy 236.384846 -208.416144) (xy 236.282738 -208.518252)
			(arc
				(start 236.282738 -209.96148)
				(mid 236.296924 -209.972289)
				(end 236.31398 -209.977482)
			)
			(arc
				(start 236.31398 -209.977482)
				(mid 236.603122 -210.127662)
				(end 236.71911 -210.432142)
			)
			(xy 236.71911 -210.441286) (xy 236.718856 -210.4517) (xy 236.726222 -210.470496)
			(arc
				(start 236.784388 -210.529678)
				(mid 236.801009 -210.540976)
				(end 236.82071 -210.544918)
			)
		)
		(stroke
			(width 0)
			(type solid)
		)
		(fill yes)
		(layer "B.Cu")
		(net "P3V3_BIC_USB2AV33")
	)
	(gr_poly
		(pts
			(xy 10.106406 -389.898636) (xy 10.106406 -389.695436) (xy 10.6299 -389.171942) (xy 11.9507 -389.171942)
			(xy 12.798552 -388.32409) (xy 12.798552 -384.725164) (xy 12.798552 -383.614422) (xy 12.759944 -383.575814)
			(xy 10.844784 -383.575814) (xy 8.104632 -383.575814) (xy 7.859014 -383.330196) (xy 7.859014 -381.15113)
			(xy 8.112252 -380.897892) (xy 8.175752 -380.834392) (xy 8.196326 -380.813818) (xy 12.784836 -380.813818)
			(xy 12.80541 -380.834392) (xy 12.86891 -380.897892) (xy 14.427962 -380.897892) (xy 14.430248 -380.900178)
			(xy 14.569186 -380.900178) (xy 15.12189 -381.452882) (xy 15.12189 -383.31267) (xy 15.498826 -383.689606)
			(xy 15.498826 -384.211576) (xy 15.89151 -384.60426) (xy 15.89151 -389.681466) (xy 16.00073 -389.790686)
			(xy 16.773652 -389.790686) (xy 16.908018 -389.65632) (xy 16.908018 -381.4064) (xy 16.246602 -380.744984)
			(xy 15.418054 -379.916436) (xy 14.754606 -379.916436) (xy 6.280912 -379.916436) (xy 5.750306 -380.447042)
			(xy 5.750306 -382.505458) (xy 6.07949 -382.834642) (xy 6.26872 -383.023872) (xy 6.26872 -383.164588)
			(xy 6.271006 -383.166874) (xy 6.271006 -383.880106) (xy 6.271006 -384.302762) (xy 6.271006 -384.39979)
			(xy 6.271514 -384.400298) (xy 5.973572 -384.69824) (xy 4.223766 -384.69824) (xy 4.133596 -384.78841)
			(xy 4.133596 -385.54787) (xy 4.247134 -385.661408) (xy 6.512814 -385.661408) (xy 7.05866 -386.207254)
			(xy 7.05866 -388.947152) (xy 6.680708 -389.325104) (xy 5.676138 -389.325104) (xy 5.636006 -389.365236)
			(xy 5.636006 -389.824976) (xy 5.771134 -389.960104) (xy 10.044938 -389.960104)
		)
		(stroke
			(width 0)
			(type solid)
		)
		(fill yes)
		(layer "B.Cu")
		(net "GND")
	)
	(gr_poly
		(pts
			(arc
				(start 70.372478 -298.952412)
				(mid 70.386485 -298.950516)
				(end 70.399402 -298.944792)
			)
			(arc
				(start 70.399402 -298.944792)
				(mid 70.483599 -298.907149)
				(end 70.574916 -298.894246)
			)
			(arc
				(start 70.574916 -298.894246)
				(mid 70.666226 -298.907174)
				(end 70.75043 -298.944792)
			)
			(xy 70.756526 -298.948602) (xy 70.770242 -298.952412)
			(arc
				(start 70.858888 -298.952412)
				(mid 70.878411 -298.948511)
				(end 70.894956 -298.937426)
			)
			(xy 70.93458 -298.897802) (xy 70.93458 -292.869112)
			(arc
				(start 70.886574 -292.821106)
				(mid 70.87004 -292.809995)
				(end 70.850506 -292.80612)
			)
			(xy 70.822312 -292.80612) (xy 70.804786 -292.812978)
			(arc
				(start 70.797674 -292.819328)
				(mid 70.574916 -292.905693)
				(end 70.352158 -292.819328)
			)
			(arc
				(start 70.352158 -292.819328)
				(mid 70.336256 -292.809477)
				(end 70.317868 -292.80612)
			)
			(arc
				(start 70.172834 -292.80612)
				(mid 70.153311 -292.810021)
				(end 70.136766 -292.821106)
			)
			(arc
				(start 70.006718 -292.951154)
				(mid 69.995607 -292.967688)
				(end 69.991732 -292.987222)
			)
			(arc
				(start 69.991732 -298.816522)
				(mid 69.995633 -298.836045)
				(end 70.006718 -298.85259)
			)
			(arc
				(start 70.091554 -298.937426)
				(mid 70.108088 -298.948537)
				(end 70.127622 -298.952412)
			)
		)
		(stroke
			(width 0)
			(type solid)
		)
		(fill yes)
		(layer "B.Cu")
		(net "P1V25_PEX0")
	)
	(gr_poly
		(pts
			(arc
				(start 189.689486 -299.406564)
				(mid 189.709009 -299.402663)
				(end 189.725554 -299.391578)
			)
			(arc
				(start 189.739016 -299.378116)
				(mid 189.745828 -299.369594)
				(end 189.7507 -299.359828)
			)
			(arc
				(start 189.7507 -299.359828)
				(mid 189.755869 -299.345764)
				(end 189.762638 -299.332396)
			)
			(xy 189.76594 -299.326554) (xy 189.769496 -299.313854) (xy 189.769496 -299.159422) (xy 189.7634 -299.142658)
			(arc
				(start 189.757558 -299.1358)
				(mid 189.673169 -298.990282)
				(end 189.643766 -298.82465)
			)
			(arc
				(start 189.643766 -298.62272)
				(mid 189.673143 -298.457078)
				(end 189.757558 -298.31157)
			)
			(arc
				(start 189.757558 -298.31157)
				(mid 189.766442 -298.296246)
				(end 189.769496 -298.278804)
			)
			(arc
				(start 189.769496 -292.456616)
				(mid 189.765595 -292.437093)
				(end 189.75451 -292.420548)
			)
			(xy 189.715394 -292.381432) (xy 189.708282 -292.374066) (xy 189.689486 -292.366446)
			(arc
				(start 189.451488 -292.366446)
				(mid 189.431965 -292.370347)
				(end 189.41542 -292.381432)
			)
			(xy 189.379352 -292.4175) (xy 189.379098 -292.417754) (xy 189.367922 -292.42893) (xy 189.367668 -292.429184)
			(arc
				(start 189.18428 -292.612572)
				(mid 189.173169 -292.629106)
				(end 189.169294 -292.64864)
			)
			(arc
				(start 189.169294 -299.226732)
				(mid 189.173195 -299.246255)
				(end 189.18428 -299.2628)
			)
			(arc
				(start 189.313058 -299.391578)
				(mid 189.329592 -299.402689)
				(end 189.349126 -299.406564)
			)
		)
		(stroke
			(width 0)
			(type solid)
		)
		(fill yes)
		(layer "B.Cu")
		(net "GND")
	)
	(gr_poly
		(pts
			(arc
				(start 263.911588 -377.749308)
				(mid 263.945196 -377.736602)
				(end 263.962134 -377.704858)
			)
			(arc
				(start 263.962134 -377.704858)
				(mid 264.831021 -374.956293)
				(end 266.61618 -372.69293)
			)
			(arc
				(start 266.61618 -372.69293)
				(mid 266.62895 -372.67562)
				(end 266.633452 -372.654576)
			)
			(arc
				(start 266.633452 -368.922046)
				(mid 266.629551 -368.902523)
				(end 266.618466 -368.885978)
			)
			(arc
				(start 266.291568 -368.55908)
				(mid 266.275034 -368.547969)
				(end 266.2555 -368.544094)
			)
			(xy 243.539264 -368.544094) (xy 243.533676 -368.538506)
			(arc
				(start 242.778534 -368.538506)
				(mid 242.759011 -368.542407)
				(end 242.742466 -368.553492)
			)
			(arc
				(start 242.620038 -368.67592)
				(mid 242.608927 -368.692454)
				(end 242.605052 -368.711988)
			)
			(arc
				(start 242.605052 -377.229624)
				(mid 242.608953 -377.249147)
				(end 242.620038 -377.265692)
			)
			(arc
				(start 243.088668 -377.734322)
				(mid 243.105202 -377.745433)
				(end 243.124736 -377.749308)
			)
		)
		(stroke
			(width 0)
			(type solid)
		)
		(fill yes)
		(layer "B.Cu")
		(net "P12V_STBY_R2")
	)
	(gr_poly
		(pts
			(arc
				(start 238.16056 -214.755476)
				(mid 238.180083 -214.751575)
				(end 238.196628 -214.74049)
			)
			(arc
				(start 238.280956 -214.656162)
				(mid 238.292067 -214.639628)
				(end 238.295942 -214.620094)
			)
			(arc
				(start 238.295942 -213.94547)
				(mid 238.179002 -214.006466)
				(end 238.0488 -214.027512)
			)
			(arc
				(start 238.0488 -214.027512)
				(mid 237.756403 -213.906397)
				(end 237.635288 -213.614)
			)
			(arc
				(start 237.635288 -213.614)
				(mid 237.696153 -213.398055)
				(end 237.86084 -213.2457)
			)
			(xy 237.602522 -213.2457) (xy 237.599728 -213.242906)
			(arc
				(start 236.505496 -213.242906)
				(mid 236.491481 -213.24495)
				(end 236.478572 -213.25078)
			)
			(xy 236.448346 -213.267544) (xy 236.44098 -213.271354)
			(arc
				(start 235.965746 -213.746588)
				(mid 235.954635 -213.763122)
				(end 235.95076 -213.782656)
			)
			(arc
				(start 235.95076 -214.49665)
				(mid 235.954661 -214.516173)
				(end 235.965746 -214.532718)
			)
			(arc
				(start 236.126528 -214.6935)
				(mid 236.181288 -214.682499)
				(end 236.237018 -214.678768)
			)
			(arc
				(start 236.237018 -214.678768)
				(mid 236.36471 -214.698395)
				(end 236.480604 -214.755476)
			)
		)
		(stroke
			(width 0)
			(type solid)
		)
		(fill yes)
		(layer "B.Cu")
		(net "P1V2_BIC_USB2AV12")
	)
	(gr_poly
		(pts
			(xy 239.607344 -217.158316)
			(arc
				(start 239.60836 -217.137996)
				(mid 239.7271 -216.881905)
				(end 239.98936 -216.77757)
			)
			(arc
				(start 239.990122 -216.77757)
				(mid 240.017754 -216.778609)
				(end 240.04524 -216.781634)
			)
			(xy 240.056416 -216.783412) (xy 240.077244 -216.777316)
			(arc
				(start 240.144046 -216.719658)
				(mid 240.157018 -216.702268)
				(end 240.161572 -216.68105)
			)
			(arc
				(start 240.161572 -215.931496)
				(mid 240.101502 -215.820916)
				(end 240.0808 -215.6968)
			)
			(arc
				(start 240.0808 -215.6968)
				(mid 240.101574 -215.572709)
				(end 240.161572 -215.462104)
			)
			(arc
				(start 240.161572 -213.08949)
				(mid 240.157671 -213.069967)
				(end 240.146586 -213.053422)
			)
			(arc
				(start 239.909096 -212.815932)
				(mid 239.892562 -212.804821)
				(end 239.873028 -212.800946)
			)
			(arc
				(start 238.9886 -212.800946)
				(mid 238.969077 -212.804847)
				(end 238.952532 -212.815932)
			)
			(arc
				(start 238.702088 -213.066376)
				(mid 238.690977 -213.08291)
				(end 238.687102 -213.102444)
			)
			(arc
				(start 238.687102 -216.961212)
				(mid 238.691003 -216.980735)
				(end 238.702088 -216.99728)
			)
			(arc
				(start 238.875824 -217.171016)
				(mid 238.892358 -217.182127)
				(end 238.911892 -217.186002)
			)
			(xy 239.578134 -217.186002)
		)
		(stroke
			(width 0)
			(type solid)
		)
		(fill yes)
		(layer "B.Cu")
		(net "P1V2_AUX")
	)
	(gr_poly
		(pts
			(arc
				(start 459.679548 -293.690802)
				(mid 459.698935 -293.686852)
				(end 459.715362 -293.675816)
			)
			(arc
				(start 460.01813 -293.373048)
				(mid 460.029192 -293.356631)
				(end 460.033116 -293.337234)
			)
			(arc
				(start 460.033116 -281.11958)
				(mid 460.029215 -281.100057)
				(end 460.01813 -281.083512)
			)
			(xy 459.997556 -281.062938) (xy 459.970124 -281.056334)
			(arc
				(start 459.956408 -281.060398)
				(mid 459.888391 -281.076343)
				(end 459.81874 -281.081734)
			)
			(arc
				(start 459.81874 -281.081734)
				(mid 459.603011 -281.027672)
				(end 459.438248 -280.87828)
			)
			(arc
				(start 459.438248 -280.87828)
				(mid 459.419875 -280.861678)
				(end 459.39583 -280.855674)
			)
			(arc
				(start 449.570602 -280.855674)
				(mid 449.551079 -280.859575)
				(end 449.534534 -280.87066)
			)
			(arc
				(start 449.134484 -281.27071)
				(mid 449.123373 -281.287244)
				(end 449.119498 -281.306778)
			)
			(arc
				(start 449.119498 -283.267912)
				(mid 449.123399 -283.287435)
				(end 449.134484 -283.30398)
			)
			(arc
				(start 449.499228 -283.668724)
				(mid 449.515762 -283.679835)
				(end 449.535296 -283.68371)
			)
			(arc
				(start 451.076822 -283.68371)
				(mid 451.096345 -283.687611)
				(end 451.11289 -283.698696)
			)
			(arc
				(start 452.050912 -284.636718)
				(mid 452.062023 -284.653252)
				(end 452.065898 -284.672786)
			)
			(arc
				(start 452.065898 -293.3192)
				(mid 452.069799 -293.338723)
				(end 452.080884 -293.355268)
			)
			(arc
				(start 452.401432 -293.675816)
				(mid 452.417966 -293.686927)
				(end 452.4375 -293.690802)
			)
		)
		(stroke
			(width 0)
			(type solid)
		)
		(fill yes)
		(layer "B.Cu")
		(net "P1V25_PEX3_R")
	)
	(gr_poly
		(pts
			(arc
				(start 132.004054 -179.035456)
				(mid 132.023441 -179.031506)
				(end 132.039868 -179.02047)
			)
			(arc
				(start 132.113782 -178.94681)
				(mid 132.130199 -178.935748)
				(end 132.149596 -178.931824)
			)
			(arc
				(start 132.632958 -178.931824)
				(mid 132.652345 -178.935774)
				(end 132.668772 -178.94681)
			)
			(arc
				(start 132.742686 -179.02047)
				(mid 132.759103 -179.031532)
				(end 132.7785 -179.035456)
			)
			(arc
				(start 133.987286 -179.035456)
				(mid 134.006477 -179.031691)
				(end 134.022846 -179.020978)
			)
			(xy 134.0231 -179.020724) (xy 134.097268 -178.946556)
			(arc
				(start 134.097776 -178.946048)
				(mid 134.108518 -178.929691)
				(end 134.112254 -178.910488)
			)
			(arc
				(start 134.112254 -176.398428)
				(mid 134.108353 -176.378905)
				(end 134.097268 -176.36236)
			)
			(xy 134.003796 -176.268888) (xy 133.996684 -176.261522) (xy 133.977888 -176.253902) (xy 133.084062 -176.253902)
			(xy 132.952744 -176.38522) (xy 131.520692 -176.38522) (xy 131.398772 -176.50714) (xy 131.398772 -177.41011)
			(xy 131.398772 -177.468276) (xy 131.398772 -177.568352) (xy 131.397248 -177.569876) (xy 131.397248 -177.655474)
			(xy 131.320032 -177.73269) (xy 131.320032 -178.002946)
			(arc
				(start 131.322826 -178.011074)
				(mid 131.339356 -178.076198)
				(end 131.344924 -178.143154)
			)
			(arc
				(start 131.344924 -178.143154)
				(mid 131.339336 -178.210107)
				(end 131.322826 -178.275234)
			)
			(xy 131.320032 -178.283362)
			(arc
				(start 131.320032 -178.682396)
				(mid 131.323797 -178.701587)
				(end 131.33451 -178.717956)
			)
			(xy 131.334764 -178.71821) (xy 131.637024 -179.02047)
			(arc
				(start 131.637532 -179.020978)
				(mid 131.653889 -179.03172)
				(end 131.673092 -179.035456)
			)
		)
		(stroke
			(width 0)
			(type solid)
		)
		(fill yes)
		(layer "B.Cu")
		(net "GND")
	)
	(gr_poly
		(pts
			(arc
				(start 184.44591 -305.263042)
				(mid 184.481831 -305.248163)
				(end 184.49671 -305.212242)
			)
			(xy 184.49671 -305.111404) (xy 184.493154 -305.09845)
			(arc
				(start 184.489598 -305.092608)
				(mid 184.455653 -305.011828)
				(end 184.444132 -304.924968)
			)
			(arc
				(start 184.444132 -304.92446)
				(mid 184.455672 -304.837606)
				(end 184.489598 -304.75682)
			)
			(xy 184.493154 -304.750978) (xy 184.49671 -304.738024) (xy 184.49671 -304.676556) (xy 184.48909 -304.65776)
			(xy 184.481724 -304.650648) (xy 184.234074 -304.402998) (xy 184.226962 -304.395632) (xy 184.208166 -304.388012)
			(arc
				(start 166.020496 -304.388012)
				(mid 166.000973 -304.391913)
				(end 165.984428 -304.402998)
			)
			(xy 165.946836 -304.44059)
			(arc
				(start 165.941756 -304.446432)
				(mid 165.934352 -304.460746)
				(end 165.93185 -304.476658)
			)
			(arc
				(start 165.93185 -304.604674)
				(mid 165.938011 -304.628923)
				(end 165.954964 -304.647346)
			)
			(arc
				(start 165.954964 -304.647346)
				(mid 166.065497 -304.766902)
				(end 166.105586 -304.924714)
			)
			(arc
				(start 166.105586 -304.924714)
				(mid 166.091689 -305.019069)
				(end 166.051484 -305.105562)
			)
			(xy 166.047674 -305.111404) (xy 166.04361 -305.124612)
			(arc
				(start 166.043356 -305.131724)
				(mid 166.044663 -305.14509)
				(end 166.049452 -305.157632)
			)
			(arc
				(start 166.09187 -305.236372)
				(mid 166.110546 -305.255868)
				(end 166.136574 -305.263042)
			)
		)
		(stroke
			(width 0)
			(type solid)
		)
		(fill yes)
		(layer "B.Cu")
		(net "P1V25_SERDES_VDDPLL_PEX1")
	)
	(gr_poly
		(pts
			(arc
				(start 300.545754 -305.263042)
				(mid 300.581675 -305.248163)
				(end 300.596554 -305.212242)
			)
			(xy 300.596554 -305.111404) (xy 300.592998 -305.09845)
			(arc
				(start 300.589442 -305.092608)
				(mid 300.555497 -305.011828)
				(end 300.543976 -304.924968)
			)
			(arc
				(start 300.543976 -304.92446)
				(mid 300.555516 -304.837606)
				(end 300.589442 -304.75682)
			)
			(xy 300.592998 -304.750978) (xy 300.596554 -304.738024) (xy 300.596554 -304.676556) (xy 300.588934 -304.65776)
			(xy 300.581568 -304.650648) (xy 300.333918 -304.402998) (xy 300.326806 -304.395632) (xy 300.30801 -304.388012)
			(arc
				(start 282.12034 -304.388012)
				(mid 282.100817 -304.391913)
				(end 282.084272 -304.402998)
			)
			(xy 282.04668 -304.44059)
			(arc
				(start 282.0416 -304.446432)
				(mid 282.034196 -304.460746)
				(end 282.031694 -304.476658)
			)
			(arc
				(start 282.031694 -304.604674)
				(mid 282.037855 -304.628923)
				(end 282.054808 -304.647346)
			)
			(arc
				(start 282.054808 -304.647346)
				(mid 282.165341 -304.766902)
				(end 282.20543 -304.924714)
			)
			(arc
				(start 282.20543 -304.924714)
				(mid 282.191533 -305.019069)
				(end 282.151328 -305.105562)
			)
			(xy 282.147518 -305.111404) (xy 282.143454 -305.124612)
			(arc
				(start 282.1432 -305.131724)
				(mid 282.144507 -305.14509)
				(end 282.149296 -305.157632)
			)
			(arc
				(start 282.191714 -305.236372)
				(mid 282.21039 -305.255868)
				(end 282.236418 -305.263042)
			)
		)
		(stroke
			(width 0)
			(type solid)
		)
		(fill yes)
		(layer "B.Cu")
		(net "P1V25_SERDES_VDDPLL_PEX2")
	)
	(gr_poly
		(pts
			(arc
				(start 303.859184 -299.389038)
				(mid 303.878707 -299.385137)
				(end 303.895252 -299.374052)
			)
			(arc
				(start 303.971198 -299.298106)
				(mid 303.982309 -299.281572)
				(end 303.986184 -299.262038)
			)
			(arc
				(start 303.986184 -299.06341)
				(mid 303.982234 -299.044023)
				(end 303.971198 -299.027596)
			)
			(arc
				(start 303.91608 -298.972224)
				(mid 303.905018 -298.955807)
				(end 303.901094 -298.93641)
			)
			(arc
				(start 303.901094 -292.826186)
				(mid 303.905044 -292.806799)
				(end 303.91608 -292.790372)
			)
			(arc
				(start 303.971198 -292.735)
				(mid 303.98226 -292.718583)
				(end 303.986184 -292.699186)
			)
			(arc
				(start 303.986184 -292.365684)
				(mid 303.982283 -292.346161)
				(end 303.971198 -292.329616)
			)
			(xy 303.970182 -292.3286) (xy 303.95164 -292.32098)
			(arc
				(start 303.495456 -292.32098)
				(mid 303.475933 -292.324881)
				(end 303.459388 -292.335966)
			)
			(arc
				(start 303.347882 -292.447472)
				(mid 303.336771 -292.464006)
				(end 303.332896 -292.48354)
			)
			(arc
				(start 303.332896 -292.68674)
				(mid 303.336846 -292.706127)
				(end 303.347882 -292.722554)
			)
			(arc
				(start 303.391062 -292.765988)
				(mid 303.401988 -292.782434)
				(end 303.405794 -292.801802)
			)
			(arc
				(start 303.405794 -298.965112)
				(mid 303.401961 -298.984469)
				(end 303.391062 -299.000926)
			)
			(arc
				(start 303.347882 -299.04436)
				(mid 303.33682 -299.060777)
				(end 303.332896 -299.080174)
			)
			(arc
				(start 303.332896 -299.279564)
				(mid 303.336797 -299.299087)
				(end 303.347882 -299.315632)
			)
			(arc
				(start 303.406302 -299.374052)
				(mid 303.422836 -299.385163)
				(end 303.44237 -299.389038)
			)
		)
		(stroke
			(width 0)
			(type solid)
		)
		(fill yes)
		(layer "B.Cu")
		(net "GND")
	)
	(gr_poly
		(pts
			(xy 132.414772 -308.32552) (xy 133.834632 -308.32552) (xy 134.04342 -308.534308) (xy 135.083804 -308.534308)
			(xy 135.127746 -308.490366) (xy 135.127746 -303.934876) (xy 135.019034 -303.826164)
			(arc
				(start 134.449312 -303.826164)
				(mid 134.432778 -303.815053)
				(end 134.413244 -303.811178)
			)
			(arc
				(start 119.66702 -303.811178)
				(mid 119.647497 -303.815079)
				(end 119.630952 -303.826164)
			)
			(arc
				(start 119.504206 -303.95291)
				(mid 119.493095 -303.969444)
				(end 119.48922 -303.988978)
			)
			(arc
				(start 119.48922 -304.957988)
				(mid 119.485319 -304.977511)
				(end 119.474234 -304.994056)
			)
			(arc
				(start 119.260112 -305.208178)
				(mid 119.243578 -305.219289)
				(end 119.224044 -305.223164)
			)
			(arc
				(start 116.12499 -305.223164)
				(mid 116.105467 -305.219263)
				(end 116.088922 -305.208178)
			)
			(arc
				(start 115.928394 -305.04765)
				(mid 115.917283 -305.031116)
				(end 115.913408 -305.011582)
			)
			(arc
				(start 115.913408 -303.861978)
				(mid 115.898529 -303.826057)
				(end 115.862608 -303.811178)
			)
			(xy 101.073712 -303.811178) (xy 100.669852 -303.811178) (xy 100.635054 -303.845976) (xy 100.480622 -304.000408)
			(xy 100.480622 -308.16423) (xy 100.626926 -308.310534)
			(arc
				(start 101.132386 -308.310534)
				(mid 101.14892 -308.321645)
				(end 101.168454 -308.32552)
			)
			(xy 102.823518 -308.32552) (xy 103.005382 -308.507384) (xy 103.529892 -308.507384) (xy 103.711756 -308.32552)
			(xy 104.017064 -308.32552) (xy 128.229868 -308.32552) (xy 128.431544 -308.527196) (xy 128.765554 -308.527196)
			(xy 128.96723 -308.32552) (xy 131.598416 -308.32552) (xy 131.814824 -308.541928) (xy 132.198364 -308.541928)
		)
		(stroke
			(width 0)
			(type solid)
		)
		(fill yes)
		(layer "B.Cu")
		(net "GND")
	)
	(gr_poly
		(pts
			(xy 354.174552 -225.522028) (xy 354.174552 -225.170238) (xy 353.98329 -224.978976) (xy 353.656392 -224.978976)
			(xy 353.248722 -224.571306)
			(arc
				(start 353.248722 -224.0534)
				(mid 353.259833 -224.036866)
				(end 353.263708 -224.017332)
			)
			(xy 353.263708 -222.855536) (xy 353.214432 -222.80626) (xy 353.214432 -222.405702) (xy 353.263708 -222.356426)
			(arc
				(start 353.263708 -221.425008)
				(mid 353.259807 -221.405485)
				(end 353.248722 -221.38894)
			)
			(arc
				(start 352.923094 -221.063312)
				(mid 352.90656 -221.052201)
				(end 352.887026 -221.048326)
			)
			(arc
				(start 351.759012 -221.048326)
				(mid 351.739489 -221.052227)
				(end 351.722944 -221.063312)
			)
			(xy 351.655888 -221.130368) (xy 351.648268 -221.150942) (xy 351.64903 -221.162118)
			(arc
				(start 351.649792 -221.186756)
				(mid 351.643611 -221.25307)
				(end 351.625154 -221.317058)
			)
			(xy 351.621598 -221.325948) (xy 351.621598 -221.847664)
			(arc
				(start 351.625154 -221.856554)
				(mid 351.643572 -221.92055)
				(end 351.649792 -221.986856)
			)
			(arc
				(start 351.649792 -221.986856)
				(mid 351.643611 -222.05317)
				(end 351.625154 -222.117158)
			)
			(xy 351.621598 -222.126048) (xy 351.621598 -222.647764)
			(arc
				(start 351.625154 -222.656654)
				(mid 351.643572 -222.72065)
				(end 351.649792 -222.786956)
			)
			(arc
				(start 351.649792 -222.786956)
				(mid 351.643611 -222.85327)
				(end 351.625154 -222.917258)
			)
			(xy 351.621598 -222.926148) (xy 351.621598 -223.44761)
			(arc
				(start 351.625154 -223.4565)
				(mid 351.643572 -223.520496)
				(end 351.649792 -223.586802)
			)
			(xy 351.730818 -223.667828) (xy 351.730818 -225.562668) (xy 351.892616 -225.724212) (xy 353.972368 -225.724212)
		)
		(stroke
			(width 0)
			(type solid)
		)
		(fill yes)
		(layer "B.Cu")
		(net "P3V3_VCC_FPGA_CORE")
	)
	(gr_poly
		(pts
			(arc
				(start 105.547668 -109.210094)
				(mid 105.567191 -109.206193)
				(end 105.583736 -109.195108)
			)
			(arc
				(start 105.778554 -109.00029)
				(mid 105.789665 -108.983756)
				(end 105.79354 -108.964222)
			)
			(arc
				(start 105.79354 -103.91013)
				(mid 105.797441 -103.890607)
				(end 105.808526 -103.874062)
			)
			(arc
				(start 106.662474 -103.020114)
				(mid 106.673585 -103.00358)
				(end 106.67746 -102.984046)
			)
			(arc
				(start 106.67746 -100.561394)
				(mid 106.673559 -100.541871)
				(end 106.662474 -100.525326)
			)
			(arc
				(start 106.482642 -100.345494)
				(mid 106.466108 -100.334383)
				(end 106.446574 -100.330508)
			)
			(arc
				(start 99.627944 -100.330508)
				(mid 99.608421 -100.334409)
				(end 99.591876 -100.345494)
			)
			(arc
				(start 99.488498 -100.448872)
				(mid 99.477387 -100.465406)
				(end 99.473512 -100.48494)
			)
			(arc
				(start 99.473512 -101.16439)
				(mid 99.469611 -101.183913)
				(end 99.458526 -101.200458)
			)
			(arc
				(start 98.784156 -101.874828)
				(mid 98.773045 -101.891362)
				(end 98.76917 -101.910896)
			)
			(arc
				(start 98.76917 -107.792012)
				(mid 98.773071 -107.811535)
				(end 98.784156 -107.82808)
			)
			(arc
				(start 98.974148 -108.018072)
				(mid 98.990682 -108.029183)
				(end 99.010216 -108.033058)
			)
			(arc
				(start 103.411528 -108.033058)
				(mid 103.431051 -108.036959)
				(end 103.447596 -108.048044)
			)
			(arc
				(start 103.624888 -108.225336)
				(mid 103.635999 -108.24187)
				(end 103.639874 -108.261404)
			)
			(arc
				(start 103.639874 -109.035342)
				(mid 103.643775 -109.054865)
				(end 103.65486 -109.07141)
			)
			(arc
				(start 103.778558 -109.195108)
				(mid 103.795092 -109.206219)
				(end 103.814626 -109.210094)
			)
		)
		(stroke
			(width 0)
			(type solid)
		)
		(fill yes)
		(layer "B.Cu")
		(net "GND")
	)
	(gr_poly
		(pts
			(xy 304.519584 -298.932854)
			(arc
				(start 304.524918 -298.93006)
				(mid 304.597735 -298.903321)
				(end 304.674778 -298.894246)
			)
			(arc
				(start 304.674778 -298.894246)
				(mid 304.751829 -298.903286)
				(end 304.824638 -298.93006)
			)
			(xy 304.829972 -298.932854) (xy 304.841656 -298.935648)
			(arc
				(start 304.86985 -298.935648)
				(mid 304.905771 -298.920769)
				(end 304.92065 -298.884848)
			)
			(arc
				(start 304.92065 -296.16781)
				(mid 304.924483 -296.148453)
				(end 304.935382 -296.131996)
			)
			(arc
				(start 304.964592 -296.102786)
				(mid 304.975703 -296.086252)
				(end 304.979578 -296.066718)
			)
			(arc
				(start 304.979578 -292.956234)
				(mid 304.972857 -292.931235)
				(end 304.954686 -292.9128)
			)
			(xy 304.86858 -292.860984) (xy 304.842164 -292.860222)
			(arc
				(start 304.830226 -292.866572)
				(mid 304.754889 -292.895538)
				(end 304.674778 -292.905434)
			)
			(arc
				(start 304.674778 -292.905434)
				(mid 304.555645 -292.883231)
				(end 304.452528 -292.819582)
			)
			(arc
				(start 304.452528 -292.819582)
				(mid 304.436626 -292.809731)
				(end 304.418238 -292.806374)
			)
			(arc
				(start 304.280824 -292.806374)
				(mid 304.261301 -292.810275)
				(end 304.244756 -292.82136)
			)
			(arc
				(start 304.170588 -292.895528)
				(mid 304.159477 -292.912062)
				(end 304.155602 -292.931596)
			)
			(arc
				(start 304.155602 -298.831)
				(mid 304.159503 -298.850523)
				(end 304.170588 -298.867068)
			)
			(arc
				(start 304.224182 -298.920662)
				(mid 304.240716 -298.931773)
				(end 304.26025 -298.935648)
			)
			(xy 304.5079 -298.935648)
		)
		(stroke
			(width 0)
			(type solid)
		)
		(fill yes)
		(layer "B.Cu")
		(net "P1V25_SERDES_VDDPLL_PEX2")
	)
	(gr_poly
		(pts
			(arc
				(start 337.74761 -109.210094)
				(mid 337.767133 -109.206193)
				(end 337.783678 -109.195108)
			)
			(arc
				(start 337.978496 -109.00029)
				(mid 337.989607 -108.983756)
				(end 337.993482 -108.964222)
			)
			(arc
				(start 337.993482 -103.91013)
				(mid 337.997383 -103.890607)
				(end 338.008468 -103.874062)
			)
			(arc
				(start 338.862416 -103.020114)
				(mid 338.873527 -103.00358)
				(end 338.877402 -102.984046)
			)
			(arc
				(start 338.877402 -100.561394)
				(mid 338.873501 -100.541871)
				(end 338.862416 -100.525326)
			)
			(arc
				(start 338.682584 -100.345494)
				(mid 338.66605 -100.334383)
				(end 338.646516 -100.330508)
			)
			(arc
				(start 331.827886 -100.330508)
				(mid 331.808363 -100.334409)
				(end 331.791818 -100.345494)
			)
			(arc
				(start 331.68844 -100.448872)
				(mid 331.677329 -100.465406)
				(end 331.673454 -100.48494)
			)
			(arc
				(start 331.673454 -101.16439)
				(mid 331.669553 -101.183913)
				(end 331.658468 -101.200458)
			)
			(arc
				(start 330.984098 -101.874828)
				(mid 330.972987 -101.891362)
				(end 330.969112 -101.910896)
			)
			(arc
				(start 330.969112 -107.792012)
				(mid 330.973013 -107.811535)
				(end 330.984098 -107.82808)
			)
			(arc
				(start 331.17409 -108.018072)
				(mid 331.190624 -108.029183)
				(end 331.210158 -108.033058)
			)
			(arc
				(start 335.61147 -108.033058)
				(mid 335.630993 -108.036959)
				(end 335.647538 -108.048044)
			)
			(arc
				(start 335.82483 -108.225336)
				(mid 335.835941 -108.24187)
				(end 335.839816 -108.261404)
			)
			(arc
				(start 335.839816 -109.035342)
				(mid 335.843717 -109.054865)
				(end 335.854802 -109.07141)
			)
			(arc
				(start 335.9785 -109.195108)
				(mid 335.995034 -109.206219)
				(end 336.014568 -109.210094)
			)
		)
		(stroke
			(width 0)
			(type solid)
		)
		(fill yes)
		(layer "B.Cu")
		(net "GND")
	)
	(gr_poly
		(pts
			(arc
				(start 302.57242 -298.952412)
				(mid 302.586427 -298.950516)
				(end 302.599344 -298.944792)
			)
			(arc
				(start 302.599344 -298.944792)
				(mid 302.683541 -298.907149)
				(end 302.774858 -298.894246)
			)
			(arc
				(start 302.774858 -298.894246)
				(mid 302.866168 -298.907174)
				(end 302.950372 -298.944792)
			)
			(xy 302.956468 -298.948602) (xy 302.970184 -298.952412)
			(arc
				(start 303.05883 -298.952412)
				(mid 303.078353 -298.948511)
				(end 303.094898 -298.937426)
			)
			(arc
				(start 303.136554 -298.89577)
				(mid 303.147665 -298.879236)
				(end 303.15154 -298.859702)
			)
			(arc
				(start 303.15154 -292.907212)
				(mid 303.147639 -292.887689)
				(end 303.136554 -292.871144)
			)
			(arc
				(start 303.086516 -292.821106)
				(mid 303.069982 -292.809995)
				(end 303.050448 -292.80612)
			)
			(xy 303.022254 -292.80612) (xy 303.004728 -292.812978)
			(arc
				(start 302.997616 -292.819328)
				(mid 302.774858 -292.905693)
				(end 302.5521 -292.819328)
			)
			(arc
				(start 302.5521 -292.819328)
				(mid 302.536198 -292.809477)
				(end 302.51781 -292.80612)
			)
			(arc
				(start 302.372776 -292.80612)
				(mid 302.353253 -292.810021)
				(end 302.336708 -292.821106)
			)
			(arc
				(start 302.20666 -292.951154)
				(mid 302.195549 -292.967688)
				(end 302.191674 -292.987222)
			)
			(arc
				(start 302.191674 -298.816522)
				(mid 302.195575 -298.836045)
				(end 302.20666 -298.85259)
			)
			(arc
				(start 302.291496 -298.937426)
				(mid 302.30803 -298.948537)
				(end 302.327564 -298.952412)
			)
		)
		(stroke
			(width 0)
			(type solid)
		)
		(fill yes)
		(layer "B.Cu")
		(net "P1V25_PEX2")
	)
	(gr_poly
		(pts
			(arc
				(start 266.167362 -82.93608)
				(mid 266.186885 -82.932179)
				(end 266.20343 -82.921094)
			)
			(arc
				(start 266.437364 -82.686906)
				(mid 266.448475 -82.670372)
				(end 266.45235 -82.650838)
			)
			(arc
				(start 266.45235 -78.0669)
				(mid 266.448449 -78.047377)
				(end 266.437364 -78.030832)
			)
			(arc
				(start 266.060174 -77.653642)
				(mid 266.051763 -77.642514)
				(end 266.046712 -77.629512)
			)
			(xy 266.044934 -77.622654) (xy 266.03833 -77.610716)
			(arc
				(start 265.474958 -77.047344)
				(mid 265.458424 -77.036233)
				(end 265.43889 -77.032358)
			)
			(arc
				(start 260.478778 -77.032358)
				(mid 260.459255 -77.036259)
				(end 260.44271 -77.047344)
			)
			(arc
				(start 260.20268 -77.287374)
				(mid 260.191569 -77.303908)
				(end 260.187694 -77.323442)
			)
			(xy 260.187694 -77.446632) (xy 260.195314 -77.465174) (xy 260.20268 -77.472286) (xy 260.20268 -78.365858)
			(arc
				(start 260.20268 -80.739234)
				(mid 260.206581 -80.758757)
				(end 260.217666 -80.775302)
			)
			(arc
				(start 260.294882 -80.852518)
				(mid 260.311299 -80.86358)
				(end 260.330696 -80.867504)
			)
			(xy 262.39216 -80.867504)
			(arc
				(start 262.49757 -80.867504)
				(mid 262.516791 -80.871385)
				(end 262.53313 -80.882236)
			)
			(xy 262.603742 -80.952848) (xy 262.604504 -80.953356) (xy 262.60806 -80.956912) (xy 263.011412 -81.360264)
			(xy 263.01573 -81.364836) (xy 263.10082 -81.449926) (xy 263.10082 -81.454244)
			(arc
				(start 263.109202 -81.474818)
				(mid 263.112026 -81.484159)
				(end 263.113012 -81.493868)
			)
			(arc
				(start 263.113012 -82.832702)
				(mid 263.116913 -82.852225)
				(end 263.127998 -82.86877)
			)
			(arc
				(start 263.180322 -82.921094)
				(mid 263.196856 -82.932205)
				(end 263.21639 -82.93608)
			)
		)
		(stroke
			(width 0)
			(type solid)
		)
		(fill yes)
		(layer "B.Cu")
		(net "P3V3_CLK_GEN_VDD_CK440")
	)
	(gr_poly
		(pts
			(xy 418.67836 -298.952158) (xy 418.690806 -298.94911)
			(arc
				(start 418.699696 -298.944538)
				(mid 418.783793 -298.907088)
				(end 418.874956 -298.894246)
			)
			(arc
				(start 418.874956 -298.894246)
				(mid 418.966134 -298.907209)
				(end 419.050216 -298.944792)
			)
			(xy 419.056312 -298.948602) (xy 419.070028 -298.952412)
			(arc
				(start 419.158928 -298.952412)
				(mid 419.178451 -298.948511)
				(end 419.194996 -298.937426)
			)
			(arc
				(start 419.219634 -298.912788)
				(mid 419.230745 -298.896254)
				(end 419.23462 -298.87672)
			)
			(arc
				(start 419.23462 -292.890194)
				(mid 419.230719 -292.870671)
				(end 419.219634 -292.854126)
			)
			(xy 419.186614 -292.821106) (xy 419.179502 -292.81374) (xy 419.160706 -292.80612)
			(arc
				(start 419.132004 -292.80612)
				(mid 419.12256 -292.807006)
				(end 419.113462 -292.809676)
			)
			(xy 419.104826 -292.812978)
			(arc
				(start 419.097714 -292.819328)
				(mid 418.874956 -292.905693)
				(end 418.652198 -292.819328)
			)
			(arc
				(start 418.652198 -292.819328)
				(mid 418.636296 -292.809477)
				(end 418.617908 -292.80612)
			)
			(arc
				(start 418.472874 -292.80612)
				(mid 418.453351 -292.810021)
				(end 418.436806 -292.821106)
			)
			(xy 418.306758 -292.951154) (xy 418.299392 -292.958266) (xy 418.291772 -292.977062)
			(arc
				(start 418.291772 -298.816522)
				(mid 418.295673 -298.836045)
				(end 418.306758 -298.85259)
			)
			(arc
				(start 418.391594 -298.937426)
				(mid 418.408128 -298.948537)
				(end 418.427662 -298.952412)
			)
			(xy 418.672772 -298.952412)
		)
		(stroke
			(width 0)
			(type solid)
		)
		(fill yes)
		(layer "B.Cu")
		(net "P1V25_PEX3")
	)
	(gr_poly
		(pts
			(arc
				(start 58.193432 -287.374076)
				(mid 58.221522 -287.370446)
				(end 58.24982 -287.36925)
			)
			(arc
				(start 58.24982 -287.36925)
				(mid 58.278116 -287.370463)
				(end 58.306208 -287.374076)
			)
			(xy 58.310526 -287.374838)
			(arc
				(start 68.208652 -287.374838)
				(mid 68.228175 -287.370937)
				(end 68.24472 -287.359852)
			)
			(arc
				(start 68.368672 -287.2359)
				(mid 68.379783 -287.219366)
				(end 68.383658 -287.199832)
			)
			(xy 68.383658 -287.038288) (xy 68.381118 -287.027112)
			(arc
				(start 68.378324 -287.021778)
				(mid 68.35272 -286.95035)
				(end 68.344034 -286.874966)
			)
			(arc
				(start 68.344034 -286.874966)
				(mid 68.352683 -286.799573)
				(end 68.378324 -286.728154)
			)
			(xy 68.381118 -286.72282) (xy 68.383658 -286.711644)
			(arc
				(start 68.383658 -286.564324)
				(mid 68.379757 -286.544801)
				(end 68.368672 -286.528256)
			)
			(xy 68.362068 -286.521652) (xy 68.343526 -286.514032)
			(arc
				(start 49.992534 -286.514032)
				(mid 49.973011 -286.517933)
				(end 49.956466 -286.529018)
			)
			(xy 49.952402 -286.533082) (xy 49.952402 -286.687768) (xy 49.955958 -286.700722)
			(arc
				(start 49.959514 -286.706564)
				(mid 49.993798 -286.787679)
				(end 50.005488 -286.874966)
			)
			(arc
				(start 50.005488 -286.874966)
				(mid 50.00243 -286.919833)
				(end 49.993296 -286.963866)
			)
			(arc
				(start 49.993296 -286.963866)
				(mid 49.991653 -286.981502)
				(end 49.99609 -286.998664)
			)
			(arc
				(start 50.009044 -287.026858)
				(mid 50.01902 -287.041479)
				(end 50.033428 -287.05175)
			)
			(arc
				(start 50.033428 -287.05175)
				(mid 50.079768 -287.078858)
				(end 50.120804 -287.113472)
			)
			(arc
				(start 50.28438 -287.277048)
				(mid 50.31372 -287.310825)
				(end 50.337974 -287.348422)
			)
			(xy 50.344832 -287.360868) (xy 50.368454 -287.374838) (xy 58.189114 -287.374838)
		)
		(stroke
			(width 0)
			(type solid)
		)
		(fill yes)
		(layer "B.Cu")
		(net "P1V25_SERDES_VDDPLL_PEX0")
	)
	(gr_poly
		(pts
			(xy 186.478418 -298.952158) (xy 186.490864 -298.94911)
			(arc
				(start 186.499754 -298.944538)
				(mid 186.583851 -298.907088)
				(end 186.675014 -298.894246)
			)
			(arc
				(start 186.675014 -298.894246)
				(mid 186.766192 -298.907209)
				(end 186.850274 -298.944792)
			)
			(xy 186.85637 -298.948602) (xy 186.870086 -298.952412)
			(arc
				(start 186.958224 -298.952412)
				(mid 186.994145 -298.937533)
				(end 187.009024 -298.901612)
			)
			(xy 187.009024 -298.882562) (xy 187.008516 -298.8818)
			(arc
				(start 187.008516 -292.863778)
				(mid 187.004566 -292.844391)
				(end 186.99353 -292.827964)
			)
			(arc
				(start 186.986672 -292.821106)
				(mid 186.970138 -292.809995)
				(end 186.950604 -292.80612)
			)
			(arc
				(start 186.932062 -292.80612)
				(mid 186.922618 -292.807006)
				(end 186.91352 -292.809676)
			)
			(xy 186.904884 -292.812978)
			(arc
				(start 186.897772 -292.819328)
				(mid 186.675014 -292.905693)
				(end 186.452256 -292.819328)
			)
			(arc
				(start 186.452256 -292.819328)
				(mid 186.436354 -292.809477)
				(end 186.417966 -292.80612)
			)
			(arc
				(start 186.272932 -292.80612)
				(mid 186.253409 -292.810021)
				(end 186.236864 -292.821106)
			)
			(xy 186.106816 -292.951154) (xy 186.09945 -292.958266) (xy 186.09183 -292.977062)
			(arc
				(start 186.09183 -298.816522)
				(mid 186.095731 -298.836045)
				(end 186.106816 -298.85259)
			)
			(arc
				(start 186.191652 -298.937426)
				(mid 186.208186 -298.948537)
				(end 186.22772 -298.952412)
			)
			(xy 186.47283 -298.952412)
		)
		(stroke
			(width 0)
			(type solid)
		)
		(fill yes)
		(layer "B.Cu")
		(net "P1V25_PEX1")
	)
	(gr_poly
		(pts
			(arc
				(start 232.325418 -216.916762)
				(mid 232.344941 -216.912861)
				(end 232.361486 -216.901776)
			)
			(xy 232.487978 -216.775284) (xy 232.489248 -216.775284)
			(arc
				(start 232.496868 -216.767664)
				(mid 232.513402 -216.756553)
				(end 232.532936 -216.752678)
			)
			(arc
				(start 232.78846 -216.752678)
				(mid 232.807983 -216.756579)
				(end 232.824528 -216.767664)
			)
			(arc
				(start 232.95864 -216.901776)
				(mid 232.975174 -216.912887)
				(end 232.994708 -216.916762)
			)
			(arc
				(start 233.122724 -216.916762)
				(mid 233.142247 -216.912861)
				(end 233.158792 -216.901776)
			)
			(arc
				(start 233.261662 -216.798906)
				(mid 233.272724 -216.782489)
				(end 233.276648 -216.763092)
			)
			(arc
				(start 233.276648 -216.662254)
				(mid 233.272698 -216.642867)
				(end 233.261662 -216.62644)
			)
			(arc
				(start 233.062526 -216.427304)
				(mid 233.051415 -216.41077)
				(end 233.04754 -216.391236)
			)
			(arc
				(start 233.04754 -216.159588)
				(mid 233.043639 -216.140065)
				(end 233.032554 -216.12352)
			)
			(arc
				(start 232.990136 -216.081102)
				(mid 232.973602 -216.069991)
				(end 232.954068 -216.066116)
			)
			(arc
				(start 232.290112 -216.066116)
				(mid 232.270589 -216.070017)
				(end 232.254044 -216.081102)
			)
			(xy 232.247948 -216.087198) (xy 232.240328 -216.10574)
			(arc
				(start 232.240328 -216.414858)
				(mid 232.236427 -216.434381)
				(end 232.225342 -216.450926)
			)
			(arc
				(start 232.073958 -216.60231)
				(mid 232.062847 -216.618844)
				(end 232.058972 -216.638378)
			)
			(arc
				(start 232.058972 -216.798398)
				(mid 232.060163 -216.809591)
				(end 232.063798 -216.820242)
			)
			(arc
				(start 232.065576 -216.824052)
				(mid 232.10596 -216.857486)
				(end 232.14076 -216.896696)
			)
			(arc
				(start 232.14076 -216.896696)
				(mid 232.158723 -216.91149)
				(end 232.1814 -216.916762)
			)
		)
		(stroke
			(width 0)
			(type solid)
		)
		(fill yes)
		(layer "B.Cu")
		(net "P3V3_BIC_USB2AV33")
	)
	(gr_poly
		(pts
			(arc
				(start 232.57256 -138.453876)
				(mid 232.593975 -138.449142)
				(end 232.611422 -138.435842)
			)
			(xy 232.668826 -138.36777) (xy 232.674668 -138.346434)
			(arc
				(start 232.672636 -138.335258)
				(mid 232.667849 -138.297038)
				(end 232.666286 -138.25855)
			)
			(arc
				(start 232.666286 -138.25855)
				(mid 233.123994 -137.800842)
				(end 233.581702 -138.25855)
			)
			(arc
				(start 233.581702 -138.25855)
				(mid 233.580145 -138.297038)
				(end 233.575352 -138.335258)
			)
			(xy 233.57332 -138.346434) (xy 233.579162 -138.36777)
			(arc
				(start 233.636566 -138.435842)
				(mid 233.654 -138.449171)
				(end 233.675428 -138.453876)
			)
			(arc
				(start 234.487974 -138.453876)
				(mid 234.507497 -138.449975)
				(end 234.524042 -138.43889)
			)
			(arc
				(start 235.079286 -137.883646)
				(mid 235.090397 -137.867112)
				(end 235.094272 -137.847578)
			)
			(xy 235.094272 -135.011922) (xy 235.094272 -134.728712) (xy 234.807252 -134.441692) (xy 230.34879 -134.441692)
			(xy 230.098346 -134.692136) (xy 230.098346 -135.478012) (xy 230.633524 -136.01319)
			(arc
				(start 230.633524 -138.241024)
				(mid 230.637425 -138.260547)
				(end 230.64851 -138.277092)
			)
			(arc
				(start 230.810308 -138.43889)
				(mid 230.826842 -138.450001)
				(end 230.846376 -138.453876)
			)
		)
		(stroke
			(width 0)
			(type solid)
		)
		(fill yes)
		(layer "B.Cu")
		(net "GND")
	)
	(gr_poly
		(pts
			(arc
				(start 232.723944 -215.728042)
				(mid 232.743467 -215.724141)
				(end 232.760012 -215.713056)
			)
			(arc
				(start 233.261662 -215.211406)
				(mid 233.272724 -215.194989)
				(end 233.276648 -215.175592)
			)
			(arc
				(start 233.276648 -215.04275)
				(mid 233.270997 -215.019465)
				(end 233.255312 -215.001348)
			)
			(arc
				(start 233.255312 -215.001348)
				(mid 233.18246 -214.932358)
				(end 233.131106 -214.846154)
			)
			(xy 233.127296 -214.83701) (xy 233.101896 -214.81161) (xy 233.094784 -214.804244) (xy 233.075988 -214.796624)
			(xy 233.019092 -214.796624) (xy 232.993438 -214.81415)
			(arc
				(start 232.987596 -214.828882)
				(mid 232.861434 -214.987842)
				(end 232.667556 -215.04783)
			)
			(arc
				(start 232.667556 -215.04783)
				(mid 232.462473 -214.979804)
				(end 232.338626 -214.80272)
			)
			(xy 232.329482 -214.796624) (xy 232.23728 -214.796624) (xy 232.226612 -214.796624) (xy 232.20807 -214.804244)
			(xy 232.190036 -214.822278)
			(arc
				(start 232.186226 -214.83193)
				(mid 232.142276 -214.910205)
				(end 232.079546 -214.974424)
			)
			(arc
				(start 232.079546 -214.974424)
				(mid 232.06531 -214.992146)
				(end 232.060242 -215.014302)
			)
			(arc
				(start 232.060242 -215.194388)
				(mid 232.065325 -215.216537)
				(end 232.079546 -215.234266)
			)
			(arc
				(start 232.079546 -215.234266)
				(mid 232.119857 -215.271552)
				(end 232.153714 -215.314784)
			)
			(xy 232.160318 -215.322658)
			(arc
				(start 232.550716 -215.713056)
				(mid 232.56725 -215.724167)
				(end 232.586784 -215.728042)
			)
		)
		(stroke
			(width 0)
			(type solid)
		)
		(fill yes)
		(layer "B.Cu")
		(net "P1V2_BIC_USB2AV12")
	)
	(gr_poly
		(pts
			(arc
				(start 290.393374 -287.374076)
				(mid 290.421464 -287.370446)
				(end 290.449762 -287.36925)
			)
			(arc
				(start 290.449762 -287.36925)
				(mid 290.478058 -287.370463)
				(end 290.50615 -287.374076)
			)
			(xy 290.510468 -287.374838)
			(arc
				(start 300.408594 -287.374838)
				(mid 300.428117 -287.370937)
				(end 300.444662 -287.359852)
			)
			(arc
				(start 300.568614 -287.2359)
				(mid 300.579725 -287.219366)
				(end 300.5836 -287.199832)
			)
			(xy 300.5836 -287.038288) (xy 300.58106 -287.027112)
			(arc
				(start 300.578266 -287.021778)
				(mid 300.552662 -286.95035)
				(end 300.543976 -286.874966)
			)
			(arc
				(start 300.543976 -286.874966)
				(mid 300.552625 -286.799573)
				(end 300.578266 -286.728154)
			)
			(xy 300.58106 -286.72282) (xy 300.5836 -286.711644)
			(arc
				(start 300.5836 -286.564324)
				(mid 300.579699 -286.544801)
				(end 300.568614 -286.528256)
			)
			(xy 300.56201 -286.521652) (xy 300.543468 -286.514032)
			(arc
				(start 282.192476 -286.514032)
				(mid 282.172953 -286.517933)
				(end 282.156408 -286.529018)
			)
			(xy 282.152344 -286.533082) (xy 282.152344 -286.687768) (xy 282.1559 -286.700722)
			(arc
				(start 282.159456 -286.706564)
				(mid 282.19374 -286.787679)
				(end 282.20543 -286.874966)
			)
			(arc
				(start 282.20543 -286.874966)
				(mid 282.202372 -286.919833)
				(end 282.193238 -286.963866)
			)
			(arc
				(start 282.193238 -286.963866)
				(mid 282.191595 -286.981502)
				(end 282.196032 -286.998664)
			)
			(arc
				(start 282.208986 -287.026858)
				(mid 282.218962 -287.041479)
				(end 282.23337 -287.05175)
			)
			(arc
				(start 282.23337 -287.05175)
				(mid 282.27971 -287.078858)
				(end 282.320746 -287.113472)
			)
			(arc
				(start 282.484322 -287.277048)
				(mid 282.513662 -287.310825)
				(end 282.537916 -287.348422)
			)
			(xy 282.544774 -287.360868) (xy 282.568396 -287.374838) (xy 290.389056 -287.374838)
		)
		(stroke
			(width 0)
			(type solid)
		)
		(fill yes)
		(layer "B.Cu")
		(net "P1V25_SERDES_VDDPLL_PEX2")
	)
	(gr_poly
		(pts
			(xy 340.67115 -308.541674) (xy 340.67115 -308.534816) (xy 340.880446 -308.32552) (xy 360.479848 -308.32552)
			(xy 360.703876 -308.549548) (xy 361.154472 -308.549548) (xy 361.3785 -308.32552) (xy 363.868462 -308.32552)
			(xy 364.073694 -308.530752) (xy 364.462568 -308.530752) (xy 364.6678 -308.32552) (xy 366.101884 -308.32552)
			(xy 366.319816 -308.543452) (xy 367.413794 -308.543452) (xy 367.443004 -308.514242) (xy 367.443004 -303.966118)
			(xy 367.288064 -303.811178) (xy 366.61344 -303.811178)
			(arc
				(start 351.867216 -303.811178)
				(mid 351.847693 -303.815079)
				(end 351.831148 -303.826164)
			)
			(arc
				(start 351.704402 -303.95291)
				(mid 351.693291 -303.969444)
				(end 351.689416 -303.988978)
			)
			(arc
				(start 351.689416 -304.957988)
				(mid 351.685515 -304.977511)
				(end 351.67443 -304.994056)
			)
			(arc
				(start 351.460308 -305.208178)
				(mid 351.443774 -305.219289)
				(end 351.42424 -305.223164)
			)
			(arc
				(start 348.325186 -305.223164)
				(mid 348.305663 -305.219263)
				(end 348.289118 -305.208178)
			)
			(arc
				(start 348.12859 -305.04765)
				(mid 348.117479 -305.031116)
				(end 348.113604 -305.011582)
			)
			(arc
				(start 348.113604 -303.861978)
				(mid 348.098725 -303.826057)
				(end 348.062804 -303.811178)
			)
			(arc
				(start 333.273908 -303.811178)
				(mid 333.254385 -303.815079)
				(end 333.23784 -303.826164)
			)
			(arc
				(start 333.111094 -303.95291)
				(mid 333.099983 -303.969444)
				(end 333.096108 -303.988978)
			)
			(arc
				(start 333.096108 -308.052978)
				(mid 333.100009 -308.072501)
				(end 333.111094 -308.089046)
			)
			(arc
				(start 333.332582 -308.310534)
				(mid 333.349116 -308.321645)
				(end 333.36865 -308.32552)
			)
			(xy 338.266532 -308.32552) (xy 338.551266 -308.610254) (xy 340.60257 -308.610254)
		)
		(stroke
			(width 0)
			(type solid)
		)
		(fill yes)
		(layer "B.Cu")
		(net "GND")
	)
	(gr_poly
		(pts
			(arc
				(start 406.493472 -287.374076)
				(mid 406.521562 -287.370446)
				(end 406.54986 -287.36925)
			)
			(arc
				(start 406.54986 -287.36925)
				(mid 406.578156 -287.370463)
				(end 406.606248 -287.374076)
			)
			(xy 406.610566 -287.374838)
			(arc
				(start 416.508692 -287.374838)
				(mid 416.528215 -287.370937)
				(end 416.54476 -287.359852)
			)
			(arc
				(start 416.668712 -287.2359)
				(mid 416.679823 -287.219366)
				(end 416.683698 -287.199832)
			)
			(xy 416.683698 -287.038288) (xy 416.681158 -287.027112)
			(arc
				(start 416.678364 -287.021778)
				(mid 416.65276 -286.95035)
				(end 416.644074 -286.874966)
			)
			(arc
				(start 416.644074 -286.874966)
				(mid 416.652723 -286.799573)
				(end 416.678364 -286.728154)
			)
			(xy 416.681158 -286.72282) (xy 416.683698 -286.711644)
			(arc
				(start 416.683698 -286.564324)
				(mid 416.679797 -286.544801)
				(end 416.668712 -286.528256)
			)
			(xy 416.662108 -286.521652) (xy 416.643566 -286.514032)
			(arc
				(start 398.292574 -286.514032)
				(mid 398.273051 -286.517933)
				(end 398.256506 -286.529018)
			)
			(xy 398.252442 -286.533082) (xy 398.252442 -286.687768) (xy 398.255998 -286.700722)
			(arc
				(start 398.259554 -286.706564)
				(mid 398.293838 -286.787679)
				(end 398.305528 -286.874966)
			)
			(arc
				(start 398.305528 -286.874966)
				(mid 398.30247 -286.919833)
				(end 398.293336 -286.963866)
			)
			(arc
				(start 398.293336 -286.963866)
				(mid 398.291693 -286.981502)
				(end 398.29613 -286.998664)
			)
			(arc
				(start 398.309084 -287.026858)
				(mid 398.31906 -287.041479)
				(end 398.333468 -287.05175)
			)
			(arc
				(start 398.333468 -287.05175)
				(mid 398.379808 -287.078858)
				(end 398.420844 -287.113472)
			)
			(arc
				(start 398.58442 -287.277048)
				(mid 398.61376 -287.310825)
				(end 398.638014 -287.348422)
			)
			(xy 398.644872 -287.360868) (xy 398.668494 -287.374838) (xy 406.489154 -287.374838)
		)
		(stroke
			(width 0)
			(type solid)
		)
		(fill yes)
		(layer "B.Cu")
		(net "P1V25_SERDES_VDDPLL_PEX3")
	)
	(gr_poly
		(pts
			(arc
				(start 135.829294 -183.866282)
				(mid 135.848817 -183.862381)
				(end 135.865362 -183.851296)
			)
			(arc
				(start 136.018016 -183.698642)
				(mid 136.029127 -183.682108)
				(end 136.033002 -183.662574)
			)
			(arc
				(start 136.033002 -182.779924)
				(mid 136.030249 -182.763427)
				(end 136.022334 -182.748682)
			)
			(arc
				(start 136.022334 -182.748682)
				(mid 135.947014 -182.609038)
				(end 135.920988 -182.452518)
			)
			(arc
				(start 135.920988 -182.452518)
				(mid 135.92225 -182.417373)
				(end 135.926068 -182.382414)
			)
			(xy 135.927846 -182.370476) (xy 135.920226 -182.347616)
			(arc
				(start 135.662924 -182.090314)
				(mid 135.64639 -182.079203)
				(end 135.626856 -182.075328)
			)
			(arc
				(start 135.180578 -182.075328)
				(mid 135.161055 -182.071427)
				(end 135.14451 -182.060342)
			)
			(xy 135.139176 -182.055008)
			(arc
				(start 135.121396 -182.055008)
				(mid 135.085475 -182.040129)
				(end 135.070596 -182.004208)
			)
			(xy 135.070596 -181.997096) (xy 135.062722 -181.978554)
			(arc
				(start 134.883398 -181.79923)
				(mid 134.872287 -181.782696)
				(end 134.868412 -181.763162)
			)
			(arc
				(start 134.868412 -181.15407)
				(mid 134.864511 -181.134547)
				(end 134.853426 -181.118002)
			)
			(arc
				(start 134.671054 -180.93563)
				(mid 134.65452 -180.924519)
				(end 134.634986 -180.920644)
			)
			(arc
				(start 133.38937 -180.920644)
				(mid 133.369847 -180.924545)
				(end 133.353302 -180.93563)
			)
			(arc
				(start 133.30936 -180.979572)
				(mid 133.298249 -180.996106)
				(end 133.294374 -181.01564)
			)
			(arc
				(start 133.294374 -183.71185)
				(mid 133.298275 -183.731373)
				(end 133.30936 -183.747918)
			)
			(arc
				(start 133.412738 -183.851296)
				(mid 133.429272 -183.862407)
				(end 133.448806 -183.866282)
			)
		)
		(stroke
			(width 0)
			(type solid)
		)
		(fill yes)
		(layer "B.Cu")
		(net "GND")
	)
	(gr_poly
		(pts
			(arc
				(start 453.847708 -109.210094)
				(mid 453.867231 -109.206193)
				(end 453.883776 -109.195108)
			)
			(arc
				(start 454.078594 -109.00029)
				(mid 454.089705 -108.983756)
				(end 454.09358 -108.964222)
			)
			(arc
				(start 454.09358 -108.789216)
				(mid 454.08963 -108.769829)
				(end 454.078594 -108.753402)
			)
			(arc
				(start 453.914256 -108.589064)
				(mid 453.903282 -108.572501)
				(end 453.899524 -108.552996)
			)
			(arc
				(start 453.899524 -103.893874)
				(mid 453.903308 -103.87438)
				(end 453.914256 -103.857806)
			)
			(arc
				(start 454.790556 -102.98176)
				(mid 454.80153 -102.965197)
				(end 454.805288 -102.945692)
			)
			(arc
				(start 454.805288 -100.541328)
				(mid 454.790409 -100.505407)
				(end 454.754488 -100.490528)
			)
			(arc
				(start 447.824352 -100.490528)
				(mid 447.788431 -100.505407)
				(end 447.773552 -100.541328)
			)
			(arc
				(start 447.773552 -101.16439)
				(mid 447.769651 -101.183913)
				(end 447.758566 -101.200458)
			)
			(arc
				(start 447.084196 -101.874828)
				(mid 447.073085 -101.891362)
				(end 447.06921 -101.910896)
			)
			(arc
				(start 447.06921 -107.792012)
				(mid 447.073111 -107.811535)
				(end 447.084196 -107.82808)
			)
			(arc
				(start 447.274188 -108.018072)
				(mid 447.290722 -108.029183)
				(end 447.310256 -108.033058)
			)
			(arc
				(start 451.711568 -108.033058)
				(mid 451.731091 -108.036959)
				(end 451.747636 -108.048044)
			)
			(arc
				(start 451.924928 -108.225336)
				(mid 451.936039 -108.24187)
				(end 451.939914 -108.261404)
			)
			(arc
				(start 451.939914 -109.035342)
				(mid 451.943815 -109.054865)
				(end 451.9549 -109.07141)
			)
			(arc
				(start 452.078598 -109.195108)
				(mid 452.095132 -109.206219)
				(end 452.114666 -109.210094)
			)
		)
		(stroke
			(width 0)
			(type solid)
		)
		(fill yes)
		(layer "B.Cu")
		(net "GND")
	)
	(gr_poly
		(pts
			(arc
				(start 208.88452 -366.404398)
				(mid 208.904043 -366.400497)
				(end 208.920588 -366.389412)
			)
			(arc
				(start 209.032094 -366.277906)
				(mid 209.043205 -366.261372)
				(end 209.04708 -366.241838)
			)
			(arc
				(start 209.04708 -365.515906)
				(mid 209.050981 -365.496383)
				(end 209.062066 -365.479838)
			)
			(arc
				(start 209.323686 -365.218218)
				(mid 209.34022 -365.207107)
				(end 209.359754 -365.203232)
			)
			(arc
				(start 210.95335 -365.203232)
				(mid 210.972873 -365.199331)
				(end 210.989418 -365.188246)
			)
			(arc
				(start 211.30387 -364.873794)
				(mid 211.314981 -364.85726)
				(end 211.318856 -364.837726)
			)
			(arc
				(start 211.318856 -362.538264)
				(mid 211.314955 -362.518741)
				(end 211.30387 -362.502196)
			)
			(arc
				(start 211.101432 -362.299758)
				(mid 211.084898 -362.288647)
				(end 211.065364 -362.284772)
			)
			(arc
				(start 207.063086 -362.284772)
				(mid 207.043563 -362.288673)
				(end 207.027018 -362.299758)
			)
			(arc
				(start 205.08595 -364.240826)
				(mid 205.074839 -364.25736)
				(end 205.070964 -364.276894)
			)
			(arc
				(start 205.070964 -364.47984)
				(mid 205.067063 -364.499363)
				(end 205.055978 -364.515908)
			)
			(arc
				(start 205.031848 -364.540038)
				(mid 205.015314 -364.551149)
				(end 204.99578 -364.555024)
			)
			(arc
				(start 204.550518 -364.555024)
				(mid 204.530995 -364.558925)
				(end 204.51445 -364.57001)
			)
			(xy 204.510386 -364.574074) (xy 204.502766 -364.592616)
			(arc
				(start 204.502766 -365.258858)
				(mid 204.506667 -365.278381)
				(end 204.517752 -365.294926)
			)
			(arc
				(start 205.54569 -366.322864)
				(mid 205.562136 -366.33379)
				(end 205.581504 -366.337596)
			)
			(arc
				(start 208.31937 -366.337596)
				(mid 208.338757 -366.341546)
				(end 208.355184 -366.352582)
			)
			(arc
				(start 208.392014 -366.389412)
				(mid 208.408548 -366.400523)
				(end 208.428082 -366.404398)
			)
		)
		(stroke
			(width 0)
			(type solid)
		)
		(fill yes)
		(layer "B.Cu")
		(net "P12V_AUX")
	)
	(gr_poly
		(pts
			(arc
				(start 421.889428 -299.406564)
				(mid 421.908951 -299.402663)
				(end 421.925496 -299.391578)
			)
			(arc
				(start 421.938958 -299.378116)
				(mid 421.94577 -299.369594)
				(end 421.950642 -299.359828)
			)
			(arc
				(start 421.950642 -299.359828)
				(mid 421.955811 -299.345764)
				(end 421.96258 -299.332396)
			)
			(xy 421.965882 -299.326554) (xy 421.969438 -299.313854) (xy 421.969438 -299.159422) (xy 421.963342 -299.142658)
			(arc
				(start 421.9575 -299.1358)
				(mid 421.873111 -298.990282)
				(end 421.843708 -298.82465)
			)
			(arc
				(start 421.843708 -298.62272)
				(mid 421.873085 -298.457078)
				(end 421.9575 -298.31157)
			)
			(arc
				(start 421.9575 -298.31157)
				(mid 421.966384 -298.296246)
				(end 421.969438 -298.278804)
			)
			(arc
				(start 421.969438 -292.456616)
				(mid 421.965537 -292.437093)
				(end 421.954452 -292.420548)
			)
			(xy 421.915336 -292.381432) (xy 421.908224 -292.374066) (xy 421.889428 -292.366446)
			(arc
				(start 421.65143 -292.366446)
				(mid 421.631907 -292.370347)
				(end 421.615362 -292.381432)
			)
			(xy 421.579294 -292.4175) (xy 421.57904 -292.417754) (xy 421.567864 -292.42893) (xy 421.567356 -292.429438)
			(arc
				(start 421.384222 -292.612572)
				(mid 421.373111 -292.629106)
				(end 421.369236 -292.64864)
			)
			(arc
				(start 421.369236 -293.03345)
				(mid 421.373186 -293.052837)
				(end 421.384222 -293.069264)
			)
			(xy 421.385238 -293.070534) (xy 421.393112 -293.089076)
			(arc
				(start 421.393112 -298.63923)
				(mid 421.389162 -298.658617)
				(end 421.378126 -298.675044)
			)
			(xy 421.376856 -298.676314) (xy 421.369236 -298.694856)
			(arc
				(start 421.369236 -299.226732)
				(mid 421.373137 -299.246255)
				(end 421.384222 -299.2628)
			)
			(arc
				(start 421.513 -299.391578)
				(mid 421.529534 -299.402689)
				(end 421.549068 -299.406564)
			)
		)
		(stroke
			(width 0)
			(type solid)
		)
		(fill yes)
		(layer "B.Cu")
		(net "GND")
	)
	(gr_poly
		(pts
			(arc
				(start 183.960516 -303.402238)
				(mid 183.979707 -303.398473)
				(end 183.996076 -303.38776)
			)
			(xy 183.99633 -303.387506) (xy 184.220612 -303.163224)
			(arc
				(start 184.22112 -303.162716)
				(mid 184.231862 -303.146359)
				(end 184.235598 -303.127156)
			)
			(xy 184.235598 -302.60036) (xy 184.227978 -302.581564) (xy 184.220612 -302.574452)
			(arc
				(start 184.19699 -302.55083)
				(mid 184.180456 -302.539719)
				(end 184.160922 -302.535844)
			)
			(xy 166.180516 -302.535844) (xy 166.179246 -302.537368)
			(arc
				(start 166.175944 -302.537368)
				(mid 166.162945 -302.542424)
				(end 166.151814 -302.55083)
			)
			(arc
				(start 166.038784 -302.66386)
				(mid 166.027673 -302.680394)
				(end 166.023798 -302.699928)
			)
			(xy 166.023798 -302.764952) (xy 166.026592 -302.776636)
			(arc
				(start 166.029386 -302.78197)
				(mid 166.036617 -302.799654)
				(end 166.040816 -302.818292)
			)
			(arc
				(start 166.040816 -302.818292)
				(mid 166.043648 -302.829431)
				(end 166.048944 -302.839628)
			)
			(arc
				(start 166.048944 -302.839628)
				(mid 166.091106 -302.927848)
				(end 166.105586 -303.02454)
			)
			(arc
				(start 166.105586 -303.025048)
				(mid 166.091061 -303.121726)
				(end 166.048944 -303.20996)
			)
			(arc
				(start 166.048944 -303.20996)
				(mid 166.043682 -303.220169)
				(end 166.040816 -303.231296)
			)
			(arc
				(start 166.040816 -303.231296)
				(mid 166.036623 -303.249936)
				(end 166.029386 -303.267618)
			)
			(xy 166.026592 -303.272952) (xy 166.023798 -303.284636)
			(arc
				(start 166.023798 -303.304956)
				(mid 166.027563 -303.324147)
				(end 166.038276 -303.340516)
			)
			(xy 166.03853 -303.34077)
			(arc
				(start 166.047166 -303.349406)
				(mid 166.063583 -303.360468)
				(end 166.08298 -303.364392)
			)
			(arc
				(start 183.8452 -303.364392)
				(mid 183.864421 -303.368273)
				(end 183.88076 -303.379124)
			)
			(arc
				(start 183.88965 -303.38776)
				(mid 183.906007 -303.398502)
				(end 183.92521 -303.402238)
			)
		)
		(stroke
			(width 0)
			(type solid)
		)
		(fill yes)
		(layer "B.Cu")
		(net "P1V25_PEX1")
	)
	(gr_poly
		(pts
			(arc
				(start 305.78933 -299.406564)
				(mid 305.808853 -299.402663)
				(end 305.825398 -299.391578)
			)
			(arc
				(start 305.83886 -299.378116)
				(mid 305.846321 -299.36871)
				(end 305.851306 -299.357796)
			)
			(arc
				(start 305.851306 -299.357542)
				(mid 305.85621 -299.344665)
				(end 305.862482 -299.332396)
			)
			(arc
				(start 305.862482 -299.332142)
				(mid 305.867529 -299.320013)
				(end 305.86934 -299.306996)
			)
			(arc
				(start 305.86934 -299.168566)
				(mid 305.866256 -299.151135)
				(end 305.857402 -299.1358)
			)
			(arc
				(start 305.857402 -299.1358)
				(mid 305.773013 -298.990282)
				(end 305.74361 -298.82465)
			)
			(arc
				(start 305.74361 -298.62272)
				(mid 305.772987 -298.457078)
				(end 305.857402 -298.31157)
			)
			(arc
				(start 305.857402 -298.31157)
				(mid 305.866286 -298.296246)
				(end 305.86934 -298.278804)
			)
			(arc
				(start 305.86934 -292.456616)
				(mid 305.865439 -292.437093)
				(end 305.854354 -292.420548)
			)
			(arc
				(start 305.815238 -292.381432)
				(mid 305.798704 -292.370321)
				(end 305.77917 -292.366446)
			)
			(arc
				(start 305.551332 -292.366446)
				(mid 305.531809 -292.370347)
				(end 305.515264 -292.381432)
			)
			(xy 305.479196 -292.4175) (xy 305.478688 -292.418008) (xy 305.467766 -292.42893) (xy 305.467258 -292.429438)
			(arc
				(start 305.248818 -292.647878)
				(mid 305.237707 -292.664412)
				(end 305.233832 -292.683946)
			)
			(arc
				(start 305.233832 -296.172128)
				(mid 305.229931 -296.191651)
				(end 305.218846 -296.208196)
			)
			(arc
				(start 305.18989 -296.237152)
				(mid 305.178779 -296.253686)
				(end 305.174904 -296.27322)
			)
			(arc
				(start 305.174904 -299.132498)
				(mid 305.178805 -299.152021)
				(end 305.18989 -299.168566)
			)
			(arc
				(start 305.412902 -299.391578)
				(mid 305.429436 -299.402689)
				(end 305.44897 -299.406564)
			)
		)
		(stroke
			(width 0)
			(type solid)
		)
		(fill yes)
		(layer "B.Cu")
		(net "GND")
	)
	(gr_poly
		(pts
			(arc
				(start 338.966556 -222.595948)
				(mid 338.989433 -222.590505)
				(end 339.00745 -222.575374)
			)
			(arc
				(start 339.00745 -222.575374)
				(mid 339.072659 -222.507885)
				(end 339.153246 -222.459804)
			)
			(xy 339.162136 -222.455994) (xy 339.358224 -222.26016) (xy 339.358224 -222.247968) (xy 339.532468 -222.073724)
			(xy 339.532468 -221.842584) (xy 339.595968 -221.779084) (xy 339.804502 -221.779084)
			(arc
				(start 339.80755 -221.775274)
				(mid 339.838841 -221.738425)
				(end 339.87486 -221.706186)
			)
			(arc
				(start 339.87486 -221.706186)
				(mid 339.889254 -221.688503)
				(end 339.894418 -221.666308)
			)
			(arc
				(start 339.894418 -221.54261)
				(mid 339.890517 -221.523087)
				(end 339.879432 -221.506542)
			)
			(arc
				(start 339.344254 -220.971364)
				(mid 339.32772 -220.960253)
				(end 339.308186 -220.956378)
			)
			(arc
				(start 339.29701 -220.956378)
				(mid 339.277487 -220.960279)
				(end 339.260942 -220.971364)
			)
			(arc
				(start 338.739734 -221.492318)
				(mid 338.724973 -221.528132)
				(end 338.739734 -221.563946)
			)
			(arc
				(start 338.85505 -221.679262)
				(mid 338.866161 -221.695796)
				(end 338.870036 -221.71533)
			)
			(arc
				(start 338.870036 -222.071692)
				(mid 338.866135 -222.091215)
				(end 338.85505 -222.10776)
			)
			(xy 338.808568 -222.154242)
			(arc
				(start 338.805012 -222.160592)
				(mid 338.74595 -222.23869)
				(end 338.667852 -222.297752)
			)
			(xy 338.661502 -222.301308)
			(arc
				(start 338.59216 -222.37065)
				(mid 338.581049 -222.387184)
				(end 338.577174 -222.406718)
			)
			(xy 338.577174 -222.41129) (xy 338.619338 -222.453454)
			(arc
				(start 338.628736 -222.457264)
				(mid 338.712791 -222.505885)
				(end 338.780628 -222.575374)
			)
			(arc
				(start 338.780628 -222.575374)
				(mid 338.798621 -222.590552)
				(end 338.821522 -222.595948)
			)
		)
		(stroke
			(width 0)
			(type solid)
		)
		(fill yes)
		(layer "B.Cu")
		(net "P3V3_FPGA_VCCIO5")
	)
	(gr_poly
		(pts
			(arc
				(start 300.06036 -303.402238)
				(mid 300.079551 -303.398473)
				(end 300.09592 -303.38776)
			)
			(xy 300.096174 -303.387506) (xy 300.320456 -303.163224)
			(arc
				(start 300.320964 -303.162716)
				(mid 300.331706 -303.146359)
				(end 300.335442 -303.127156)
			)
			(xy 300.335442 -302.60036) (xy 300.327822 -302.581564) (xy 300.320456 -302.574452)
			(arc
				(start 300.296834 -302.55083)
				(mid 300.2803 -302.539719)
				(end 300.260766 -302.535844)
			)
			(xy 282.28036 -302.535844) (xy 282.27909 -302.537368)
			(arc
				(start 282.275788 -302.537368)
				(mid 282.262789 -302.542424)
				(end 282.251658 -302.55083)
			)
			(arc
				(start 282.138628 -302.66386)
				(mid 282.127517 -302.680394)
				(end 282.123642 -302.699928)
			)
			(xy 282.123642 -302.764952) (xy 282.126436 -302.776636)
			(arc
				(start 282.12923 -302.78197)
				(mid 282.136461 -302.799654)
				(end 282.14066 -302.818292)
			)
			(arc
				(start 282.14066 -302.818292)
				(mid 282.143492 -302.829431)
				(end 282.148788 -302.839628)
			)
			(arc
				(start 282.148788 -302.839628)
				(mid 282.19095 -302.927848)
				(end 282.20543 -303.02454)
			)
			(arc
				(start 282.20543 -303.025048)
				(mid 282.190905 -303.121726)
				(end 282.148788 -303.20996)
			)
			(arc
				(start 282.148788 -303.20996)
				(mid 282.143526 -303.220169)
				(end 282.14066 -303.231296)
			)
			(arc
				(start 282.14066 -303.231296)
				(mid 282.136467 -303.249936)
				(end 282.12923 -303.267618)
			)
			(xy 282.126436 -303.272952) (xy 282.123642 -303.284636)
			(arc
				(start 282.123642 -303.304956)
				(mid 282.127407 -303.324147)
				(end 282.13812 -303.340516)
			)
			(xy 282.138374 -303.34077)
			(arc
				(start 282.14701 -303.349406)
				(mid 282.162404 -303.359884)
				(end 282.180538 -303.364138)
			)
			(xy 282.183586 -303.364392)
			(arc
				(start 299.945044 -303.364392)
				(mid 299.964265 -303.368273)
				(end 299.980604 -303.379124)
			)
			(arc
				(start 299.989494 -303.38776)
				(mid 300.005851 -303.398502)
				(end 300.025054 -303.402238)
			)
		)
		(stroke
			(width 0)
			(type solid)
		)
		(fill yes)
		(layer "B.Cu")
		(net "P1V25_PEX2")
	)
	(gr_poly
		(pts
			(arc
				(start 464.888834 -272.159476)
				(mid 464.908357 -272.155575)
				(end 464.924902 -272.14449)
			)
			(arc
				(start 465.199222 -271.87017)
				(mid 465.210333 -271.853636)
				(end 465.214208 -271.834102)
			)
			(arc
				(start 465.214208 -254.649986)
				(mid 465.210307 -254.630463)
				(end 465.199222 -254.613918)
			)
			(arc
				(start 464.952588 -254.367284)
				(mid 464.936054 -254.356173)
				(end 464.91652 -254.352298)
			)
			(xy 453.37349 -254.352298) (xy 452.728584 -254.997204) (xy 452.699882 -254.997204) (xy 452.685404 -255.011682)
			(xy 449.545456 -255.011682) (xy 446.963038 -257.5941) (xy 446.963038 -258.340098) (xy 447.830194 -259.207254)
			(xy 447.830194 -260.143244) (xy 446.952878 -261.02056) (xy 446.952878 -271.825212)
			(arc
				(start 447.21653 -272.088864)
				(mid 447.233064 -272.099975)
				(end 447.252598 -272.10385)
			)
			(arc
				(start 450.261736 -272.10385)
				(mid 450.281259 -272.099949)
				(end 450.297804 -272.088864)
			)
			(arc
				(start 450.318886 -272.067782)
				(mid 450.328345 -272.05496)
				(end 450.333364 -272.039842)
			)
			(xy 450.333872 -272.031714)
			(arc
				(start 450.333872 -262.043418)
				(mid 450.337616 -262.024529)
				(end 450.348096 -262.008366)
			)
			(xy 450.348604 -262.007858)
			(arc
				(start 450.352922 -262.003032)
				(mid 450.362648 -261.987234)
				(end 450.36613 -261.968996)
			)
			(arc
				(start 450.36613 -261.580376)
				(mid 450.370031 -261.560853)
				(end 450.381116 -261.544308)
			)
			(arc
				(start 450.670422 -261.255002)
				(mid 450.686956 -261.243891)
				(end 450.70649 -261.240016)
			)
			(arc
				(start 457.143612 -261.240016)
				(mid 457.163135 -261.243917)
				(end 457.17968 -261.255002)
			)
			(arc
				(start 457.676758 -261.75208)
				(mid 457.687869 -261.768614)
				(end 457.691744 -261.788148)
			)
			(arc
				(start 457.691744 -272.082768)
				(mid 457.695645 -272.102291)
				(end 457.70673 -272.118836)
			)
			(arc
				(start 457.732384 -272.14449)
				(mid 457.748918 -272.155601)
				(end 457.768452 -272.159476)
			)
		)
		(stroke
			(width 0)
			(type solid)
		)
		(fill yes)
		(layer "B.Cu")
		(net "P1V25_SERDES_VDDPLL_PEX3")
	)
	(gr_poly
		(pts
			(arc
				(start 345.205558 -318.761872)
				(mid 345.225081 -318.757971)
				(end 345.241626 -318.746886)
			)
			(arc
				(start 345.497658 -318.490854)
				(mid 345.508769 -318.47432)
				(end 345.512644 -318.454786)
			)
			(arc
				(start 345.512644 -308.820566)
				(mid 345.508743 -308.801043)
				(end 345.497658 -308.784498)
			)
			(arc
				(start 345.382342 -308.669182)
				(mid 345.365808 -308.658071)
				(end 345.346274 -308.654196)
			)
			(xy 341.099902 -308.654196) (xy 340.889844 -308.864254) (xy 340.877144 -308.876954) (xy 338.313776 -308.876954)
			(xy 338.300822 -308.864) (xy 338.091018 -308.654196)
			(arc
				(start 333.292958 -308.654196)
				(mid 333.273435 -308.650295)
				(end 333.25689 -308.63921)
			)
			(arc
				(start 332.827376 -308.209696)
				(mid 332.816265 -308.193162)
				(end 332.81239 -308.173628)
			)
			(arc
				(start 332.81239 -303.665128)
				(mid 332.816291 -303.645605)
				(end 332.827376 -303.62906)
			)
			(arc
				(start 333.039974 -303.416462)
				(mid 333.056508 -303.405351)
				(end 333.076042 -303.401476)
			)
			(arc
				(start 348.010226 -303.401476)
				(mid 348.029749 -303.397575)
				(end 348.046294 -303.38649)
			)
			(xy 348.18574 -303.247044) (xy 348.18574 -302.679862) (xy 348.28353 -302.582072) (xy 348.850712 -302.582072)
			(arc
				(start 350.17964 -301.253144)
				(mid 350.190751 -301.23661)
				(end 350.194626 -301.217076)
			)
			(arc
				(start 350.194626 -294.085772)
				(mid 350.190725 -294.066249)
				(end 350.17964 -294.049704)
			)
			(arc
				(start 350.087946 -293.95801)
				(mid 350.071412 -293.946899)
				(end 350.051878 -293.943024)
			)
			(arc
				(start 328.38898 -293.943024)
				(mid 328.369457 -293.946925)
				(end 328.352912 -293.95801)
			)
			(xy 327.93305 -294.377872) (xy 327.925684 -294.384984) (xy 327.918064 -294.40378) (xy 327.918064 -313.594242)
			(xy 329.660504 -315.336682) (xy 333.516224 -315.336682) (xy 333.831692 -315.65215) (xy 333.831692 -317.092838)
			(xy 333.73568 -317.18885) (xy 332.555596 -317.18885) (xy 332.459584 -317.284862) (xy 332.459584 -318.350138)
			(xy 332.871318 -318.761872)
		)
		(stroke
			(width 0)
			(type solid)
		)
		(fill yes)
		(layer "B.Cu")
		(net "P0V8_PEX2")
	)
	(gr_poly
		(pts
			(arc
				(start 230.03256 -272.036032)
				(mid 230.048624 -272.033425)
				(end 230.06304 -272.025872)
			)
			(xy 230.068628 -272.021046) (xy 230.316278 -271.773396)
			(arc
				(start 230.321104 -271.767808)
				(mid 230.328657 -271.753392)
				(end 230.331264 -271.737328)
			)
			(xy 230.331264 -255.479296) (xy 230.026972 -255.175004) (xy 221.259654 -255.175004) (xy 219.300044 -257.134614)
			(arc
				(start 216.270078 -257.134614)
				(mid 216.254014 -257.137221)
				(end 216.239598 -257.144774)
			)
			(xy 216.23401 -257.1496) (xy 215.805766 -257.577844)
			(arc
				(start 215.80094 -257.583432)
				(mid 215.793387 -257.597848)
				(end 215.79078 -257.613912)
			)
			(arc
				(start 215.79078 -258.00812)
				(mid 215.875903 -258.133018)
				(end 215.905842 -258.28117)
			)
			(arc
				(start 215.905842 -258.28117)
				(mid 215.875901 -258.429321)
				(end 215.79078 -258.55422)
			)
			(arc
				(start 215.79078 -271.140682)
				(mid 215.793387 -271.156746)
				(end 215.80094 -271.171162)
			)
			(xy 215.805766 -271.17675) (xy 216.594436 -271.96542)
			(arc
				(start 216.600024 -271.970246)
				(mid 216.61444 -271.977799)
				(end 216.630504 -271.980406)
			)
			(arc
				(start 219.640658 -271.980406)
				(mid 219.656722 -271.977799)
				(end 219.671138 -271.970246)
			)
			(xy 219.676726 -271.96542) (xy 219.730066 -271.91208)
			(arc
				(start 219.734892 -271.906492)
				(mid 219.742445 -271.892076)
				(end 219.745052 -271.876012)
			)
			(arc
				(start 219.745052 -261.456932)
				(mid 219.748953 -261.437409)
				(end 219.760038 -261.420864)
			)
			(arc
				(start 220.049344 -261.131558)
				(mid 220.065878 -261.120447)
				(end 220.085412 -261.116572)
			)
			(arc
				(start 226.522534 -261.116572)
				(mid 226.542057 -261.120473)
				(end 226.558602 -261.131558)
			)
			(arc
				(start 227.05568 -261.628636)
				(mid 227.066791 -261.64517)
				(end 227.070666 -261.664704)
			)
			(xy 227.070666 -271.806162) (xy 227.300536 -272.036032)
		)
		(stroke
			(width 0)
			(type solid)
		)
		(fill yes)
		(layer "B.Cu")
		(net "P1V25_SERDES_VDDPLL_PEX1")
	)
	(gr_poly
		(pts
			(arc
				(start 104.26065 -337.319112)
				(mid 104.280173 -337.315211)
				(end 104.296718 -337.304126)
			)
			(arc
				(start 104.480614 -337.12023)
				(mid 104.491725 -337.103696)
				(end 104.4956 -337.084162)
			)
			(arc
				(start 104.4956 -336.091022)
				(mid 104.491699 -336.071499)
				(end 104.480614 -336.054954)
			)
			(arc
				(start 104.272334 -335.846674)
				(mid 104.261223 -335.83014)
				(end 104.257348 -335.810606)
			)
			(arc
				(start 104.257348 -335.194656)
				(mid 104.261249 -335.175133)
				(end 104.272334 -335.158588)
			)
			(arc
				(start 104.480614 -334.950308)
				(mid 104.491725 -334.933774)
				(end 104.4956 -334.91424)
			)
			(xy 104.4956 -334.638904) (xy 104.490266 -334.63357)
			(arc
				(start 104.490266 -334.48752)
				(mid 104.494167 -334.467997)
				(end 104.505252 -334.451452)
			)
			(arc
				(start 104.642412 -334.314292)
				(mid 104.653523 -334.297758)
				(end 104.657398 -334.278224)
			)
			(arc
				(start 104.657398 -333.724758)
				(mid 104.653497 -333.705235)
				(end 104.642412 -333.68869)
			)
			(arc
				(start 104.635808 -333.682086)
				(mid 104.619274 -333.670975)
				(end 104.59974 -333.6671)
			)
			(xy 104.045258 -333.6671)
			(arc
				(start 104.038654 -333.668878)
				(mid 103.98955 -333.678615)
				(end 103.939594 -333.681832)
			)
			(arc
				(start 103.581962 -333.681832)
				(mid 103.562575 -333.685782)
				(end 103.546148 -333.696818)
			)
			(arc
				(start 103.413306 -333.82966)
				(mid 103.402195 -333.846194)
				(end 103.39832 -333.865728)
			)
			(arc
				(start 103.39832 -334.2259)
				(mid 103.394419 -334.245423)
				(end 103.383334 -334.261968)
			)
			(arc
				(start 102.786434 -334.858868)
				(mid 102.7699 -334.869979)
				(end 102.750366 -334.873854)
			)
			(arc
				(start 100.859336 -334.873854)
				(mid 100.839813 -334.877755)
				(end 100.823268 -334.88884)
			)
			(arc
				(start 100.727764 -334.984344)
				(mid 100.716653 -335.000878)
				(end 100.712778 -335.020412)
			)
			(arc
				(start 100.712778 -336.95894)
				(mid 100.716679 -336.978463)
				(end 100.727764 -336.995008)
			)
			(arc
				(start 101.036882 -337.304126)
				(mid 101.053416 -337.315237)
				(end 101.07295 -337.319112)
			)
		)
		(stroke
			(width 0)
			(type solid)
		)
		(fill yes)
		(layer "B.Cu")
		(net "P3V3_CLK_BUFFER_9ZXL0451E_VZX3P3")
	)
	(gr_poly
		(pts
			(arc
				(start 109.099096 -357.3653)
				(mid 109.118619 -357.361399)
				(end 109.135164 -357.350314)
			)
			(arc
				(start 109.444282 -357.041196)
				(mid 109.455393 -357.024662)
				(end 109.459268 -357.005128)
			)
			(arc
				(start 109.459268 -353.817428)
				(mid 109.455367 -353.797905)
				(end 109.444282 -353.78136)
			)
			(arc
				(start 109.260386 -353.597464)
				(mid 109.243852 -353.586353)
				(end 109.224318 -353.582478)
			)
			(arc
				(start 108.231178 -353.582478)
				(mid 108.211655 -353.586379)
				(end 108.19511 -353.597464)
			)
			(arc
				(start 107.98683 -353.805744)
				(mid 107.970296 -353.816855)
				(end 107.950762 -353.82073)
			)
			(arc
				(start 107.334812 -353.82073)
				(mid 107.315289 -353.816829)
				(end 107.298744 -353.805744)
			)
			(arc
				(start 107.090464 -353.597464)
				(mid 107.07393 -353.586353)
				(end 107.054396 -353.582478)
			)
			(xy 106.77906 -353.582478) (xy 106.773726 -353.587812)
			(arc
				(start 106.627676 -353.587812)
				(mid 106.608153 -353.583911)
				(end 106.591608 -353.572826)
			)
			(arc
				(start 106.454448 -353.435666)
				(mid 106.437914 -353.424555)
				(end 106.41838 -353.42068)
			)
			(arc
				(start 105.864914 -353.42068)
				(mid 105.845391 -353.424581)
				(end 105.828846 -353.435666)
			)
			(arc
				(start 105.822242 -353.44227)
				(mid 105.811131 -353.458804)
				(end 105.807256 -353.478338)
			)
			(xy 105.807256 -354.03282)
			(arc
				(start 105.809034 -354.039424)
				(mid 105.818771 -354.088528)
				(end 105.821988 -354.138484)
			)
			(arc
				(start 105.821988 -354.496116)
				(mid 105.825938 -354.515503)
				(end 105.836974 -354.53193)
			)
			(arc
				(start 105.969816 -354.664772)
				(mid 105.98635 -354.675883)
				(end 106.005884 -354.679758)
			)
			(arc
				(start 106.366056 -354.679758)
				(mid 106.385579 -354.683659)
				(end 106.402124 -354.694744)
			)
			(arc
				(start 106.999024 -355.291644)
				(mid 107.010135 -355.308178)
				(end 107.01401 -355.327712)
			)
			(arc
				(start 107.01401 -357.218742)
				(mid 107.017911 -357.238265)
				(end 107.028996 -357.25481)
			)
			(arc
				(start 107.1245 -357.350314)
				(mid 107.141034 -357.361425)
				(end 107.160568 -357.3653)
			)
		)
		(stroke
			(width 0)
			(type solid)
		)
		(fill yes)
		(layer "B.Cu")
		(net "P3V3_CLK_BUFFER_9ZXL0451E_S3_VZX3P3")
	)
	(gr_poly
		(pts
			(arc
				(start 14.9733 -269.74927)
				(mid 14.992823 -269.745369)
				(end 15.009368 -269.734284)
			)
			(xy 15.257018 -269.486634)
			(arc
				(start 15.261844 -269.481046)
				(mid 15.269397 -269.46663)
				(end 15.272004 -269.450566)
			)
			(arc
				(start 15.272004 -255.27127)
				(mid 15.268103 -255.251747)
				(end 15.257018 -255.235202)
			)
			(xy 14.884654 -254.862838) (xy 14.877542 -254.855472)
			(arc
				(start 14.86789 -254.851662)
				(mid 14.858549 -254.848838)
				(end 14.84884 -254.847852)
			)
			(arc
				(start 2.824988 -254.847852)
				(mid 2.808924 -254.850459)
				(end 2.794508 -254.858012)
			)
			(xy 2.78892 -254.862838) (xy 1.942592 -255.709166)
			(arc
				(start 1.937766 -255.714754)
				(mid 1.930213 -255.72917)
				(end 1.927606 -255.745234)
			)
			(arc
				(start 1.927606 -269.26667)
				(mid 1.930213 -269.282734)
				(end 1.937766 -269.29715)
			)
			(xy 1.942592 -269.302738) (xy 2.318512 -269.678658)
			(arc
				(start 2.3241 -269.683484)
				(mid 2.338516 -269.691037)
				(end 2.35458 -269.693644)
			)
			(arc
				(start 4.510024 -269.693644)
				(mid 4.545945 -269.678765)
				(end 4.560824 -269.642844)
			)
			(arc
				(start 4.560824 -259.784342)
				(mid 4.584113 -259.667642)
				(end 4.650232 -259.568696)
			)
			(arc
				(start 4.670806 -259.548122)
				(mid 4.681868 -259.531705)
				(end 4.685792 -259.512308)
			)
			(arc
				(start 4.685792 -259.17017)
				(mid 4.689693 -259.150647)
				(end 4.700778 -259.134102)
			)
			(arc
				(start 4.990084 -258.844796)
				(mid 5.006618 -258.833685)
				(end 5.026152 -258.82981)
			)
			(arc
				(start 11.463274 -258.82981)
				(mid 11.482797 -258.833711)
				(end 11.499342 -258.844796)
			)
			(arc
				(start 11.99642 -259.341874)
				(mid 12.007531 -259.358408)
				(end 12.011406 -259.377942)
			)
			(arc
				(start 12.011406 -269.672562)
				(mid 12.015307 -269.692085)
				(end 12.026392 -269.70863)
			)
			(xy 12.052046 -269.734284)
			(arc
				(start 12.057634 -269.73911)
				(mid 12.07205 -269.746663)
				(end 12.088114 -269.74927)
			)
		)
		(stroke
			(width 0)
			(type solid)
		)
		(fill yes)
		(layer "B.Cu")
		(net "P1V25_SERDES_VDDPLL_PEX0")
	)
	(gr_poly
		(pts
			(arc
				(start 339.82279 -89.923112)
				(mid 339.842313 -89.919211)
				(end 339.858858 -89.908126)
			)
			(arc
				(start 340.060534 -89.70645)
				(mid 340.071645 -89.689916)
				(end 340.07552 -89.670382)
			)
			(arc
				(start 340.07552 -89.21115)
				(mid 340.079421 -89.191627)
				(end 340.090506 -89.175082)
			)
			(arc
				(start 340.239096 -89.026492)
				(mid 340.250207 -89.009958)
				(end 340.254082 -88.990424)
			)
			(arc
				(start 340.254082 -84.881212)
				(mid 340.250181 -84.861689)
				(end 340.239096 -84.845144)
			)
			(arc
				(start 340.078568 -84.684616)
				(mid 340.062122 -84.67369)
				(end 340.042754 -84.669884)
			)
			(arc
				(start 336.086196 -84.669884)
				(mid 336.066702 -84.673668)
				(end 336.050128 -84.684616)
			)
			(arc
				(start 335.935066 -84.799678)
				(mid 335.924092 -84.816241)
				(end 335.920334 -84.835746)
			)
			(arc
				(start 335.920334 -86.149688)
				(mid 335.916384 -86.169075)
				(end 335.905348 -86.185502)
			)
			(arc
				(start 335.85404 -86.237064)
				(mid 335.842978 -86.253481)
				(end 335.839054 -86.272878)
			)
			(xy 335.839054 -87.773764)
			(arc
				(start 335.841848 -87.781638)
				(mid 335.856882 -87.841905)
				(end 335.861914 -87.903812)
			)
			(arc
				(start 335.861914 -87.903812)
				(mid 335.856858 -87.965715)
				(end 335.841848 -88.025986)
			)
			(xy 335.839054 -88.03386)
			(arc
				(start 335.839054 -89.178638)
				(mid 335.842955 -89.198161)
				(end 335.85404 -89.214706)
			)
			(arc
				(start 336.012282 -89.372948)
				(mid 336.028816 -89.384059)
				(end 336.04835 -89.387934)
			)
			(arc
				(start 337.437476 -89.387934)
				(mid 337.456999 -89.384033)
				(end 337.473544 -89.372948)
			)
			(arc
				(start 337.699858 -89.146634)
				(mid 337.716392 -89.135523)
				(end 337.735926 -89.131648)
			)
			(arc
				(start 338.31149 -89.131648)
				(mid 338.331013 -89.135549)
				(end 338.347558 -89.146634)
			)
			(arc
				(start 338.491322 -89.290398)
				(mid 338.502433 -89.306932)
				(end 338.506308 -89.326466)
			)
			(arc
				(start 338.506308 -89.82075)
				(mid 338.510209 -89.840273)
				(end 338.521294 -89.856818)
			)
			(arc
				(start 338.572602 -89.908126)
				(mid 338.589136 -89.919237)
				(end 338.60867 -89.923112)
			)
		)
		(stroke
			(width 0)
			(type solid)
		)
		(fill yes)
		(layer "B.Cu")
		(net "GND")
	)
	(gr_poly
		(pts
			(arc
				(start 191.57823 -112.901984)
				(mid 191.595527 -112.898857)
				(end 191.610742 -112.890046)
			)
			(arc
				(start 191.610742 -112.890046)
				(mid 191.920622 -112.7775)
				(end 192.230502 -112.890046)
			)
			(arc
				(start 192.230502 -112.890046)
				(mid 192.245707 -112.898886)
				(end 192.263014 -112.901984)
			)
			(arc
				(start 192.547748 -112.901984)
				(mid 192.567105 -112.898151)
				(end 192.583562 -112.887252)
			)
			(arc
				(start 192.583562 -112.887252)
				(mid 192.739863 -112.783474)
				(end 192.923922 -112.747044)
			)
			(arc
				(start 192.923922 -112.747044)
				(mid 193.108009 -112.783408)
				(end 193.264282 -112.887252)
			)
			(arc
				(start 193.264282 -112.887252)
				(mid 193.280728 -112.898178)
				(end 193.300096 -112.901984)
			)
			(arc
				(start 195.722494 -112.901984)
				(mid 195.742017 -112.898083)
				(end 195.758562 -112.886998)
			)
			(arc
				(start 197.15861 -111.48695)
				(mid 197.175144 -111.475839)
				(end 197.194678 -111.471964)
			)
			(arc
				(start 214.310976 -111.471964)
				(mid 214.330499 -111.468063)
				(end 214.347044 -111.456978)
			)
			(arc
				(start 214.721186 -111.082836)
				(mid 214.732297 -111.066302)
				(end 214.736172 -111.046768)
			)
			(arc
				(start 214.736172 -107.241848)
				(mid 214.732271 -107.222325)
				(end 214.721186 -107.20578)
			)
			(arc
				(start 214.496904 -106.981498)
				(mid 214.48037 -106.970387)
				(end 214.460836 -106.966512)
			)
			(arc
				(start 200.091548 -106.966512)
				(mid 200.072025 -106.970413)
				(end 200.05548 -106.981498)
			)
			(xy 199.589644 -107.44708) (xy 193.630804 -107.44708) (xy 192.034668 -109.043216)
			(arc
				(start 189.719204 -109.043216)
				(mid 189.683283 -109.058095)
				(end 189.668404 -109.094016)
			)
			(arc
				(start 189.668404 -112.851184)
				(mid 189.683283 -112.887105)
				(end 189.719204 -112.901984)
			)
		)
		(stroke
			(width 0)
			(type solid)
		)
		(fill yes)
		(layer "B.Cu")
		(net "P12V_NIC3")
	)
	(gr_poly
		(pts
			(arc
				(start 202.175872 -370.10848)
				(mid 202.195395 -370.104579)
				(end 202.21194 -370.093494)
			)
			(arc
				(start 202.279758 -370.025676)
				(mid 202.290869 -370.009142)
				(end 202.294744 -369.989608)
			)
			(arc
				(start 202.294744 -369.38712)
				(mid 202.298645 -369.367597)
				(end 202.30973 -369.351052)
			)
			(xy 202.832462 -368.82832) (xy 202.835256 -368.82832) (xy 202.835764 -368.827812) (xy 202.854306 -368.820192)
			(arc
				(start 203.993496 -368.820192)
				(mid 204.012883 -368.816242)
				(end 204.02931 -368.805206)
			)
			(arc
				(start 204.043788 -368.790728)
				(mid 204.054899 -368.774194)
				(end 204.058774 -368.75466)
			)
			(arc
				(start 204.058774 -368.383312)
				(mid 204.062675 -368.363789)
				(end 204.07376 -368.347244)
			)
			(arc
				(start 204.278738 -368.142266)
				(mid 204.289849 -368.125732)
				(end 204.293724 -368.106198)
			)
			(arc
				(start 204.293724 -367.261648)
				(mid 204.289823 -367.242125)
				(end 204.278738 -367.22558)
			)
			(arc
				(start 204.197966 -367.144808)
				(mid 204.181432 -367.133697)
				(end 204.161898 -367.129822)
			)
			(arc
				(start 201.795888 -367.129822)
				(mid 201.776365 -367.133723)
				(end 201.75982 -367.144808)
			)
			(arc
				(start 201.563224 -367.341404)
				(mid 201.552113 -367.357938)
				(end 201.548238 -367.377472)
			)
			(xy 201.548238 -368.05362) (xy 201.570844 -368.081306)
			(arc
				(start 201.588624 -368.085116)
				(mid 201.952854 -368.533172)
				(end 201.588624 -368.981228)
			)
			(xy 201.570844 -368.985038) (xy 201.548238 -369.012724)
			(arc
				(start 201.548238 -370.006626)
				(mid 201.552139 -370.026149)
				(end 201.563224 -370.042694)
			)
			(arc
				(start 201.614024 -370.093494)
				(mid 201.630558 -370.104605)
				(end 201.650092 -370.10848)
			)
		)
		(stroke
			(width 0)
			(type solid)
		)
		(fill yes)
		(layer "B.Cu")
		(net "HSC_VDD_R")
	)
	(gr_poly
		(pts
			(arc
				(start 216.92743 -281.04973)
				(mid 216.946953 -281.045829)
				(end 216.963498 -281.034744)
			)
			(arc
				(start 217.386408 -280.611834)
				(mid 217.402942 -280.600723)
				(end 217.422476 -280.596848)
			)
			(arc
				(start 217.667078 -280.596848)
				(mid 217.686465 -280.592898)
				(end 217.702892 -280.581862)
			)
			(arc
				(start 217.7923 -280.492708)
				(mid 217.808746 -280.481782)
				(end 217.828114 -280.477976)
			)
			(arc
				(start 223.311974 -280.477976)
				(mid 223.347895 -280.463097)
				(end 223.362774 -280.427176)
			)
			(arc
				(start 223.362774 -280.15819)
				(mid 223.358873 -280.138667)
				(end 223.347788 -280.122122)
			)
			(arc
				(start 223.299528 -280.073862)
				(mid 223.283111 -280.0628)
				(end 223.263714 -280.058876)
			)
			(arc
				(start 219.098876 -280.058876)
				(mid 219.079489 -280.062826)
				(end 219.063062 -280.073862)
			)
			(arc
				(start 218.959938 -280.176986)
				(mid 218.943404 -280.188097)
				(end 218.92387 -280.191972)
			)
			(xy 218.546934 -280.191972) (xy 218.54414 -280.189432)
			(arc
				(start 217.883232 -280.189432)
				(mid 217.863845 -280.185482)
				(end 217.847418 -280.174446)
			)
			(arc
				(start 217.69451 -280.021792)
				(mid 217.678093 -280.01073)
				(end 217.658696 -280.006806)
			)
			(arc
				(start 217.6145 -280.006806)
				(mid 217.594977 -280.002905)
				(end 217.578432 -279.99182)
			)
			(arc
				(start 217.361516 -279.774904)
				(mid 217.350405 -279.75837)
				(end 217.34653 -279.738836)
			)
			(arc
				(start 217.34653 -272.28546)
				(mid 217.331651 -272.249539)
				(end 217.29573 -272.23466)
			)
			(arc
				(start 216.630504 -272.23466)
				(mid 216.599743 -272.233157)
				(end 216.56929 -272.228564)
			)
			(xy 216.56421 -272.227548)
			(arc
				(start 215.776048 -272.227548)
				(mid 215.756525 -272.231449)
				(end 215.73998 -272.242534)
			)
			(arc
				(start 215.550496 -272.432018)
				(mid 215.539385 -272.448552)
				(end 215.53551 -272.468086)
			)
			(arc
				(start 215.53551 -280.35631)
				(mid 215.539411 -280.375833)
				(end 215.550496 -280.392378)
			)
			(arc
				(start 216.192862 -281.034744)
				(mid 216.209396 -281.045855)
				(end 216.22893 -281.04973)
			)
		)
		(stroke
			(width 0)
			(type solid)
		)
		(fill yes)
		(layer "B.Cu")
		(net "GND")
	)
	(gr_poly
		(pts
			(arc
				(start 238.067596 -222.338138)
				(mid 238.087119 -222.334237)
				(end 238.103664 -222.323152)
			)
			(arc
				(start 238.10976 -222.317056)
				(mid 238.059651 -222.211843)
				(end 238.04245 -222.096584)
			)
			(arc
				(start 238.04245 -222.096584)
				(mid 238.437166 -221.701868)
				(end 238.831882 -222.096584)
			)
			(arc
				(start 238.831882 -222.096584)
				(mid 238.827294 -222.156845)
				(end 238.813594 -222.21571)
			)
			(xy 239.737138 -222.21571) (xy 239.881918 -222.07093) (xy 239.881918 -221.124018) (xy 239.832642 -221.074742)
			(xy 239.04702 -221.074742) (xy 238.967518 -220.99524)
			(arc
				(start 238.967518 -220.917516)
				(mid 238.952639 -220.881595)
				(end 238.916718 -220.866716)
			)
			(arc
				(start 238.893096 -220.866716)
				(mid 238.747143 -220.837778)
				(end 238.623348 -220.75521)
			)
			(arc
				(start 238.44631 -220.577918)
				(mid 238.429776 -220.566807)
				(end 238.410242 -220.562932)
			)
			(arc
				(start 236.811312 -220.562932)
				(mid 236.684276 -220.541055)
				(end 236.57179 -220.478096)
			)
			(xy 236.564932 -220.472508) (xy 236.548676 -220.466666)
			(arc
				(start 236.48162 -220.466666)
				(mid 236.462097 -220.470567)
				(end 236.445552 -220.481652)
			)
			(arc
				(start 236.339634 -220.58757)
				(mid 236.328523 -220.604104)
				(end 236.324648 -220.623638)
			)
			(arc
				(start 236.324648 -222.125286)
				(mid 236.328549 -222.144809)
				(end 236.339634 -222.161354)
			)
			(arc
				(start 236.501432 -222.323152)
				(mid 236.517966 -222.334263)
				(end 236.5375 -222.338138)
			)
		)
		(stroke
			(width 0)
			(type solid)
		)
		(fill yes)
		(layer "B.Cu")
		(net "P3V3_BIC_ADCAV33")
	)
	(gr_poly
		(pts
			(arc
				(start 397.644112 -303.364392)
				(mid 397.680033 -303.349513)
				(end 397.694912 -303.313592)
			)
			(xy 397.694912 -303.18202) (xy 397.692372 -303.170844)
			(arc
				(start 397.689578 -303.16551)
				(mid 397.665071 -303.09704)
				(end 397.656812 -303.024794)
			)
			(arc
				(start 397.656812 -303.024794)
				(mid 397.659796 -302.981076)
				(end 397.66875 -302.93818)
			)
			(arc
				(start 397.66875 -302.93818)
				(mid 397.669094 -302.911502)
				(end 397.655796 -302.888396)
			)
			(arc
				(start 397.531082 -302.763682)
				(mid 397.519971 -302.747148)
				(end 397.516096 -302.727614)
			)
			(arc
				(start 397.516096 -301.662846)
				(mid 397.513166 -301.645844)
				(end 397.504666 -301.630842)
			)
			(xy 397.501364 -301.627032)
			(arc
				(start 397.463264 -301.588932)
				(mid 397.455316 -301.582491)
				(end 397.446246 -301.577756)
			)
			(xy 397.43761 -301.5742)
			(arc
				(start 396.320518 -301.5742)
				(mid 396.303516 -301.57713)
				(end 396.288514 -301.58563)
			)
			(xy 396.284704 -301.588932)
			(arc
				(start 396.176754 -301.696882)
				(mid 396.170313 -301.70483)
				(end 396.165578 -301.7139)
			)
			(xy 396.162022 -301.722536)
			(arc
				(start 396.162022 -302.66894)
				(mid 396.164295 -302.683964)
				(end 396.170912 -302.697642)
			)
			(arc
				(start 396.170912 -302.697896)
				(mid 396.181238 -302.708772)
				(end 396.19428 -302.716184)
			)
			(xy 396.194534 -302.716438) (xy 396.202662 -302.71974)
			(arc
				(start 396.2273 -302.71974)
				(mid 396.302437 -302.747824)
				(end 396.340838 -302.818292)
			)
			(arc
				(start 396.340838 -302.818292)
				(mid 396.34367 -302.829431)
				(end 396.348966 -302.839628)
			)
			(arc
				(start 396.348966 -302.839628)
				(mid 396.391133 -302.927976)
				(end 396.405608 -303.024794)
			)
			(arc
				(start 396.405608 -303.024794)
				(mid 396.391142 -303.121498)
				(end 396.348966 -303.209706)
			)
			(arc
				(start 396.348966 -303.209706)
				(mid 396.343704 -303.219915)
				(end 396.340838 -303.231042)
			)
			(arc
				(start 396.33906 -303.24044)
				(mid 396.339115 -303.263033)
				(end 396.348966 -303.283366)
			)
			(arc
				(start 396.39875 -303.345342)
				(mid 396.416397 -303.359364)
				(end 396.438374 -303.364392)
			)
		)
		(stroke
			(width 0)
			(type solid)
		)
		(fill yes)
		(layer "B.Cu")
		(net "P1V8_VDDA_PEX3")
	)
	(gr_poly
		(pts
			(arc
				(start 236.67593 -218.280742)
				(mid 236.695317 -218.276792)
				(end 236.711744 -218.265756)
			)
			(arc
				(start 237.207806 -217.769948)
				(mid 237.22434 -217.758837)
				(end 237.243874 -217.754962)
			)
			(arc
				(start 237.339886 -217.754962)
				(mid 237.359409 -217.751061)
				(end 237.375954 -217.739976)
			)
			(arc
				(start 237.606332 -217.509598)
				(mid 237.617443 -217.493064)
				(end 237.621318 -217.47353)
			)
			(arc
				(start 237.621318 -217.36939)
				(mid 237.617417 -217.349867)
				(end 237.606332 -217.333322)
			)
			(xy 237.601252 -217.328242) (xy 237.58271 -217.320622)
			(arc
				(start 234.751626 -217.320622)
				(mid 234.732239 -217.324572)
				(end 234.715812 -217.335608)
			)
			(arc
				(start 234.54868 -217.502486)
				(mid 234.537717 -217.518668)
				(end 234.533694 -217.537792)
			)
			(xy 234.532424 -217.618564) (xy 234.539282 -217.636598)
			(arc
				(start 234.54614 -217.643964)
				(mid 234.560727 -217.660576)
				(end 234.574334 -217.678)
			)
			(xy 234.579414 -217.683842)
			(arc
				(start 234.625134 -217.729562)
				(mid 234.643957 -217.741398)
				(end 234.666028 -217.74404)
			)
			(xy 234.755944 -217.73515) (xy 234.774994 -217.72372)
			(arc
				(start 234.781598 -217.714068)
				(mid 234.905245 -217.601616)
				(end 235.067348 -217.560906)
			)
			(arc
				(start 235.067348 -217.560906)
				(mid 235.310174 -217.661488)
				(end 235.410756 -217.904314)
			)
			(arc
				(start 235.410756 -217.904314)
				(mid 235.40292 -217.977227)
				(end 235.379768 -218.046808)
			)
			(xy 235.374434 -218.058746) (xy 235.376212 -218.0844)
			(arc
				(start 235.429552 -218.167204)
				(mid 235.447915 -218.184297)
				(end 235.472224 -218.190572)
			)
			(xy 236.167422 -218.190572) (xy 236.17682 -218.190572)
			(arc
				(start 236.177836 -218.190826)
				(mid 236.299665 -218.211501)
				(end 236.408468 -218.270074)
			)
			(xy 236.415072 -218.275154)
			(arc
				(start 236.4232 -218.277948)
				(mid 236.43134 -218.280013)
				(end 236.43971 -218.280742)
			)
		)
		(stroke
			(width 0)
			(type solid)
		)
		(fill yes)
		(layer "B.Cu")
		(net "GND")
	)
	(gr_poly
		(pts
			(arc
				(start 307.624226 -112.954054)
				(mid 307.644902 -112.949656)
				(end 307.662072 -112.93729)
			)
			(arc
				(start 307.662072 -112.93729)
				(mid 307.824437 -112.819345)
				(end 308.02072 -112.777524)
			)
			(arc
				(start 308.02072 -112.777524)
				(mid 308.217017 -112.819314)
				(end 308.379368 -112.93729)
			)
			(arc
				(start 308.379368 -112.93729)
				(mid 308.396497 -112.949747)
				(end 308.417214 -112.954054)
			)
			(arc
				(start 308.601872 -112.954054)
				(mid 308.624271 -112.948849)
				(end 308.642004 -112.934242)
			)
			(arc
				(start 308.642004 -112.934242)
				(mid 308.811284 -112.796301)
				(end 309.02402 -112.747044)
			)
			(arc
				(start 309.02402 -112.747044)
				(mid 309.236753 -112.796307)
				(end 309.406036 -112.934242)
			)
			(arc
				(start 309.406036 -112.934242)
				(mid 309.423811 -112.948762)
				(end 309.446168 -112.954054)
			)
			(arc
				(start 321.912996 -112.954054)
				(mid 321.932519 -112.950153)
				(end 321.949064 -112.939068)
			)
			(arc
				(start 322.44411 -112.444022)
				(mid 322.455221 -112.427488)
				(end 322.459096 -112.407954)
			)
			(arc
				(start 322.459096 -104.585516)
				(mid 322.455195 -104.565993)
				(end 322.44411 -104.549448)
			)
			(arc
				(start 322.279518 -104.384856)
				(mid 322.262984 -104.373745)
				(end 322.24345 -104.36987)
			)
			(xy 317.379604 -104.36987) (xy 317.379604 -104.370124)
			(arc
				(start 312.455814 -104.370124)
				(mid 312.436291 -104.374025)
				(end 312.419746 -104.38511)
			)
			(arc
				(start 307.776626 -109.02823)
				(mid 307.760092 -109.039341)
				(end 307.740558 -109.043216)
			)
			(arc
				(start 305.819048 -109.043216)
				(mid 305.783127 -109.058095)
				(end 305.768248 -109.094016)
			)
			(arc
				(start 305.768248 -112.832642)
				(mid 305.772198 -112.852029)
				(end 305.783234 -112.868456)
			)
			(arc
				(start 305.853846 -112.939068)
				(mid 305.87038 -112.950179)
				(end 305.889914 -112.954054)
			)
		)
		(stroke
			(width 0)
			(type solid)
		)
		(fill yes)
		(layer "B.Cu")
		(net "P12V_NIC5")
	)
	(gr_poly
		(pts
			(arc
				(start 165.44417 -303.364392)
				(mid 165.480091 -303.349513)
				(end 165.49497 -303.313592)
			)
			(xy 165.49497 -303.18202) (xy 165.49243 -303.170844)
			(arc
				(start 165.489636 -303.16551)
				(mid 165.465129 -303.09704)
				(end 165.45687 -303.024794)
			)
			(arc
				(start 165.45687 -303.024794)
				(mid 165.465182 -302.95256)
				(end 165.489636 -302.884078)
			)
			(xy 165.49243 -302.878744) (xy 165.49497 -302.867568)
			(arc
				(start 165.49497 -302.853852)
				(mid 165.491069 -302.834329)
				(end 165.479984 -302.817784)
			)
			(arc
				(start 165.33114 -302.66894)
				(mid 165.320029 -302.652406)
				(end 165.316154 -302.632872)
			)
			(arc
				(start 165.316154 -301.662846)
				(mid 165.313224 -301.645844)
				(end 165.304724 -301.630842)
			)
			(xy 165.301422 -301.627032)
			(arc
				(start 165.263322 -301.588932)
				(mid 165.255374 -301.582491)
				(end 165.246304 -301.577756)
			)
			(xy 165.237668 -301.5742)
			(arc
				(start 164.120576 -301.5742)
				(mid 164.103574 -301.57713)
				(end 164.088572 -301.58563)
			)
			(xy 164.084762 -301.588932)
			(arc
				(start 163.976812 -301.696882)
				(mid 163.970371 -301.70483)
				(end 163.965636 -301.7139)
			)
			(xy 163.96208 -301.722536)
			(arc
				(start 163.96208 -302.66894)
				(mid 163.964353 -302.683964)
				(end 163.97097 -302.697642)
			)
			(arc
				(start 163.97097 -302.697896)
				(mid 163.981296 -302.708772)
				(end 163.994338 -302.716184)
			)
			(xy 163.994592 -302.716438) (xy 164.00272 -302.71974)
			(arc
				(start 164.027358 -302.71974)
				(mid 164.102495 -302.747824)
				(end 164.140896 -302.818292)
			)
			(arc
				(start 164.140896 -302.818292)
				(mid 164.143728 -302.829431)
				(end 164.149024 -302.839628)
			)
			(arc
				(start 164.149024 -302.839628)
				(mid 164.191191 -302.927976)
				(end 164.205666 -303.024794)
			)
			(arc
				(start 164.205666 -303.024794)
				(mid 164.1912 -303.121498)
				(end 164.149024 -303.209706)
			)
			(arc
				(start 164.149024 -303.209706)
				(mid 164.143762 -303.219915)
				(end 164.140896 -303.231042)
			)
			(arc
				(start 164.139118 -303.24044)
				(mid 164.139173 -303.263033)
				(end 164.149024 -303.283366)
			)
			(arc
				(start 164.198808 -303.345342)
				(mid 164.216455 -303.359364)
				(end 164.238432 -303.364392)
			)
		)
		(stroke
			(width 0)
			(type solid)
		)
		(fill yes)
		(layer "B.Cu")
		(net "P1V8_VDDA_PEX1")
	)
	(gr_poly
		(pts
			(arc
				(start 265.123168 -90.454988)
				(mid 265.142691 -90.451087)
				(end 265.159236 -90.440002)
			)
			(arc
				(start 265.310366 -90.288872)
				(mid 265.321477 -90.272338)
				(end 265.325352 -90.252804)
			)
			(arc
				(start 265.325352 -88.441784)
				(mid 265.322081 -88.423849)
				(end 265.312652 -88.408256)
			)
			(arc
				(start 265.312652 -88.408256)
				(mid 265.192252 -88.089232)
				(end 265.312652 -87.770208)
			)
			(arc
				(start 265.312652 -87.770208)
				(mid 265.322036 -87.754598)
				(end 265.325352 -87.73668)
			)
			(xy 265.325352 -85.057488) (xy 265.325606 -85.057234)
			(arc
				(start 265.325606 -84.957666)
				(mid 265.321705 -84.938143)
				(end 265.31062 -84.921598)
			)
			(xy 264.92454 -84.535518) (xy 264.917428 -84.528152) (xy 264.898632 -84.520532)
			(arc
				(start 263.360662 -84.520532)
				(mid 263.341139 -84.524433)
				(end 263.324594 -84.535518)
			)
			(arc
				(start 263.115806 -84.744306)
				(mid 263.104744 -84.760723)
				(end 263.10082 -84.78012)
			)
			(xy 263.10082 -86.176612) (xy 263.09828 -86.179152) (xy 263.09828 -86.473792)
			(arc
				(start 263.09828 -86.579202)
				(mid 263.094399 -86.598423)
				(end 263.083548 -86.614762)
			)
			(xy 263.01319 -86.68512) (xy 263.012936 -86.685374) (xy 263.008872 -86.689692) (xy 262.608568 -87.089996)
			(xy 262.603996 -87.094314)
			(arc
				(start 262.533638 -87.164672)
				(mid 262.51731 -87.175549)
				(end 262.498078 -87.179404)
			)
			(xy 262.473694 -87.179404)
			(arc
				(start 262.465566 -87.179912)
				(mid 262.450458 -87.184952)
				(end 262.437626 -87.19439)
			)
			(arc
				(start 262.433054 -87.198962)
				(mid 262.41652 -87.210073)
				(end 262.396986 -87.213948)
			)
			(arc
				(start 258.66471 -87.213948)
				(mid 258.645187 -87.217849)
				(end 258.628642 -87.228934)
			)
			(xy 258.421378 -87.436198) (xy 258.414012 -87.44331) (xy 258.406392 -87.462106)
			(arc
				(start 258.406392 -90.071702)
				(mid 258.410293 -90.091225)
				(end 258.421378 -90.10777)
			)
			(arc
				(start 258.737862 -90.424254)
				(mid 258.754396 -90.435365)
				(end 258.77393 -90.43924)
			)
			(arc
				(start 259.0292 -90.43924)
				(mid 259.043347 -90.44125)
				(end 259.056378 -90.447114)
			)
			(xy 259.062728 -90.450924) (xy 259.07619 -90.454988)
		)
		(stroke
			(width 0)
			(type solid)
		)
		(fill yes)
		(layer "B.Cu")
		(net "P3V3_CLK_GEN_VDDMXCK_CK440")
	)
	(gr_poly
		(pts
			(arc
				(start 281.544014 -303.364392)
				(mid 281.579935 -303.349513)
				(end 281.594814 -303.313592)
			)
			(xy 281.594814 -303.18202) (xy 281.592274 -303.170844)
			(arc
				(start 281.58948 -303.16551)
				(mid 281.564973 -303.09704)
				(end 281.556714 -303.024794)
			)
			(arc
				(start 281.556714 -303.024794)
				(mid 281.565026 -302.95256)
				(end 281.58948 -302.884078)
			)
			(xy 281.592274 -302.878744) (xy 281.594814 -302.867568)
			(arc
				(start 281.594814 -302.850296)
				(mid 281.590913 -302.830773)
				(end 281.579828 -302.814228)
			)
			(arc
				(start 281.430984 -302.665384)
				(mid 281.419873 -302.64885)
				(end 281.415998 -302.629316)
			)
			(arc
				(start 281.415998 -301.662846)
				(mid 281.413068 -301.645844)
				(end 281.404568 -301.630842)
			)
			(xy 281.401266 -301.627032)
			(arc
				(start 281.363166 -301.588932)
				(mid 281.355218 -301.582491)
				(end 281.346148 -301.577756)
			)
			(xy 281.337512 -301.5742)
			(arc
				(start 280.22042 -301.5742)
				(mid 280.203418 -301.57713)
				(end 280.188416 -301.58563)
			)
			(xy 280.184606 -301.588932)
			(arc
				(start 280.076656 -301.696882)
				(mid 280.070215 -301.70483)
				(end 280.06548 -301.7139)
			)
			(xy 280.061924 -301.722536)
			(arc
				(start 280.061924 -302.66894)
				(mid 280.064197 -302.683964)
				(end 280.070814 -302.697642)
			)
			(arc
				(start 280.070814 -302.697896)
				(mid 280.08114 -302.708772)
				(end 280.094182 -302.716184)
			)
			(xy 280.094436 -302.716438) (xy 280.102564 -302.71974)
			(arc
				(start 280.127202 -302.71974)
				(mid 280.202339 -302.747824)
				(end 280.24074 -302.818292)
			)
			(arc
				(start 280.24074 -302.818292)
				(mid 280.243572 -302.829431)
				(end 280.248868 -302.839628)
			)
			(arc
				(start 280.248868 -302.839628)
				(mid 280.291035 -302.927976)
				(end 280.30551 -303.024794)
			)
			(arc
				(start 280.30551 -303.024794)
				(mid 280.291044 -303.121498)
				(end 280.248868 -303.209706)
			)
			(arc
				(start 280.248868 -303.209706)
				(mid 280.243606 -303.219915)
				(end 280.24074 -303.231042)
			)
			(arc
				(start 280.24074 -303.231042)
				(mid 280.233354 -303.258544)
				(end 280.219404 -303.283366)
			)
			(xy 280.214578 -303.28997) (xy 280.209498 -303.30521) (xy 280.209498 -303.34839)
			(arc
				(start 280.210514 -303.349406)
				(mid 280.223336 -303.358865)
				(end 280.238454 -303.363884)
			)
			(xy 280.244804 -303.364392)
		)
		(stroke
			(width 0)
			(type solid)
		)
		(fill yes)
		(layer "B.Cu")
		(net "P1V8_VDDA_PEX2")
	)
	(gr_poly
		(pts
			(arc
				(start 368.924078 -318.761872)
				(mid 368.943601 -318.757971)
				(end 368.960146 -318.746886)
			)
			(xy 369.111784 -318.595248) (xy 369.118134 -318.58458)
			(arc
				(start 369.119912 -318.578484)
				(mid 370.230676 -316.299485)
				(end 371.998748 -314.48248)
			)
			(xy 372.003828 -314.478924) (xy 372.01094 -314.470034)
			(arc
				(start 372.023386 -314.44565)
				(mid 372.027541 -314.434423)
				(end 372.028974 -314.422536)
			)
			(arc
				(start 372.028974 -294.41394)
				(mid 372.025073 -294.394417)
				(end 372.013988 -294.377872)
			)
			(xy 371.594126 -293.95801) (xy 371.587014 -293.950644) (xy 371.568218 -293.943024)
			(arc
				(start 350.984312 -293.943024)
				(mid 350.964789 -293.946925)
				(end 350.948244 -293.95801)
			)
			(arc
				(start 350.898968 -294.007286)
				(mid 350.887857 -294.02382)
				(end 350.883982 -294.043354)
			)
			(arc
				(start 350.883982 -302.454564)
				(mid 350.887883 -302.474087)
				(end 350.898968 -302.490632)
			)
			(xy 351.041208 -302.632872) (xy 351.558606 -302.632872) (xy 351.696528 -302.770794) (xy 351.696528 -303.272444)
			(xy 351.702116 -303.272698) (xy 366.858804 -303.272698) (xy 367.63452 -303.272698) (xy 367.782348 -303.420526)
			(xy 367.782348 -308.709822) (xy 367.674144 -308.818026) (xy 365.895128 -308.818026) (xy 365.731298 -308.654196)
			(xy 364.715806 -308.654196) (xy 364.558834 -308.811168) (xy 363.984286 -308.811168) (xy 363.827314 -308.654196)
			(xy 361.464352 -308.654196) (xy 361.316016 -308.802532) (xy 361.29722 -308.821328) (xy 360.49966 -308.821328)
			(xy 360.480864 -308.802532) (xy 360.332528 -308.654196)
			(arc
				(start 355.937566 -308.654196)
				(mid 355.918043 -308.658097)
				(end 355.901498 -308.669182)
			)
			(arc
				(start 355.680518 -308.890162)
				(mid 355.669407 -308.906696)
				(end 355.665532 -308.92623)
			)
			(arc
				(start 355.665532 -318.553338)
				(mid 355.669433 -318.572861)
				(end 355.680518 -318.589406)
			)
			(arc
				(start 355.837998 -318.746886)
				(mid 355.854532 -318.757997)
				(end 355.874066 -318.761872)
			)
		)
		(stroke
			(width 0)
			(type solid)
		)
		(fill yes)
		(layer "B.Cu")
		(net "P0V8_PEX3")
	)
	(gr_poly
		(pts
			(arc
				(start 423.724324 -112.954054)
				(mid 423.745 -112.949656)
				(end 423.76217 -112.93729)
			)
			(arc
				(start 423.76217 -112.93729)
				(mid 423.924535 -112.819345)
				(end 424.120818 -112.777524)
			)
			(arc
				(start 424.120818 -112.777524)
				(mid 424.317115 -112.819314)
				(end 424.479466 -112.93729)
			)
			(arc
				(start 424.479466 -112.93729)
				(mid 424.496595 -112.949747)
				(end 424.517312 -112.954054)
			)
			(arc
				(start 424.70197 -112.954054)
				(mid 424.724369 -112.948849)
				(end 424.742102 -112.934242)
			)
			(arc
				(start 424.742102 -112.934242)
				(mid 424.911382 -112.796301)
				(end 425.124118 -112.747044)
			)
			(arc
				(start 425.124118 -112.747044)
				(mid 425.336851 -112.796307)
				(end 425.506134 -112.934242)
			)
			(arc
				(start 425.506134 -112.934242)
				(mid 425.523909 -112.948762)
				(end 425.546266 -112.954054)
			)
			(arc
				(start 438.013094 -112.954054)
				(mid 438.032617 -112.950153)
				(end 438.049162 -112.939068)
			)
			(arc
				(start 438.544208 -112.444022)
				(mid 438.555319 -112.427488)
				(end 438.559194 -112.407954)
			)
			(arc
				(start 438.559194 -104.585516)
				(mid 438.555293 -104.565993)
				(end 438.544208 -104.549448)
			)
			(arc
				(start 438.379616 -104.384856)
				(mid 438.363082 -104.373745)
				(end 438.343548 -104.36987)
			)
			(arc
				(start 433.500784 -104.36987)
				(mid 433.481261 -104.373771)
				(end 433.464716 -104.384856)
			)
			(arc
				(start 429.979836 -107.869736)
				(mid 429.963302 -107.880847)
				(end 429.943768 -107.884722)
			)
			(arc
				(start 425.72178 -107.884722)
				(mid 425.702257 -107.888623)
				(end 425.685712 -107.899708)
			)
			(arc
				(start 424.55719 -109.02823)
				(mid 424.540656 -109.039341)
				(end 424.521122 -109.043216)
			)
			(arc
				(start 421.9194 -109.043216)
				(mid 421.883479 -109.058095)
				(end 421.8686 -109.094016)
			)
			(arc
				(start 421.8686 -112.832642)
				(mid 421.872433 -112.851999)
				(end 421.883332 -112.868456)
			)
			(arc
				(start 421.953944 -112.939068)
				(mid 421.970478 -112.950179)
				(end 421.990012 -112.954054)
			)
		)
		(stroke
			(width 0)
			(type solid)
		)
		(fill yes)
		(layer "B.Cu")
		(net "P12V_NIC7")
	)
	(gr_poly
		(pts
			(arc
				(start 49.344072 -303.364392)
				(mid 49.379993 -303.349513)
				(end 49.394872 -303.313592)
			)
			(xy 49.394872 -303.18202) (xy 49.392332 -303.170844)
			(arc
				(start 49.389538 -303.16551)
				(mid 49.365031 -303.09704)
				(end 49.356772 -303.024794)
			)
			(arc
				(start 49.356772 -303.024794)
				(mid 49.365084 -302.95256)
				(end 49.389538 -302.884078)
			)
			(xy 49.392332 -302.878744) (xy 49.394872 -302.867568)
			(arc
				(start 49.394872 -302.831754)
				(mid 49.390971 -302.812231)
				(end 49.379886 -302.795686)
			)
			(arc
				(start 49.231042 -302.646842)
				(mid 49.219931 -302.630308)
				(end 49.216056 -302.610774)
			)
			(arc
				(start 49.216056 -301.662846)
				(mid 49.214644 -301.650953)
				(end 49.210468 -301.639732)
			)
			(arc
				(start 49.210468 -301.639732)
				(mid 49.206394 -301.633023)
				(end 49.201324 -301.627032)
			)
			(arc
				(start 49.163224 -301.588932)
				(mid 49.157226 -301.583872)
				(end 49.150524 -301.579788)
			)
			(arc
				(start 49.150524 -301.579788)
				(mid 49.139297 -301.575633)
				(end 49.12741 -301.5742)
			)
			(arc
				(start 48.020478 -301.5742)
				(mid 48.008585 -301.575612)
				(end 47.997364 -301.579788)
			)
			(arc
				(start 47.997364 -301.579788)
				(mid 47.990655 -301.583862)
				(end 47.984664 -301.588932)
			)
			(arc
				(start 47.876714 -301.696882)
				(mid 47.871654 -301.70288)
				(end 47.86757 -301.709582)
			)
			(arc
				(start 47.86757 -301.709582)
				(mid 47.863415 -301.720809)
				(end 47.861982 -301.732696)
			)
			(arc
				(start 47.861982 -302.669194)
				(mid 47.864255 -302.684218)
				(end 47.870872 -302.697896)
			)
			(xy 47.87519 -302.704246) (xy 47.887382 -302.713644) (xy 47.894494 -302.716438) (xy 47.902622 -302.71974)
			(arc
				(start 47.92726 -302.71974)
				(mid 48.002397 -302.747824)
				(end 48.040798 -302.818292)
			)
			(arc
				(start 48.040798 -302.818292)
				(mid 48.04363 -302.829431)
				(end 48.048926 -302.839628)
			)
			(arc
				(start 48.048926 -302.839628)
				(mid 48.091093 -302.927976)
				(end 48.105568 -303.024794)
			)
			(arc
				(start 48.105568 -303.024794)
				(mid 48.091092 -303.121492)
				(end 48.048926 -303.209706)
			)
			(arc
				(start 48.048926 -303.209706)
				(mid 48.043664 -303.219915)
				(end 48.040798 -303.231042)
			)
			(arc
				(start 48.03902 -303.24044)
				(mid 48.039075 -303.263033)
				(end 48.048926 -303.283366)
			)
			(arc
				(start 48.09871 -303.345342)
				(mid 48.116357 -303.359364)
				(end 48.138334 -303.364392)
			)
		)
		(stroke
			(width 0)
			(type solid)
		)
		(fill yes)
		(layer "B.Cu")
		(net "P1V8_VDDA_PEX0")
	)
	(gr_poly
		(pts
			(xy 166.602918 -287.374584) (xy 174.28972 -287.374584) (xy 174.292514 -287.37433)
			(arc
				(start 174.29353 -287.374076)
				(mid 174.32162 -287.370446)
				(end 174.349918 -287.36925)
			)
			(arc
				(start 174.349918 -287.36925)
				(mid 174.378214 -287.370463)
				(end 174.406306 -287.374076)
			)
			(xy 174.407322 -287.37433) (xy 174.410116 -287.374584) (xy 183.961278 -287.374584) (xy 183.968898 -287.374838)
			(arc
				(start 184.30875 -287.374838)
				(mid 184.320643 -287.373426)
				(end 184.331864 -287.36925)
			)
			(arc
				(start 184.331864 -287.36925)
				(mid 184.338573 -287.365176)
				(end 184.344564 -287.360106)
			)
			(arc
				(start 184.469024 -287.235646)
				(mid 184.474084 -287.229648)
				(end 184.478168 -287.222946)
			)
			(arc
				(start 184.478168 -287.222946)
				(mid 184.482323 -287.211719)
				(end 184.483756 -287.199832)
			)
			(xy 184.483756 -287.038288) (xy 184.481216 -287.02762)
			(arc
				(start 184.478422 -287.021778)
				(mid 184.452818 -286.95035)
				(end 184.444132 -286.874966)
			)
			(arc
				(start 184.444132 -286.874966)
				(mid 184.452781 -286.799573)
				(end 184.478422 -286.728154)
			)
			(xy 184.481216 -286.722312) (xy 184.483756 -286.711644)
			(arc
				(start 184.483756 -286.564324)
				(mid 184.481149 -286.54826)
				(end 184.473596 -286.533844)
			)
			(xy 184.46877 -286.528256) (xy 184.462166 -286.521652)
			(arc
				(start 184.453022 -286.517842)
				(mid 184.443556 -286.514993)
				(end 184.433718 -286.514032)
			)
			(arc
				(start 166.092632 -286.514032)
				(mid 166.076568 -286.516639)
				(end 166.062152 -286.524192)
			)
			(xy 166.056564 -286.529018) (xy 166.0525 -286.533082) (xy 166.0525 -286.68091) (xy 166.054278 -286.694372)
			(xy 166.056056 -286.700468)
			(arc
				(start 166.059612 -286.706564)
				(mid 166.093862 -286.787556)
				(end 166.105586 -286.874712)
			)
			(arc
				(start 166.105586 -286.874966)
				(mid 166.102705 -286.91827)
				(end 166.094156 -286.960818)
			)
			(xy 166.092886 -286.967422)
			(arc
				(start 166.091616 -286.977328)
				(mid 166.092747 -286.988243)
				(end 166.096188 -286.998664)
			)
			(arc
				(start 166.105332 -287.01873)
				(mid 166.109664 -287.026392)
				(end 166.115238 -287.033208)
			)
			(xy 166.133272 -287.051496)
			(arc
				(start 166.137082 -287.053528)
				(mid 166.181478 -287.080026)
				(end 166.220902 -287.113472)
			)
			(arc
				(start 166.384478 -287.277048)
				(mid 166.413818 -287.310825)
				(end 166.438072 -287.348422)
			)
			(arc
				(start 166.438326 -287.348676)
				(mid 166.446306 -287.359568)
				(end 166.456868 -287.36798)
			)
			(xy 166.46271 -287.371282) (xy 166.47541 -287.374838) (xy 166.595298 -287.374838)
		)
		(stroke
			(width 0)
			(type solid)
		)
		(fill yes)
		(layer "B.Cu")
		(net "P1V25_SERDES_VDDPLL_PEX1")
	)
	(gr_poly
		(pts
			(arc
				(start 25.75941 -263.299448)
				(mid 25.778933 -263.295547)
				(end 25.795478 -263.284462)
			)
			(arc
				(start 26.007822 -263.072118)
				(mid 26.018933 -263.055584)
				(end 26.022808 -263.03605)
			)
			(arc
				(start 26.022808 -262.526018)
				(mid 26.018907 -262.506495)
				(end 26.007822 -262.48995)
			)
			(arc
				(start 24.981916 -261.464044)
				(mid 24.970805 -261.44751)
				(end 24.96693 -261.427976)
			)
			(arc
				(start 24.96693 -260.839966)
				(mid 24.970831 -260.820443)
				(end 24.981916 -260.803898)
			)
			(xy 24.988012 -260.797802)
			(arc
				(start 24.983948 -260.793484)
				(mid 24.973022 -260.777038)
				(end 24.969216 -260.75767)
			)
			(arc
				(start 24.969216 -259.201666)
				(mid 24.954337 -259.165745)
				(end 24.918416 -259.150866)
			)
			(arc
				(start 24.122634 -259.150866)
				(mid 24.103111 -259.154767)
				(end 24.086566 -259.165852)
			)
			(arc
				(start 23.66391 -259.588508)
				(mid 23.652799 -259.605042)
				(end 23.648924 -259.624576)
			)
			(arc
				(start 23.648924 -259.672836)
				(mid 23.656244 -259.699107)
				(end 23.676102 -259.717794)
			)
			(xy 23.768304 -259.766308) (xy 23.796498 -259.76453)
			(arc
				(start 23.808182 -259.756656)
				(mid 23.91137 -259.706385)
				(end 24.024844 -259.689092)
			)
			(arc
				(start 24.024844 -259.689092)
				(mid 24.406352 -260.0706)
				(end 24.024844 -260.452108)
			)
			(arc
				(start 24.024844 -260.452108)
				(mid 23.911366 -260.434828)
				(end 23.808182 -260.384544)
			)
			(xy 23.796498 -260.37667) (xy 23.768304 -260.374892)
			(arc
				(start 23.676102 -260.423406)
				(mid 23.656256 -260.4421)
				(end 23.648924 -260.468364)
			)
			(arc
				(start 23.648924 -262.183372)
				(mid 23.652825 -262.202895)
				(end 23.66391 -262.21944)
			)
			(arc
				(start 24.728932 -263.284462)
				(mid 24.745466 -263.295573)
				(end 24.765 -263.299448)
			)
		)
		(stroke
			(width 0)
			(type solid)
		)
		(fill yes)
		(layer "B.Cu")
		(net "GND")
	)
	(gr_poly
		(pts
			(arc
				(start 256.12725 -83.5533)
				(mid 256.141198 -83.54848)
				(end 256.153158 -83.539838)
			)
			(arc
				(start 256.182876 -83.51012)
				(mid 256.193802 -83.493674)
				(end 256.197608 -83.474306)
			)
			(arc
				(start 256.197608 -81.750408)
				(mid 256.193707 -81.730885)
				(end 256.182622 -81.71434)
			)
			(arc
				(start 256.132584 -81.664302)
				(mid 256.11605 -81.653191)
				(end 256.096516 -81.649316)
			)
			(arc
				(start 254.508762 -81.649316)
				(mid 254.490492 -81.652715)
				(end 254.474726 -81.662524)
			)
			(xy 254.386334 -81.750662)
			(arc
				(start 254.248412 -81.888584)
				(mid 254.242509 -81.895728)
				(end 254.237998 -81.903824)
			)
			(xy 254.234188 -81.912206) (xy 254.234188 -81.912714)
			(arc
				(start 254.233934 -81.91881)
				(mid 254.116955 -82.178549)
				(end 253.85268 -82.284824)
			)
			(arc
				(start 253.851664 -82.284824)
				(mid 253.786702 -82.279121)
				(end 253.723648 -82.262472)
			)
			(arc
				(start 253.723648 -82.262472)
				(mid 253.694408 -82.250571)
				(end 253.666244 -82.23631)
			)
			(arc
				(start 253.666244 -82.23631)
				(mid 253.655433 -82.231856)
				(end 253.643892 -82.22996)
			)
			(arc
				(start 253.643892 -82.22996)
				(mid 253.542355 -82.211245)
				(end 253.449582 -82.165952)
			)
			(arc
				(start 253.449074 -82.165444)
				(mid 253.435825 -82.159341)
				(end 253.421388 -82.157316)
			)
			(xy 252.349762 -82.157316)
			(arc
				(start 252.342142 -82.157824)
				(mid 252.328769 -82.161784)
				(end 252.316996 -82.169254)
			)
			(xy 252.163834 -82.322162) (xy 252.160024 -82.325972)
			(arc
				(start 252.089666 -82.39633)
				(mid 252.073132 -82.407441)
				(end 252.053598 -82.411316)
			)
			(arc
				(start 251.037852 -82.411316)
				(mid 251.027067 -82.412474)
				(end 251.01677 -82.415888)
			)
			(arc
				(start 251.01677 -82.415888)
				(mid 251.010231 -82.419611)
				(end 251.004324 -82.42427)
			)
			(arc
				(start 250.918726 -82.50936)
				(mid 250.902398 -82.520237)
				(end 250.883166 -82.524092)
			)
			(xy 250.329446 -82.524092) (xy 250.327668 -82.525108) (xy 250.319286 -82.525108) (xy 250.30303 -82.531966)
			(xy 250.29668 -82.538316) (xy 250.29668 -83.406234)
			(arc
				(start 250.297696 -83.415886)
				(mid 250.302516 -83.429834)
				(end 250.311158 -83.441794)
			)
			(arc
				(start 250.409202 -83.539838)
				(mid 250.421167 -83.548471)
				(end 250.43511 -83.5533)
			)
			(xy 250.444762 -83.554316) (xy 256.117598 -83.554316)
		)
		(stroke
			(width 0)
			(type solid)
		)
		(fill yes)
		(layer "B.Cu")
		(net "P3V3_CLK_GEN_VDDXTAL_CK440")
	)
	(gr_poly
		(pts
			(arc
				(start 113.005362 -318.761872)
				(mid 113.024885 -318.757971)
				(end 113.04143 -318.746886)
			)
			(arc
				(start 113.297462 -318.490854)
				(mid 113.308573 -318.47432)
				(end 113.312448 -318.454786)
			)
			(arc
				(start 113.312448 -308.820566)
				(mid 113.308547 -308.801043)
				(end 113.297462 -308.784498)
			)
			(xy 113.182146 -308.669182) (xy 113.175034 -308.661816) (xy 113.156238 -308.654196) (xy 104.017064 -308.654196)
			(xy 103.868982 -308.802278) (xy 102.731316 -308.802278) (xy 102.583234 -308.654196) (xy 101.092762 -308.654196)
			(xy 100.414582 -308.654196) (xy 100.308918 -308.548532) (xy 100.095304 -308.334918) (xy 100.095304 -303.973738)
			(xy 100.667566 -303.401476) (xy 100.882704 -303.401476)
			(arc
				(start 115.81003 -303.401476)
				(mid 115.829553 -303.397575)
				(end 115.846098 -303.38649)
			)
			(arc
				(start 116.11102 -303.121568)
				(mid 116.121946 -303.105122)
				(end 116.125752 -303.085754)
			)
			(arc
				(start 116.125752 -302.875188)
				(mid 116.140631 -302.839267)
				(end 116.176552 -302.824388)
			)
			(arc
				(start 116.189252 -302.824388)
				(mid 116.235882 -302.777498)
				(end 116.299742 -302.76038)
			)
			(arc
				(start 116.467382 -302.76038)
				(mid 116.475776 -302.755668)
				(end 116.48313 -302.749458)
			)
			(arc
				(start 117.979444 -301.253144)
				(mid 117.990555 -301.23661)
				(end 117.99443 -301.217076)
			)
			(arc
				(start 117.99443 -294.085772)
				(mid 117.990529 -294.066249)
				(end 117.979444 -294.049704)
			)
			(xy 117.88775 -293.95801) (xy 117.880638 -293.950644) (xy 117.861842 -293.943024) (xy 96.178624 -293.943024)
			(xy 96.159828 -293.950644) (xy 96.152716 -293.95801)
			(arc
				(start 95.732854 -294.377872)
				(mid 95.721743 -294.394406)
				(end 95.717868 -294.41394)
			)
			(arc
				(start 95.717868 -314.422536)
				(mid 95.71928 -314.434429)
				(end 95.723456 -314.44565)
			)
			(xy 95.735902 -314.470288) (xy 95.743268 -314.478924)
			(arc
				(start 95.748094 -314.48248)
				(mid 97.516192 -316.299616)
				(end 98.62693 -318.578738)
			)
			(xy 98.628962 -318.584834) (xy 98.635058 -318.595248)
			(arc
				(start 98.786696 -318.746886)
				(mid 98.80323 -318.757997)
				(end 98.822764 -318.761872)
			)
		)
		(stroke
			(width 0)
			(type solid)
		)
		(fill yes)
		(layer "B.Cu")
		(net "P0V8_PEX0")
	)
	(gr_poly
		(pts
			(arc
				(start 186.610244 -286.290766)
				(mid 186.629767 -286.286865)
				(end 186.646312 -286.27578)
			)
			(arc
				(start 186.887612 -286.03448)
				(mid 186.898723 -286.017946)
				(end 186.902598 -285.998412)
			)
			(arc
				(start 186.902598 -285.773114)
				(mid 186.898697 -285.753591)
				(end 186.887612 -285.737046)
			)
			(arc
				(start 186.880246 -285.72968)
				(mid 186.8638 -285.718754)
				(end 186.844432 -285.714948)
			)
			(arc
				(start 179.716684 -285.714948)
				(mid 179.603458 -285.694285)
				(end 179.504848 -285.634938)
			)
			(arc
				(start 179.504848 -285.634938)
				(mid 179.489238 -285.625554)
				(end 179.47132 -285.622238)
			)
			(arc
				(start 178.5874 -285.622238)
				(mid 178.567877 -285.626139)
				(end 178.551332 -285.637224)
			)
			(arc
				(start 178.542188 -285.646368)
				(mid 178.438253 -285.715908)
				(end 178.31562 -285.740348)
			)
			(arc
				(start 176.1236 -285.740348)
				(mid 176.000985 -285.715865)
				(end 175.897032 -285.646368)
			)
			(arc
				(start 175.592232 -285.341568)
				(mid 175.522692 -285.237633)
				(end 175.498252 -285.115)
			)
			(arc
				(start 175.498252 -285.112968)
				(mid 175.483373 -285.077047)
				(end 175.447452 -285.062168)
			)
			(arc
				(start 174.865538 -285.062168)
				(mid 174.846015 -285.066069)
				(end 174.82947 -285.077154)
			)
			(arc
				(start 174.299372 -285.607252)
				(mid 174.282838 -285.618363)
				(end 174.263304 -285.622238)
			)
			(arc
				(start 166.129716 -285.622238)
				(mid 166.110193 -285.626139)
				(end 166.093648 -285.637224)
			)
			(arc
				(start 166.057072 -285.6738)
				(mid 166.043782 -285.697476)
				(end 166.044626 -285.7246)
			)
			(xy 166.049198 -285.73984)
			(arc
				(start 166.053008 -285.745682)
				(mid 166.092236 -285.831678)
				(end 166.105586 -285.92526)
			)
			(arc
				(start 166.105586 -285.93161)
				(mid 166.078404 -286.05623)
				(end 166.006018 -286.161226)
			)
			(xy 165.998652 -286.168592) (xy 165.990778 -286.187134)
			(arc
				(start 165.990778 -286.208724)
				(mid 166.005657 -286.244645)
				(end 166.041578 -286.259524)
			)
			(arc
				(start 184.538874 -286.259524)
				(mid 184.557597 -286.263201)
				(end 184.573672 -286.273494)
			)
			(xy 184.574942 -286.274764)
			(arc
				(start 184.580022 -286.279082)
				(mid 184.595249 -286.287803)
				(end 184.612534 -286.290766)
			)
		)
		(stroke
			(width 0)
			(type solid)
		)
		(fill yes)
		(layer "B.Cu")
		(net "GND")
	)
	(gr_poly
		(pts
			(xy 68.97497 -286.290512) (xy 70.20814 -286.290512) (xy 70.21576 -286.290766) (xy 70.216522 -286.290766)
			(arc
				(start 70.510146 -286.290766)
				(mid 70.529337 -286.287001)
				(end 70.545706 -286.276288)
			)
			(xy 70.54596 -286.276034) (xy 70.55612 -286.265874) (xy 70.556374 -286.26562) (xy 70.55993 -286.262064)
			(xy 70.73519 -286.086804) (xy 70.787514 -286.03448)
			(arc
				(start 70.788022 -286.033972)
				(mid 70.798764 -286.017615)
				(end 70.8025 -285.998412)
			)
			(arc
				(start 70.8025 -285.773114)
				(mid 70.798599 -285.753591)
				(end 70.787514 -285.737046)
			)
			(xy 70.771004 -285.720536) (xy 70.750176 -285.712916) (xy 70.739 -285.713932) (xy 70.7136 -285.714948)
			(arc
				(start 63.616586 -285.714948)
				(mid 63.50336 -285.694285)
				(end 63.40475 -285.634938)
			)
			(arc
				(start 63.40475 -285.634938)
				(mid 63.38914 -285.625554)
				(end 63.371222 -285.622238)
			)
			(arc
				(start 62.486286 -285.622238)
				(mid 62.468351 -285.625509)
				(end 62.452758 -285.634938)
			)
			(arc
				(start 62.452758 -285.634938)
				(mid 62.354138 -285.694259)
				(end 62.240922 -285.714948)
			)
			(arc
				(start 59.9948 -285.714948)
				(mid 59.872185 -285.690465)
				(end 59.768232 -285.620968)
			)
			(arc
				(start 59.514232 -285.366968)
				(mid 59.444692 -285.263033)
				(end 59.420252 -285.1404)
			)
			(xy 59.420252 -285.063692) (xy 59.40806 -285.062168)
			(arc
				(start 58.76544 -285.062168)
				(mid 58.745917 -285.066069)
				(end 58.729372 -285.077154)
			)
			(arc
				(start 58.199274 -285.607252)
				(mid 58.18274 -285.618363)
				(end 58.163206 -285.622238)
			)
			(arc
				(start 50.029618 -285.622238)
				(mid 50.010095 -285.626139)
				(end 49.99355 -285.637224)
			)
			(arc
				(start 49.956974 -285.6738)
				(mid 49.943684 -285.697476)
				(end 49.944528 -285.7246)
			)
			(xy 49.9491 -285.73984)
			(arc
				(start 49.95291 -285.745682)
				(mid 49.992138 -285.831678)
				(end 50.005488 -285.92526)
			)
			(arc
				(start 50.005488 -285.93161)
				(mid 49.978306 -286.05623)
				(end 49.90592 -286.161226)
			)
			(xy 49.898554 -286.168592) (xy 49.89068 -286.187134)
			(arc
				(start 49.89068 -286.208724)
				(mid 49.905559 -286.244645)
				(end 49.94148 -286.259524)
			)
			(arc
				(start 68.438776 -286.259524)
				(mid 68.457499 -286.263201)
				(end 68.473574 -286.273494)
			)
			(xy 68.474844 -286.274764)
			(arc
				(start 68.479924 -286.279082)
				(mid 68.495151 -286.287803)
				(end 68.512436 -286.290766)
			)
			(xy 68.97497 -286.290766)
		)
		(stroke
			(width 0)
			(type solid)
		)
		(fill yes)
		(layer "B.Cu")
		(net "GND")
	)
	(gr_poly
		(pts
			(arc
				(start 136.723882 -318.761872)
				(mid 136.743405 -318.757971)
				(end 136.75995 -318.746886)
			)
			(xy 136.911588 -318.595248) (xy 136.917684 -318.584834)
			(arc
				(start 136.919716 -318.578738)
				(mid 138.03047 -316.299627)
				(end 139.798552 -314.48248)
			)
			(xy 139.803378 -314.478924) (xy 139.810744 -314.470288)
			(arc
				(start 139.82319 -314.44565)
				(mid 139.827345 -314.434423)
				(end 139.828778 -314.422536)
			)
			(xy 139.828778 -294.40378) (xy 139.821158 -294.384984) (xy 139.813792 -294.377872)
			(arc
				(start 139.39393 -293.95801)
				(mid 139.377396 -293.946899)
				(end 139.357862 -293.943024)
			)
			(arc
				(start 118.784116 -293.943024)
				(mid 118.764593 -293.946925)
				(end 118.748048 -293.95801)
			)
			(xy 118.698772 -294.007286) (xy 118.691406 -294.014398) (xy 118.683786 -294.033194)
			(arc
				(start 118.683786 -302.454564)
				(mid 118.687687 -302.474087)
				(end 118.698772 -302.490632)
			)
			(arc
				(start 118.953534 -302.745394)
				(mid 118.969951 -302.756456)
				(end 118.989348 -302.76038)
			)
			(arc
				(start 119.176038 -302.76038)
				(mid 119.23055 -302.772527)
				(end 119.27459 -302.806862)
			)
			(arc
				(start 119.27459 -302.806862)
				(mid 119.288918 -302.818833)
				(end 119.306594 -302.824896)
			)
			(arc
				(start 119.306594 -302.824896)
				(mid 119.337685 -302.841953)
				(end 119.350028 -302.875188)
			)
			(arc
				(start 119.350028 -303.120806)
				(mid 119.353929 -303.140329)
				(end 119.365014 -303.156874)
			)
			(arc
				(start 119.465852 -303.257712)
				(mid 119.482386 -303.268823)
				(end 119.50192 -303.272698)
			)
			(xy 134.658608 -303.272698) (xy 135.494268 -303.272698) (xy 135.690102 -303.468532) (xy 135.690102 -308.640988)
			(xy 135.539226 -308.791864) (xy 133.721602 -308.791864) (xy 133.583934 -308.654196) (xy 132.582412 -308.654196)
			(xy 132.451348 -308.78526) (xy 132.449824 -308.78526) (xy 132.424678 -308.810406) (xy 131.709668 -308.810406)
			(xy 131.684522 -308.78526) (xy 131.553458 -308.654196) (xy 129.207514 -308.654196) (xy 129.069592 -308.792118)
			(xy 128.13792 -308.792118) (xy 127.999998 -308.654196)
			(arc
				(start 123.73737 -308.654196)
				(mid 123.717847 -308.658097)
				(end 123.701302 -308.669182)
			)
			(xy 123.480322 -308.890162) (xy 123.472956 -308.897274) (xy 123.465336 -308.91607)
			(arc
				(start 123.465336 -318.553338)
				(mid 123.469237 -318.572861)
				(end 123.480322 -318.589406)
			)
			(arc
				(start 123.637802 -318.746886)
				(mid 123.654336 -318.757997)
				(end 123.67387 -318.761872)
			)
		)
		(stroke
			(width 0)
			(type solid)
		)
		(fill yes)
		(layer "B.Cu")
		(net "P0V8_PEX1")
	)
	(gr_poly
		(pts
			(xy 242.324128 -94.4372) (xy 242.334196 -94.436772) (xy 242.352793 -94.42905) (xy 242.360196 -94.422214)
			(xy 243.164614 -93.617796) (xy 243.171469 -93.610401) (xy 243.179216 -93.591802) (xy 243.1796 -93.581728)
			(xy 243.1796 -92.274136) (xy 243.177314 -92.266516) (xy 243.169043 -92.238536) (xy 243.160111 -92.180879)
			(xy 243.159534 -92.151708) (xy 243.160105 -92.122536) (xy 243.169033 -92.064878) (xy 243.177314 -92.0369)
			(xy 243.1796 -92.02928) (xy 243.1796 -90.454988) (xy 243.179175 -90.444919) (xy 243.171457 -90.426318)
			(xy 243.164614 -90.41892) (xy 242.802918 -90.057224) (xy 242.795516 -90.050388) (xy 242.776918 -90.04268)
			(xy 242.76685 -90.042238) (xy 238.789464 -90.042238) (xy 238.779397 -90.042668) (xy 238.760806 -90.050396)
			(xy 238.753396 -90.057224) (xy 238.648494 -90.162126) (xy 238.641652 -90.169526) (xy 238.633928 -90.188124)
			(xy 238.633508 -90.198194) (xy 238.633508 -91.68028) (xy 239.379234 -91.68028) (xy 239.379234 -91.620344)
			(xy 239.387057 -91.560922) (xy 239.40257 -91.503029) (xy 239.425506 -91.447656) (xy 239.455473 -91.39575)
			(xy 239.49196 -91.3482) (xy 239.53434 -91.30582) (xy 239.58189 -91.269333) (xy 239.633796 -91.239366)
			(xy 239.689169 -91.21643) (xy 239.747062 -91.200917) (xy 239.806484 -91.193094) (xy 239.86642 -91.193094)
			(xy 239.925842 -91.200917) (xy 239.983735 -91.21643) (xy 240.039108 -91.239366) (xy 240.091014 -91.269333)
			(xy 240.138564 -91.30582) (xy 240.180944 -91.3482) (xy 240.217431 -91.39575) (xy 240.247398 -91.447656)
			(xy 240.270334 -91.503029) (xy 240.285847 -91.560922) (xy 240.29367 -91.620344) (xy 240.29416 -91.650312)
			(xy 240.29367 -91.68028) (xy 240.285847 -91.739702) (xy 240.270334 -91.797595) (xy 240.247398 -91.852968)
			(xy 240.217431 -91.904874) (xy 240.180944 -91.952424) (xy 240.138564 -91.994804) (xy 240.091014 -92.031291)
			(xy 240.039108 -92.061258) (xy 239.983735 -92.084194) (xy 239.925842 -92.099707) (xy 239.86642 -92.10753)
			(xy 239.806484 -92.10753) (xy 239.747062 -92.099707) (xy 239.689169 -92.084194) (xy 239.633796 -92.061258)
			(xy 239.58189 -92.031291) (xy 239.53434 -91.994804) (xy 239.49196 -91.952424) (xy 239.455473 -91.904874)
			(xy 239.425506 -91.852968) (xy 239.40257 -91.797595) (xy 239.387057 -91.739702) (xy 239.379234 -91.68028)
			(xy 238.633508 -91.68028) (xy 238.633508 -91.693492) (xy 238.634044 -91.70348) (xy 238.641757 -91.721913)
			(xy 238.648494 -91.729306) (xy 238.669317 -91.750919) (xy 238.704589 -91.799472) (xy 238.731828 -91.852947)
			(xy 238.750363 -91.910025) (xy 238.759738 -91.969301) (xy 238.760254 -91.999308) (xy 238.759717 -92.029315)
			(xy 238.750363 -92.088595) (xy 238.731839 -92.145678) (xy 238.704603 -92.199155) (xy 238.669327 -92.247707)
			(xy 238.648494 -92.26931) (xy 238.641685 -92.276656) (xy 238.633958 -92.295118) (xy 238.633508 -92.305124)
			(xy 238.633508 -94.188026) (xy 238.633936 -94.198094) (xy 238.641658 -94.216691) (xy 238.648494 -94.224094)
			(xy 238.846614 -94.422214) (xy 238.854009 -94.429068) (xy 238.872608 -94.43681) (xy 238.882682 -94.4372)
		)
		(stroke
			(width 0)
			(type solid)
		)
		(fill yes)
		(layer "B.Cu")
		(net "GND")
	)
	(gr_poly
		(pts
			(arc
				(start 330.202794 -206.651606)
				(mid 330.225333 -206.646458)
				(end 330.24318 -206.631794)
			)
			(xy 330.299568 -206.558388) (xy 330.30414 -206.535528)
			(arc
				(start 330.301092 -206.524098)
				(mid 330.289668 -206.465918)
				(end 330.285852 -206.40675)
			)
			(arc
				(start 330.285852 -206.40675)
				(mid 330.74356 -205.949042)
				(end 331.201268 -206.40675)
			)
			(arc
				(start 331.201268 -206.40675)
				(mid 331.19746 -206.465919)
				(end 331.186028 -206.524098)
			)
			(xy 331.18298 -206.535528) (xy 331.187552 -206.558388)
			(arc
				(start 331.24394 -206.631794)
				(mid 331.261829 -206.64637)
				(end 331.284326 -206.651606)
			)
			(arc
				(start 331.785214 -206.651606)
				(mid 331.804737 -206.647705)
				(end 331.821282 -206.63662)
			)
			(arc
				(start 332.494382 -205.96352)
				(mid 332.505493 -205.946986)
				(end 332.509368 -205.927452)
			)
			(arc
				(start 332.509368 -203.284074)
				(mid 332.505467 -203.264551)
				(end 332.494382 -203.248006)
			)
			(arc
				(start 331.947774 -202.701398)
				(mid 331.93124 -202.690287)
				(end 331.911706 -202.686412)
			)
			(arc
				(start 330.413106 -202.686412)
				(mid 330.390547 -202.691696)
				(end 330.37272 -202.706478)
			)
			(xy 330.316586 -202.780646) (xy 330.312268 -202.804014)
			(arc
				(start 330.315316 -202.815444)
				(mid 330.328214 -202.876954)
				(end 330.332588 -202.93965)
			)
			(arc
				(start 330.332588 -202.93965)
				(mid 330.198528 -203.263298)
				(end 329.87488 -203.397358)
			)
			(arc
				(start 329.87488 -203.397358)
				(mid 329.711479 -203.367215)
				(end 329.569572 -203.280772)
			)
			(xy 329.554332 -203.267056) (xy 329.5142 -203.268072)
			(arc
				(start 329.26655 -203.515722)
				(mid 329.250133 -203.526784)
				(end 329.230736 -203.530708)
			)
			(arc
				(start 329.169268 -203.530708)
				(mid 329.149911 -203.534541)
				(end 329.133454 -203.54544)
			)
			(arc
				(start 329.023218 -203.655676)
				(mid 329.012107 -203.67221)
				(end 329.008232 -203.691744)
			)
			(arc
				(start 329.008232 -206.264764)
				(mid 329.012133 -206.284287)
				(end 329.023218 -206.300832)
			)
			(arc
				(start 329.359006 -206.63662)
				(mid 329.37554 -206.647731)
				(end 329.395074 -206.651606)
			)
		)
		(stroke
			(width 0)
			(type solid)
		)
		(fill yes)
		(layer "B.Cu")
		(net "GND")
	)
	(gr_poly
		(pts
			(xy 417.3093 -286.290512) (xy 418.507672 -286.290512) (xy 418.5158 -286.290766) (xy 418.516562 -286.290766)
			(arc
				(start 418.810186 -286.290766)
				(mid 418.829709 -286.286865)
				(end 418.846254 -286.27578)
			)
			(xy 418.927026 -286.195008) (xy 419.034976 -286.086804) (xy 419.035484 -286.086804)
			(arc
				(start 419.087554 -286.03448)
				(mid 419.098665 -286.017946)
				(end 419.10254 -285.998412)
			)
			(arc
				(start 419.10254 -285.773114)
				(mid 419.098639 -285.753591)
				(end 419.087554 -285.737046)
			)
			(arc
				(start 419.054788 -285.70428)
				(mid 419.038342 -285.693354)
				(end 419.018974 -285.689548)
			)
			(arc
				(start 412.013146 -285.689548)
				(mid 411.942563 -285.681623)
				(end 411.875478 -285.658306)
			)
			(arc
				(start 411.875478 -285.658306)
				(mid 411.86532 -285.654792)
				(end 411.85465 -285.65348)
			)
			(arc
				(start 411.85465 -285.65348)
				(mid 411.79325 -285.645951)
				(end 411.734508 -285.626556)
			)
			(xy 411.724856 -285.622238)
			(arc
				(start 410.779468 -285.622238)
				(mid 410.764142 -285.624525)
				(end 410.750258 -285.631382)
			)
			(arc
				(start 410.750258 -285.631382)
				(mid 410.662789 -285.674628)
				(end 410.566362 -285.689548)
			)
			(arc
				(start 408.272742 -285.689548)
				(mid 408.150127 -285.665065)
				(end 408.046174 -285.595568)
			)
			(arc
				(start 407.80081 -285.350204)
				(mid 407.731436 -285.246239)
				(end 407.707084 -285.123636)
			)
			(arc
				(start 407.707084 -285.112968)
				(mid 407.692205 -285.077047)
				(end 407.656284 -285.062168)
			)
			(arc
				(start 407.06548 -285.062168)
				(mid 407.045957 -285.066069)
				(end 407.029412 -285.077154)
			)
			(arc
				(start 406.499314 -285.607252)
				(mid 406.48278 -285.618363)
				(end 406.463246 -285.622238)
			)
			(arc
				(start 398.329658 -285.622238)
				(mid 398.310135 -285.626139)
				(end 398.29359 -285.637224)
			)
			(arc
				(start 398.257014 -285.6738)
				(mid 398.243724 -285.697476)
				(end 398.244568 -285.7246)
			)
			(xy 398.24914 -285.73984)
			(arc
				(start 398.25295 -285.745682)
				(mid 398.292178 -285.831678)
				(end 398.305528 -285.92526)
			)
			(arc
				(start 398.305528 -285.93161)
				(mid 398.278346 -286.05623)
				(end 398.20596 -286.161226)
			)
			(xy 398.198594 -286.168592) (xy 398.19072 -286.187134)
			(arc
				(start 398.19072 -286.208724)
				(mid 398.205599 -286.244645)
				(end 398.24152 -286.259524)
			)
			(arc
				(start 416.738816 -286.259524)
				(mid 416.757539 -286.263201)
				(end 416.773614 -286.273494)
			)
			(xy 416.774884 -286.274764)
			(arc
				(start 416.779964 -286.279082)
				(mid 416.795191 -286.287803)
				(end 416.812476 -286.290766)
			)
			(xy 417.30676 -286.290766)
		)
		(stroke
			(width 0)
			(type solid)
		)
		(fill yes)
		(layer "B.Cu")
		(net "GND")
	)
	(gr_poly
		(pts
			(xy 301.209202 -286.290512) (xy 302.407574 -286.290512) (xy 302.415702 -286.290766) (xy 302.416464 -286.290766)
			(arc
				(start 302.710088 -286.290766)
				(mid 302.729611 -286.286865)
				(end 302.746156 -286.27578)
			)
			(xy 302.826928 -286.195008) (xy 302.934878 -286.086804) (xy 302.935132 -286.086804)
			(arc
				(start 302.987456 -286.03448)
				(mid 302.998567 -286.017946)
				(end 303.002442 -285.998412)
			)
			(arc
				(start 303.002442 -285.773114)
				(mid 302.998541 -285.753591)
				(end 302.987456 -285.737046)
			)
			(xy 302.971708 -285.721298) (xy 302.951388 -285.713424) (xy 302.940466 -285.714186) (xy 302.920654 -285.714948)
			(arc
				(start 295.91 -285.714948)
				(mid 295.81371 -285.700144)
				(end 295.726358 -285.657036)
			)
			(arc
				(start 295.726358 -285.657036)
				(mid 295.716651 -285.651754)
				(end 295.706038 -285.648654)
			)
			(arc
				(start 295.706038 -285.648654)
				(mid 295.669562 -285.63975)
				(end 295.63441 -285.626556)
			)
			(xy 295.624758 -285.622238)
			(arc
				(start 294.686228 -285.622238)
				(mid 294.668293 -285.625509)
				(end 294.6527 -285.634938)
			)
			(arc
				(start 294.6527 -285.634938)
				(mid 294.55408 -285.694259)
				(end 294.440864 -285.714948)
			)
			(arc
				(start 292.1762 -285.714948)
				(mid 292.053585 -285.690465)
				(end 291.949632 -285.620968)
			)
			(arc
				(start 291.695632 -285.366968)
				(mid 291.626092 -285.263033)
				(end 291.601652 -285.1404)
			)
			(arc
				(start 291.601652 -285.112968)
				(mid 291.586773 -285.077047)
				(end 291.550852 -285.062168)
			)
			(arc
				(start 290.965382 -285.062168)
				(mid 290.945859 -285.066069)
				(end 290.929314 -285.077154)
			)
			(arc
				(start 290.399216 -285.607252)
				(mid 290.382682 -285.618363)
				(end 290.363148 -285.622238)
			)
			(arc
				(start 282.22956 -285.622238)
				(mid 282.210037 -285.626139)
				(end 282.193492 -285.637224)
			)
			(arc
				(start 282.156916 -285.6738)
				(mid 282.143626 -285.697476)
				(end 282.14447 -285.7246)
			)
			(xy 282.149042 -285.73984)
			(arc
				(start 282.152852 -285.745682)
				(mid 282.19208 -285.831678)
				(end 282.20543 -285.92526)
			)
			(arc
				(start 282.20543 -285.93161)
				(mid 282.178248 -286.05623)
				(end 282.105862 -286.161226)
			)
			(xy 282.098496 -286.168592) (xy 282.090622 -286.187134)
			(arc
				(start 282.090622 -286.208724)
				(mid 282.105501 -286.244645)
				(end 282.141422 -286.259524)
			)
			(arc
				(start 300.638718 -286.259524)
				(mid 300.657441 -286.263201)
				(end 300.673516 -286.273494)
			)
			(xy 300.674786 -286.274764)
			(arc
				(start 300.679866 -286.279082)
				(mid 300.695093 -286.287803)
				(end 300.712378 -286.290766)
			)
			(xy 301.206662 -286.290766)
		)
		(stroke
			(width 0)
			(type solid)
		)
		(fill yes)
		(layer "B.Cu")
		(net "GND")
	)
	(gr_poly
		(pts
			(arc
				(start 75.424284 -112.954054)
				(mid 75.44496 -112.949656)
				(end 75.46213 -112.93729)
			)
			(arc
				(start 75.46213 -112.93729)
				(mid 75.624495 -112.819345)
				(end 75.820778 -112.777524)
			)
			(arc
				(start 75.820778 -112.777524)
				(mid 76.017075 -112.819314)
				(end 76.179426 -112.93729)
			)
			(arc
				(start 76.179426 -112.93729)
				(mid 76.196555 -112.949747)
				(end 76.217272 -112.954054)
			)
			(arc
				(start 76.40193 -112.954054)
				(mid 76.424329 -112.948849)
				(end 76.442062 -112.934242)
			)
			(arc
				(start 76.442062 -112.934242)
				(mid 76.611342 -112.796301)
				(end 76.824078 -112.747044)
			)
			(arc
				(start 76.824078 -112.747044)
				(mid 77.036811 -112.796307)
				(end 77.206094 -112.934242)
			)
			(arc
				(start 77.206094 -112.934242)
				(mid 77.223869 -112.948762)
				(end 77.246226 -112.954054)
			)
			(arc
				(start 81.293716 -112.954054)
				(mid 81.319648 -112.946937)
				(end 81.33842 -112.927638)
			)
			(arc
				(start 81.33842 -112.927638)
				(mid 81.673446 -112.728563)
				(end 82.008472 -112.927638)
			)
			(arc
				(start 82.008472 -112.927638)
				(mid 82.027182 -112.947042)
				(end 82.053176 -112.954054)
			)
			(arc
				(start 89.713054 -112.954054)
				(mid 89.732577 -112.950153)
				(end 89.749122 -112.939068)
			)
			(arc
				(start 90.244168 -112.444022)
				(mid 90.255279 -112.427488)
				(end 90.259154 -112.407954)
			)
			(arc
				(start 90.259154 -104.585516)
				(mid 90.255253 -104.565993)
				(end 90.244168 -104.549448)
			)
			(arc
				(start 90.079576 -104.384856)
				(mid 90.063042 -104.373745)
				(end 90.043508 -104.36987)
			)
			(arc
				(start 85.200744 -104.36987)
				(mid 85.181221 -104.373771)
				(end 85.164676 -104.384856)
			)
			(arc
				(start 81.679796 -107.869736)
				(mid 81.663262 -107.880847)
				(end 81.643728 -107.884722)
			)
			(arc
				(start 77.42174 -107.884722)
				(mid 77.402217 -107.888623)
				(end 77.385672 -107.899708)
			)
			(arc
				(start 76.25715 -109.02823)
				(mid 76.240616 -109.039341)
				(end 76.221082 -109.043216)
			)
			(arc
				(start 73.61936 -109.043216)
				(mid 73.583439 -109.058095)
				(end 73.56856 -109.094016)
			)
			(arc
				(start 73.56856 -112.832642)
				(mid 73.572393 -112.851999)
				(end 73.583292 -112.868456)
			)
			(arc
				(start 73.653904 -112.939068)
				(mid 73.670438 -112.950179)
				(end 73.689972 -112.954054)
			)
		)
		(stroke
			(width 0)
			(type solid)
		)
		(fill yes)
		(layer "B.Cu")
		(net "P12V_NIC1")
	)
	(gr_poly
		(pts
			(xy 337.074002 -91.436444) (xy 337.084071 -91.436019) (xy 337.102669 -91.428298) (xy 337.11007 -91.421458)
			(xy 337.262978 -91.26855) (xy 337.269819 -91.26115) (xy 337.277539 -91.242551) (xy 337.277964 -91.232482)
			(xy 337.277964 -90.59926) (xy 337.277533 -90.589194) (xy 337.269804 -90.570603) (xy 337.262978 -90.563192)
			(xy 337.144614 -90.445082) (xy 337.127915 -90.427794) (xy 337.099624 -90.388941) (xy 337.077773 -90.346133)
			(xy 337.062902 -90.300429) (xy 337.055379 -90.252959) (xy 337.054952 -90.228928) (xy 337.054952 -89.8271)
			(xy 337.053936 -89.810844) (xy 337.053936 -89.810082) (xy 337.05165 -89.793318) (xy 337.050888 -89.786206)
			(xy 337.050888 -89.692988) (xy 337.050398 -89.682983) (xy 337.042736 -89.664497) (xy 337.028583 -89.650351)
			(xy 337.010093 -89.642698) (xy 337.000088 -89.642188) (xy 336.048096 -89.642188) (xy 336.024105 -89.641711)
			(xy 335.976714 -89.634198) (xy 335.93108 -89.619373) (xy 335.888322 -89.5976) (xy 335.849491 -89.569414)
			(xy 335.832196 -89.55278) (xy 335.674208 -89.394792) (xy 335.653669 -89.373213) (xy 335.620542 -89.323709)
			(xy 335.608422 -89.296494) (xy 335.604358 -89.287096) (xy 335.598008 -89.280746) (xy 335.591169 -89.273345)
			(xy 335.583453 -89.254747) (xy 335.583022 -89.244678) (xy 335.583022 -87.781384) (xy 335.582597 -87.771315)
			(xy 335.574881 -87.752712) (xy 335.568036 -87.745316) (xy 335.305146 -87.482426) (xy 335.297746 -87.475585)
			(xy 335.279147 -87.467867) (xy 335.269078 -87.46744) (xy 332.005432 -87.46744) (xy 331.995368 -87.467877)
			(xy 331.976786 -87.475613) (xy 331.969364 -87.482426) (xy 331.827124 -87.624666) (xy 331.820285 -87.632067)
			(xy 331.812571 -87.650665) (xy 331.812138 -87.660734) (xy 331.812138 -88.22817) (xy 331.812671 -88.238159)
			(xy 331.820381 -88.256595) (xy 331.827124 -88.263984) (xy 332.434946 -88.871806) (xy 333.8863 -88.871806)
			(xy 333.890371 -88.816184) (xy 333.902497 -88.761747) (xy 333.92242 -88.709656) (xy 333.949716 -88.661021)
			(xy 333.983802 -88.616878) (xy 334.023951 -88.578169) (xy 334.069309 -88.545718) (xy 334.118909 -88.520217)
			(xy 334.171693 -88.50221) (xy 334.226536 -88.49208) (xy 334.28227 -88.490043) (xy 334.337707 -88.496143)
			(xy 334.391664 -88.510249) (xy 334.442993 -88.532061) (xy 334.490599 -88.561115) (xy 334.533467 -88.59679)
			(xy 334.570684 -88.638327) (xy 334.601457 -88.68484) (xy 334.625129 -88.735337) (xy 334.641197 -88.788744)
			(xy 334.649317 -88.84392) (xy 334.649826 -88.871806) (xy 334.649317 -88.899692) (xy 334.641197 -88.954868)
			(xy 334.625129 -89.008275) (xy 334.601457 -89.058772) (xy 334.570684 -89.105285) (xy 334.533467 -89.146822)
			(xy 334.490599 -89.182497) (xy 334.442993 -89.211551) (xy 334.391664 -89.233363) (xy 334.337707 -89.247469)
			(xy 334.28227 -89.253569) (xy 334.226536 -89.251532) (xy 334.171693 -89.241402) (xy 334.118909 -89.223395)
			(xy 334.069309 -89.197894) (xy 334.023951 -89.165443) (xy 333.983802 -89.126734) (xy 333.949716 -89.082591)
			(xy 333.92242 -89.033956) (xy 333.902497 -88.981865) (xy 333.890371 -88.927428) (xy 333.8863 -88.871806)
			(xy 332.434946 -88.871806) (xy 334.984598 -91.421458) (xy 334.991941 -91.428273) (xy 335.010404 -91.436013)
			(xy 335.020412 -91.436444)
		)
		(stroke
			(width 0)
			(type solid)
		)
		(fill yes)
		(layer "B.Cu")
		(net "P3V3_VDDAR_9ZXL0851_8_15")
	)
	(gr_poly
		(pts
			(arc
				(start 426.734478 -296.647362)
				(mid 426.749133 -296.64261)
				(end 426.761656 -296.633646)
			)
			(arc
				(start 426.851318 -296.543984)
				(mid 426.862429 -296.52745)
				(end 426.866304 -296.507916)
			)
			(xy 426.866304 -294.780462) (xy 426.850048 -294.755316) (xy 426.836078 -294.74922) (xy 426.737272 -294.705278)
			(xy 426.708062 -294.710104)
			(arc
				(start 426.696632 -294.720264)
				(mid 426.593691 -294.783541)
				(end 426.47489 -294.805608)
			)
			(arc
				(start 426.47489 -294.805608)
				(mid 426.241044 -294.708746)
				(end 426.144182 -294.4749)
			)
			(arc
				(start 426.144182 -294.4749)
				(mid 426.147764 -294.425589)
				(end 426.15866 -294.377364)
			)
			(xy 426.162216 -294.36568) (xy 426.158152 -294.342058)
			(arc
				(start 426.102526 -294.266874)
				(mid 426.084533 -294.251696)
				(end 426.061632 -294.2463)
			)
			(arc
				(start 424.988228 -294.2463)
				(mid 424.965351 -294.251743)
				(end 424.947334 -294.266874)
			)
			(arc
				(start 424.89882 -294.332406)
				(mid 424.889713 -294.353978)
				(end 424.8912 -294.377364)
			)
			(arc
				(start 424.8912 -294.377364)
				(mid 424.902093 -294.425589)
				(end 424.905678 -294.4749)
			)
			(arc
				(start 424.905678 -294.4749)
				(mid 424.808816 -294.708746)
				(end 424.57497 -294.805608)
			)
			(arc
				(start 424.574716 -294.805608)
				(mid 424.445564 -294.779238)
				(end 424.336972 -294.704516)
			)
			(xy 424.32859 -294.695626) (xy 424.326304 -294.693086)
			(arc
				(start 424.322748 -294.689022)
				(mid 424.296803 -294.672625)
				(end 424.266106 -294.674036)
			)
			(xy 424.177206 -294.707056) (xy 424.161966 -294.712644) (xy 424.143932 -294.738552) (xy 424.143932 -296.111168)
			(xy 424.161966 -296.137076) (xy 424.177206 -296.142664)
			(arc
				(start 424.266106 -296.175684)
				(mid 424.296834 -296.177214)
				(end 424.322748 -296.160698)
			)
			(xy 424.32732 -296.155364)
			(arc
				(start 424.336972 -296.145204)
				(mid 424.445681 -296.070434)
				(end 424.57497 -296.044112)
			)
			(xy 424.596814 -296.044112) (xy 424.604942 -296.044874)
			(arc
				(start 424.627548 -296.04843)
				(mid 424.811804 -296.144159)
				(end 424.90263 -296.330878)
			)
			(arc
				(start 424.904408 -296.343578)
				(mid 424.901873 -296.426606)
				(end 424.878754 -296.506392)
			)
			(xy 424.87342 -296.518076) (xy 424.875706 -296.543476)
			(arc
				(start 424.9293 -296.625264)
				(mid 424.947627 -296.64204)
				(end 424.971718 -296.648124)
			)
			(xy 426.726096 -296.648124)
		)
		(stroke
			(width 0)
			(type solid)
		)
		(fill yes)
		(layer "B.Cu")
		(net "P1V25_PEX3")
	)
	(gr_poly
		(pts
			(arc
				(start 265.996928 -366.083342)
				(mid 266.016451 -366.079441)
				(end 266.032996 -366.068356)
			)
			(arc
				(start 266.307062 -365.79429)
				(mid 266.318173 -365.777756)
				(end 266.322048 -365.758222)
			)
			(arc
				(start 266.322048 -365.378238)
				(mid 266.325949 -365.358715)
				(end 266.337034 -365.34217)
			)
			(xy 266.479528 -365.199676) (xy 266.48664 -365.185452)
			(arc
				(start 266.48791 -365.177578)
				(mid 266.643294 -364.902573)
				(end 266.939776 -364.79353)
			)
			(arc
				(start 266.939776 -364.79353)
				(mid 266.991153 -364.796365)
				(end 267.041884 -364.80496)
			)
			(xy 267.047472 -364.806484)
			(arc
				(start 267.555218 -364.806484)
				(mid 267.725404 -364.840354)
				(end 267.86967 -364.936786)
			)
			(arc
				(start 267.886434 -364.953296)
				(mid 267.90288 -364.964222)
				(end 267.922248 -364.968028)
			)
			(arc
				(start 267.931646 -364.968028)
				(mid 268.01531 -364.942584)
				(end 268.102334 -364.933992)
			)
			(arc
				(start 268.102334 -364.933992)
				(mid 268.194371 -364.943619)
				(end 268.28242 -364.972092)
			)
			(xy 268.292326 -364.976664) (xy 268.41958 -364.976664) (xy 268.41958 -364.979712) (xy 268.782292 -364.979712)
			(xy 268.782292 -364.976664) (xy 268.824964 -364.976664) (xy 268.83868 -364.972854)
			(arc
				(start 268.844776 -364.969044)
				(mid 268.967198 -364.91486)
				(end 269.099792 -364.8964)
			)
			(arc
				(start 269.099792 -364.8964)
				(mid 269.232378 -364.914888)
				(end 269.354808 -364.969044)
			)
			(xy 269.360904 -364.972854) (xy 269.37462 -364.976664)
			(arc
				(start 269.419578 -364.976664)
				(mid 269.438935 -364.972831)
				(end 269.455392 -364.961932)
			)
			(arc
				(start 269.726664 -364.69066)
				(mid 269.737775 -364.674126)
				(end 269.74165 -364.654592)
			)
			(arc
				(start 269.74165 -361.978194)
				(mid 269.737749 -361.958671)
				(end 269.726664 -361.942126)
			)
			(arc
				(start 264.694162 -356.909624)
				(mid 264.677628 -356.898513)
				(end 264.658094 -356.894638)
			)
			(arc
				(start 252.427232 -356.894638)
				(mid 252.407709 -356.898539)
				(end 252.391164 -356.909624)
			)
			(arc
				(start 249.53976 -359.761028)
				(mid 249.523226 -359.772139)
				(end 249.503692 -359.776014)
			)
			(arc
				(start 244.6274 -359.776014)
				(mid 244.607877 -359.779915)
				(end 244.591332 -359.791)
			)
			(arc
				(start 243.586508 -360.795824)
				(mid 243.569974 -360.806935)
				(end 243.55044 -360.81081)
			)
			(arc
				(start 237.565692 -360.81081)
				(mid 237.546169 -360.814711)
				(end 237.529624 -360.825796)
			)
			(arc
				(start 237.018322 -361.337098)
				(mid 237.007211 -361.353632)
				(end 237.003336 -361.373166)
			)
			(arc
				(start 237.003336 -365.637064)
				(mid 237.007237 -365.656587)
				(end 237.018322 -365.673132)
			)
			(arc
				(start 237.413546 -366.068356)
				(mid 237.43008 -366.079467)
				(end 237.449614 -366.083342)
			)
		)
		(stroke
			(width 0)
			(type solid)
		)
		(fill yes)
		(layer "B.Cu")
		(net "P12V_AUX")
	)
	(gr_poly
		(pts
			(arc
				(start 105.56367 -284.699202)
				(mid 105.583193 -284.695301)
				(end 105.599738 -284.684216)
			)
			(arc
				(start 105.626154 -284.6578)
				(mid 105.637265 -284.641266)
				(end 105.64114 -284.621732)
			)
			(arc
				(start 105.64114 -281.26309)
				(mid 105.637239 -281.243567)
				(end 105.626154 -281.227022)
			)
			(arc
				(start 105.34015 -280.941018)
				(mid 105.323616 -280.929907)
				(end 105.304082 -280.926032)
			)
			(xy 105.2322 -280.926032) (xy 105.227374 -280.931112)
			(arc
				(start 103.669084 -280.931112)
				(mid 103.649697 -280.927162)
				(end 103.63327 -280.916126)
			)
			(arc
				(start 103.47325 -280.756106)
				(mid 103.462188 -280.739689)
				(end 103.458264 -280.720292)
			)
			(arc
				(start 103.458264 -279.40635)
				(mid 103.462214 -279.386963)
				(end 103.47325 -279.370536)
			)
			(arc
				(start 104.350312 -278.493474)
				(mid 104.366729 -278.482412)
				(end 104.386126 -278.478488)
			)
			(arc
				(start 108.264198 -278.478488)
				(mid 108.283585 -278.482438)
				(end 108.300012 -278.493474)
			)
			(xy 108.306108 -278.49957) (xy 108.32465 -278.50719)
			(arc
				(start 109.043978 -278.50719)
				(mid 109.063501 -278.511091)
				(end 109.080046 -278.522176)
			)
			(arc
				(start 110.176056 -279.618186)
				(mid 110.187167 -279.63472)
				(end 110.191042 -279.654254)
			)
			(arc
				(start 110.191042 -284.58541)
				(mid 110.194943 -284.604933)
				(end 110.206028 -284.621478)
			)
			(arc
				(start 110.268766 -284.684216)
				(mid 110.2853 -284.695327)
				(end 110.304834 -284.699202)
			)
			(arc
				(start 113.66754 -284.699202)
				(mid 113.687063 -284.695301)
				(end 113.703608 -284.684216)
			)
			(arc
				(start 113.786666 -284.601158)
				(mid 113.797777 -284.584624)
				(end 113.801652 -284.56509)
			)
			(arc
				(start 113.801652 -281.26309)
				(mid 113.797751 -281.243567)
				(end 113.786666 -281.227022)
			)
			(arc
				(start 113.500662 -280.941018)
				(mid 113.484128 -280.929907)
				(end 113.464594 -280.926032)
			)
			(xy 113.392712 -280.926032) (xy 113.387886 -280.931112)
			(arc
				(start 111.829596 -280.931112)
				(mid 111.810209 -280.927162)
				(end 111.793782 -280.916126)
			)
			(arc
				(start 111.633762 -280.756106)
				(mid 111.6227 -280.739689)
				(end 111.618776 -280.720292)
			)
			(arc
				(start 111.618776 -279.40635)
				(mid 111.622726 -279.386963)
				(end 111.633762 -279.370536)
			)
			(arc
				(start 112.31245 -278.691594)
				(mid 112.323512 -278.675177)
				(end 112.327436 -278.65578)
			)
			(xy 112.327436 -278.642064) (xy 112.330992 -278.638508) (xy 112.338612 -278.619966)
			(arc
				(start 112.338612 -272.61185)
				(mid 112.334711 -272.592327)
				(end 112.323626 -272.575782)
			)
			(arc
				(start 112.212628 -272.464784)
				(mid 112.196094 -272.453673)
				(end 112.17656 -272.449798)
			)
			(arc
				(start 102.26294 -272.449798)
				(mid 102.243417 -272.453699)
				(end 102.226872 -272.464784)
			)
			(arc
				(start 102.045516 -272.64614)
				(mid 102.034405 -272.662674)
				(end 102.03053 -272.682208)
			)
			(xy 102.03053 -280.633678) (xy 102.031038 -280.641806) (xy 102.031038 -280.645362) (xy 102.03053 -280.65349)
			(arc
				(start 102.03053 -284.585156)
				(mid 102.034431 -284.604679)
				(end 102.045516 -284.621224)
			)
			(arc
				(start 102.108508 -284.684216)
				(mid 102.125042 -284.695327)
				(end 102.144576 -284.699202)
			)
		)
		(stroke
			(width 0)
			(type solid)
		)
		(fill yes)
		(layer "B.Cu")
		(net "SW_P12V_P0V8_PEX0_FLT")
	)
	(gr_poly
		(pts
			(arc
				(start 337.763866 -284.699202)
				(mid 337.783389 -284.695301)
				(end 337.799934 -284.684216)
			)
			(arc
				(start 337.82635 -284.6578)
				(mid 337.837461 -284.641266)
				(end 337.841336 -284.621732)
			)
			(arc
				(start 337.841336 -281.26309)
				(mid 337.837435 -281.243567)
				(end 337.82635 -281.227022)
			)
			(arc
				(start 337.540346 -280.941018)
				(mid 337.523812 -280.929907)
				(end 337.504278 -280.926032)
			)
			(xy 337.432396 -280.926032) (xy 337.42757 -280.931112)
			(arc
				(start 335.86928 -280.931112)
				(mid 335.849893 -280.927162)
				(end 335.833466 -280.916126)
			)
			(arc
				(start 335.673446 -280.756106)
				(mid 335.662384 -280.739689)
				(end 335.65846 -280.720292)
			)
			(arc
				(start 335.65846 -279.40635)
				(mid 335.66241 -279.386963)
				(end 335.673446 -279.370536)
			)
			(arc
				(start 336.550508 -278.493474)
				(mid 336.566925 -278.482412)
				(end 336.586322 -278.478488)
			)
			(arc
				(start 340.464394 -278.478488)
				(mid 340.483781 -278.482438)
				(end 340.500208 -278.493474)
			)
			(xy 340.506304 -278.49957) (xy 340.524846 -278.50719)
			(arc
				(start 341.244174 -278.50719)
				(mid 341.263697 -278.511091)
				(end 341.280242 -278.522176)
			)
			(arc
				(start 342.376252 -279.618186)
				(mid 342.387363 -279.63472)
				(end 342.391238 -279.654254)
			)
			(arc
				(start 342.391238 -284.58541)
				(mid 342.395139 -284.604933)
				(end 342.406224 -284.621478)
			)
			(arc
				(start 342.468962 -284.684216)
				(mid 342.485496 -284.695327)
				(end 342.50503 -284.699202)
			)
			(arc
				(start 345.867736 -284.699202)
				(mid 345.887259 -284.695301)
				(end 345.903804 -284.684216)
			)
			(arc
				(start 345.986862 -284.601158)
				(mid 345.997973 -284.584624)
				(end 346.001848 -284.56509)
			)
			(arc
				(start 346.001848 -281.26309)
				(mid 345.997947 -281.243567)
				(end 345.986862 -281.227022)
			)
			(arc
				(start 345.700858 -280.941018)
				(mid 345.684324 -280.929907)
				(end 345.66479 -280.926032)
			)
			(xy 345.592908 -280.926032) (xy 345.588082 -280.931112)
			(arc
				(start 344.029792 -280.931112)
				(mid 344.010405 -280.927162)
				(end 343.993978 -280.916126)
			)
			(arc
				(start 343.833958 -280.756106)
				(mid 343.822896 -280.739689)
				(end 343.818972 -280.720292)
			)
			(arc
				(start 343.818972 -279.40635)
				(mid 343.822922 -279.386963)
				(end 343.833958 -279.370536)
			)
			(arc
				(start 344.512646 -278.691594)
				(mid 344.523708 -278.675177)
				(end 344.527632 -278.65578)
			)
			(xy 344.527632 -278.642064) (xy 344.531188 -278.638508) (xy 344.538808 -278.619966)
			(arc
				(start 344.538808 -272.61185)
				(mid 344.534907 -272.592327)
				(end 344.523822 -272.575782)
			)
			(arc
				(start 344.412824 -272.464784)
				(mid 344.39629 -272.453673)
				(end 344.376756 -272.449798)
			)
			(arc
				(start 334.463136 -272.449798)
				(mid 334.443613 -272.453699)
				(end 334.427068 -272.464784)
			)
			(arc
				(start 334.245712 -272.64614)
				(mid 334.234601 -272.662674)
				(end 334.230726 -272.682208)
			)
			(xy 334.230726 -280.633678) (xy 334.231234 -280.641806) (xy 334.231234 -280.645362) (xy 334.230726 -280.65349)
			(arc
				(start 334.230726 -284.585156)
				(mid 334.234627 -284.604679)
				(end 334.245712 -284.621224)
			)
			(arc
				(start 334.308704 -284.684216)
				(mid 334.325238 -284.695327)
				(end 334.344772 -284.699202)
			)
		)
		(stroke
			(width 0)
			(type solid)
		)
		(fill yes)
		(layer "B.Cu")
		(net "SW_P12V_P0V8_PEX2_FLT")
	)
	(gr_poly
		(pts
			(arc
				(start 46.599094 -302.768)
				(mid 46.61499 -302.765449)
				(end 46.62932 -302.758094)
			)
			(arc
				(start 46.62932 -302.758094)
				(mid 46.8249 -302.694067)
				(end 47.02048 -302.758094)
			)
			(arc
				(start 47.02048 -302.758094)
				(mid 47.034794 -302.765498)
				(end 47.050706 -302.768)
			)
			(arc
				(start 47.299118 -302.768)
				(mid 47.318641 -302.764099)
				(end 47.335186 -302.753014)
			)
			(arc
				(start 47.457614 -302.630586)
				(mid 47.468725 -302.614052)
				(end 47.4726 -302.594518)
			)
			(arc
				(start 47.4726 -301.569882)
				(mid 47.468699 -301.550359)
				(end 47.457614 -301.533814)
			)
			(arc
				(start 47.436786 -301.512986)
				(mid 47.420252 -301.501875)
				(end 47.400718 -301.498)
			)
			(arc
				(start 46.553882 -301.498)
				(mid 46.534359 -301.494099)
				(end 46.517814 -301.483014)
			)
			(arc
				(start 46.293786 -301.258986)
				(mid 46.282675 -301.242452)
				(end 46.2788 -301.222918)
			)
			(arc
				(start 46.2788 -298.826682)
				(mid 46.282701 -298.807159)
				(end 46.293786 -298.790614)
			)
			(arc
				(start 46.644814 -298.439586)
				(mid 46.655925 -298.423052)
				(end 46.6598 -298.403518)
			)
			(arc
				(start 46.6598 -297.963082)
				(mid 46.655899 -297.943559)
				(end 46.644814 -297.927014)
			)
			(arc
				(start 46.268386 -297.550586)
				(mid 46.257275 -297.534052)
				(end 46.2534 -297.514518)
			)
			(arc
				(start 46.2534 -292.248082)
				(mid 46.257301 -292.228559)
				(end 46.268386 -292.212014)
			)
			(arc
				(start 46.619414 -291.860986)
				(mid 46.630525 -291.844452)
				(end 46.6344 -291.824918)
			)
			(arc
				(start 46.6344 -291.490908)
				(mid 46.619521 -291.454987)
				(end 46.5836 -291.440108)
			)
			(arc
				(start 45.740574 -291.440108)
				(mid 45.721217 -291.443941)
				(end 45.70476 -291.45484)
			)
			(arc
				(start 45.57141 -291.58819)
				(mid 45.560348 -291.604607)
				(end 45.556424 -291.624004)
			)
			(arc
				(start 45.556424 -296.440606)
				(mid 45.553381 -296.48384)
				(end 45.544232 -296.526204)
			)
			(xy 45.5422 -296.533062) (xy 45.5422 -297.650916)
			(arc
				(start 45.545248 -297.659552)
				(mid 45.559621 -297.711652)
				(end 45.564552 -297.76547)
			)
			(arc
				(start 45.564552 -300.425866)
				(mid 45.55959 -300.479678)
				(end 45.545248 -300.531784)
			)
			(xy 45.5422 -300.54042)
			(arc
				(start 45.5422 -301.27067)
				(mid 45.548945 -301.295964)
				(end 45.567346 -301.314612)
			)
			(arc
				(start 45.567346 -301.314612)
				(mid 45.730688 -301.599854)
				(end 45.567346 -301.885096)
			)
			(arc
				(start 45.567346 -301.885096)
				(mid 45.548873 -301.903703)
				(end 45.5422 -301.929038)
			)
			(arc
				(start 45.5422 -302.137318)
				(mid 45.546101 -302.156841)
				(end 45.557186 -302.173386)
			)
			(arc
				(start 46.136814 -302.753014)
				(mid 46.153348 -302.764125)
				(end 46.172882 -302.768)
			)
		)
		(stroke
			(width 0)
			(type solid)
		)
		(fill yes)
		(layer "B.Cu")
		(net "GND")
	)
	(gr_poly
		(pts
			(arc
				(start 278.799036 -302.768)
				(mid 278.814932 -302.765449)
				(end 278.829262 -302.758094)
			)
			(arc
				(start 278.829262 -302.758094)
				(mid 279.024842 -302.694067)
				(end 279.220422 -302.758094)
			)
			(arc
				(start 279.220422 -302.758094)
				(mid 279.234736 -302.765498)
				(end 279.250648 -302.768)
			)
			(arc
				(start 279.49906 -302.768)
				(mid 279.518583 -302.764099)
				(end 279.535128 -302.753014)
			)
			(arc
				(start 279.657556 -302.630586)
				(mid 279.668667 -302.614052)
				(end 279.672542 -302.594518)
			)
			(arc
				(start 279.672542 -301.569882)
				(mid 279.668641 -301.550359)
				(end 279.657556 -301.533814)
			)
			(arc
				(start 279.636728 -301.512986)
				(mid 279.620194 -301.501875)
				(end 279.60066 -301.498)
			)
			(arc
				(start 278.753824 -301.498)
				(mid 278.734301 -301.494099)
				(end 278.717756 -301.483014)
			)
			(arc
				(start 278.493728 -301.258986)
				(mid 278.482617 -301.242452)
				(end 278.478742 -301.222918)
			)
			(arc
				(start 278.478742 -298.826682)
				(mid 278.482643 -298.807159)
				(end 278.493728 -298.790614)
			)
			(arc
				(start 278.844756 -298.439586)
				(mid 278.855867 -298.423052)
				(end 278.859742 -298.403518)
			)
			(arc
				(start 278.859742 -297.963082)
				(mid 278.855841 -297.943559)
				(end 278.844756 -297.927014)
			)
			(arc
				(start 278.468328 -297.550586)
				(mid 278.457217 -297.534052)
				(end 278.453342 -297.514518)
			)
			(arc
				(start 278.453342 -292.248082)
				(mid 278.457243 -292.228559)
				(end 278.468328 -292.212014)
			)
			(arc
				(start 278.819356 -291.860986)
				(mid 278.830467 -291.844452)
				(end 278.834342 -291.824918)
			)
			(arc
				(start 278.834342 -291.490908)
				(mid 278.819463 -291.454987)
				(end 278.783542 -291.440108)
			)
			(arc
				(start 277.940516 -291.440108)
				(mid 277.921159 -291.443941)
				(end 277.904702 -291.45484)
			)
			(arc
				(start 277.771352 -291.58819)
				(mid 277.76029 -291.604607)
				(end 277.756366 -291.624004)
			)
			(arc
				(start 277.756366 -296.440606)
				(mid 277.753323 -296.48384)
				(end 277.744174 -296.526204)
			)
			(xy 277.742142 -296.533062) (xy 277.742142 -297.650916)
			(arc
				(start 277.74519 -297.659552)
				(mid 277.759563 -297.711652)
				(end 277.764494 -297.76547)
			)
			(arc
				(start 277.764494 -300.425866)
				(mid 277.759532 -300.479678)
				(end 277.74519 -300.531784)
			)
			(xy 277.742142 -300.54042)
			(arc
				(start 277.742142 -301.27067)
				(mid 277.748887 -301.295964)
				(end 277.767288 -301.314612)
			)
			(arc
				(start 277.767288 -301.314612)
				(mid 277.93063 -301.599854)
				(end 277.767288 -301.885096)
			)
			(arc
				(start 277.767288 -301.885096)
				(mid 277.748815 -301.903703)
				(end 277.742142 -301.929038)
			)
			(arc
				(start 277.742142 -302.137318)
				(mid 277.746043 -302.156841)
				(end 277.757128 -302.173386)
			)
			(arc
				(start 278.336756 -302.753014)
				(mid 278.35329 -302.764125)
				(end 278.372824 -302.768)
			)
		)
		(stroke
			(width 0)
			(type solid)
		)
		(fill yes)
		(layer "B.Cu")
		(net "GND")
	)
	(gr_poly
		(pts
			(arc
				(start 310.63438 -296.647362)
				(mid 310.649035 -296.64261)
				(end 310.661558 -296.633646)
			)
			(arc
				(start 310.75122 -296.543984)
				(mid 310.762331 -296.52745)
				(end 310.766206 -296.507916)
			)
			(xy 310.766206 -294.760396)
			(arc
				(start 310.766206 -294.759634)
				(mid 310.758539 -294.733795)
				(end 310.738774 -294.715438)
			)
			(xy 310.73471 -294.713406) (xy 310.633364 -294.672004)
			(arc
				(start 310.622696 -294.67429)
				(mid 310.51221 -294.761753)
				(end 310.374792 -294.792908)
			)
			(arc
				(start 310.374792 -294.792908)
				(mid 310.149926 -294.699766)
				(end 310.056784 -294.4749)
			)
			(arc
				(start 310.056784 -294.4749)
				(mid 310.06147 -294.420762)
				(end 310.075326 -294.36822)
			)
			(xy 310.07939 -294.356282) (xy 310.076088 -294.331644)
			(arc
				(start 310.029352 -294.267382)
				(mid 310.011311 -294.251907)
				(end 309.988204 -294.2463)
			)
			(arc
				(start 308.88813 -294.2463)
				(mid 308.865253 -294.251743)
				(end 308.847236 -294.266874)
			)
			(arc
				(start 308.798722 -294.332406)
				(mid 308.789615 -294.353978)
				(end 308.791102 -294.377364)
			)
			(arc
				(start 308.791102 -294.377364)
				(mid 308.801995 -294.425589)
				(end 308.80558 -294.4749)
			)
			(arc
				(start 308.80558 -294.4749)
				(mid 308.708718 -294.708746)
				(end 308.474872 -294.805608)
			)
			(arc
				(start 308.474618 -294.805608)
				(mid 308.335791 -294.775058)
				(end 308.22265 -294.689022)
			)
			(arc
				(start 308.222396 -294.688768)
				(mid 308.19664 -294.672638)
				(end 308.166262 -294.674036)
			)
			(xy 308.077108 -294.707056) (xy 308.061868 -294.712644) (xy 308.043834 -294.738552) (xy 308.043834 -296.111168)
			(xy 308.061868 -296.137076) (xy 308.077108 -296.142664)
			(arc
				(start 308.166262 -296.175684)
				(mid 308.196656 -296.177144)
				(end 308.222396 -296.160952)
			)
			(arc
				(start 308.22265 -296.160698)
				(mid 308.335811 -296.074705)
				(end 308.474618 -296.044112)
			)
			(arc
				(start 308.474872 -296.044112)
				(mid 308.708718 -296.140974)
				(end 308.80558 -296.37482)
			)
			(arc
				(start 308.80558 -296.37482)
				(mid 308.798968 -296.440646)
				(end 308.779418 -296.503852)
			)
			(arc
				(start 308.778656 -296.505376)
				(mid 308.774127 -296.528729)
				(end 308.780688 -296.551604)
			)
			(xy 308.782466 -296.554398)
			(arc
				(start 308.829202 -296.625264)
				(mid 308.847529 -296.64204)
				(end 308.87162 -296.648124)
			)
			(xy 310.625998 -296.648124)
		)
		(stroke
			(width 0)
			(type solid)
		)
		(fill yes)
		(layer "B.Cu")
		(net "P1V25_PEX2")
	)
	(gr_poly
		(pts
			(arc
				(start 394.899134 -302.768)
				(mid 394.91503 -302.765449)
				(end 394.92936 -302.758094)
			)
			(arc
				(start 394.92936 -302.758094)
				(mid 395.12494 -302.694067)
				(end 395.32052 -302.758094)
			)
			(arc
				(start 395.32052 -302.758094)
				(mid 395.334834 -302.765498)
				(end 395.350746 -302.768)
			)
			(arc
				(start 395.599158 -302.768)
				(mid 395.618681 -302.764099)
				(end 395.635226 -302.753014)
			)
			(arc
				(start 395.757654 -302.630586)
				(mid 395.768765 -302.614052)
				(end 395.77264 -302.594518)
			)
			(arc
				(start 395.77264 -301.569882)
				(mid 395.768739 -301.550359)
				(end 395.757654 -301.533814)
			)
			(arc
				(start 395.736826 -301.512986)
				(mid 395.720292 -301.501875)
				(end 395.700758 -301.498)
			)
			(arc
				(start 394.853922 -301.498)
				(mid 394.834399 -301.494099)
				(end 394.817854 -301.483014)
			)
			(arc
				(start 394.593826 -301.258986)
				(mid 394.582715 -301.242452)
				(end 394.57884 -301.222918)
			)
			(arc
				(start 394.57884 -298.826682)
				(mid 394.582741 -298.807159)
				(end 394.593826 -298.790614)
			)
			(arc
				(start 394.944854 -298.439586)
				(mid 394.955965 -298.423052)
				(end 394.95984 -298.403518)
			)
			(arc
				(start 394.95984 -297.963082)
				(mid 394.955939 -297.943559)
				(end 394.944854 -297.927014)
			)
			(arc
				(start 394.568426 -297.550586)
				(mid 394.557315 -297.534052)
				(end 394.55344 -297.514518)
			)
			(arc
				(start 394.55344 -292.248082)
				(mid 394.557341 -292.228559)
				(end 394.568426 -292.212014)
			)
			(arc
				(start 394.919454 -291.860986)
				(mid 394.930565 -291.844452)
				(end 394.93444 -291.824918)
			)
			(arc
				(start 394.93444 -291.490908)
				(mid 394.919561 -291.454987)
				(end 394.88364 -291.440108)
			)
			(arc
				(start 394.040614 -291.440108)
				(mid 394.021257 -291.443941)
				(end 394.0048 -291.45484)
			)
			(arc
				(start 393.87145 -291.58819)
				(mid 393.860388 -291.604607)
				(end 393.856464 -291.624004)
			)
			(arc
				(start 393.856464 -296.440606)
				(mid 393.853421 -296.48384)
				(end 393.844272 -296.526204)
			)
			(xy 393.84224 -296.533062) (xy 393.84224 -297.650916)
			(arc
				(start 393.845288 -297.659552)
				(mid 393.859661 -297.711652)
				(end 393.864592 -297.76547)
			)
			(arc
				(start 393.864592 -300.425866)
				(mid 393.85963 -300.479678)
				(end 393.845288 -300.531784)
			)
			(xy 393.84224 -300.54042)
			(arc
				(start 393.84224 -301.27067)
				(mid 393.848985 -301.295964)
				(end 393.867386 -301.314612)
			)
			(arc
				(start 393.867386 -301.314612)
				(mid 394.030728 -301.599854)
				(end 393.867386 -301.885096)
			)
			(arc
				(start 393.867386 -301.885096)
				(mid 393.848913 -301.903703)
				(end 393.84224 -301.929038)
			)
			(arc
				(start 393.84224 -302.137318)
				(mid 393.846141 -302.156841)
				(end 393.857226 -302.173386)
			)
			(arc
				(start 394.436854 -302.753014)
				(mid 394.453388 -302.764125)
				(end 394.472922 -302.768)
			)
		)
		(stroke
			(width 0)
			(type solid)
		)
		(fill yes)
		(layer "B.Cu")
		(net "GND")
	)
	(gr_poly
		(pts
			(arc
				(start 122.222768 -284.699202)
				(mid 122.242291 -284.695301)
				(end 122.258836 -284.684216)
			)
			(arc
				(start 122.285252 -284.6578)
				(mid 122.296363 -284.641266)
				(end 122.300238 -284.621732)
			)
			(arc
				(start 122.300238 -281.26309)
				(mid 122.296337 -281.243567)
				(end 122.285252 -281.227022)
			)
			(arc
				(start 121.999248 -280.941018)
				(mid 121.982714 -280.929907)
				(end 121.96318 -280.926032)
			)
			(xy 121.921016 -280.926032) (xy 121.91619 -280.931112)
			(arc
				(start 120.378982 -280.931112)
				(mid 120.359595 -280.927162)
				(end 120.343168 -280.916126)
			)
			(arc
				(start 120.183148 -280.756106)
				(mid 120.172222 -280.73966)
				(end 120.168416 -280.720292)
			)
			(arc
				(start 120.168416 -279.40635)
				(mid 120.172249 -279.386993)
				(end 120.183148 -279.370536)
			)
			(arc
				(start 121.06021 -278.493474)
				(mid 121.076627 -278.482412)
				(end 121.096024 -278.478488)
			)
			(arc
				(start 124.974096 -278.478488)
				(mid 124.993483 -278.482438)
				(end 125.00991 -278.493474)
			)
			(xy 125.016006 -278.49957) (xy 125.034548 -278.50719)
			(arc
				(start 125.703076 -278.50719)
				(mid 125.722599 -278.511091)
				(end 125.739144 -278.522176)
			)
			(arc
				(start 126.835154 -279.618186)
				(mid 126.846265 -279.63472)
				(end 126.85014 -279.654254)
			)
			(arc
				(start 126.85014 -284.58541)
				(mid 126.854041 -284.604933)
				(end 126.865126 -284.621478)
			)
			(arc
				(start 126.927864 -284.684216)
				(mid 126.944398 -284.695327)
				(end 126.963932 -284.699202)
			)
			(arc
				(start 130.326638 -284.699202)
				(mid 130.346161 -284.695301)
				(end 130.362706 -284.684216)
			)
			(arc
				(start 130.445764 -284.601158)
				(mid 130.456875 -284.584624)
				(end 130.46075 -284.56509)
			)
			(arc
				(start 130.46075 -281.26309)
				(mid 130.456849 -281.243567)
				(end 130.445764 -281.227022)
			)
			(arc
				(start 130.15976 -280.941018)
				(mid 130.143226 -280.929907)
				(end 130.123692 -280.926032)
			)
			(xy 130.081528 -280.926032) (xy 130.076702 -280.931112)
			(arc
				(start 128.539494 -280.931112)
				(mid 128.520107 -280.927162)
				(end 128.50368 -280.916126)
			)
			(arc
				(start 128.34366 -280.756106)
				(mid 128.332734 -280.73966)
				(end 128.328928 -280.720292)
			)
			(arc
				(start 128.328928 -279.40635)
				(mid 128.332761 -279.386993)
				(end 128.34366 -279.370536)
			)
			(arc
				(start 129.004822 -278.709374)
				(mid 129.015933 -278.69284)
				(end 129.019808 -278.673306)
			)
			(xy 129.019808 -277.479252) (xy 129.026412 -277.472648)
			(arc
				(start 129.026412 -276.503892)
				(mid 129.025346 -276.494035)
				(end 129.022348 -276.484588)
			)
			(xy 129.018284 -276.474682)
			(arc
				(start 129.018284 -272.513044)
				(mid 129.014451 -272.493687)
				(end 129.003552 -272.47723)
			)
			(arc
				(start 128.991106 -272.464784)
				(mid 128.974572 -272.453673)
				(end 128.955038 -272.449798)
			)
			(arc
				(start 118.922038 -272.449798)
				(mid 118.902515 -272.453699)
				(end 118.88597 -272.464784)
			)
			(arc
				(start 118.704614 -272.64614)
				(mid 118.693503 -272.662674)
				(end 118.689628 -272.682208)
			)
			(xy 118.689628 -280.633678) (xy 118.690136 -280.641806) (xy 118.690136 -280.645362) (xy 118.689628 -280.65349)
			(arc
				(start 118.689628 -284.585156)
				(mid 118.693529 -284.604679)
				(end 118.704614 -284.621224)
			)
			(arc
				(start 118.767606 -284.684216)
				(mid 118.78414 -284.695327)
				(end 118.803674 -284.699202)
			)
		)
		(stroke
			(width 0)
			(type solid)
		)
		(fill yes)
		(layer "B.Cu")
		(net "SW_P12V_P0V8_PEX1_FLT")
	)
	(gr_poly
		(pts
			(arc
				(start 354.422964 -284.699202)
				(mid 354.442487 -284.695301)
				(end 354.459032 -284.684216)
			)
			(arc
				(start 354.485448 -284.6578)
				(mid 354.496559 -284.641266)
				(end 354.500434 -284.621732)
			)
			(arc
				(start 354.500434 -281.26309)
				(mid 354.496533 -281.243567)
				(end 354.485448 -281.227022)
			)
			(arc
				(start 354.199444 -280.941018)
				(mid 354.18291 -280.929907)
				(end 354.163376 -280.926032)
			)
			(xy 354.121212 -280.926032) (xy 354.116386 -280.931112)
			(arc
				(start 352.579178 -280.931112)
				(mid 352.559791 -280.927162)
				(end 352.543364 -280.916126)
			)
			(arc
				(start 352.383344 -280.756106)
				(mid 352.372418 -280.73966)
				(end 352.368612 -280.720292)
			)
			(arc
				(start 352.368612 -279.40635)
				(mid 352.372445 -279.386993)
				(end 352.383344 -279.370536)
			)
			(arc
				(start 353.260406 -278.493474)
				(mid 353.276823 -278.482412)
				(end 353.29622 -278.478488)
			)
			(arc
				(start 357.174292 -278.478488)
				(mid 357.193679 -278.482438)
				(end 357.210106 -278.493474)
			)
			(xy 357.216202 -278.49957) (xy 357.234744 -278.50719)
			(arc
				(start 357.903272 -278.50719)
				(mid 357.922795 -278.511091)
				(end 357.93934 -278.522176)
			)
			(arc
				(start 359.03535 -279.618186)
				(mid 359.046461 -279.63472)
				(end 359.050336 -279.654254)
			)
			(arc
				(start 359.050336 -284.58541)
				(mid 359.054237 -284.604933)
				(end 359.065322 -284.621478)
			)
			(arc
				(start 359.12806 -284.684216)
				(mid 359.144594 -284.695327)
				(end 359.164128 -284.699202)
			)
			(arc
				(start 362.526834 -284.699202)
				(mid 362.546357 -284.695301)
				(end 362.562902 -284.684216)
			)
			(arc
				(start 362.64596 -284.601158)
				(mid 362.657071 -284.584624)
				(end 362.660946 -284.56509)
			)
			(arc
				(start 362.660946 -281.26309)
				(mid 362.657045 -281.243567)
				(end 362.64596 -281.227022)
			)
			(arc
				(start 362.359956 -280.941018)
				(mid 362.343422 -280.929907)
				(end 362.323888 -280.926032)
			)
			(xy 362.281724 -280.926032) (xy 362.276898 -280.931112)
			(arc
				(start 360.73969 -280.931112)
				(mid 360.720303 -280.927162)
				(end 360.703876 -280.916126)
			)
			(arc
				(start 360.543856 -280.756106)
				(mid 360.53293 -280.73966)
				(end 360.529124 -280.720292)
			)
			(arc
				(start 360.529124 -279.40635)
				(mid 360.532957 -279.386993)
				(end 360.543856 -279.370536)
			)
			(arc
				(start 361.205018 -278.709374)
				(mid 361.216129 -278.69284)
				(end 361.220004 -278.673306)
			)
			(xy 361.220004 -277.479252) (xy 361.226608 -277.472648)
			(arc
				(start 361.226608 -276.503892)
				(mid 361.225542 -276.494035)
				(end 361.222544 -276.484588)
			)
			(xy 361.21848 -276.474682)
			(arc
				(start 361.21848 -272.513044)
				(mid 361.214647 -272.493687)
				(end 361.203748 -272.47723)
			)
			(arc
				(start 361.191302 -272.464784)
				(mid 361.174768 -272.453673)
				(end 361.155234 -272.449798)
			)
			(arc
				(start 351.122234 -272.449798)
				(mid 351.102711 -272.453699)
				(end 351.086166 -272.464784)
			)
			(arc
				(start 350.90481 -272.64614)
				(mid 350.893699 -272.662674)
				(end 350.889824 -272.682208)
			)
			(xy 350.889824 -280.633678) (xy 350.890332 -280.641806) (xy 350.890332 -280.645362) (xy 350.889824 -280.65349)
			(arc
				(start 350.889824 -284.585156)
				(mid 350.893725 -284.604679)
				(end 350.90481 -284.621224)
			)
			(arc
				(start 350.967802 -284.684216)
				(mid 350.984336 -284.695327)
				(end 351.00387 -284.699202)
			)
		)
		(stroke
			(width 0)
			(type solid)
		)
		(fill yes)
		(layer "B.Cu")
		(net "SW_P12V_P0V8_PEX3_FLT")
	)
	(gr_poly
		(pts
			(arc
				(start 2.062988 -379.893576)
				(mid 2.087732 -379.887142)
				(end 2.106168 -379.869446)
			)
			(xy 2.158746 -379.784356) (xy 2.159762 -379.758194)
			(arc
				(start 2.153666 -379.746256)
				(mid 2.11726 -379.646238)
				(end 2.104898 -379.540516)
			)
			(arc
				(start 2.104898 -379.540516)
				(mid 2.562606 -379.082808)
				(end 3.020314 -379.540516)
			)
			(arc
				(start 3.020314 -379.540516)
				(mid 3.007995 -379.646248)
				(end 2.971546 -379.746256)
			)
			(xy 2.96545 -379.758194) (xy 2.966466 -379.784356)
			(arc
				(start 3.019044 -379.869446)
				(mid 3.037503 -379.887101)
				(end 3.062224 -379.893576)
			)
			(arc
				(start 3.536188 -379.893576)
				(mid 3.560932 -379.887142)
				(end 3.579368 -379.869446)
			)
			(xy 3.631946 -379.784356) (xy 3.632962 -379.758194)
			(arc
				(start 3.626866 -379.746256)
				(mid 3.59046 -379.646238)
				(end 3.578098 -379.540516)
			)
			(arc
				(start 3.578098 -379.540516)
				(mid 4.035806 -379.082808)
				(end 4.493514 -379.540516)
			)
			(arc
				(start 4.493514 -379.540516)
				(mid 4.481195 -379.646248)
				(end 4.444746 -379.746256)
			)
			(xy 4.43865 -379.758194) (xy 4.439666 -379.784356)
			(arc
				(start 4.492244 -379.869446)
				(mid 4.510703 -379.887101)
				(end 4.535424 -379.893576)
			)
			(arc
				(start 5.661406 -379.893576)
				(mid 5.697327 -379.878697)
				(end 5.712206 -379.842776)
			)
			(arc
				(start 5.712206 -375.054876)
				(mid 5.697327 -375.018955)
				(end 5.661406 -375.004076)
			)
			(arc
				(start 1.902206 -375.004076)
				(mid 1.866285 -375.018955)
				(end 1.851406 -375.054876)
			)
			(xy 1.851406 -379.81509) (xy 1.865884 -379.838966)
			(arc
				(start 1.87833 -379.845824)
				(mid 1.90747 -379.86298)
				(end 1.934972 -379.882654)
			)
			(xy 1.94183 -379.887988) (xy 1.957832 -379.893576)
		)
		(stroke
			(width 0)
			(type solid)
		)
		(fill yes)
		(layer "B.Cu")
		(net "GND")
	)
	(gr_poly
		(pts
			(arc
				(start 8.640318 -278.015446)
				(mid 8.656382 -278.012839)
				(end 8.670798 -278.005286)
			)
			(xy 8.676386 -278.00046) (xy 8.714486 -277.96236)
			(arc
				(start 8.719312 -277.956772)
				(mid 8.726865 -277.942356)
				(end 8.729472 -277.926292)
			)
			(arc
				(start 8.729472 -276.659848)
				(mid 8.733373 -276.640325)
				(end 8.744458 -276.62378)
			)
			(xy 8.982202 -276.386036)
			(arc
				(start 8.987028 -276.380448)
				(mid 8.994581 -276.366032)
				(end 8.997188 -276.349968)
			)
			(arc
				(start 8.997188 -273.740372)
				(mid 9.001089 -273.720849)
				(end 9.012174 -273.704304)
			)
			(arc
				(start 9.990328 -272.72615)
				(mid 10.006862 -272.715039)
				(end 10.026396 -272.711164)
			)
			(arc
				(start 10.454386 -272.711164)
				(mid 10.47045 -272.708557)
				(end 10.484866 -272.701004)
			)
			(xy 10.490454 -272.696178) (xy 10.503408 -272.683224)
			(arc
				(start 10.508234 -272.677636)
				(mid 10.515787 -272.66322)
				(end 10.518394 -272.647156)
			)
			(arc
				(start 10.518394 -272.219166)
				(mid 10.522295 -272.199643)
				(end 10.53338 -272.183098)
			)
			(arc
				(start 11.481816 -271.234408)
				(mid 11.49835 -271.223297)
				(end 11.517884 -271.219422)
			)
			(arc
				(start 11.94308 -271.219422)
				(mid 11.959144 -271.216815)
				(end 11.97356 -271.209262)
			)
			(xy 11.979148 -271.204436) (xy 12.36091 -270.822674)
			(arc
				(start 12.365736 -270.817086)
				(mid 12.373289 -270.80267)
				(end 12.375896 -270.786606)
			)
			(arc
				(start 12.375896 -270.180562)
				(mid 12.373289 -270.164498)
				(end 12.365736 -270.150082)
			)
			(xy 12.36091 -270.144494) (xy 12.332462 -270.116046)
			(arc
				(start 12.326874 -270.11122)
				(mid 12.312458 -270.103667)
				(end 12.296394 -270.10106)
			)
			(arc
				(start 11.732006 -270.10106)
				(mid 11.712483 -270.097159)
				(end 11.695938 -270.086074)
			)
			(arc
				(start 11.526774 -269.91691)
				(mid 11.515663 -269.900376)
				(end 11.511788 -269.880842)
			)
			(arc
				(start 11.511788 -259.692394)
				(mid 11.507887 -259.672871)
				(end 11.496802 -259.656326)
			)
			(xy 11.34364 -259.503164) (xy 11.336528 -259.495798)
			(arc
				(start 11.326876 -259.491988)
				(mid 11.317535 -259.489164)
				(end 11.307826 -259.488178)
			)
			(arc
				(start 5.111496 -259.488178)
				(mid 5.101787 -259.489164)
				(end 5.092446 -259.491988)
			)
			(xy 5.082794 -259.495798) (xy 5.075682 -259.503164)
			(arc
				(start 4.830064 -259.748782)
				(mid 4.820605 -259.761604)
				(end 4.815586 -259.776722)
			)
			(xy 4.815078 -259.78485)
			(arc
				(start 4.815078 -269.773146)
				(mid 4.811334 -269.792035)
				(end 4.800854 -269.808198)
			)
			(xy 4.800346 -269.808706)
			(arc
				(start 4.796028 -269.813532)
				(mid 4.786302 -269.82933)
				(end 4.78282 -269.847568)
			)
			(arc
				(start 4.78282 -269.85976)
				(mid 4.778919 -269.879283)
				(end 4.767834 -269.895828)
			)
			(arc
				(start 4.466336 -270.197326)
				(mid 4.449802 -270.208437)
				(end 4.430268 -270.212312)
			)
			(arc
				(start 3.19278 -270.212312)
				(mid 3.176716 -270.214919)
				(end 3.1623 -270.222472)
			)
			(xy 3.156712 -270.227298) (xy 3.153664 -270.230346)
			(arc
				(start 3.153664 -277.837646)
				(mid 3.156271 -277.85371)
				(end 3.163824 -277.868126)
			)
			(xy 3.16865 -277.873714) (xy 3.295396 -278.00046)
			(arc
				(start 3.300984 -278.005286)
				(mid 3.3154 -278.012839)
				(end 3.331464 -278.015446)
			)
		)
		(stroke
			(width 0)
			(type solid)
		)
		(fill yes)
		(layer "B.Cu")
		(net "P1V25_PEX0")
	)
	(gr_poly
		(pts
			(arc
				(start 78.426056 -296.648124)
				(mid 78.445247 -296.644359)
				(end 78.461616 -296.633646)
			)
			(xy 78.46187 -296.633392) (xy 78.551278 -296.543984)
			(arc
				(start 78.551786 -296.543476)
				(mid 78.562528 -296.527119)
				(end 78.566264 -296.507916)
			)
			(arc
				(start 78.566264 -294.795702)
				(mid 78.558038 -294.767988)
				(end 78.536038 -294.74922)
			)
			(xy 78.437232 -294.705278) (xy 78.407768 -294.710104)
			(arc
				(start 78.396592 -294.720264)
				(mid 78.293651 -294.783541)
				(end 78.17485 -294.805608)
			)
			(arc
				(start 78.17485 -294.805608)
				(mid 77.941004 -294.708746)
				(end 77.844142 -294.4749)
			)
			(arc
				(start 77.844142 -294.4749)
				(mid 77.847743 -294.425718)
				(end 77.85862 -294.377618)
			)
			(xy 77.86243 -294.366188) (xy 77.858366 -294.342312)
			(arc
				(start 77.802486 -294.266874)
				(mid 77.784493 -294.251696)
				(end 77.761592 -294.2463)
			)
			(arc
				(start 76.688188 -294.2463)
				(mid 76.665311 -294.251743)
				(end 76.647294 -294.266874)
			)
			(xy 76.591668 -294.342058) (xy 76.587604 -294.36568)
			(arc
				(start 76.59116 -294.377364)
				(mid 76.602053 -294.425589)
				(end 76.605638 -294.4749)
			)
			(arc
				(start 76.605638 -294.4749)
				(mid 76.508776 -294.708746)
				(end 76.27493 -294.805608)
			)
			(arc
				(start 76.274676 -294.805608)
				(mid 76.135988 -294.775005)
				(end 76.022962 -294.689022)
			)
			(arc
				(start 76.022708 -294.689022)
				(mid 75.996878 -294.672655)
				(end 75.96632 -294.674036)
			)
			(arc
				(start 75.877166 -294.707056)
				(mid 75.852985 -294.725688)
				(end 75.843892 -294.754808)
			)
			(arc
				(start 75.843892 -296.094912)
				(mid 75.85304 -296.123994)
				(end 75.877166 -296.142664)
			)
			(arc
				(start 75.96632 -296.175684)
				(mid 75.996887 -296.177099)
				(end 76.022708 -296.160698)
			)
			(arc
				(start 76.022962 -296.160698)
				(mid 76.136105 -296.074641)
				(end 76.27493 -296.044112)
			)
			(xy 76.284836 -296.044112)
			(arc
				(start 76.284836 -296.044366)
				(mid 76.512178 -296.144578)
				(end 76.605638 -296.37482)
			)
			(arc
				(start 76.605892 -296.37482)
				(mid 76.599029 -296.441871)
				(end 76.578714 -296.506138)
			)
			(arc
				(start 76.57846 -296.506138)
				(mid 76.574543 -296.530803)
				(end 76.582778 -296.554398)
			)
			(arc
				(start 76.62926 -296.625264)
				(mid 76.647587 -296.64204)
				(end 76.671678 -296.648124)
			)
		)
		(stroke
			(width 0)
			(type solid)
		)
		(fill yes)
		(layer "B.Cu")
		(net "P1V25_PEX0")
	)
	(gr_poly
		(pts
			(arc
				(start 194.526154 -296.648124)
				(mid 194.545345 -296.644359)
				(end 194.561714 -296.633646)
			)
			(xy 194.561968 -296.633392) (xy 194.651376 -296.543984)
			(arc
				(start 194.651884 -296.543476)
				(mid 194.662626 -296.527119)
				(end 194.666362 -296.507916)
			)
			(arc
				(start 194.666362 -294.795702)
				(mid 194.658136 -294.767988)
				(end 194.636136 -294.74922)
			)
			(xy 194.53733 -294.705278) (xy 194.507866 -294.710104)
			(arc
				(start 194.49669 -294.720264)
				(mid 194.393749 -294.783541)
				(end 194.274948 -294.805608)
			)
			(arc
				(start 194.274948 -294.805608)
				(mid 194.041102 -294.708746)
				(end 193.94424 -294.4749)
			)
			(arc
				(start 193.94424 -294.4749)
				(mid 193.947841 -294.425718)
				(end 193.958718 -294.377618)
			)
			(xy 193.962528 -294.366188) (xy 193.958464 -294.342312)
			(arc
				(start 193.902584 -294.266874)
				(mid 193.884591 -294.251696)
				(end 193.86169 -294.2463)
			)
			(arc
				(start 192.788286 -294.2463)
				(mid 192.765409 -294.251743)
				(end 192.747392 -294.266874)
			)
			(xy 192.691766 -294.342058) (xy 192.687702 -294.36568)
			(arc
				(start 192.691258 -294.377364)
				(mid 192.702151 -294.425589)
				(end 192.705736 -294.4749)
			)
			(arc
				(start 192.705736 -294.4749)
				(mid 192.608874 -294.708746)
				(end 192.375028 -294.805608)
			)
			(arc
				(start 192.374774 -294.805608)
				(mid 192.236086 -294.775005)
				(end 192.12306 -294.689022)
			)
			(arc
				(start 192.122806 -294.689022)
				(mid 192.096976 -294.672655)
				(end 192.066418 -294.674036)
			)
			(arc
				(start 191.977264 -294.707056)
				(mid 191.953083 -294.725688)
				(end 191.94399 -294.754808)
			)
			(arc
				(start 191.94399 -296.094912)
				(mid 191.953138 -296.123994)
				(end 191.977264 -296.142664)
			)
			(arc
				(start 192.066418 -296.175684)
				(mid 192.096985 -296.177099)
				(end 192.122806 -296.160698)
			)
			(arc
				(start 192.12306 -296.160698)
				(mid 192.236203 -296.074641)
				(end 192.375028 -296.044112)
			)
			(xy 192.384934 -296.044112)
			(arc
				(start 192.384934 -296.044366)
				(mid 192.612276 -296.144578)
				(end 192.705736 -296.37482)
			)
			(arc
				(start 192.70599 -296.37482)
				(mid 192.699127 -296.441871)
				(end 192.678812 -296.506138)
			)
			(arc
				(start 192.678558 -296.506138)
				(mid 192.674641 -296.530803)
				(end 192.682876 -296.554398)
			)
			(arc
				(start 192.729358 -296.625264)
				(mid 192.747685 -296.64204)
				(end 192.771776 -296.648124)
			)
		)
		(stroke
			(width 0)
			(type solid)
		)
		(fill yes)
		(layer "B.Cu")
		(net "P1V25_PEX1")
	)
	(gr_poly
		(pts
			(arc
				(start 234.000294 -147.411948)
				(mid 234.017939 -147.407449)
				(end 234.032806 -147.396962)
			)
			(arc
				(start 234.54106 -146.888708)
				(mid 234.552171 -146.872174)
				(end 234.556046 -146.85264)
			)
			(arc
				(start 234.556046 -145.29689)
				(mid 234.559947 -145.277367)
				(end 234.571032 -145.260822)
			)
			(arc
				(start 234.665774 -145.16608)
				(mid 234.676885 -145.149546)
				(end 234.68076 -145.130012)
			)
			(arc
				(start 234.68076 -145.099024)
				(mid 234.665881 -145.063103)
				(end 234.62996 -145.048224)
			)
			(xy 234.625642 -145.048224)
			(arc
				(start 234.621324 -145.048732)
				(mid 234.589311 -145.052883)
				(end 234.557062 -145.05432)
			)
			(arc
				(start 234.557062 -145.05432)
				(mid 234.175554 -144.672812)
				(end 234.557062 -144.291304)
			)
			(arc
				(start 234.557062 -144.291304)
				(mid 234.726655 -144.331101)
				(end 234.860846 -144.44218)
			)
			(xy 234.867704 -144.45107) (xy 234.886754 -144.461484)
			(arc
				(start 234.974384 -144.467326)
				(mid 234.995675 -144.464246)
				(end 235.013754 -144.452594)
			)
			(xy 235.01731 -144.449038) (xy 235.035852 -144.441418)
			(arc
				(start 235.741972 -144.441418)
				(mid 235.761495 -144.437517)
				(end 235.77804 -144.426432)
			)
			(arc
				(start 235.867448 -144.337024)
				(mid 235.878559 -144.32049)
				(end 235.882434 -144.300956)
			)
			(arc
				(start 235.882434 -143.87195)
				(mid 235.878533 -143.852427)
				(end 235.867448 -143.835882)
			)
			(arc
				(start 235.68025 -143.648684)
				(mid 235.663716 -143.637573)
				(end 235.644182 -143.633698)
			)
			(arc
				(start 234.287314 -143.633698)
				(mid 234.267791 -143.629797)
				(end 234.251246 -143.618712)
			)
			(arc
				(start 233.53014 -143.618712)
				(mid 233.510617 -143.622613)
				(end 233.494072 -143.633698)
			)
			(xy 233.31805 -143.80972) (xy 233.310684 -143.816832) (xy 233.303064 -143.835628)
			(arc
				(start 233.303064 -144.067022)
				(mid 233.306965 -144.086545)
				(end 233.31805 -144.10309)
			)
			(arc
				(start 233.326432 -144.111472)
				(mid 233.337543 -144.128006)
				(end 233.341418 -144.14754)
			)
			(arc
				(start 233.341418 -144.46504)
				(mid 233.337517 -144.484563)
				(end 233.326432 -144.501108)
			)
			(arc
				(start 233.215942 -144.611598)
				(mid 233.199408 -144.622709)
				(end 233.179874 -144.626584)
			)
			(arc
				(start 232.211118 -144.626584)
				(mid 232.191595 -144.630485)
				(end 232.17505 -144.64157)
			)
			(arc
				(start 232.06583 -144.75079)
				(mid 232.054719 -144.767324)
				(end 232.050844 -144.786858)
			)
			(arc
				(start 232.050844 -145.137886)
				(mid 232.049882 -145.147724)
				(end 232.047034 -145.15719)
			)
			(arc
				(start 232.039922 -145.174208)
				(mid 232.037049 -145.183798)
				(end 232.036112 -145.193766)
			)
			(arc
				(start 232.036112 -147.205954)
				(mid 232.040013 -147.225477)
				(end 232.051098 -147.242022)
			)
			(arc
				(start 232.206038 -147.396962)
				(mid 232.222455 -147.408024)
				(end 232.241852 -147.411948)
			)
		)
		(stroke
			(width 0)
			(type solid)
		)
		(fill yes)
		(layer "B.Cu")
		(net "P3V3_CLK_GEN_VDDA100M_CK440_PEX")
	)
	(gr_poly
		(pts
			(xy 332.149196 -213.041992) (xy 332.159164 -213.041518) (xy 332.177605 -213.033948) (xy 332.18501 -213.02726)
			(xy 332.20787 -213.004654) (xy 332.215216 -212.997848) (xy 332.23368 -212.990133) (xy 332.243684 -212.989668)
			(xy 333.343504 -212.989668) (xy 333.353471 -212.989192) (xy 333.371908 -212.981617) (xy 333.379318 -212.974936)
			(xy 333.465932 -212.888322) (xy 333.472773 -212.880922) (xy 333.48049 -212.862323) (xy 333.480918 -212.852254)
			(xy 333.480918 -212.66277) (xy 333.476854 -212.653118) (xy 333.457488 -212.636729) (xy 333.423328 -212.599222)
			(xy 333.395062 -212.557095) (xy 333.373306 -212.511265) (xy 333.358534 -212.462732) (xy 333.351068 -212.412553)
			(xy 333.351069 -212.361822) (xy 333.35854 -212.311643) (xy 333.373316 -212.263111) (xy 333.395075 -212.217283)
			(xy 333.423344 -212.175158) (xy 333.457506 -212.137653) (xy 333.476854 -212.121242) (xy 333.480918 -212.11159)
			(xy 333.480918 -211.862924) (xy 333.476854 -211.853272) (xy 333.457484 -211.836883) (xy 333.423316 -211.799375)
			(xy 333.395043 -211.757245) (xy 333.37328 -211.711412) (xy 333.358501 -211.662875) (xy 333.351028 -211.61269)
			(xy 333.351025 -211.561953) (xy 333.358491 -211.511767) (xy 333.373264 -211.463228) (xy 333.395022 -211.417392)
			(xy 333.42329 -211.375259) (xy 333.457453 -211.337746) (xy 333.476854 -211.321396) (xy 333.480918 -211.311744)
			(xy 333.480918 -211.062824) (xy 333.476854 -211.053172) (xy 333.457484 -211.036783) (xy 333.423316 -210.999275)
			(xy 333.395043 -210.957145) (xy 333.37328 -210.911312) (xy 333.358501 -210.862775) (xy 333.351028 -210.81259)
			(xy 333.351025 -210.761853) (xy 333.358491 -210.711667) (xy 333.373264 -210.663128) (xy 333.395022 -210.617292)
			(xy 333.42329 -210.575159) (xy 333.457453 -210.537646) (xy 333.476854 -210.521296) (xy 333.480918 -210.511644)
			(xy 333.480918 -210.203034) (xy 333.480483 -210.192969) (xy 333.472754 -210.17438) (xy 333.465932 -210.166966)
			(xy 333.22006 -209.921094) (xy 333.212948 -209.913728) (xy 333.194152 -209.906108) (xy 331.781912 -209.906108)
			(xy 331.771841 -209.906529) (xy 331.753234 -209.914241) (xy 331.745844 -209.921094) (xy 331.624686 -210.042252)
			(xy 331.61732 -210.049364) (xy 331.6097 -210.06816) (xy 331.6097 -212.363304) (xy 332.06766 -212.363304)
			(xy 332.071731 -212.307682) (xy 332.083857 -212.253245) (xy 332.10378 -212.201154) (xy 332.131076 -212.152519)
			(xy 332.165162 -212.108376) (xy 332.205311 -212.069667) (xy 332.250669 -212.037216) (xy 332.300269 -212.011715)
			(xy 332.353053 -211.993708) (xy 332.407896 -211.983578) (xy 332.46363 -211.981541) (xy 332.519067 -211.987641)
			(xy 332.573024 -212.001747) (xy 332.624353 -212.023559) (xy 332.671959 -212.052613) (xy 332.714827 -212.088288)
			(xy 332.752044 -212.129825) (xy 332.782817 -212.176338) (xy 332.806489 -212.226835) (xy 332.822557 -212.280242)
			(xy 332.830677 -212.335418) (xy 332.831186 -212.363304) (xy 332.830677 -212.39119) (xy 332.822557 -212.446366)
			(xy 332.806489 -212.499773) (xy 332.782817 -212.55027) (xy 332.752044 -212.596783) (xy 332.714827 -212.63832)
			(xy 332.671959 -212.673995) (xy 332.624353 -212.703049) (xy 332.573024 -212.724861) (xy 332.519067 -212.738967)
			(xy 332.46363 -212.745067) (xy 332.407896 -212.74303) (xy 332.353053 -212.7329) (xy 332.300269 -212.714893)
			(xy 332.250669 -212.689392) (xy 332.205311 -212.656941) (xy 332.165162 -212.618232) (xy 332.131076 -212.574089)
			(xy 332.10378 -212.525454) (xy 332.083857 -212.473363) (xy 332.071731 -212.418926) (xy 332.06766 -212.363304)
			(xy 331.6097 -212.363304) (xy 331.6097 -212.914484) (xy 331.610139 -212.924547) (xy 331.617874 -212.94313)
			(xy 331.624686 -212.950552) (xy 331.70114 -213.027006) (xy 331.708541 -213.033845) (xy 331.727139 -213.041564)
			(xy 331.737208 -213.041992)
		)
		(stroke
			(width 0)
			(type solid)
		)
		(fill yes)
		(layer "B.Cu")
		(net "P3V3_FPGA_VCCIO2")
	)
	(gr_poly
		(pts
			(xy 246.818404 -156.313124) (xy 246.828474 -156.312701) (xy 246.84708 -156.304988) (xy 246.854472 -156.298138)
			(xy 246.958866 -156.193744) (xy 246.965707 -156.186344) (xy 246.973427 -156.167746) (xy 246.973852 -156.157676)
			(xy 246.973852 -145.596864) (xy 246.974283 -145.586798) (xy 246.982013 -145.568208) (xy 246.988838 -145.560796)
			(xy 247.847612 -144.702022) (xy 247.85501 -144.695175) (xy 247.873608 -144.687442) (xy 247.88368 -144.687036)
			(xy 249.441716 -144.687036) (xy 249.451784 -144.687463) (xy 249.470381 -144.695185) (xy 249.477784 -144.702022)
			(xy 249.671586 -144.895824) (xy 250.166886 -145.391378) (xy 250.173722 -145.39878) (xy 250.18143 -145.417378)
			(xy 250.181872 -145.427446) (xy 250.181872 -146.4945) (xy 250.182294 -146.504571) (xy 250.190006 -146.523178)
			(xy 250.196858 -146.530568) (xy 250.346464 -146.680174) (xy 250.353865 -146.687013) (xy 250.372463 -146.694728)
			(xy 250.382532 -146.69516) (xy 251.491496 -146.69516) (xy 251.501566 -146.694736) (xy 251.520167 -146.687019)
			(xy 251.527564 -146.680174) (xy 251.652024 -146.555714) (xy 251.658865 -146.548315) (xy 251.66658 -146.529715)
			(xy 251.66701 -146.519646) (xy 251.66701 -144.98828) (xy 251.666584 -144.978211) (xy 251.658865 -144.959611)
			(xy 251.652024 -144.952212) (xy 251.123196 -144.423384) (xy 251.116353 -144.415984) (xy 251.108625 -144.397386)
			(xy 251.10821 -144.387316) (xy 251.10821 -141.441424) (xy 251.115576 -141.434058) (xy 251.115576 -140.074396)
			(xy 251.115999 -140.064326) (xy 251.123712 -140.04572) (xy 251.130562 -140.038328) (xy 251.5489 -139.61999)
			(xy 251.556294 -139.613134) (xy 251.574893 -139.605385) (xy 251.584968 -139.605004) (xy 252.387862 -139.605004)
			(xy 252.397927 -139.604569) (xy 252.416516 -139.59684) (xy 252.42393 -139.590018) (xy 252.64872 -139.365228)
			(xy 252.655564 -139.357829) (xy 252.663285 -139.33923) (xy 252.663706 -139.32916) (xy 252.663706 -136.35228)
			(xy 252.66328 -136.342211) (xy 252.655561 -136.323611) (xy 252.64872 -136.316212) (xy 252.4887 -136.156192)
			(xy 252.481301 -136.149346) (xy 252.462703 -136.141613) (xy 252.452632 -136.141206) (xy 243.248688 -136.141206)
			(xy 243.238619 -136.141632) (xy 243.220018 -136.14935) (xy 243.21262 -136.156192) (xy 243.074698 -136.294114)
			(xy 243.067854 -136.301514) (xy 243.060125 -136.320111) (xy 243.059712 -136.330182) (xy 243.059712 -138.89482)
			(xy 244.47703 -138.89482) (xy 244.481101 -138.839198) (xy 244.493227 -138.784761) (xy 244.51315 -138.73267)
			(xy 244.540446 -138.684035) (xy 244.574532 -138.639892) (xy 244.614681 -138.601183) (xy 244.660039 -138.568732)
			(xy 244.709639 -138.543231) (xy 244.762423 -138.525224) (xy 244.817266 -138.515094) (xy 244.873 -138.513057)
			(xy 244.928437 -138.519157) (xy 244.982394 -138.533263) (xy 245.033723 -138.555075) (xy 245.081329 -138.584129)
			(xy 245.124197 -138.619804) (xy 245.161414 -138.661341) (xy 245.192187 -138.707854) (xy 245.215859 -138.758351)
			(xy 245.231927 -138.811758) (xy 245.240047 -138.866934) (xy 245.240556 -138.89482) (xy 245.240047 -138.922706)
			(xy 245.231927 -138.977882) (xy 245.215859 -139.031289) (xy 245.192187 -139.081786) (xy 245.161414 -139.128299)
			(xy 245.124197 -139.169836) (xy 245.081329 -139.205511) (xy 245.033723 -139.234565) (xy 244.982394 -139.256377)
			(xy 244.928437 -139.270483) (xy 244.873 -139.276583) (xy 244.817266 -139.274546) (xy 244.762423 -139.264416)
			(xy 244.709639 -139.246409) (xy 244.660039 -139.220908) (xy 244.614681 -139.188457) (xy 244.574532 -139.149748)
			(xy 244.540446 -139.105605) (xy 244.51315 -139.05697) (xy 244.493227 -139.004879) (xy 244.481101 -138.950442)
			(xy 244.47703 -138.89482) (xy 243.059712 -138.89482) (xy 243.059712 -140.814806) (xy 243.05514 -140.819378)
			(xy 243.05514 -156.288232) (xy 243.06276 -156.306774) (xy 243.06911 -156.313124)
		)
		(stroke
			(width 0)
			(type solid)
		)
		(fill yes)
		(layer "B.Cu")
		(net "P12V_NIC4_R")
	)
	(gr_poly
		(pts
			(arc
				(start 228.526848 -215.991186)
				(mid 228.595727 -215.968573)
				(end 228.667818 -215.96096)
			)
			(arc
				(start 228.667818 -215.96096)
				(mid 228.739901 -215.96861)
				(end 228.808788 -215.991186)
			)
			(xy 228.818948 -215.995758) (xy 230.11638 -215.995758)
			(arc
				(start 230.12654 -215.991186)
				(mid 230.195419 -215.968573)
				(end 230.26751 -215.96096)
			)
			(arc
				(start 230.26751 -215.96096)
				(mid 230.339593 -215.96861)
				(end 230.40848 -215.991186)
			)
			(xy 230.41864 -215.995758)
			(arc
				(start 230.720646 -215.995758)
				(mid 230.739837 -215.991993)
				(end 230.756206 -215.98128)
			)
			(xy 230.75646 -215.981026) (xy 230.869744 -215.867742)
			(arc
				(start 230.870252 -215.867234)
				(mid 230.880994 -215.850877)
				(end 230.88473 -215.831674)
			)
			(xy 230.88473 -215.809576) (xy 230.873808 -215.78824)
			(arc
				(start 230.863902 -215.780874)
				(mid 230.760954 -215.659258)
				(end 230.723948 -215.504268)
			)
			(arc
				(start 230.723948 -215.504268)
				(mid 230.761705 -215.347722)
				(end 230.866696 -215.22563)
			)
			(arc
				(start 230.866696 -215.22563)
				(mid 230.875873 -215.21723)
				(end 230.882698 -215.206834)
			)
			(xy 230.88473 -215.202516) (xy 230.88473 -215.150954) (xy 230.884476 -215.143588)
			(arc
				(start 230.884476 -215.017858)
				(mid 230.883253 -215.006258)
				(end 230.879396 -214.995252)
			)
			(arc
				(start 230.876856 -214.990172)
				(mid 230.834049 -214.956513)
				(end 230.7971 -214.916512)
			)
			(arc
				(start 230.7971 -214.916512)
				(mid 230.779417 -214.902118)
				(end 230.757222 -214.896954)
			)
			(arc
				(start 230.577644 -214.896954)
				(mid 230.555475 -214.90217)
				(end 230.537766 -214.916512)
			)
			(arc
				(start 230.537766 -214.916512)
				(mid 230.26751 -215.047866)
				(end 229.997254 -214.916512)
			)
			(arc
				(start 229.997254 -214.916512)
				(mid 229.979571 -214.902118)
				(end 229.957376 -214.896954)
			)
			(arc
				(start 228.977952 -214.896954)
				(mid 228.955783 -214.90217)
				(end 228.938074 -214.916512)
			)
			(arc
				(start 228.938074 -214.916512)
				(mid 228.667818 -215.047866)
				(end 228.397562 -214.916512)
			)
			(arc
				(start 228.397562 -214.916512)
				(mid 228.379879 -214.902118)
				(end 228.357684 -214.896954)
			)
			(arc
				(start 228.18598 -214.896954)
				(mid 228.163511 -214.902193)
				(end 228.145594 -214.916766)
			)
			(arc
				(start 228.145594 -214.916766)
				(mid 228.079272 -214.9829)
				(end 227.997766 -215.029034)
			)
			(xy 227.98786 -215.033098) (xy 227.557076 -215.463882) (xy 227.54971 -215.470994) (xy 227.54209 -215.48979)
			(arc
				(start 227.54209 -215.822276)
				(mid 227.545855 -215.841467)
				(end 227.556568 -215.857836)
			)
			(xy 227.556822 -215.85809) (xy 227.687632 -215.9889) (xy 227.718366 -215.994996)
			(arc
				(start 227.73259 -215.988646)
				(mid 227.798873 -215.967915)
				(end 227.867972 -215.96096)
			)
			(arc
				(start 227.867972 -215.96096)
				(mid 227.940055 -215.96861)
				(end 228.008942 -215.991186)
			)
			(xy 228.019102 -215.995758) (xy 228.516688 -215.995758)
		)
		(stroke
			(width 0)
			(type solid)
		)
		(fill yes)
		(layer "B.Cu")
		(net "P3V3_AUX")
	)
	(gr_poly
		(pts
			(xy 130.718306 -156.313124) (xy 130.728376 -156.3127) (xy 130.746981 -156.304987) (xy 130.754374 -156.298138)
			(xy 130.858768 -156.193744) (xy 130.865609 -156.186344) (xy 130.873328 -156.167745) (xy 130.873754 -156.157676)
			(xy 130.873754 -145.596864) (xy 130.874185 -145.586798) (xy 130.881915 -145.568208) (xy 130.88874 -145.560796)
			(xy 131.747514 -144.702022) (xy 131.754912 -144.695175) (xy 131.77351 -144.687443) (xy 131.783582 -144.687036)
			(xy 133.341618 -144.687036) (xy 133.351686 -144.687463) (xy 133.370282 -144.695186) (xy 133.377686 -144.702022)
			(xy 133.571488 -144.895824) (xy 134.066788 -145.391378) (xy 134.073623 -145.39878) (xy 134.081331 -145.417379)
			(xy 134.081774 -145.427446) (xy 134.081774 -146.595592) (xy 134.082195 -146.605663) (xy 134.089904 -146.624272)
			(xy 134.09676 -146.63166) (xy 134.177786 -146.712686) (xy 134.185189 -146.71952) (xy 134.203787 -146.727226)
			(xy 134.213854 -146.727672) (xy 135.358886 -146.727672) (xy 135.368949 -146.727233) (xy 135.387528 -146.719493)
			(xy 135.394954 -146.712686) (xy 135.551926 -146.555714) (xy 135.558767 -146.548314) (xy 135.566482 -146.529715)
			(xy 135.566912 -146.519646) (xy 135.566912 -144.98828) (xy 135.566486 -144.978211) (xy 135.558768 -144.959611)
			(xy 135.551926 -144.952212) (xy 135.023098 -144.423384) (xy 135.016255 -144.415984) (xy 135.008526 -144.397387)
			(xy 135.008112 -144.387316) (xy 135.008112 -141.441424) (xy 135.015478 -141.434058) (xy 135.015478 -140.074396)
			(xy 135.015901 -140.064326) (xy 135.023614 -140.04572) (xy 135.030464 -140.038328) (xy 135.448802 -139.61999)
			(xy 135.456196 -139.613134) (xy 135.474795 -139.605386) (xy 135.48487 -139.605004) (xy 136.287764 -139.605004)
			(xy 136.297829 -139.604569) (xy 136.316417 -139.596839) (xy 136.323832 -139.590018) (xy 136.548622 -139.365228)
			(xy 136.555465 -139.357829) (xy 136.563186 -139.33923) (xy 136.563608 -139.32916) (xy 136.563608 -136.35228)
			(xy 136.563182 -136.342211) (xy 136.555463 -136.323611) (xy 136.548622 -136.316212) (xy 136.388602 -136.156192)
			(xy 136.381203 -136.149346) (xy 136.362605 -136.141612) (xy 136.352534 -136.141206) (xy 127.393192 -136.141206)
			(xy 127.383123 -136.141631) (xy 127.364521 -136.149348) (xy 127.357124 -136.156192) (xy 126.9746 -136.538716)
			(xy 126.967756 -136.546116) (xy 126.960028 -136.564713) (xy 126.959614 -136.574784) (xy 126.959614 -138.924788)
			(xy 128.301732 -138.924788) (xy 128.301732 -138.864852) (xy 128.309555 -138.80543) (xy 128.325068 -138.747537)
			(xy 128.348004 -138.692164) (xy 128.377971 -138.640258) (xy 128.414458 -138.592708) (xy 128.456838 -138.550328)
			(xy 128.504388 -138.513841) (xy 128.556294 -138.483874) (xy 128.611667 -138.460938) (xy 128.66956 -138.445425)
			(xy 128.728982 -138.437602) (xy 128.788918 -138.437602) (xy 128.84834 -138.445425) (xy 128.906233 -138.460938)
			(xy 128.961606 -138.483874) (xy 129.013512 -138.513841) (xy 129.061062 -138.550328) (xy 129.103442 -138.592708)
			(xy 129.139929 -138.640258) (xy 129.169896 -138.692164) (xy 129.192832 -138.747537) (xy 129.208345 -138.80543)
			(xy 129.216168 -138.864852) (xy 129.216658 -138.89482) (xy 129.216168 -138.924788) (xy 129.208345 -138.98421)
			(xy 129.192832 -139.042103) (xy 129.169896 -139.097476) (xy 129.139929 -139.149382) (xy 129.103442 -139.196932)
			(xy 129.061062 -139.239312) (xy 129.013512 -139.275799) (xy 128.961606 -139.305766) (xy 128.906233 -139.328702)
			(xy 128.84834 -139.344215) (xy 128.788918 -139.352038) (xy 128.728982 -139.352038) (xy 128.66956 -139.344215)
			(xy 128.611667 -139.328702) (xy 128.556294 -139.305766) (xy 128.504388 -139.275799) (xy 128.456838 -139.239312)
			(xy 128.414458 -139.196932) (xy 128.377971 -139.149382) (xy 128.348004 -139.097476) (xy 128.325068 -139.042103)
			(xy 128.309555 -138.98421) (xy 128.301732 -138.924788) (xy 126.959614 -138.924788) (xy 126.959614 -140.814806)
			(xy 126.955042 -140.819378) (xy 126.955042 -156.288232) (xy 126.962662 -156.306774) (xy 126.969012 -156.313124)
		)
		(stroke
			(width 0)
			(type solid)
		)
		(fill yes)
		(layer "B.Cu")
		(net "P12V_NIC2_R")
	)
	(gr_poly
		(pts
			(xy 42.390314 -13.820648) (xy 42.390314 -13.401548) (xy 42.34688 -13.358114)
			(arc
				(start 34.964878 -13.358114)
				(mid 33.898562 -12.916432)
				(end 33.45688 -11.850116)
			)
			(arc
				(start 33.45688 -1.999996)
				(mid 33.019884 -0.944996)
				(end 31.964884 -0.508)
			)
			(arc
				(start 19.964908 -0.508)
				(mid 18.909908 -0.944996)
				(end 18.472912 -1.999996)
			)
			(xy 18.472912 -11.631422) (xy 18.980404 -11.631422)
			(arc
				(start 18.980404 -1.999996)
				(mid 19.268759 -1.303847)
				(end 19.964908 -1.015492)
			)
			(arc
				(start 31.964884 -1.015492)
				(mid 32.661033 -1.303847)
				(end 32.949388 -1.999996)
			)
			(arc
				(start 32.949388 -11.850116)
				(mid 33.539801 -13.275118)
				(end 34.964878 -13.865352)
			)
			(xy 42.34561 -13.865352)
		)
		(stroke
			(width 0)
			(type solid)
		)
		(fill yes)
		(layer "B.Cu")
		(net "GND")
	)
	(gr_poly
		(pts
			(xy 68.431156 -13.728954) (xy 68.431156 -13.494512) (xy 68.294758 -13.358114)
			(arc
				(start 60.96508 -13.358114)
				(mid 59.898764 -12.916432)
				(end 59.457082 -11.850116)
			)
			(arc
				(start 59.457082 -1.999996)
				(mid 59.020086 -0.944996)
				(end 57.965086 -0.508)
			)
			(arc
				(start 45.96511 -0.508)
				(mid 44.91011 -0.944996)
				(end 44.473114 -1.999996)
			)
			(xy 44.473114 -11.726418) (xy 44.980352 -11.726418)
			(arc
				(start 44.980352 -1.999996)
				(mid 45.268617 -1.303936)
				(end 45.964602 -1.015492)
			)
			(arc
				(start 57.965086 -1.015492)
				(mid 58.661325 -1.303831)
				(end 58.949844 -1.999996)
			)
			(arc
				(start 58.949844 -11.850116)
				(mid 59.540093 -13.275103)
				(end 60.96508 -13.865352)
			)
			(xy 68.294758 -13.865352)
		)
		(stroke
			(width 0)
			(type solid)
		)
		(fill yes)
		(layer "B.Cu")
		(net "GND")
	)
	(gr_poly
		(pts
			(xy 71.493888 -288.4424) (xy 71.503959 -288.441979) (xy 71.522567 -288.434268) (xy 71.529956 -288.427414)
			(xy 71.848472 -288.108898) (xy 71.859394 -288.100516) (xy 71.863458 -288.096706) (xy 71.884471 -288.076467)
			(xy 71.931638 -288.042135) (xy 71.983594 -288.015603) (xy 72.03906 -287.997524) (xy 72.096671 -287.988344)
			(xy 72.12584 -287.98774) (xy 72.953118 -287.98774) (xy 72.963126 -287.987249) (xy 72.981619 -287.979588)
			(xy 72.995776 -287.965437) (xy 73.003445 -287.946948) (xy 73.003918 -287.93694) (xy 73.003918 -286.257238)
			(xy 73.003505 -286.24721) (xy 72.995843 -286.228677) (xy 72.98167 -286.214489) (xy 72.963145 -286.206806)
			(xy 72.953118 -286.206438) (xy 70.99681 -286.206438) (xy 70.98674 -286.20686) (xy 70.968136 -286.214576)
			(xy 70.960742 -286.221424) (xy 70.841108 -286.341058) (xy 70.8406 -286.341058) (xy 70.740016 -286.441642)
			(xy 70.732481 -286.450108) (xy 70.72499 -286.471467) (xy 70.725538 -286.48279) (xy 70.734682 -286.572452)
			(xy 70.74662 -286.59201) (xy 70.756272 -286.59836) (xy 70.77881 -286.613803) (xy 70.818956 -286.650854)
			(xy 70.852462 -286.694003) (xy 70.878417 -286.742074) (xy 70.896113 -286.793759) (xy 70.90507 -286.84765)
			(xy 70.905624 -286.874966) (xy 70.905114 -286.900953) (xy 70.896984 -286.952288) (xy 70.880923 -287.001718)
			(xy 70.857327 -287.048028) (xy 70.826777 -287.090076) (xy 70.790026 -287.126827) (xy 70.747978 -287.157377)
			(xy 70.701668 -287.180973) (xy 70.652238 -287.197034) (xy 70.600903 -287.205164) (xy 70.548929 -287.205164)
			(xy 70.497594 -287.197034) (xy 70.448164 -287.180973) (xy 70.401854 -287.157377) (xy 70.359806 -287.126827)
			(xy 70.323055 -287.090076) (xy 70.292505 -287.048028) (xy 70.268909 -287.001718) (xy 70.252848 -286.952288)
			(xy 70.244718 -286.900953) (xy 70.244208 -286.874966) (xy 70.244605 -286.85198) (xy 70.250978 -286.806452)
			(xy 70.263595 -286.762245) (xy 70.282214 -286.720212) (xy 70.293992 -286.700468) (xy 70.294246 -286.700214)
			(xy 70.298603 -286.692345) (xy 70.302073 -286.674707) (xy 70.299293 -286.656948) (xy 70.295262 -286.648906)
			(xy 70.252082 -286.571182) (xy 70.246262 -286.561808) (xy 70.22848 -286.548782) (xy 70.217792 -286.546036)
			(xy 70.207632 -286.54502) (xy 69.101462 -286.54502) (xy 69.091395 -286.545451) (xy 69.072803 -286.553177)
			(xy 69.065394 -286.560006) (xy 69.042534 -286.582866) (xy 69.035694 -286.590266) (xy 69.027979 -286.608865)
			(xy 69.027548 -286.618934) (xy 69.027548 -287.849915) (xy 70.257398 -287.849915) (xy 70.257398 -287.799937)
			(xy 70.265217 -287.750574) (xy 70.280661 -287.703042) (xy 70.303351 -287.65851) (xy 70.332727 -287.618077)
			(xy 70.368067 -287.582737) (xy 70.4085 -287.553361) (xy 70.453032 -287.530671) (xy 70.500564 -287.515227)
			(xy 70.549927 -287.507408) (xy 70.599905 -287.507408) (xy 70.649268 -287.515227) (xy 70.6968 -287.530671)
			(xy 70.741332 -287.553361) (xy 70.781765 -287.582737) (xy 70.817105 -287.618077) (xy 70.846481 -287.65851)
			(xy 70.869171 -287.703042) (xy 70.884615 -287.750574) (xy 70.892434 -287.799937) (xy 70.892924 -287.824926)
			(xy 70.892434 -287.849915) (xy 70.884615 -287.899278) (xy 70.869171 -287.94681) (xy 70.846481 -287.991342)
			(xy 70.817105 -288.031775) (xy 70.781765 -288.067115) (xy 70.741332 -288.096491) (xy 70.6968 -288.119181)
			(xy 70.649268 -288.134625) (xy 70.599905 -288.142444) (xy 70.549927 -288.142444) (xy 70.500564 -288.134625)
			(xy 70.453032 -288.119181) (xy 70.4085 -288.096491) (xy 70.368067 -288.067115) (xy 70.332727 -288.031775)
			(xy 70.303351 -287.991342) (xy 70.280661 -287.94681) (xy 70.265217 -287.899278) (xy 70.257398 -287.849915)
			(xy 69.027548 -287.849915) (xy 69.027548 -288.32937) (xy 69.027985 -288.339433) (xy 69.035723 -288.358015)
			(xy 69.042534 -288.365438) (xy 69.104764 -288.427668) (xy 69.112185 -288.434455) (xy 69.130782 -288.442067)
			(xy 69.140832 -288.4424)
		)
		(stroke
			(width 0)
			(type solid)
		)
		(fill yes)
		(layer "B.Cu")
		(net "P1V8_VDDA_PEX0")
	)
	(gr_poly
		(pts
			(xy 94.285816 -13.833856) (xy 94.285816 -13.444728) (xy 94.199202 -13.358114)
			(arc
				(start 86.965028 -13.358114)
				(mid 85.898712 -12.916432)
				(end 85.45703 -11.850116)
			)
			(arc
				(start 85.45703 -1.999996)
				(mid 85.020034 -0.944996)
				(end 83.965034 -0.508)
			)
			(arc
				(start 71.965058 -0.508)
				(mid 70.910058 -0.944996)
				(end 70.473062 -1.999996)
			)
			(xy 70.473062 -11.716004) (xy 70.9803 -11.716004)
			(arc
				(start 70.9803 -1.999996)
				(mid 71.268565 -1.303936)
				(end 71.96455 -1.015492)
			)
			(arc
				(start 83.965034 -1.015492)
				(mid 84.661273 -1.303831)
				(end 84.949792 -1.999996)
			)
			(arc
				(start 84.949792 -11.850116)
				(mid 85.540041 -13.275103)
				(end 86.965028 -13.865352)
			)
			(xy 94.25432 -13.865352)
		)
		(stroke
			(width 0)
			(type solid)
		)
		(fill yes)
		(layer "B.Cu")
		(net "GND")
	)
	(gr_poly
		(pts
			(xy 132.291582 -13.80998) (xy 132.291582 -13.413486) (xy 132.23621 -13.358114)
			(arc
				(start 125.065028 -13.358114)
				(mid 123.998712 -12.916432)
				(end 123.55703 -11.850116)
			)
			(arc
				(start 123.55703 -1.999996)
				(mid 123.120034 -0.944996)
				(end 122.065034 -0.508)
			)
			(arc
				(start 97.965006 -0.508)
				(mid 96.910006 -0.944996)
				(end 96.47301 -1.999996)
			)
			(xy 96.47301 -11.72464) (xy 96.980248 -11.72464)
			(arc
				(start 96.980248 -1.999996)
				(mid 97.268513 -1.303936)
				(end 97.964498 -1.015492)
			)
			(arc
				(start 122.065034 -1.015492)
				(mid 122.761273 -1.303831)
				(end 123.049792 -1.999996)
			)
			(arc
				(start 123.049792 -11.850116)
				(mid 123.640041 -13.275103)
				(end 125.065028 -13.865352)
			)
			(xy 132.23621 -13.865352)
		)
		(stroke
			(width 0)
			(type solid)
		)
		(fill yes)
		(layer "B.Cu")
		(net "GND")
	)
	(gr_poly
		(pts
			(xy 158.365444 -13.805662) (xy 158.365444 -13.417804) (xy 158.305754 -13.358114)
			(arc
				(start 151.064976 -13.358114)
				(mid 149.99866 -12.916432)
				(end 149.556978 -11.850116)
			)
			(arc
				(start 149.556978 -1.999996)
				(mid 149.119982 -0.944996)
				(end 148.064982 -0.508)
			)
			(arc
				(start 136.065006 -0.508)
				(mid 135.010006 -0.944996)
				(end 134.57301 -1.999996)
			)
			(xy 134.57301 -11.817604) (xy 135.080248 -11.817604)
			(arc
				(start 135.080248 -1.999996)
				(mid 135.368513 -1.303936)
				(end 136.064498 -1.015492)
			)
			(arc
				(start 148.064982 -1.015492)
				(mid 148.761221 -1.303831)
				(end 149.04974 -1.999996)
			)
			(arc
				(start 149.04974 -11.850116)
				(mid 149.639989 -13.275103)
				(end 151.064976 -13.865352)
			)
			(xy 158.305754 -13.865352)
		)
		(stroke
			(width 0)
			(type solid)
		)
		(fill yes)
		(layer "B.Cu")
		(net "GND")
	)
	(gr_poly
		(pts
			(xy 184.389268 -13.77569) (xy 184.389268 -13.447776) (xy 184.299606 -13.358114)
			(arc
				(start 177.064924 -13.358114)
				(mid 175.998608 -12.916432)
				(end 175.556926 -11.850116)
			)
			(arc
				(start 175.556926 -1.999996)
				(mid 175.11993 -0.944996)
				(end 174.06493 -0.508)
			)
			(arc
				(start 162.064954 -0.508)
				(mid 161.009954 -0.944996)
				(end 160.572958 -1.999996)
			)
			(xy 160.572958 -11.62304) (xy 161.080196 -11.62304)
			(arc
				(start 161.080196 -1.999996)
				(mid 161.368461 -1.303936)
				(end 162.064446 -1.015492)
			)
			(arc
				(start 174.06493 -1.015492)
				(mid 174.761169 -1.303831)
				(end 175.049688 -1.999996)
			)
			(arc
				(start 175.049688 -11.850116)
				(mid 175.639937 -13.275103)
				(end 177.064924 -13.865352)
			)
			(xy 184.299606 -13.865352)
		)
		(stroke
			(width 0)
			(type solid)
		)
		(fill yes)
		(layer "B.Cu")
		(net "GND")
	)
	(gr_poly
		(pts
			(xy 210.250024 -13.829284) (xy 210.250024 -13.394182) (xy 210.213956 -13.358114)
			(arc
				(start 203.064872 -13.358114)
				(mid 201.998721 -12.916342)
				(end 201.556874 -11.850116)
			)
			(arc
				(start 201.556874 -1.999996)
				(mid 201.119878 -0.944996)
				(end 200.064878 -0.508)
			)
			(arc
				(start 188.064902 -0.508)
				(mid 187.009902 -0.944996)
				(end 186.572906 -1.999996)
			)
			(xy 186.572906 -11.750294) (xy 187.080144 -11.750294)
			(arc
				(start 187.080144 -1.999996)
				(mid 187.368409 -1.303936)
				(end 188.064394 -1.015492)
			)
			(arc
				(start 200.064878 -1.015492)
				(mid 200.761117 -1.303831)
				(end 201.049636 -1.999996)
			)
			(arc
				(start 201.049636 -11.850116)
				(mid 201.63987 -13.275193)
				(end 203.064872 -13.865352)
			)
			(xy 210.213956 -13.865352)
		)
		(stroke
			(width 0)
			(type solid)
		)
		(fill yes)
		(layer "B.Cu")
		(net "GND")
	)
	(gr_poly
		(pts
			(xy 300.515782 -13.7541) (xy 300.515782 -13.469366) (xy 300.40453 -13.358114)
			(arc
				(start 293.165022 -13.358114)
				(mid 292.098706 -12.916432)
				(end 291.657024 -11.850116)
			)
			(arc
				(start 291.657024 -1.999996)
				(mid 291.220028 -0.944996)
				(end 290.165028 -0.508)
			)
			(arc
				(start 278.165052 -0.508)
				(mid 277.110052 -0.944996)
				(end 276.673056 -1.999996)
			)
			(xy 276.673056 -11.825732) (xy 277.180548 -11.825732)
			(arc
				(start 277.180548 -1.999996)
				(mid 277.468903 -1.303847)
				(end 278.165052 -1.015492)
			)
			(arc
				(start 290.165028 -1.015492)
				(mid 290.861177 -1.303847)
				(end 291.149532 -1.999996)
			)
			(arc
				(start 291.149532 -11.850116)
				(mid 291.739945 -13.275118)
				(end 293.165022 -13.865352)
			)
			(xy 300.40453 -13.865352)
		)
		(stroke
			(width 0)
			(type solid)
		)
		(fill yes)
		(layer "B.Cu")
		(net "GND")
	)
	(gr_poly
		(pts
			(xy 442.67882 -13.82903) (xy 442.67882 -13.394436) (xy 442.642498 -13.358114)
			(arc
				(start 435.265068 -13.358114)
				(mid 434.198752 -12.916432)
				(end 433.75707 -11.850116)
			)
			(arc
				(start 433.75707 -1.999996)
				(mid 433.320074 -0.944996)
				(end 432.265074 -0.508)
			)
			(arc
				(start 420.265098 -0.508)
				(mid 419.210098 -0.944996)
				(end 418.773102 -1.999996)
			)
			(xy 418.773102 -11.73734) (xy 419.28034 -11.73734)
			(arc
				(start 419.28034 -1.999996)
				(mid 419.568605 -1.303936)
				(end 420.26459 -1.015492)
			)
			(arc
				(start 432.265074 -1.015492)
				(mid 432.961313 -1.303831)
				(end 433.249832 -1.999996)
			)
			(arc
				(start 433.249832 -11.850116)
				(mid 433.840081 -13.275103)
				(end 435.265068 -13.865352)
			)
			(xy 442.642498 -13.865352)
		)
		(stroke
			(width 0)
			(type solid)
		)
		(fill yes)
		(layer "B.Cu")
		(net "GND")
	)
	(gr_poly
		(pts
			(xy 248.61139 -13.829538) (xy 248.61139 -13.393928) (xy 248.575576 -13.358114)
			(arc
				(start 241.164872 -13.358114)
				(mid 240.098721 -12.916342)
				(end 239.656874 -11.850116)
			)
			(arc
				(start 239.656874 -1.999996)
				(mid 239.219878 -0.944996)
				(end 238.164878 -0.508)
			)
			(arc
				(start 214.065104 -0.508)
				(mid 213.010104 -0.944996)
				(end 212.573108 -1.999996)
			)
			(xy 212.573108 -11.851132) (xy 212.571584 -11.91895) (xy 213.07933 -11.91895) (xy 213.0806 -11.850116)
			(arc
				(start 213.0806 -1.999996)
				(mid 213.368955 -1.303847)
				(end 214.065104 -1.015492)
			)
			(arc
				(start 238.164878 -1.015492)
				(mid 238.861117 -1.303831)
				(end 239.149636 -1.999996)
			)
			(arc
				(start 239.149636 -11.850116)
				(mid 239.73987 -13.275193)
				(end 241.164872 -13.865352)
			)
			(xy 248.575576 -13.865352)
		)
		(stroke
			(width 0)
			(type solid)
		)
		(fill yes)
		(layer "B.Cu")
		(net "GND")
	)
	(gr_poly
		(pts
			(xy 274.599654 -13.810742) (xy 274.599654 -13.412724) (xy 274.545044 -13.358114)
			(arc
				(start 267.165074 -13.358114)
				(mid 266.098758 -12.916432)
				(end 265.657076 -11.850116)
			)
			(arc
				(start 265.657076 -1.999996)
				(mid 265.22008 -0.944996)
				(end 264.16508 -0.508)
			)
			(arc
				(start 252.165104 -0.508)
				(mid 251.110104 -0.944996)
				(end 250.673108 -1.999996)
			)
			(xy 250.673108 -11.850116) (xy 250.673108 -11.851386) (xy 251.1806 -11.851386) (xy 251.1806 -11.850116)
			(arc
				(start 251.1806 -1.999996)
				(mid 251.468955 -1.303847)
				(end 252.165104 -1.015492)
			)
			(arc
				(start 264.16508 -1.015492)
				(mid 264.861229 -1.303847)
				(end 265.149584 -1.999996)
			)
			(arc
				(start 265.149584 -11.850116)
				(mid 265.739997 -13.275118)
				(end 267.165074 -13.865352)
			)
			(xy 274.545044 -13.865352)
		)
		(stroke
			(width 0)
			(type solid)
		)
		(fill yes)
		(layer "B.Cu")
		(net "GND")
	)
	(gr_poly
		(pts
			(xy 105.962958 -395.522958) (xy 105.973023 -395.522523) (xy 105.991608 -395.514789) (xy 105.999026 -395.507972)
			(xy 106.654854 -394.852144) (xy 106.654854 -393.293092) (xy 106.865928 -393.082018) (xy 106.865928 -392.786108)
			(xy 106.865532 -392.776845) (xy 106.858922 -392.759539) (xy 106.846544 -392.745757) (xy 106.838496 -392.74115)
			(xy 106.812593 -392.727186) (xy 106.764275 -392.693596) (xy 106.720656 -392.654094) (xy 106.682456 -392.609331)
			(xy 106.650304 -392.560044) (xy 106.62473 -392.507045) (xy 106.606155 -392.451206) (xy 106.594885 -392.393449)
			(xy 106.591106 -392.334723) (xy 106.594879 -392.275997) (xy 106.606144 -392.218238) (xy 106.624713 -392.162398)
			(xy 106.650282 -392.109396) (xy 106.682428 -392.060106) (xy 106.720624 -392.015339) (xy 106.764238 -391.975833)
			(xy 106.812554 -391.942238) (xy 106.838496 -391.92835) (xy 106.846515 -391.923716) (xy 106.85884 -391.909909)
			(xy 106.865502 -391.892643) (xy 106.865928 -391.883392) (xy 106.865928 -389.376666) (xy 106.865499 -389.366598)
			(xy 106.85778 -389.348) (xy 106.850942 -389.340598) (xy 106.195368 -388.685024) (xy 106.187969 -388.67818)
			(xy 106.169371 -388.670453) (xy 106.1593 -388.670038) (xy 100.805488 -388.670038) (xy 100.79542 -388.670464)
			(xy 100.776822 -388.678186) (xy 100.76942 -388.685024) (xy 99.908614 -389.54583) (xy 99.901771 -389.55323)
			(xy 99.894045 -389.571828) (xy 99.893628 -389.581898) (xy 99.893628 -391.043668) (xy 99.893834 -391.05025)
			(xy 99.89717 -391.062985) (xy 99.900232 -391.068814) (xy 99.914369 -391.094703) (xy 99.936608 -391.149338)
			(xy 99.951644 -391.206378) (xy 99.959226 -391.264876) (xy 99.95923 -391.323864) (xy 99.951655 -391.382364)
			(xy 99.936627 -391.439406) (xy 99.914395 -391.494044) (xy 99.900232 -391.519918) (xy 99.897131 -391.525734)
			(xy 99.893778 -391.538475) (xy 99.893628 -391.545064) (xy 99.893628 -392.339068) (xy 99.893834 -392.34565)
			(xy 99.89717 -392.358385) (xy 99.900232 -392.364214) (xy 99.914369 -392.390103) (xy 99.936608 -392.444738)
			(xy 99.951644 -392.501778) (xy 99.959226 -392.560276) (xy 99.95923 -392.619264) (xy 99.951655 -392.677764)
			(xy 99.936627 -392.734806) (xy 99.914395 -392.789444) (xy 99.900232 -392.815318) (xy 99.897131 -392.821134)
			(xy 99.893778 -392.833875) (xy 99.893628 -392.840464) (xy 99.893628 -393.634468) (xy 99.893834 -393.64105)
			(xy 99.89717 -393.653785) (xy 99.900232 -393.659614) (xy 99.914366 -393.685503) (xy 99.931533 -393.727686)
			(xy 101.126036 -393.727686) (xy 101.126036 -389.597138) (xy 101.126486 -389.587132) (xy 101.134213 -389.56867)
			(xy 101.141022 -389.561324) (xy 101.309678 -389.392668) (xy 101.31709 -389.38599) (xy 101.335526 -389.378413)
			(xy 101.345492 -389.377936) (xy 101.906324 -389.377936) (xy 101.916293 -389.37839) (xy 101.934729 -389.385981)
			(xy 101.942138 -389.392668) (xy 102.45979 -389.91032) (xy 102.467252 -389.917038) (xy 102.485826 -389.924615)
			(xy 102.495858 -389.925052) (xy 104.929178 -389.925052) (xy 104.939185 -389.925489) (xy 104.957648 -389.933225)
			(xy 104.964992 -389.940038) (xy 105.446576 -390.421622) (xy 105.453236 -390.429048) (xy 105.460822 -390.447474)
			(xy 105.461308 -390.457436) (xy 105.461308 -393.86383) (xy 105.460871 -393.873802) (xy 105.45327 -393.892238)
			(xy 105.446576 -393.899644) (xy 105.078276 -394.267944) (xy 105.070847 -394.274601) (xy 105.052424 -394.28219)
			(xy 105.042462 -394.282676) (xy 101.68128 -394.282676) (xy 101.671311 -394.282216) (xy 101.652876 -394.274629)
			(xy 101.645466 -394.267944) (xy 101.141022 -393.7635) (xy 101.134286 -393.756106) (xy 101.126572 -393.737674)
			(xy 101.126036 -393.727686) (xy 99.931533 -393.727686) (xy 99.9366 -393.740138) (xy 99.951632 -393.797177)
			(xy 99.959213 -393.855673) (xy 99.959668 -393.885166) (xy 99.959232 -393.914004) (xy 99.951987 -393.971224)
			(xy 99.937606 -394.027079) (xy 99.916319 -394.080684) (xy 99.902772 -394.106146) (xy 99.89439 -394.121132)
			(xy 99.899216 -394.15466) (xy 101.252528 -395.507972) (xy 101.259927 -395.514817) (xy 101.278525 -395.522546)
			(xy 101.288596 -395.522958)
		)
		(stroke
			(width 0)
			(type solid)
		)
		(fill yes)
		(layer "B.Cu")
		(net "P3V3_BIC_USB_HUB")
	)
	(gr_poly
		(pts
			(xy 68.089018 -301.471838) (xy 68.099085 -301.47141) (xy 68.117679 -301.463684) (xy 68.125086 -301.456852)
			(xy 68.34759 -301.234348) (xy 68.354702 -301.209456) (xy 68.351908 -301.196756) (xy 68.348224 -301.179014)
			(xy 68.344277 -301.142993) (xy 68.344034 -301.124874) (xy 68.344513 -301.099627) (xy 68.352194 -301.049721)
			(xy 68.367373 -301.001562) (xy 68.389698 -300.956271) (xy 68.418648 -300.914901) (xy 68.453552 -300.878413)
			(xy 68.493598 -300.847656) (xy 68.515484 -300.83506) (xy 68.52793 -300.828202) (xy 68.5419 -300.80458)
			(xy 68.5419 -300.495208) (xy 68.52793 -300.471586) (xy 68.515484 -300.464728) (xy 68.494077 -300.452449)
			(xy 68.454834 -300.422527) (xy 68.420476 -300.387104) (xy 68.391767 -300.346965) (xy 68.369343 -300.303005)
			(xy 68.353705 -300.2562) (xy 68.345199 -300.207589) (xy 68.344015 -300.158255) (xy 68.350178 -300.109292)
			(xy 68.363553 -300.06179) (xy 68.383841 -300.016804) (xy 68.396866 -299.995844) (xy 68.396866 -299.404278)
			(xy 68.384357 -299.384141) (xy 68.364607 -299.341048) (xy 68.351213 -299.295575) (xy 68.34445 -299.248656)
			(xy 68.344034 -299.224954) (xy 68.34437 -299.20284) (xy 68.350232 -299.159003) (xy 68.355718 -299.137578)
			(xy 68.359528 -299.12437) (xy 68.352416 -299.097954) (xy 68.321936 -299.067474) (xy 68.314537 -299.06063)
			(xy 68.295938 -299.052907) (xy 68.285868 -299.052488) (xy 67.780662 -299.052488) (xy 67.766043 -299.052048)
			(xy 67.737581 -299.045348) (xy 67.711377 -299.032375) (xy 67.688793 -299.013802) (xy 67.67957 -299.00245)
			(xy 67.672204 -298.993052) (xy 67.651122 -298.982638) (xy 50.173382 -298.982638) (xy 50.163314 -298.983065)
			(xy 50.144718 -298.990788) (xy 50.137314 -298.997624) (xy 50.005234 -299.129704) (xy 49.997868 -299.153326)
			(xy 50.000154 -299.165772) (xy 50.002652 -299.18044) (xy 50.005319 -299.210076) (xy 50.005488 -299.224954)
			(xy 50.00496 -299.252564) (xy 49.995831 -299.307023) (xy 49.977771 -299.359204) (xy 49.951281 -299.407654)
			(xy 49.934622 -299.429678) (xy 49.929628 -299.436506) (xy 49.924052 -299.452468) (xy 49.9237 -299.46092)
			(xy 49.9237 -299.938948) (xy 49.92405 -299.947401) (xy 49.929626 -299.963364) (xy 49.934622 -299.97019)
			(xy 49.951252 -299.992231) (xy 49.97771 -300.040688) (xy 49.995766 -300.092863) (xy 50.004919 -300.147309)
			(xy 50.005488 -300.174914) (xy 50.004963 -300.202525) (xy 49.99584 -300.256987) (xy 49.977785 -300.309173)
			(xy 49.951299 -300.357627) (xy 49.934622 -300.379638) (xy 49.929622 -300.386464) (xy 49.926232 -300.396148)
			(xy 50.188876 -300.396148) (xy 50.188876 -299.94479) (xy 50.189342 -299.934786) (xy 50.197057 -299.916322)
			(xy 50.203862 -299.908976) (xy 50.533554 -299.579284) (xy 50.540976 -299.572618) (xy 50.559404 -299.565033)
			(xy 50.569368 -299.564552) (xy 67.744848 -299.564552) (xy 67.754814 -299.565041) (xy 67.77325 -299.572607)
			(xy 67.780662 -299.579284) (xy 68.171822 -299.970444) (xy 68.17854 -299.977852) (xy 68.186263 -299.996274)
			(xy 68.186808 -300.006258) (xy 68.186808 -300.40453) (xy 68.186357 -300.414536) (xy 68.178632 -300.433)
			(xy 68.171822 -300.440344) (xy 67.975734 -300.636432) (xy 67.968318 -300.643105) (xy 67.949885 -300.650685)
			(xy 67.93992 -300.651164) (xy 50.444146 -300.651164) (xy 50.434181 -300.650673) (xy 50.415745 -300.643108)
			(xy 50.408332 -300.636432) (xy 50.203862 -300.431962) (xy 50.197101 -300.424588) (xy 50.189403 -300.40614)
			(xy 50.188876 -300.396148) (xy 49.926232 -300.396148) (xy 49.924034 -300.402426) (xy 49.9237 -300.41088)
			(xy 49.9237 -300.888908) (xy 49.92406 -300.897357) (xy 49.92965 -300.913308) (xy 49.934622 -300.92015)
			(xy 49.951255 -300.94219) (xy 49.977719 -300.990647) (xy 49.995781 -301.042821) (xy 50.004941 -301.097268)
			(xy 50.005488 -301.124874) (xy 50.004958 -301.152483) (xy 49.995827 -301.206941) (xy 49.977764 -301.25912)
			(xy 49.951272 -301.307568) (xy 49.934622 -301.329598) (xy 49.929288 -301.336456) (xy 49.9237 -301.352204)
			(xy 49.9237 -301.425356) (xy 49.924134 -301.435422) (xy 49.931862 -301.454011) (xy 49.938686 -301.461424)
			(xy 49.94148 -301.464472) (xy 67.92849 -301.464472) (xy 67.935856 -301.471838)
		)
		(stroke
			(width 0)
			(type solid)
		)
		(fill yes)
		(layer "B.Cu")
		(net "P0V8_SERDES_VDDA_PEX0")
	)
	(gr_poly
		(pts
			(xy 300.28896 -301.471838) (xy 300.299024 -301.471402) (xy 300.317607 -301.463666) (xy 300.325028 -301.456852)
			(xy 300.547532 -301.234348) (xy 300.554644 -301.209456) (xy 300.55185 -301.196756) (xy 300.548165 -301.179014)
			(xy 300.544218 -301.142993) (xy 300.543976 -301.124874) (xy 300.544455 -301.099628) (xy 300.552137 -301.049722)
			(xy 300.567317 -301.001566) (xy 300.589643 -300.956277) (xy 300.618596 -300.914909) (xy 300.653502 -300.878425)
			(xy 300.69355 -300.847673) (xy 300.715426 -300.83506) (xy 300.727872 -300.828202) (xy 300.741842 -300.80458)
			(xy 300.741842 -300.495208) (xy 300.727872 -300.471586) (xy 300.715426 -300.464728) (xy 300.694016 -300.452451)
			(xy 300.654769 -300.422531) (xy 300.620407 -300.387109) (xy 300.591693 -300.34697) (xy 300.569267 -300.303009)
			(xy 300.553627 -300.256201) (xy 300.54512 -300.207589) (xy 300.543935 -300.158252) (xy 300.5501 -300.109287)
			(xy 300.563477 -300.061783) (xy 300.583768 -300.016796) (xy 300.596808 -299.995844) (xy 300.596808 -299.404278)
			(xy 300.584298 -299.384142) (xy 300.564545 -299.341049) (xy 300.551149 -299.295576) (xy 300.544385 -299.248656)
			(xy 300.543976 -299.224954) (xy 300.544312 -299.20284) (xy 300.550174 -299.159003) (xy 300.55566 -299.137578)
			(xy 300.55947 -299.12437) (xy 300.552358 -299.097954) (xy 300.521878 -299.067474) (xy 300.514482 -299.060623)
			(xy 300.495883 -299.052885) (xy 300.48581 -299.052488) (xy 299.980604 -299.052488) (xy 299.965983 -299.052053)
			(xy 299.937515 -299.04536) (xy 299.911303 -299.032392) (xy 299.888712 -299.013821) (xy 299.879512 -299.00245)
			(xy 299.872146 -298.993052) (xy 299.851064 -298.982638) (xy 282.373324 -298.982638) (xy 282.363261 -298.983076)
			(xy 282.34468 -298.990814) (xy 282.337256 -298.997624) (xy 282.205176 -299.129704) (xy 282.19781 -299.153326)
			(xy 282.200096 -299.165772) (xy 282.202594 -299.18044) (xy 282.205261 -299.210076) (xy 282.20543 -299.224954)
			(xy 282.204902 -299.252564) (xy 282.195772 -299.307021) (xy 282.177709 -299.359201) (xy 282.151216 -299.407649)
			(xy 282.134564 -299.429678) (xy 282.129567 -299.436505) (xy 282.123986 -299.452467) (xy 282.123642 -299.46092)
			(xy 282.123642 -299.938948) (xy 282.123991 -299.947401) (xy 282.129561 -299.963368) (xy 282.134564 -299.97019)
			(xy 282.151192 -299.992231) (xy 282.177647 -300.04069) (xy 282.1957 -300.092864) (xy 282.204853 -300.147309)
			(xy 282.20543 -300.174914) (xy 282.204905 -300.202525) (xy 282.195781 -300.256986) (xy 282.177723 -300.30917)
			(xy 282.151234 -300.357622) (xy 282.134564 -300.379638) (xy 282.129561 -300.386463) (xy 282.126167 -300.396148)
			(xy 282.388818 -300.396148) (xy 282.388818 -299.94479) (xy 282.3893 -299.934788) (xy 282.397005 -299.916325)
			(xy 282.403804 -299.908976) (xy 282.733496 -299.579284) (xy 282.740903 -299.5726) (xy 282.759343 -299.565026)
			(xy 282.76931 -299.564552) (xy 299.94479 -299.564552) (xy 299.954758 -299.56502) (xy 299.973194 -299.572601)
			(xy 299.980604 -299.579284) (xy 300.371764 -299.970444) (xy 300.378474 -299.977859) (xy 300.386204 -299.996275)
			(xy 300.38675 -300.006258) (xy 300.38675 -300.40453) (xy 300.386287 -300.414534) (xy 300.37857 -300.432997)
			(xy 300.371764 -300.440344) (xy 300.175676 -300.636432) (xy 300.168246 -300.643087) (xy 300.149824 -300.650677)
			(xy 300.139862 -300.651164) (xy 282.644088 -300.651164) (xy 282.634119 -300.650703) (xy 282.615684 -300.643117)
			(xy 282.608274 -300.636432) (xy 282.403804 -300.431962) (xy 282.397049 -300.424583) (xy 282.389346 -300.406139)
			(xy 282.388818 -300.396148) (xy 282.126167 -300.396148) (xy 282.123968 -300.402425) (xy 282.123642 -300.41088)
			(xy 282.123642 -300.888908) (xy 282.12404 -300.897351) (xy 282.129621 -300.913293) (xy 282.134564 -300.92015)
			(xy 282.151195 -300.94219) (xy 282.177656 -300.990648) (xy 282.195716 -301.042822) (xy 282.204875 -301.097268)
			(xy 282.20543 -301.124874) (xy 282.2049 -301.152483) (xy 282.195767 -301.206939) (xy 282.177701 -301.259117)
			(xy 282.151207 -301.307562) (xy 282.134564 -301.329598) (xy 282.12923 -301.336456) (xy 282.123642 -301.352204)
			(xy 282.123642 -301.425356) (xy 282.124077 -301.435421) (xy 282.13181 -301.454006) (xy 282.138628 -301.461424)
			(xy 282.141422 -301.464472) (xy 300.128432 -301.464472) (xy 300.135798 -301.471838)
		)
		(stroke
			(width 0)
			(type solid)
		)
		(fill yes)
		(layer "B.Cu")
		(net "P0V8_SERDES_VDDA_PEX2")
	)
	(gr_poly
		(pts
			(xy 416.389058 -301.471838) (xy 416.399122 -301.471403) (xy 416.417705 -301.463666) (xy 416.425126 -301.456852)
			(xy 416.64763 -301.234348) (xy 416.654742 -301.209456) (xy 416.651948 -301.196756) (xy 416.648263 -301.179014)
			(xy 416.644316 -301.142993) (xy 416.644074 -301.124874) (xy 416.644553 -301.099628) (xy 416.652235 -301.049722)
			(xy 416.667415 -301.001565) (xy 416.689741 -300.956277) (xy 416.718694 -300.914909) (xy 416.7536 -300.878425)
			(xy 416.793647 -300.847672) (xy 416.815524 -300.83506) (xy 416.82797 -300.828202) (xy 416.84194 -300.80458)
			(xy 416.84194 -300.495208) (xy 416.82797 -300.471586) (xy 416.815524 -300.464728) (xy 416.794114 -300.452451)
			(xy 416.754867 -300.422531) (xy 416.720505 -300.387108) (xy 416.691792 -300.34697) (xy 416.669366 -300.303009)
			(xy 416.653726 -300.256201) (xy 416.645219 -300.207589) (xy 416.644034 -300.158252) (xy 416.650199 -300.109287)
			(xy 416.663576 -300.061784) (xy 416.683867 -300.016797) (xy 416.696906 -299.995844) (xy 416.696906 -299.404278)
			(xy 416.684396 -299.384142) (xy 416.664643 -299.341049) (xy 416.651247 -299.295576) (xy 416.644483 -299.248656)
			(xy 416.644074 -299.224954) (xy 416.64441 -299.20284) (xy 416.650272 -299.159003) (xy 416.655758 -299.137578)
			(xy 416.659568 -299.12437) (xy 416.652456 -299.097954) (xy 416.621976 -299.067474) (xy 416.61458 -299.060623)
			(xy 416.595981 -299.052886) (xy 416.585908 -299.052488) (xy 416.080702 -299.052488) (xy 416.066081 -299.052052)
			(xy 416.037613 -299.04536) (xy 416.011402 -299.032391) (xy 415.988811 -299.01382) (xy 415.97961 -299.00245)
			(xy 415.972244 -298.993052) (xy 415.951162 -298.982638) (xy 398.473422 -298.982638) (xy 398.463359 -298.983076)
			(xy 398.444779 -298.990815) (xy 398.437354 -298.997624) (xy 398.305274 -299.129704) (xy 398.297908 -299.153326)
			(xy 398.300194 -299.165772) (xy 398.302692 -299.18044) (xy 398.305359 -299.210076) (xy 398.305528 -299.224954)
			(xy 398.305 -299.252564) (xy 398.29587 -299.307021) (xy 398.277806 -299.359201) (xy 398.251313 -299.407648)
			(xy 398.234662 -299.429678) (xy 398.229664 -299.436505) (xy 398.224084 -299.452467) (xy 398.22374 -299.46092)
			(xy 398.22374 -299.938948) (xy 398.224089 -299.947401) (xy 398.229659 -299.963368) (xy 398.234662 -299.97019)
			(xy 398.25129 -299.992231) (xy 398.277745 -300.04069) (xy 398.295799 -300.092864) (xy 398.304951 -300.147309)
			(xy 398.305528 -300.174914) (xy 398.305003 -300.202525) (xy 398.295879 -300.256986) (xy 398.27782 -300.30917)
			(xy 398.251331 -300.357621) (xy 398.234662 -300.379638) (xy 398.229659 -300.386463) (xy 398.226265 -300.396148)
			(xy 398.488916 -300.396148) (xy 398.488916 -299.94479) (xy 398.489398 -299.934788) (xy 398.497103 -299.916325)
			(xy 398.503902 -299.908976) (xy 398.833594 -299.579284) (xy 398.841002 -299.572601) (xy 398.859441 -299.565026)
			(xy 398.869408 -299.564552) (xy 416.044888 -299.564552) (xy 416.054856 -299.565021) (xy 416.073292 -299.572601)
			(xy 416.080702 -299.579284) (xy 416.471862 -299.970444) (xy 416.478572 -299.977859) (xy 416.486301 -299.996275)
			(xy 416.486848 -300.006258) (xy 416.486848 -300.40453) (xy 416.486386 -300.414534) (xy 416.478668 -300.432998)
			(xy 416.471862 -300.440344) (xy 416.275774 -300.636432) (xy 416.268344 -300.643088) (xy 416.249922 -300.650678)
			(xy 416.23996 -300.651164) (xy 398.744186 -300.651164) (xy 398.734217 -300.650705) (xy 398.715782 -300.643117)
			(xy 398.708372 -300.636432) (xy 398.503902 -300.431962) (xy 398.497146 -300.424584) (xy 398.489444 -300.406139)
			(xy 398.488916 -300.396148) (xy 398.226265 -300.396148) (xy 398.224066 -300.402425) (xy 398.22374 -300.41088)
			(xy 398.22374 -300.888908) (xy 398.224138 -300.897351) (xy 398.229719 -300.913293) (xy 398.234662 -300.92015)
			(xy 398.251293 -300.94219) (xy 398.277754 -300.990648) (xy 398.295814 -301.042822) (xy 398.304973 -301.097268)
			(xy 398.305528 -301.124874) (xy 398.304998 -301.152483) (xy 398.295865 -301.206939) (xy 398.277799 -301.259117)
			(xy 398.251304 -301.307562) (xy 398.234662 -301.329598) (xy 398.229328 -301.336456) (xy 398.22374 -301.352204)
			(xy 398.22374 -301.425356) (xy 398.224175 -301.435421) (xy 398.231908 -301.454007) (xy 398.238726 -301.461424)
			(xy 398.24152 -301.464472) (xy 416.22853 -301.464472) (xy 416.235896 -301.471838)
		)
		(stroke
			(width 0)
			(type solid)
		)
		(fill yes)
		(layer "B.Cu")
		(net "P0V8_SERDES_VDDA_PEX3")
	)
	(gr_poly
		(pts
			(xy 105.383076 -90.586306) (xy 105.39581 -90.585605) (xy 105.418208 -90.573478) (xy 105.425748 -90.563192)
			(xy 105.442695 -90.537959) (xy 105.482216 -90.491777) (xy 105.527503 -90.451233) (xy 105.577758 -90.417041)
			(xy 105.632097 -90.389802) (xy 105.689563 -90.369996) (xy 105.749146 -90.357971) (xy 105.809796 -90.353939)
			(xy 105.870446 -90.357971) (xy 105.930029 -90.369996) (xy 105.987495 -90.389802) (xy 106.041834 -90.417041)
			(xy 106.092089 -90.451233) (xy 106.137376 -90.491777) (xy 106.176897 -90.537959) (xy 106.193844 -90.563192)
			(xy 106.198708 -90.57012) (xy 106.212045 -90.580529) (xy 106.228055 -90.585999) (xy 106.236516 -90.586306)
			(xy 108.326682 -90.586306) (xy 108.336746 -90.585868) (xy 108.355329 -90.578134) (xy 108.36275 -90.57132)
			(xy 108.543598 -90.390472) (xy 108.55044 -90.383072) (xy 108.558165 -90.364474) (xy 108.558584 -90.354404)
			(xy 108.558584 -90.132916) (xy 108.558145 -90.122853) (xy 108.550407 -90.104272) (xy 108.543598 -90.096848)
			(xy 108.13415 -89.6874) (xy 108.127298 -89.680004) (xy 108.119556 -89.661405) (xy 108.119164 -89.651332)
			(xy 108.119164 -88.94953) (xy 108.118727 -88.939466) (xy 108.110991 -88.920884) (xy 108.104178 -88.913462)
			(xy 108.062522 -88.871806) (xy 108.055173 -88.865007) (xy 108.03671 -88.857302) (xy 108.026708 -88.85682)
			(xy 106.68635 -88.85682) (xy 106.676386 -88.856337) (xy 106.657956 -88.848756) (xy 106.650536 -88.842088)
			(xy 106.342942 -88.534494) (xy 106.336128 -88.52715) (xy 106.328391 -88.508688) (xy 106.327956 -88.49868)
			(xy 106.327956 -86.918038) (xy 106.327469 -86.908076) (xy 106.319878 -86.889655) (xy 106.313224 -86.882224)
			(xy 106.063288 -86.632288) (xy 106.055893 -86.625434) (xy 106.037294 -86.61769) (xy 106.02722 -86.617302)
			(xy 103.814118 -86.617302) (xy 103.804055 -86.61774) (xy 103.785472 -86.625476) (xy 103.77805 -86.632288)
			(xy 103.345234 -87.065104) (xy 103.338385 -87.072501) (xy 103.330646 -87.091099) (xy 103.330248 -87.101172)
			(xy 103.330248 -88.086438) (xy 104.62971 -88.086438) (xy 104.633781 -88.030816) (xy 104.645907 -87.976379)
			(xy 104.66583 -87.924288) (xy 104.693126 -87.875653) (xy 104.727212 -87.83151) (xy 104.767361 -87.792801)
			(xy 104.812719 -87.76035) (xy 104.862319 -87.734849) (xy 104.915103 -87.716842) (xy 104.969946 -87.706712)
			(xy 105.02568 -87.704675) (xy 105.081117 -87.710775) (xy 105.135074 -87.724881) (xy 105.186403 -87.746693)
			(xy 105.234009 -87.775747) (xy 105.276877 -87.811422) (xy 105.314094 -87.852959) (xy 105.344867 -87.899472)
			(xy 105.368539 -87.949969) (xy 105.384607 -88.003376) (xy 105.392727 -88.058552) (xy 105.393236 -88.086438)
			(xy 105.392727 -88.114324) (xy 105.384607 -88.1695) (xy 105.368539 -88.222907) (xy 105.344867 -88.273404)
			(xy 105.314094 -88.319917) (xy 105.276877 -88.361454) (xy 105.234009 -88.397129) (xy 105.186403 -88.426183)
			(xy 105.135074 -88.447995) (xy 105.081117 -88.462101) (xy 105.02568 -88.468201) (xy 104.969946 -88.466164)
			(xy 104.915103 -88.456034) (xy 104.862319 -88.438027) (xy 104.812719 -88.412526) (xy 104.767361 -88.380075)
			(xy 104.727212 -88.341366) (xy 104.693126 -88.297223) (xy 104.66583 -88.248588) (xy 104.645907 -88.196497)
			(xy 104.633781 -88.14206) (xy 104.62971 -88.086438) (xy 103.330248 -88.086438) (xy 103.330248 -89.267538)
			(xy 103.330679 -89.277604) (xy 103.338409 -89.296194) (xy 103.345234 -89.303606) (xy 103.63581 -89.594182)
			(xy 103.645462 -89.597992) (xy 103.669122 -89.607947) (xy 103.713759 -89.633295) (xy 103.754595 -89.664399)
			(xy 103.790893 -89.700695) (xy 103.821997 -89.74153) (xy 103.847347 -89.786166) (xy 103.857298 -89.809828)
			(xy 103.861108 -89.81948) (xy 104.215946 -90.174318) (xy 104.243378 -90.180922) (xy 104.257094 -90.176604)
			(xy 104.290875 -90.16652) (xy 104.360531 -90.15567) (xy 104.395778 -90.155014) (xy 104.425294 -90.155473)
			(xy 104.483837 -90.16306) (xy 104.540918 -90.178112) (xy 104.59559 -90.200377) (xy 104.646945 -90.229487)
			(xy 104.694132 -90.264958) (xy 104.736366 -90.306202) (xy 104.772947 -90.352534) (xy 104.803267 -90.403184)
			(xy 104.826823 -90.457313) (xy 104.843224 -90.514021) (xy 104.848152 -90.543126) (xy 104.850946 -90.561922)
			(xy 104.879394 -90.586306)
		)
		(stroke
			(width 0)
			(type solid)
		)
		(fill yes)
		(layer "B.Cu")
		(net "P3V3_VDDAR_9ZXL0851_0_7")
	)
	(gr_poly
		(pts
			(arc
				(start 162.691318 -302.768)
				(mid 162.699297 -302.76737)
				(end 162.707066 -302.76546)
			)
			(xy 162.729164 -302.758094)
			(arc
				(start 162.73526 -302.753776)
				(mid 162.924998 -302.69396)
				(end 163.114736 -302.753776)
			)
			(xy 163.120832 -302.758094)
			(arc
				(start 163.14293 -302.76546)
				(mid 163.150705 -302.767334)
				(end 163.158678 -302.768)
			)
			(arc
				(start 163.399216 -302.768)
				(mid 163.418739 -302.764099)
				(end 163.435284 -302.753014)
			)
			(arc
				(start 163.557712 -302.630586)
				(mid 163.568823 -302.614052)
				(end 163.572698 -302.594518)
			)
			(arc
				(start 163.572698 -301.569882)
				(mid 163.568797 -301.550359)
				(end 163.557712 -301.533814)
			)
			(xy 163.536884 -301.512986) (xy 163.529772 -301.50562) (xy 163.510976 -301.498)
			(arc
				(start 162.65398 -301.498)
				(mid 162.634457 -301.494099)
				(end 162.617912 -301.483014)
			)
			(xy 162.50031 -301.365412)
			(arc
				(start 162.496246 -301.362618)
				(mid 162.478953 -301.348415)
				(end 162.46475 -301.331122)
			)
			(xy 162.461956 -301.327058)
			(arc
				(start 162.393884 -301.258986)
				(mid 162.382773 -301.242452)
				(end 162.378898 -301.222918)
			)
			(arc
				(start 162.378898 -298.826682)
				(mid 162.382799 -298.807159)
				(end 162.393884 -298.790614)
			)
			(arc
				(start 162.744912 -298.439586)
				(mid 162.756023 -298.423052)
				(end 162.759898 -298.403518)
			)
			(arc
				(start 162.759898 -297.963082)
				(mid 162.755997 -297.943559)
				(end 162.744912 -297.927014)
			)
			(arc
				(start 162.368484 -297.550586)
				(mid 162.357373 -297.534052)
				(end 162.353498 -297.514518)
			)
			(arc
				(start 162.353498 -292.248082)
				(mid 162.357399 -292.228559)
				(end 162.368484 -292.212014)
			)
			(arc
				(start 162.719512 -291.860986)
				(mid 162.730623 -291.844452)
				(end 162.734498 -291.824918)
			)
			(arc
				(start 162.734498 -291.490908)
				(mid 162.719619 -291.454987)
				(end 162.683698 -291.440108)
			)
			(arc
				(start 162.089084 -291.440108)
				(mid 162.069697 -291.444058)
				(end 162.05327 -291.455094)
			)
			(xy 161.971482 -291.536628) (xy 161.960814 -291.544756) (xy 161.935668 -291.559234)
			(arc
				(start 161.932874 -291.561012)
				(mid 161.92099 -291.570718)
				(end 161.911284 -291.582602)
			)
			(xy 161.909506 -291.585396) (xy 161.895028 -291.610542) (xy 161.8869 -291.62121)
			(arc
				(start 161.671508 -291.836602)
				(mid 161.660534 -291.853165)
				(end 161.656776 -291.87267)
			)
			(arc
				(start 161.656776 -296.440606)
				(mid 161.653589 -296.483846)
				(end 161.64433 -296.526204)
			)
			(xy 161.642298 -296.533062) (xy 161.642298 -297.650916)
			(arc
				(start 161.645346 -297.659552)
				(mid 161.653413 -297.684526)
				(end 161.659316 -297.710098)
			)
			(arc
				(start 161.659316 -297.710098)
				(mid 161.663255 -297.737662)
				(end 161.66465 -297.76547)
			)
			(arc
				(start 161.66465 -300.425866)
				(mid 161.66324 -300.453673)
				(end 161.659316 -300.481238)
			)
			(arc
				(start 161.659316 -300.481238)
				(mid 161.653425 -300.506814)
				(end 161.645346 -300.531784)
			)
			(xy 161.642298 -300.54042)
			(arc
				(start 161.642298 -301.257208)
				(mid 161.644032 -301.270369)
				(end 161.649156 -301.282608)
			)
			(xy 161.664142 -301.30877) (xy 161.67227 -301.317406)
			(arc
				(start 161.677604 -301.320962)
				(mid 161.830786 -301.599854)
				(end 161.677604 -301.878746)
			)
			(xy 161.67227 -301.882302) (xy 161.664142 -301.890938)
			(arc
				(start 161.649156 -301.9171)
				(mid 161.644076 -301.929351)
				(end 161.642298 -301.9425)
			)
			(arc
				(start 161.642298 -302.137318)
				(mid 161.646199 -302.156841)
				(end 161.657284 -302.173386)
			)
			(arc
				(start 162.236912 -302.753014)
				(mid 162.253446 -302.764125)
				(end 162.27298 -302.768)
			)
		)
		(stroke
			(width 0)
			(type solid)
		)
		(fill yes)
		(layer "B.Cu")
		(net "GND")
	)
	(gr_poly
		(pts
			(arc
				(start 265.075924 -76.533248)
				(mid 265.09977 -76.527303)
				(end 265.118088 -76.510896)
			)
			(xy 265.17219 -76.430632) (xy 265.174984 -76.40574)
			(arc
				(start 265.170158 -76.393802)
				(mid 265.145625 -76.310279)
				(end 265.137392 -76.223622)
			)
			(arc
				(start 265.137392 -76.223622)
				(mid 265.271452 -75.899974)
				(end 265.5951 -75.765914)
			)
			(arc
				(start 265.5951 -75.765914)
				(mid 265.881898 -75.86691)
				(end 266.04214 -76.125324)
			)
			(xy 266.045188 -76.13904) (xy 266.063984 -76.159106)
			(arc
				(start 266.163044 -76.188062)
				(mid 266.189809 -76.188383)
				(end 266.213082 -76.175108)
			)
			(arc
				(start 266.337288 -76.051156)
				(mid 266.353734 -76.04023)
				(end 266.373102 -76.036424)
			)
			(arc
				(start 268.130528 -76.036424)
				(mid 268.158812 -76.027822)
				(end 268.177518 -76.004928)
			)
			(xy 268.183614 -75.99045) (xy 268.177518 -75.960732)
			(arc
				(start 267.04671 -74.82967)
				(mid 267.030176 -74.818559)
				(end 267.010642 -74.814684)
			)
			(arc
				(start 263.914636 -74.814684)
				(mid 263.887736 -74.822391)
				(end 263.868916 -74.843132)
			)
			(xy 263.822434 -74.938128) (xy 263.825228 -74.96683)
			(arc
				(start 263.834118 -74.978514)
				(mid 263.905197 -75.110527)
				(end 263.929876 -75.258422)
			)
			(arc
				(start 263.929876 -75.258422)
				(mid 263.795742 -75.58225)
				(end 263.471914 -75.716384)
			)
			(arc
				(start 262.608314 -75.716384)
				(mid 262.341568 -75.630621)
				(end 262.174736 -75.405488)
			)
			(xy 262.170418 -75.393042) (xy 262.151114 -75.375516)
			(arc
				(start 262.054086 -75.35291)
				(mid 262.028729 -75.353553)
				(end 262.006842 -75.366372)
			)
			(arc
				(start 261.849616 -75.523344)
				(mid 261.621657 -75.675598)
				(end 261.352792 -75.729084)
			)
			(arc
				(start 260.84784 -75.729084)
				(mid 260.819556 -75.737686)
				(end 260.80085 -75.76058)
			)
			(xy 260.795008 -75.775058) (xy 260.80085 -75.804776)
			(arc
				(start 261.04723 -76.051156)
				(mid 261.06641 -76.063118)
				(end 261.088886 -76.065634)
			)
			(xy 261.17931 -76.055474) (xy 261.198868 -76.043282)
			(arc
				(start 261.204964 -76.033122)
				(mid 261.343561 -75.901993)
				(end 261.528306 -75.854306)
			)
			(arc
				(start 261.528306 -75.854306)
				(mid 261.798073 -75.966047)
				(end 261.909814 -76.235814)
			)
			(arc
				(start 261.909814 -76.235814)
				(mid 261.901532 -76.314873)
				(end 261.877048 -76.3905)
			)
			(xy 261.871714 -76.402438) (xy 261.873746 -76.427838)
			(arc
				(start 261.92734 -76.510134)
				(mid 261.945731 -76.527145)
				(end 261.970012 -76.533248)
			)
		)
		(stroke
			(width 0)
			(type solid)
		)
		(fill yes)
		(layer "B.Cu")
		(net "GND")
	)
	(gr_poly
		(pts
			(arc
				(start 345.46159 -280.676604)
				(mid 345.481113 -280.672703)
				(end 345.497658 -280.661618)
			)
			(arc
				(start 345.932252 -280.227024)
				(mid 345.948786 -280.215913)
				(end 345.96832 -280.212038)
			)
			(arc
				(start 346.940378 -280.212038)
				(mid 346.959901 -280.208137)
				(end 346.976446 -280.197052)
			)
			(arc
				(start 347.782388 -279.39111)
				(mid 347.798922 -279.379999)
				(end 347.818456 -279.376124)
			)
			(arc
				(start 350.27489 -279.376124)
				(mid 350.294413 -279.372223)
				(end 350.310958 -279.361138)
			)
			(arc
				(start 350.507554 -279.164542)
				(mid 350.518665 -279.148008)
				(end 350.52254 -279.128474)
			)
			(arc
				(start 350.52254 -272.477992)
				(mid 350.526441 -272.458469)
				(end 350.537526 -272.441924)
			)
			(arc
				(start 350.929194 -272.050002)
				(mid 350.945728 -272.038891)
				(end 350.965262 -272.035016)
			)
			(arc
				(start 356.173532 -272.035016)
				(mid 356.193055 -272.031115)
				(end 356.2096 -272.02003)
			)
			(arc
				(start 356.278434 -271.951196)
				(mid 356.289545 -271.934662)
				(end 356.29342 -271.915128)
			)
			(xy 356.29342 -268.927072) (xy 356.29342 -268.344396) (xy 356.468426 -268.16939) (xy 361.152186 -268.16939)
			(xy 361.472988 -268.490192) (xy 361.472988 -268.985746)
			(arc
				(start 361.472988 -276.414484)
				(mid 361.47395 -276.424322)
				(end 361.476798 -276.433788)
			)
			(xy 361.480862 -276.44344) (xy 361.480862 -277.578058) (xy 361.474258 -277.584662)
			(arc
				(start 361.474258 -278.778716)
				(mid 361.470357 -278.798239)
				(end 361.459272 -278.814784)
			)
			(arc
				(start 360.798364 -279.475692)
				(mid 360.787253 -279.492226)
				(end 360.783378 -279.51176)
			)
			(arc
				(start 360.783378 -280.614882)
				(mid 360.787279 -280.634405)
				(end 360.798364 -280.65095)
			)
			(arc
				(start 360.809032 -280.661618)
				(mid 360.825566 -280.672729)
				(end 360.8451 -280.676604)
			)
			(arc
				(start 362.171488 -280.676604)
				(mid 362.191011 -280.672703)
				(end 362.207556 -280.661618)
			)
			(arc
				(start 362.64215 -280.227024)
				(mid 362.658684 -280.215913)
				(end 362.678218 -280.212038)
			)
			(arc
				(start 363.650276 -280.212038)
				(mid 363.669799 -280.208137)
				(end 363.686344 -280.197052)
			)
			(arc
				(start 364.494572 -279.388824)
				(mid 364.511106 -279.377713)
				(end 364.53064 -279.373838)
			)
			(arc
				(start 365.240062 -279.373838)
				(mid 365.259585 -279.369937)
				(end 365.27613 -279.358852)
			)
			(arc
				(start 365.433102 -279.20188)
				(mid 365.444213 -279.185346)
				(end 365.448088 -279.165812)
			)
			(arc
				(start 365.448088 -278.85517)
				(mid 365.444187 -278.835647)
				(end 365.433102 -278.819102)
			)
			(arc
				(start 364.203488 -277.589742)
				(mid 364.192377 -277.573208)
				(end 364.188502 -277.553674)
			)
			(arc
				(start 364.188502 -267.010388)
				(mid 364.184601 -266.990865)
				(end 364.173516 -266.97432)
			)
			(xy 364.120938 -266.921742) (xy 364.113826 -266.914376) (xy 364.09503 -266.906756)
			(arc
				(start 332.823058 -266.906756)
				(mid 332.803535 -266.910657)
				(end 332.78699 -266.921742)
			)
			(xy 332.31201 -267.396722) (xy 332.304644 -267.403834) (xy 332.297024 -267.42263) (xy 332.297024 -278.354282)
			(xy 332.297024 -278.918924) (xy 332.417674 -279.039574) (xy 333.722218 -279.039574) (xy 333.856838 -278.904954)
			(xy 333.856838 -278.38908) (xy 333.856838 -268.784578) (xy 333.856838 -268.453616) (xy 334.208628 -268.101826)
			(xy 338.87791 -268.101826) (xy 339.099144 -268.32306) (xy 339.099144 -268.940534)
			(arc
				(start 339.099144 -272.052796)
				(mid 339.103045 -272.072319)
				(end 339.11413 -272.088864)
			)
			(arc
				(start 339.168486 -272.14322)
				(mid 339.18502 -272.154331)
				(end 339.204554 -272.158206)
			)
			(arc
				(start 344.460322 -272.158206)
				(mid 344.479845 -272.162107)
				(end 344.49639 -272.173192)
			)
			(arc
				(start 344.841322 -272.518124)
				(mid 344.852433 -272.534658)
				(end 344.856308 -272.554192)
			)
			(xy 344.856308 -278.70785)
			(arc
				(start 344.088466 -279.475692)
				(mid 344.077355 -279.492226)
				(end 344.07348 -279.51176)
			)
			(arc
				(start 344.07348 -280.614882)
				(mid 344.077381 -280.634405)
				(end 344.088466 -280.65095)
			)
			(arc
				(start 344.099134 -280.661618)
				(mid 344.115668 -280.672729)
				(end 344.135202 -280.676604)
			)
		)
		(stroke
			(width 0)
			(type solid)
		)
		(fill yes)
		(layer "B.Cu")
		(net "GND")
	)
	(gr_poly
		(pts
			(arc
				(start 132.108448 -327.204832)
				(mid 132.127971 -327.200931)
				(end 132.144516 -327.189846)
			)
			(arc
				(start 132.732018 -326.602344)
				(mid 132.748552 -326.591233)
				(end 132.768086 -326.587358)
			)
			(arc
				(start 134.578344 -326.587358)
				(mid 134.597867 -326.583457)
				(end 134.614412 -326.572372)
			)
			(arc
				(start 134.831328 -326.355456)
				(mid 134.842439 -326.338922)
				(end 134.846314 -326.319388)
			)
			(arc
				(start 134.846314 -325.689214)
				(mid 134.842413 -325.669691)
				(end 134.831328 -325.653146)
			)
			(arc
				(start 134.820152 -325.64197)
				(mid 134.803618 -325.630859)
				(end 134.784084 -325.626984)
			)
			(arc
				(start 128.994916 -325.626984)
				(mid 128.975393 -325.630885)
				(end 128.958848 -325.64197)
			)
			(arc
				(start 128.879092 -325.721726)
				(mid 128.862558 -325.732837)
				(end 128.843024 -325.736712)
			)
			(arc
				(start 125.263402 -325.736712)
				(mid 125.243879 -325.732811)
				(end 125.227334 -325.721726)
			)
			(arc
				(start 124.814838 -325.30923)
				(mid 124.798304 -325.298119)
				(end 124.77877 -325.294244)
			)
			(xy 117.655594 -325.294244) (xy 117.637052 -325.286624) (xy 117.634258 -325.28383)
			(arc
				(start 108.19511 -325.28383)
				(mid 108.175587 -325.287731)
				(end 108.159042 -325.298816)
			)
			(arc
				(start 107.79125 -325.666608)
				(mid 107.780139 -325.683142)
				(end 107.776264 -325.702676)
			)
			(arc
				(start 107.776264 -326.401684)
				(mid 107.780165 -326.421207)
				(end 107.79125 -326.437752)
			)
			(arc
				(start 108.049314 -326.695816)
				(mid 108.065848 -326.706927)
				(end 108.085382 -326.710802)
			)
			(arc
				(start 109.387894 -326.710802)
				(mid 109.407417 -326.714703)
				(end 109.423962 -326.725788)
			)
			(xy 109.681264 -326.98309) (xy 109.687614 -326.988424)
			(arc
				(start 109.68863 -326.989186)
				(mid 109.702731 -326.996333)
				(end 109.718348 -326.998838)
			)
			(arc
				(start 109.89691 -326.998838)
				(mid 109.920849 -326.992844)
				(end 109.939074 -326.976232)
			)
			(arc
				(start 109.986064 -326.906128)
				(mid 109.994358 -326.883105)
				(end 109.99089 -326.858884)
			)
			(arc
				(start 109.99089 -326.85863)
				(mid 109.969425 -326.787519)
				(end 109.962188 -326.713596)
			)
			(arc
				(start 109.962188 -326.713596)
				(mid 110.343696 -326.332088)
				(end 110.725204 -326.713596)
			)
			(arc
				(start 110.725204 -326.713596)
				(mid 110.717901 -326.787381)
				(end 110.696502 -326.858376)
			)
			(arc
				(start 110.696502 -326.858884)
				(mid 110.693051 -326.883103)
				(end 110.701328 -326.906128)
			)
			(arc
				(start 110.748318 -326.976232)
				(mid 110.76658 -326.992775)
				(end 110.790482 -326.998838)
			)
			(xy 110.873794 -326.998838) (xy 110.888526 -326.994012)
			(arc
				(start 110.89513 -326.98944)
				(mid 111.053958 -326.909422)
				(end 111.229648 -326.881744)
			)
			(arc
				(start 111.990124 -326.881744)
				(mid 112.155205 -326.906047)
				(end 112.306354 -326.97674)
			)
			(arc
				(start 112.306354 -326.97674)
				(mid 112.31971 -326.982976)
				(end 112.334294 -326.985122)
			)
			(arc
				(start 112.721898 -326.985122)
				(mid 112.741421 -326.989023)
				(end 112.757966 -327.000108)
			)
			(arc
				(start 112.796574 -327.038716)
				(mid 112.813108 -327.049827)
				(end 112.832642 -327.053702)
			)
			(arc
				(start 117.688614 -327.053702)
				(mid 117.708137 -327.049801)
				(end 117.724682 -327.038716)
			)
			(arc
				(start 117.763036 -327.000362)
				(mid 117.79885 -326.985601)
				(end 117.834664 -327.000362)
			)
			(arc
				(start 118.024148 -327.189846)
				(mid 118.040682 -327.200957)
				(end 118.060216 -327.204832)
			)
		)
		(stroke
			(width 0)
			(type solid)
		)
		(fill yes)
		(layer "B.Cu")
		(net "GND")
	)
	(gr_poly
		(pts
			(xy 416.458146 -13.816076) (xy 416.458146 -13.40739) (xy 416.40887 -13.358114)
			(arc
				(start 409.26512 -13.358114)
				(mid 408.198804 -12.916432)
				(end 407.757122 -11.850116)
			)
			(arc
				(start 407.757122 -1.999996)
				(mid 407.320126 -0.944996)
				(end 406.265126 -0.508)
			)
			(arc
				(start 394.264896 -0.508)
				(mid 393.209896 -0.944996)
				(end 392.7729 -1.999996)
			)
			(arc
				(start 392.7729 -11.850116)
				(mid 392.702216 -12.306469)
				(end 392.496802 -12.720066)
			)
			(xy 392.496802 -12.748514) (xy 392.499088 -12.7508)
			(arc
				(start 393.067794 -12.7508)
				(mid 393.226496 -12.312827)
				(end 393.280392 -11.850116)
			)
			(arc
				(start 393.280392 -1.999996)
				(mid 393.568747 -1.303847)
				(end 394.264896 -1.015492)
			)
			(arc
				(start 406.265126 -1.015492)
				(mid 406.961365 -1.303831)
				(end 407.249884 -1.999996)
			)
			(arc
				(start 407.249884 -11.850116)
				(mid 407.840133 -13.275103)
				(end 409.26512 -13.865352)
			)
			(xy 416.40887 -13.865352)
		)
		(stroke
			(width 0)
			(type solid)
		)
		(fill yes)
		(layer "B.Cu")
		(net "GND")
	)
	(gr_poly
		(pts
			(arc
				(start 113.261394 -280.676604)
				(mid 113.280917 -280.672703)
				(end 113.297462 -280.661618)
			)
			(arc
				(start 113.732056 -280.227024)
				(mid 113.74859 -280.215913)
				(end 113.768124 -280.212038)
			)
			(arc
				(start 114.740182 -280.212038)
				(mid 114.759705 -280.208137)
				(end 114.77625 -280.197052)
			)
			(arc
				(start 115.582192 -279.39111)
				(mid 115.598726 -279.379999)
				(end 115.61826 -279.376124)
			)
			(arc
				(start 118.074694 -279.376124)
				(mid 118.094217 -279.372223)
				(end 118.110762 -279.361138)
			)
			(arc
				(start 118.307358 -279.164542)
				(mid 118.318469 -279.148008)
				(end 118.322344 -279.128474)
			)
			(arc
				(start 118.322344 -272.477992)
				(mid 118.326245 -272.458469)
				(end 118.33733 -272.441924)
			)
			(arc
				(start 118.728998 -272.050002)
				(mid 118.745532 -272.038891)
				(end 118.765066 -272.035016)
			)
			(arc
				(start 123.973336 -272.035016)
				(mid 123.992859 -272.031115)
				(end 124.009404 -272.02003)
			)
			(arc
				(start 124.078238 -271.951196)
				(mid 124.089349 -271.934662)
				(end 124.093224 -271.915128)
			)
			(xy 124.093224 -268.927072) (xy 124.093224 -268.662658) (xy 124.330968 -268.424914) (xy 124.43714 -268.318742)
			(xy 124.653548 -268.102334) (xy 129.03454 -268.102334) (xy 129.272792 -268.340586) (xy 129.272792 -268.460982)
			(xy 129.272792 -268.985746)
			(arc
				(start 129.272792 -276.414484)
				(mid 129.273754 -276.424322)
				(end 129.276602 -276.433788)
			)
			(xy 129.280666 -276.44344) (xy 129.280666 -277.578058) (xy 129.274062 -277.584662)
			(arc
				(start 129.274062 -278.778716)
				(mid 129.270161 -278.798239)
				(end 129.259076 -278.814784)
			)
			(arc
				(start 128.598168 -279.475692)
				(mid 128.587057 -279.492226)
				(end 128.583182 -279.51176)
			)
			(arc
				(start 128.583182 -280.614882)
				(mid 128.587083 -280.634405)
				(end 128.598168 -280.65095)
			)
			(arc
				(start 128.608836 -280.661618)
				(mid 128.62537 -280.672729)
				(end 128.644904 -280.676604)
			)
			(arc
				(start 129.971292 -280.676604)
				(mid 129.990815 -280.672703)
				(end 130.00736 -280.661618)
			)
			(arc
				(start 130.441954 -280.227024)
				(mid 130.458488 -280.215913)
				(end 130.478022 -280.212038)
			)
			(arc
				(start 131.45008 -280.212038)
				(mid 131.469603 -280.208137)
				(end 131.486148 -280.197052)
			)
			(arc
				(start 132.294376 -279.388824)
				(mid 132.31091 -279.377713)
				(end 132.330444 -279.373838)
			)
			(arc
				(start 133.039866 -279.373838)
				(mid 133.059389 -279.369937)
				(end 133.075934 -279.358852)
			)
			(arc
				(start 133.232906 -279.20188)
				(mid 133.244017 -279.185346)
				(end 133.247892 -279.165812)
			)
			(arc
				(start 133.247892 -278.85517)
				(mid 133.243991 -278.835647)
				(end 133.232906 -278.819102)
			)
			(arc
				(start 132.003292 -277.589742)
				(mid 131.992181 -277.573208)
				(end 131.988306 -277.553674)
			)
			(arc
				(start 131.988306 -267.010388)
				(mid 131.984405 -266.990865)
				(end 131.97332 -266.97432)
			)
			(xy 131.920742 -266.921742) (xy 131.91363 -266.914376) (xy 131.894834 -266.906756)
			(arc
				(start 100.622862 -266.906756)
				(mid 100.603339 -266.910657)
				(end 100.586794 -266.921742)
			)
			(xy 100.111814 -267.396722) (xy 100.104448 -267.403834) (xy 100.096828 -267.42263) (xy 100.096828 -278.354282)
			(xy 100.096828 -278.815546) (xy 100.311204 -279.029922) (xy 101.562662 -279.029922) (xy 101.656642 -278.935942)
			(xy 101.656642 -278.38908) (xy 101.656642 -268.784578) (xy 101.656642 -268.415262) (xy 101.825298 -268.246606)
			(xy 101.83495 -268.246606) (xy 101.926644 -268.154912) (xy 102.311454 -268.154912) (xy 102.313232 -268.15669)
			(xy 106.80573 -268.15669) (xy 106.898948 -268.249908) (xy 106.898948 -268.940534)
			(arc
				(start 106.898948 -272.052796)
				(mid 106.902849 -272.072319)
				(end 106.913934 -272.088864)
			)
			(arc
				(start 106.96829 -272.14322)
				(mid 106.984824 -272.154331)
				(end 107.004358 -272.158206)
			)
			(arc
				(start 112.260126 -272.158206)
				(mid 112.279649 -272.162107)
				(end 112.296194 -272.173192)
			)
			(arc
				(start 112.641126 -272.518124)
				(mid 112.652237 -272.534658)
				(end 112.656112 -272.554192)
			)
			(xy 112.656112 -278.70785)
			(arc
				(start 111.88827 -279.475692)
				(mid 111.877159 -279.492226)
				(end 111.873284 -279.51176)
			)
			(arc
				(start 111.873284 -280.614882)
				(mid 111.877185 -280.634405)
				(end 111.88827 -280.65095)
			)
			(arc
				(start 111.898938 -280.661618)
				(mid 111.915472 -280.672729)
				(end 111.935006 -280.676604)
			)
		)
		(stroke
			(width 0)
			(type solid)
		)
		(fill yes)
		(layer "B.Cu")
		(net "GND")
	)
	(gr_poly
		(pts
			(xy 364.71606 -13.770102) (xy 364.71606 -13.453364) (xy 364.62081 -13.358114)
			(arc
				(start 357.26497 -13.358114)
				(mid 356.198654 -12.916432)
				(end 355.756972 -11.850116)
			)
			(arc
				(start 355.756972 -1.999996)
				(mid 355.319976 -0.944996)
				(end 354.264976 -0.508)
			)
			(arc
				(start 330.164948 -0.508)
				(mid 329.109948 -0.944996)
				(end 328.672952 -1.999996)
			)
			(arc
				(start 328.672952 -11.850116)
				(mid 328.570197 -12.397292)
				(end 328.27595 -12.869926)
			)
			(xy 328.27595 -12.876784) (xy 328.28738 -12.888214) (xy 328.885042 -12.888214)
			(arc
				(start 328.90333 -12.869926)
				(mid 329.10994 -12.378512)
				(end 329.180444 -11.850116)
			)
			(arc
				(start 329.180444 -1.999996)
				(mid 329.468799 -1.303847)
				(end 330.164948 -1.015492)
			)
			(arc
				(start 354.264976 -1.015492)
				(mid 354.961125 -1.303847)
				(end 355.24948 -1.999996)
			)
			(arc
				(start 355.24948 -11.850116)
				(mid 355.839893 -13.275118)
				(end 357.26497 -13.865352)
			)
			(xy 364.62081 -13.865352)
		)
		(stroke
			(width 0)
			(type solid)
		)
		(fill yes)
		(layer "B.Cu")
		(net "GND")
	)
	(gr_poly
		(pts
			(xy 390.499092 -13.810996) (xy 390.499092 -13.41247) (xy 390.444736 -13.358114)
			(arc
				(start 383.264918 -13.358114)
				(mid 382.198602 -12.916432)
				(end 381.75692 -11.850116)
			)
			(arc
				(start 381.75692 -1.999996)
				(mid 381.319924 -0.944996)
				(end 380.264924 -0.508)
			)
			(arc
				(start 368.264948 -0.508)
				(mid 367.209948 -0.944996)
				(end 366.772952 -1.999996)
			)
			(arc
				(start 366.772952 -11.850116)
				(mid 366.670132 -12.397459)
				(end 366.375696 -12.87018)
			)
			(xy 366.375696 -12.899644) (xy 366.434878 -12.958826) (xy 366.914684 -12.958826)
			(arc
				(start 367.00333 -12.87018)
				(mid 367.209881 -12.378884)
				(end 367.280444 -11.850624)
			)
			(arc
				(start 367.280444 -1.999996)
				(mid 367.568799 -1.303847)
				(end 368.264948 -1.015492)
			)
			(arc
				(start 380.264924 -1.015492)
				(mid 380.961073 -1.303847)
				(end 381.249428 -1.999996)
			)
			(arc
				(start 381.249428 -11.850116)
				(mid 381.839841 -13.275118)
				(end 383.264918 -13.865352)
			)
			(xy 390.444736 -13.865352)
		)
		(stroke
			(width 0)
			(type solid)
		)
		(fill yes)
		(layer "B.Cu")
		(net "GND")
	)
	(gr_poly
		(pts
			(xy 326.45985 -13.852906) (xy 326.45985 -13.37945) (xy 326.438514 -13.358114)
			(arc
				(start 319.16497 -13.358114)
				(mid 318.098654 -12.916432)
				(end 317.656972 -11.850116)
			)
			(arc
				(start 317.656972 -1.999996)
				(mid 317.219976 -0.944996)
				(end 316.164976 -0.508)
			)
			(arc
				(start 304.165 -0.508)
				(mid 303.11 -0.944996)
				(end 302.673004 -1.999996)
			)
			(arc
				(start 302.673004 -11.850116)
				(mid 302.577528 -12.378214)
				(end 302.30318 -12.839446)
			)
			(xy 302.30318 -12.884912) (xy 302.304196 -12.885928) (xy 302.874426 -12.885928)
			(arc
				(start 302.920908 -12.839446)
				(mid 303.114524 -12.361527)
				(end 303.180496 -11.850116)
			)
			(arc
				(start 303.180496 -1.999996)
				(mid 303.468851 -1.303847)
				(end 304.165 -1.015492)
			)
			(arc
				(start 316.164976 -1.015492)
				(mid 316.861125 -1.303847)
				(end 317.14948 -1.999996)
			)
			(arc
				(start 317.14948 -11.850116)
				(mid 317.739893 -13.275118)
				(end 319.16497 -13.865352)
			)
			(xy 326.438514 -13.865352) (xy 326.447404 -13.865352)
		)
		(stroke
			(width 0)
			(type solid)
		)
		(fill yes)
		(layer "B.Cu")
		(net "GND")
	)
	(gr_poly
		(pts
			(arc
				(start 234.349544 -217.320876)
				(mid 234.365608 -217.318269)
				(end 234.380024 -217.310716)
			)
			(xy 234.384088 -217.307414) (xy 234.46994 -217.221562)
			(arc
				(start 234.470448 -217.221054)
				(mid 234.48119 -217.204697)
				(end 234.484926 -217.185494)
			)
			(arc
				(start 234.484926 -217.000836)
				(mid 234.488827 -216.981313)
				(end 234.499912 -216.964768)
			)
			(arc
				(start 234.544616 -216.920064)
				(mid 234.56115 -216.908953)
				(end 234.580684 -216.905078)
			)
			(arc
				(start 234.698032 -216.905078)
				(mid 234.70787 -216.90604)
				(end 234.717336 -216.908888)
			)
			(xy 234.726734 -216.912952) (xy 234.755944 -216.912952) (xy 234.76966 -216.934542) (xy 234.77093 -216.93632)
			(xy 234.774232 -216.941654) (xy 234.77474 -216.942416)
			(arc
				(start 235.344208 -216.942416)
				(mid 235.363731 -216.938515)
				(end 235.380276 -216.92743)
			)
			(arc
				(start 235.412026 -216.89568)
				(mid 235.42856 -216.884569)
				(end 235.448094 -216.880694)
			)
			(arc
				(start 237.988856 -216.880694)
				(mid 238.008379 -216.876793)
				(end 238.024924 -216.865708)
			)
			(xy 238.275114 -216.615518)
			(arc
				(start 238.275622 -216.61501)
				(mid 238.286364 -216.598653)
				(end 238.2901 -216.57945)
			)
			(arc
				(start 238.2901 -215.448896)
				(mid 238.286199 -215.429373)
				(end 238.275114 -215.412828)
			)
			(xy 238.240316 -215.37803) (xy 238.233204 -215.370664) (xy 238.214408 -215.363044)
			(arc
				(start 236.59211 -215.363044)
				(mid 236.571021 -215.367628)
				(end 236.553756 -215.38057)
			)
			(arc
				(start 236.553756 -215.38057)
				(mid 236.237018 -215.524567)
				(end 235.92028 -215.38057)
			)
			(arc
				(start 235.92028 -215.38057)
				(mid 235.903005 -215.36765)
				(end 235.881926 -215.363044)
			)
			(arc
				(start 235.594652 -215.363044)
				(mid 235.575129 -215.366945)
				(end 235.558584 -215.37803)
			)
			(arc
				(start 235.118402 -215.818212)
				(mid 235.105446 -215.840604)
				(end 235.105194 -215.866472)
			)
			(xy 235.12653 -215.950292) (xy 235.14558 -215.969596)
			(arc
				(start 235.158788 -215.973406)
				(mid 235.340564 -216.096401)
				(end 235.410756 -216.304368)
			)
			(arc
				(start 235.410756 -216.304368)
				(mid 235.067348 -216.647776)
				(end 234.72394 -216.304368)
			)
			(arc
				(start 234.72394 -216.30386)
				(mid 234.726057 -216.266037)
				(end 234.732322 -216.228676)
			)
			(xy 234.733592 -216.223088)
			(arc
				(start 234.733592 -216.2175)
				(mid 234.718713 -216.181579)
				(end 234.682792 -216.1667)
			)
			(arc
				(start 234.652058 -216.1667)
				(mid 234.616137 -216.181579)
				(end 234.601258 -216.2175)
			)
			(xy 234.601258 -216.223088)
			(arc
				(start 234.602528 -216.228676)
				(mid 234.608799 -216.266036)
				(end 234.61091 -216.30386)
			)
			(arc
				(start 234.61091 -216.304368)
				(mid 234.528175 -216.527928)
				(end 234.319826 -216.643712)
			)
			(xy 234.311444 -216.644982) (xy 234.29722 -216.652348) (xy 234.20324 -216.746328)
			(arc
				(start 234.20324 -216.822528)
				(mid 234.199359 -216.841749)
				(end 234.188508 -216.858088)
			)
			(arc
				(start 234.02163 -217.024966)
				(mid 234.005213 -217.036028)
				(end 233.985816 -217.039952)
			)
			(arc
				(start 233.885994 -217.039952)
				(mid 233.850073 -217.054831)
				(end 233.835194 -217.090752)
			)
			(arc
				(start 233.835194 -217.165936)
				(mid 233.838959 -217.185127)
				(end 233.849672 -217.201496)
			)
			(xy 233.954066 -217.30589)
			(arc
				(start 233.954574 -217.306398)
				(mid 233.970931 -217.31714)
				(end 233.990134 -217.320876)
			)
		)
		(stroke
			(width 0)
			(type solid)
		)
		(fill yes)
		(layer "B.Cu")
		(net "P1V2_BIC_PLL")
	)
	(gr_poly
		(pts
			(xy 158.95701 -146.779234) (xy 161.611564 -146.779234) (xy 161.621628 -146.778797) (xy 161.640209 -146.771059)
			(xy 161.647632 -146.764248) (xy 161.833306 -146.578574) (xy 161.840148 -146.571174) (xy 161.847872 -146.552576)
			(xy 161.848292 -146.542506) (xy 161.848292 -146.504914) (xy 161.847757 -146.494926) (xy 161.840046 -146.476491)
			(xy 161.833306 -146.4691) (xy 161.826448 -146.462242) (xy 161.826448 -142.600172) (xy 161.825967 -142.590208)
			(xy 161.818384 -142.571778) (xy 161.811716 -142.564358) (xy 161.80308 -142.555722) (xy 161.795681 -142.548876)
			(xy 161.777083 -142.541146) (xy 161.767012 -142.540736) (xy 158.77286 -142.540736) (xy 158.762794 -142.540304)
			(xy 158.744207 -142.532572) (xy 158.736792 -142.52575) (xy 156.522166 -140.311124) (xy 156.514767 -140.30428)
			(xy 156.496168 -140.296554) (xy 156.486098 -140.296138) (xy 152.585166 -140.296138) (xy 152.555956 -140.324078)
			(xy 152.55494 -140.344398) (xy 152.553137 -140.372028) (xy 152.54255 -140.426375) (xy 152.524217 -140.47862)
			(xy 152.498522 -140.527665) (xy 152.466006 -140.57248) (xy 152.427352 -140.612123) (xy 152.383372 -140.64576)
			(xy 152.334991 -140.672685) (xy 152.283225 -140.692332) (xy 152.229163 -140.704287) (xy 152.17394 -140.708301)
			(xy 152.118717 -140.704287) (xy 152.064655 -140.692332) (xy 152.012889 -140.672685) (xy 151.964508 -140.64576)
			(xy 151.920528 -140.612123) (xy 151.881874 -140.57248) (xy 151.849358 -140.527665) (xy 151.823663 -140.47862)
			(xy 151.80533 -140.426375) (xy 151.794743 -140.372028) (xy 151.79294 -140.344398) (xy 151.791924 -140.324078)
			(xy 151.762714 -140.296138) (xy 135.843518 -140.296138) (xy 135.833455 -140.296577) (xy 135.814876 -140.304316)
			(xy 135.80745 -140.311124) (xy 135.506206 -140.612368) (xy 135.49937 -140.61977) (xy 135.491659 -140.638368)
			(xy 135.49122 -140.648436) (xy 135.49122 -141.029436) (xy 155.691076 -141.029436) (xy 155.695147 -140.973814)
			(xy 155.707273 -140.919377) (xy 155.727196 -140.867286) (xy 155.754492 -140.818651) (xy 155.788578 -140.774508)
			(xy 155.828727 -140.735799) (xy 155.874085 -140.703348) (xy 155.923685 -140.677847) (xy 155.976469 -140.65984)
			(xy 156.031312 -140.64971) (xy 156.087046 -140.647673) (xy 156.142483 -140.653773) (xy 156.19644 -140.667879)
			(xy 156.247769 -140.689691) (xy 156.295375 -140.718745) (xy 156.338243 -140.75442) (xy 156.37546 -140.795957)
			(xy 156.406233 -140.84247) (xy 156.429905 -140.892967) (xy 156.445973 -140.946374) (xy 156.454093 -141.00155)
			(xy 156.454602 -141.029436) (xy 156.454093 -141.057322) (xy 156.445973 -141.112498) (xy 156.429905 -141.165905)
			(xy 156.406233 -141.216402) (xy 156.37546 -141.262915) (xy 156.338243 -141.304452) (xy 156.295375 -141.340127)
			(xy 156.247769 -141.369181) (xy 156.19644 -141.390993) (xy 156.142483 -141.405099) (xy 156.087046 -141.411199)
			(xy 156.031312 -141.409162) (xy 155.976469 -141.399032) (xy 155.923685 -141.381025) (xy 155.874085 -141.355524)
			(xy 155.828727 -141.323073) (xy 155.788578 -141.284364) (xy 155.754492 -141.240221) (xy 155.727196 -141.191586)
			(xy 155.707273 -141.139495) (xy 155.695147 -141.085058) (xy 155.691076 -141.029436) (xy 135.49122 -141.029436)
			(xy 135.49122 -142.748762) (xy 155.618686 -142.748762) (xy 155.622757 -142.69314) (xy 155.634883 -142.638703)
			(xy 155.654806 -142.586612) (xy 155.682102 -142.537977) (xy 155.716188 -142.493834) (xy 155.756337 -142.455125)
			(xy 155.801695 -142.422674) (xy 155.851295 -142.397173) (xy 155.904079 -142.379166) (xy 155.958922 -142.369036)
			(xy 156.014656 -142.366999) (xy 156.070093 -142.373099) (xy 156.12405 -142.387205) (xy 156.175379 -142.409017)
			(xy 156.222985 -142.438071) (xy 156.265853 -142.473746) (xy 156.30307 -142.515283) (xy 156.333843 -142.561796)
			(xy 156.357515 -142.612293) (xy 156.373583 -142.6657) (xy 156.381703 -142.720876) (xy 156.382212 -142.748762)
			(xy 156.381703 -142.776648) (xy 156.373583 -142.831824) (xy 156.357515 -142.885231) (xy 156.333843 -142.935728)
			(xy 156.30307 -142.982241) (xy 156.265853 -143.023778) (xy 156.222985 -143.059453) (xy 156.175379 -143.088507)
			(xy 156.12405 -143.110319) (xy 156.070093 -143.124425) (xy 156.014656 -143.130525) (xy 155.958922 -143.128488)
			(xy 155.904079 -143.118358) (xy 155.851295 -143.100351) (xy 155.801695 -143.07485) (xy 155.756337 -143.042399)
			(xy 155.716188 -143.00369) (xy 155.682102 -142.959547) (xy 155.654806 -142.910912) (xy 155.634883 -142.858821)
			(xy 155.622757 -142.804384) (xy 155.618686 -142.748762) (xy 135.49122 -142.748762) (xy 135.49122 -144.039844)
			(xy 135.491652 -144.04991) (xy 135.49938 -144.068501) (xy 135.506206 -144.075912) (xy 137.006838 -145.576544)
			(xy 137.014236 -145.58339) (xy 137.032835 -145.59112) (xy 137.042906 -145.59153) (xy 138.924284 -145.59153)
			(xy 138.934347 -145.591969) (xy 138.952926 -145.599708) (xy 138.960352 -145.606516) (xy 141.011656 -147.65782)
			(xy 141.019054 -147.664667) (xy 141.037653 -147.672393) (xy 141.047724 -147.672806) (xy 156.730954 -147.672806)
			(xy 158.063438 -147.672806)
		)
		(stroke
			(width 0)
			(type solid)
		)
		(fill yes)
		(layer "B.Cu")
		(net "P12V_NIC2")
	)
	(gr_poly
		(pts
			(xy 391.650982 -146.779234) (xy 393.871958 -146.779234) (xy 393.882022 -146.778799) (xy 393.900605 -146.771062)
			(xy 393.908026 -146.764248) (xy 394.034518 -146.637756) (xy 394.041367 -146.630359) (xy 394.049098 -146.61176)
			(xy 394.049504 -146.601688) (xy 394.049504 -146.502374) (xy 394.048962 -146.492389) (xy 394.041242 -146.473963)
			(xy 394.034518 -146.46656) (xy 394.033248 -146.465036) (xy 394.025628 -146.446494) (xy 394.025628 -142.59179)
			(xy 394.02509 -142.581803) (xy 394.017377 -142.563371) (xy 394.010642 -142.555976) (xy 394.010388 -142.555722)
			(xy 394.00299 -142.548875) (xy 393.984392 -142.541142) (xy 393.97432 -142.540736) (xy 390.973056 -142.540736)
			(xy 390.962991 -142.540303) (xy 390.944404 -142.53257) (xy 390.936988 -142.52575) (xy 388.722362 -140.311124)
			(xy 388.714963 -140.304281) (xy 388.696364 -140.296556) (xy 388.686294 -140.296138) (xy 384.785362 -140.296138)
			(xy 384.756152 -140.324078) (xy 384.755136 -140.344398) (xy 384.753333 -140.372028) (xy 384.742746 -140.426375)
			(xy 384.724413 -140.47862) (xy 384.698718 -140.527665) (xy 384.666202 -140.57248) (xy 384.627548 -140.612123)
			(xy 384.583568 -140.64576) (xy 384.535187 -140.672685) (xy 384.483421 -140.692332) (xy 384.429359 -140.704287)
			(xy 384.374136 -140.708301) (xy 384.318913 -140.704287) (xy 384.264851 -140.692332) (xy 384.213085 -140.672685)
			(xy 384.164704 -140.64576) (xy 384.120724 -140.612123) (xy 384.08207 -140.57248) (xy 384.049554 -140.527665)
			(xy 384.023859 -140.47862) (xy 384.005526 -140.426375) (xy 383.994939 -140.372028) (xy 383.993136 -140.344398)
			(xy 383.99212 -140.324078) (xy 383.96291 -140.296138) (xy 368.043714 -140.296138) (xy 368.033652 -140.296578)
			(xy 368.015073 -140.304318) (xy 368.007646 -140.311124) (xy 367.706402 -140.612368) (xy 367.699566 -140.61977)
			(xy 367.691856 -140.638368) (xy 367.691416 -140.648436) (xy 367.691416 -141.029436) (xy 387.891272 -141.029436)
			(xy 387.895343 -140.973814) (xy 387.907469 -140.919377) (xy 387.927392 -140.867286) (xy 387.954688 -140.818651)
			(xy 387.988774 -140.774508) (xy 388.028923 -140.735799) (xy 388.074281 -140.703348) (xy 388.123881 -140.677847)
			(xy 388.176665 -140.65984) (xy 388.231508 -140.64971) (xy 388.287242 -140.647673) (xy 388.342679 -140.653773)
			(xy 388.396636 -140.667879) (xy 388.447965 -140.689691) (xy 388.495571 -140.718745) (xy 388.538439 -140.75442)
			(xy 388.575656 -140.795957) (xy 388.606429 -140.84247) (xy 388.630101 -140.892967) (xy 388.646169 -140.946374)
			(xy 388.654289 -141.00155) (xy 388.654798 -141.029436) (xy 388.654289 -141.057322) (xy 388.646169 -141.112498)
			(xy 388.630101 -141.165905) (xy 388.606429 -141.216402) (xy 388.575656 -141.262915) (xy 388.538439 -141.304452)
			(xy 388.495571 -141.340127) (xy 388.447965 -141.369181) (xy 388.396636 -141.390993) (xy 388.342679 -141.405099)
			(xy 388.287242 -141.411199) (xy 388.231508 -141.409162) (xy 388.176665 -141.399032) (xy 388.123881 -141.381025)
			(xy 388.074281 -141.355524) (xy 388.028923 -141.323073) (xy 387.988774 -141.284364) (xy 387.954688 -141.240221)
			(xy 387.927392 -141.191586) (xy 387.907469 -141.139495) (xy 387.895343 -141.085058) (xy 387.891272 -141.029436)
			(xy 367.691416 -141.029436) (xy 367.691416 -142.748762) (xy 387.818882 -142.748762) (xy 387.822953 -142.69314)
			(xy 387.835079 -142.638703) (xy 387.855002 -142.586612) (xy 387.882298 -142.537977) (xy 387.916384 -142.493834)
			(xy 387.956533 -142.455125) (xy 388.001891 -142.422674) (xy 388.051491 -142.397173) (xy 388.104275 -142.379166)
			(xy 388.159118 -142.369036) (xy 388.214852 -142.366999) (xy 388.270289 -142.373099) (xy 388.324246 -142.387205)
			(xy 388.375575 -142.409017) (xy 388.423181 -142.438071) (xy 388.466049 -142.473746) (xy 388.503266 -142.515283)
			(xy 388.534039 -142.561796) (xy 388.557711 -142.612293) (xy 388.573779 -142.6657) (xy 388.581899 -142.720876)
			(xy 388.582408 -142.748762) (xy 388.581899 -142.776648) (xy 388.573779 -142.831824) (xy 388.557711 -142.885231)
			(xy 388.534039 -142.935728) (xy 388.503266 -142.982241) (xy 388.466049 -143.023778) (xy 388.423181 -143.059453)
			(xy 388.375575 -143.088507) (xy 388.324246 -143.110319) (xy 388.270289 -143.124425) (xy 388.214852 -143.130525)
			(xy 388.159118 -143.128488) (xy 388.104275 -143.118358) (xy 388.051491 -143.100351) (xy 388.001891 -143.07485)
			(xy 387.956533 -143.042399) (xy 387.916384 -143.00369) (xy 387.882298 -142.959547) (xy 387.855002 -142.910912)
			(xy 387.835079 -142.858821) (xy 387.822953 -142.804384) (xy 387.818882 -142.748762) (xy 367.691416 -142.748762)
			(xy 367.691416 -144.039844) (xy 367.691848 -144.04991) (xy 367.699575 -144.068502) (xy 367.706402 -144.075912)
			(xy 369.207034 -145.576544) (xy 369.214432 -145.583391) (xy 369.23303 -145.591122) (xy 369.243102 -145.59153)
			(xy 371.12448 -145.59153) (xy 371.134543 -145.591968) (xy 371.153124 -145.599707) (xy 371.160548 -145.606516)
			(xy 373.211852 -147.65782) (xy 373.219249 -147.664667) (xy 373.237849 -147.672395) (xy 373.24792 -147.672806)
			(xy 389.021066 -147.672806) (xy 390.75741 -147.672806)
		)
		(stroke
			(width 0)
			(type solid)
		)
		(fill yes)
		(layer "B.Cu")
		(net "P12V_NIC6")
	)
	(gr_poly
		(pts
			(xy 43.115484 -146.779234) (xy 45.550074 -146.779234) (xy 45.560137 -146.778796) (xy 45.578715 -146.771055)
			(xy 45.586142 -146.764248) (xy 45.73524 -146.61515) (xy 45.742085 -146.607752) (xy 45.749811 -146.589153)
			(xy 45.750226 -146.579082) (xy 45.750226 -146.511518) (xy 45.749693 -146.501528) (xy 45.741987 -146.483089)
			(xy 45.73524 -146.475704) (xy 45.734732 -146.474942) (xy 45.728038 -146.467536) (xy 45.720436 -146.4491)
			(xy 45.72 -146.439128) (xy 45.72 -142.593822) (xy 45.719466 -142.583833) (xy 45.711759 -142.565395)
			(xy 45.705014 -142.558008) (xy 45.702728 -142.555722) (xy 45.695327 -142.548885) (xy 45.676728 -142.541173)
			(xy 45.66666 -142.540736) (xy 42.673016 -142.540736) (xy 42.662954 -142.540296) (xy 42.644378 -142.532553)
			(xy 42.636948 -142.52575) (xy 40.422322 -140.311124) (xy 40.41492 -140.304287) (xy 40.396322 -140.296577)
			(xy 40.386254 -140.296138) (xy 36.485322 -140.296138) (xy 36.456112 -140.324078) (xy 36.455096 -140.344398)
			(xy 36.453293 -140.372028) (xy 36.442706 -140.426375) (xy 36.424373 -140.47862) (xy 36.398678 -140.527665)
			(xy 36.366162 -140.57248) (xy 36.327508 -140.612123) (xy 36.283528 -140.64576) (xy 36.235147 -140.672685)
			(xy 36.183381 -140.692332) (xy 36.129319 -140.704287) (xy 36.074096 -140.708301) (xy 36.018873 -140.704287)
			(xy 35.964811 -140.692332) (xy 35.913045 -140.672685) (xy 35.864664 -140.64576) (xy 35.820684 -140.612123)
			(xy 35.78203 -140.57248) (xy 35.749514 -140.527665) (xy 35.723819 -140.47862) (xy 35.705486 -140.426375)
			(xy 35.694899 -140.372028) (xy 35.693096 -140.344398) (xy 35.69208 -140.324078) (xy 35.66287 -140.296138)
			(xy 19.743674 -140.296138) (xy 19.733607 -140.296567) (xy 19.715013 -140.304292) (xy 19.707606 -140.311124)
			(xy 19.406362 -140.612368) (xy 19.399519 -140.619767) (xy 19.3918 -140.638366) (xy 19.391376 -140.648436)
			(xy 19.391376 -141.029436) (xy 39.591232 -141.029436) (xy 39.595303 -140.973814) (xy 39.607429 -140.919377)
			(xy 39.627352 -140.867286) (xy 39.654648 -140.818651) (xy 39.688734 -140.774508) (xy 39.728883 -140.735799)
			(xy 39.774241 -140.703348) (xy 39.823841 -140.677847) (xy 39.876625 -140.65984) (xy 39.931468 -140.64971)
			(xy 39.987202 -140.647673) (xy 40.042639 -140.653773) (xy 40.096596 -140.667879) (xy 40.147925 -140.689691)
			(xy 40.195531 -140.718745) (xy 40.238399 -140.75442) (xy 40.275616 -140.795957) (xy 40.306389 -140.84247)
			(xy 40.330061 -140.892967) (xy 40.346129 -140.946374) (xy 40.354249 -141.00155) (xy 40.354758 -141.029436)
			(xy 40.354249 -141.057322) (xy 40.346129 -141.112498) (xy 40.330061 -141.165905) (xy 40.306389 -141.216402)
			(xy 40.275616 -141.262915) (xy 40.238399 -141.304452) (xy 40.195531 -141.340127) (xy 40.147925 -141.369181)
			(xy 40.096596 -141.390993) (xy 40.042639 -141.405099) (xy 39.987202 -141.411199) (xy 39.931468 -141.409162)
			(xy 39.876625 -141.399032) (xy 39.823841 -141.381025) (xy 39.774241 -141.355524) (xy 39.728883 -141.323073)
			(xy 39.688734 -141.284364) (xy 39.654648 -141.240221) (xy 39.627352 -141.191586) (xy 39.607429 -141.139495)
			(xy 39.595303 -141.085058) (xy 39.591232 -141.029436) (xy 19.391376 -141.029436) (xy 19.391376 -142.748762)
			(xy 39.518842 -142.748762) (xy 39.522913 -142.69314) (xy 39.535039 -142.638703) (xy 39.554962 -142.586612)
			(xy 39.582258 -142.537977) (xy 39.616344 -142.493834) (xy 39.656493 -142.455125) (xy 39.701851 -142.422674)
			(xy 39.751451 -142.397173) (xy 39.804235 -142.379166) (xy 39.859078 -142.369036) (xy 39.914812 -142.366999)
			(xy 39.970249 -142.373099) (xy 40.024206 -142.387205) (xy 40.075535 -142.409017) (xy 40.123141 -142.438071)
			(xy 40.166009 -142.473746) (xy 40.203226 -142.515283) (xy 40.233999 -142.561796) (xy 40.257671 -142.612293)
			(xy 40.273739 -142.6657) (xy 40.281859 -142.720876) (xy 40.282368 -142.748762) (xy 40.281859 -142.776648)
			(xy 40.273739 -142.831824) (xy 40.257671 -142.885231) (xy 40.233999 -142.935728) (xy 40.203226 -142.982241)
			(xy 40.166009 -143.023778) (xy 40.123141 -143.059453) (xy 40.075535 -143.088507) (xy 40.024206 -143.110319)
			(xy 39.970249 -143.124425) (xy 39.914812 -143.130525) (xy 39.859078 -143.128488) (xy 39.804235 -143.118358)
			(xy 39.751451 -143.100351) (xy 39.701851 -143.07485) (xy 39.656493 -143.042399) (xy 39.616344 -143.00369)
			(xy 39.582258 -142.959547) (xy 39.554962 -142.910912) (xy 39.535039 -142.858821) (xy 39.522913 -142.804384)
			(xy 39.518842 -142.748762) (xy 19.391376 -142.748762) (xy 19.391376 -144.039844) (xy 19.391806 -144.049911)
			(xy 19.399529 -144.068506) (xy 19.406362 -144.075912) (xy 20.906994 -145.576544) (xy 20.914389 -145.583397)
			(xy 20.932988 -145.591143) (xy 20.943062 -145.59153) (xy 22.82444 -145.59153) (xy 22.834506 -145.591961)
			(xy 22.853097 -145.599689) (xy 22.860508 -145.606516) (xy 24.911812 -147.65782) (xy 24.919207 -147.664673)
			(xy 24.937806 -147.672416) (xy 24.94788 -147.672806) (xy 40.721026 -147.672806) (xy 42.221912 -147.672806)
		)
		(stroke
			(width 0)
			(type solid)
		)
		(fill yes)
		(layer "B.Cu")
		(net "P12V_NIC0")
	)
	(gr_poly
		(pts
			(xy 362.436918 -156.313124) (xy 362.446987 -156.312698) (xy 362.465589 -156.304982) (xy 362.472986 -156.298138)
			(xy 362.824014 -155.94711) (xy 362.830871 -155.939716) (xy 362.838623 -155.921117) (xy 362.839 -155.911042)
			(xy 362.839 -153.418286) (xy 362.838771 -153.411768) (xy 362.83544 -153.399162) (xy 362.832396 -153.393394)
			(xy 362.814752 -153.360991) (xy 362.787004 -153.292624) (xy 362.768247 -153.221266) (xy 362.758791 -153.148091)
			(xy 362.758228 -153.1112) (xy 362.758838 -153.074312) (xy 362.768309 -153.001145) (xy 362.787056 -152.92979)
			(xy 362.814773 -152.861417) (xy 362.832396 -152.829006) (xy 362.835698 -152.823164) (xy 362.839 -152.810718)
			(xy 362.839 -152.611582) (xy 362.835698 -152.599136) (xy 362.832396 -152.593294) (xy 362.814752 -152.560891)
			(xy 362.787004 -152.492524) (xy 362.768247 -152.421166) (xy 362.758791 -152.347991) (xy 362.758228 -152.3111)
			(xy 362.758228 -151.13) (xy 362.758838 -151.093112) (xy 362.768309 -151.019945) (xy 362.787056 -150.94859)
			(xy 362.814773 -150.880217) (xy 362.832396 -150.847806) (xy 362.835456 -150.842042) (xy 362.838812 -150.829436)
			(xy 362.839 -150.822914) (xy 362.839 -149.627082) (xy 362.839427 -149.617013) (xy 362.847146 -149.598414)
			(xy 362.853986 -149.591014) (xy 363.058964 -149.386036) (xy 363.065804 -149.378636) (xy 363.073521 -149.360037)
			(xy 363.07395 -149.349968) (xy 363.07395 -145.596864) (xy 363.074381 -145.586798) (xy 363.08211 -145.568208)
			(xy 363.088936 -145.560796) (xy 363.94771 -144.702022) (xy 363.955108 -144.695175) (xy 363.973706 -144.687441)
			(xy 363.983778 -144.687036) (xy 365.541814 -144.687036) (xy 365.551882 -144.687462) (xy 365.57048 -144.695184)
			(xy 365.577882 -144.702022) (xy 365.771684 -144.895824) (xy 366.266984 -145.391378) (xy 366.27382 -145.39878)
			(xy 366.281528 -145.417378) (xy 366.28197 -145.427446) (xy 366.28197 -146.595592) (xy 366.282391 -146.605664)
			(xy 366.2901 -146.624273) (xy 366.296956 -146.63166) (xy 366.406176 -146.74088) (xy 366.413578 -146.747717)
			(xy 366.432176 -146.755426) (xy 366.442244 -146.755866) (xy 367.65865 -146.755866) (xy 367.668715 -146.755433)
			(xy 367.687304 -146.747702) (xy 367.694718 -146.74088) (xy 367.752122 -146.683476) (xy 367.758973 -146.67608)
			(xy 367.766711 -146.657481) (xy 367.767108 -146.647408) (xy 367.767108 -144.98828) (xy 367.766682 -144.978211)
			(xy 367.758963 -144.959611) (xy 367.752122 -144.952212) (xy 367.223294 -144.423384) (xy 367.216451 -144.415984)
			(xy 367.208723 -144.397386) (xy 367.208308 -144.387316) (xy 367.208308 -141.441424) (xy 367.215674 -141.434058)
			(xy 367.215674 -140.074396) (xy 367.216097 -140.064326) (xy 367.22381 -140.04572) (xy 367.23066 -140.038328)
			(xy 367.648998 -139.61999) (xy 367.656392 -139.613134) (xy 367.674991 -139.605384) (xy 367.685066 -139.605004)
			(xy 368.48796 -139.605004) (xy 368.498025 -139.60457) (xy 368.516614 -139.596841) (xy 368.524028 -139.590018)
			(xy 368.748818 -139.365228) (xy 368.755662 -139.35783) (xy 368.763383 -139.33923) (xy 368.763804 -139.32916)
			(xy 368.763804 -136.35228) (xy 368.763377 -136.342211) (xy 368.755658 -136.323612) (xy 368.748818 -136.316212)
			(xy 368.588798 -136.156192) (xy 368.581399 -136.149347) (xy 368.562801 -136.141614) (xy 368.55273 -136.141206)
			(xy 359.476548 -136.141206) (xy 359.466482 -136.141639) (xy 359.447892 -136.149367) (xy 359.44048 -136.156192)
			(xy 359.174796 -136.421876) (xy 359.167962 -136.429279) (xy 359.160256 -136.447877) (xy 359.15981 -136.457944)
			(xy 359.15981 -138.924788) (xy 360.501928 -138.924788) (xy 360.501928 -138.864852) (xy 360.509751 -138.80543)
			(xy 360.525264 -138.747537) (xy 360.5482 -138.692164) (xy 360.578167 -138.640258) (xy 360.614654 -138.592708)
			(xy 360.657034 -138.550328) (xy 360.704584 -138.513841) (xy 360.75649 -138.483874) (xy 360.811863 -138.460938)
			(xy 360.869756 -138.445425) (xy 360.929178 -138.437602) (xy 360.989114 -138.437602) (xy 361.048536 -138.445425)
			(xy 361.106429 -138.460938) (xy 361.161802 -138.483874) (xy 361.213708 -138.513841) (xy 361.261258 -138.550328)
			(xy 361.303638 -138.592708) (xy 361.340125 -138.640258) (xy 361.370092 -138.692164) (xy 361.393028 -138.747537)
			(xy 361.408541 -138.80543) (xy 361.416364 -138.864852) (xy 361.416854 -138.89482) (xy 361.416364 -138.924788)
			(xy 361.408541 -138.98421) (xy 361.393028 -139.042103) (xy 361.370092 -139.097476) (xy 361.340125 -139.149382)
			(xy 361.303638 -139.196932) (xy 361.261258 -139.239312) (xy 361.213708 -139.275799) (xy 361.161802 -139.305766)
			(xy 361.106429 -139.328702) (xy 361.048536 -139.344215) (xy 360.989114 -139.352038) (xy 360.929178 -139.352038)
			(xy 360.869756 -139.344215) (xy 360.811863 -139.328702) (xy 360.75649 -139.305766) (xy 360.704584 -139.275799)
			(xy 360.657034 -139.239312) (xy 360.614654 -139.196932) (xy 360.578167 -139.149382) (xy 360.5482 -139.097476)
			(xy 360.525264 -139.042103) (xy 360.509751 -138.98421) (xy 360.501928 -138.924788) (xy 359.15981 -138.924788)
			(xy 359.15981 -140.814806) (xy 359.155238 -140.819378) (xy 359.155238 -156.299154) (xy 359.161588 -156.305504)
			(xy 359.18013 -156.313124)
		)
		(stroke
			(width 0)
			(type solid)
		)
		(fill yes)
		(layer "B.Cu")
		(net "P12V_NIC6_R")
	)
	(gr_poly
		(pts
			(arc
				(start 239.526318 -205.606396)
				(mid 239.546502 -205.602214)
				(end 239.563402 -205.590394)
			)
			(xy 239.62106 -205.52918) (xy 239.628172 -205.509876) (xy 239.627664 -205.499208)
			(arc
				(start 239.627156 -205.47711)
				(mid 239.738897 -205.207343)
				(end 240.008664 -205.095602)
			)
			(arc
				(start 240.008664 -205.095602)
				(mid 240.120973 -205.112586)
				(end 240.223294 -205.161896)
			)
			(xy 240.235232 -205.16977) (xy 240.263172 -205.171294)
			(arc
				(start 240.35512 -205.12278)
				(mid 240.374775 -205.104029)
				(end 240.382044 -205.077822)
			)
			(arc
				(start 240.382044 -203.605892)
				(mid 240.416576 -203.409962)
				(end 240.515902 -203.237592)
			)
			(arc
				(start 240.530126 -203.220574)
				(mid 240.54697 -203.201261)
				(end 240.56467 -203.182728)
			)
			(arc
				(start 240.78057 -202.966574)
				(mid 240.791632 -202.950157)
				(end 240.795556 -202.93076)
			)
			(arc
				(start 240.795556 -202.422252)
				(mid 240.79421 -202.410636)
				(end 240.790222 -202.399646)
			)
			(arc
				(start 240.790222 -202.399646)
				(mid 240.754945 -202.301019)
				(end 240.742978 -202.196954)
			)
			(arc
				(start 240.742978 -202.196954)
				(mid 240.754908 -202.092881)
				(end 240.790222 -201.994262)
			)
			(arc
				(start 240.790222 -201.994262)
				(mid 240.794187 -201.983267)
				(end 240.795556 -201.971656)
			)
			(arc
				(start 240.795556 -200.381108)
				(mid 240.791655 -200.361585)
				(end 240.78057 -200.34504)
			)
			(xy 240.643156 -200.207626) (xy 240.636044 -200.20026) (xy 240.617248 -200.19264) (xy 240.57356 -200.19264)
			(xy 240.571274 -200.192894) (xy 240.53038 -200.194672) (xy 240.489486 -200.192894) (xy 240.4872 -200.19264)
			(arc
				(start 239.886236 -200.19264)
				(mid 239.862297 -200.198634)
				(end 239.844072 -200.215246)
			)
			(xy 239.78997 -200.296018) (xy 239.78743 -200.321164)
			(arc
				(start 239.792256 -200.333102)
				(mid 239.813879 -200.404451)
				(end 239.821212 -200.478644)
			)
			(arc
				(start 239.821212 -200.478644)
				(mid 239.439704 -200.860152)
				(end 239.058196 -200.478644)
			)
			(arc
				(start 239.058196 -200.478644)
				(mid 239.06553 -200.404452)
				(end 239.087152 -200.333102)
			)
			(xy 239.091978 -200.321164) (xy 239.089438 -200.296018)
			(arc
				(start 239.035336 -200.215246)
				(mid 239.017074 -200.198703)
				(end 238.993172 -200.19264)
			)
			(arc
				(start 237.593378 -200.19264)
				(mid 237.573855 -200.196541)
				(end 237.55731 -200.207626)
			)
			(xy 237.352586 -200.41235) (xy 237.34522 -200.419462) (xy 237.3376 -200.438258)
			(arc
				(start 237.3376 -202.40371)
				(mid 237.341571 -202.423399)
				(end 237.35284 -202.440032)
			)
			(arc
				(start 237.35284 -202.440032)
				(mid 237.490796 -202.767438)
				(end 237.35284 -203.094844)
			)
			(arc
				(start 237.35284 -203.094844)
				(mid 237.341542 -203.111465)
				(end 237.3376 -203.131166)
			)
			(arc
				(start 237.3376 -205.017878)
				(mid 237.341501 -205.037401)
				(end 237.352586 -205.053946)
			)
			(arc
				(start 237.361984 -205.063344)
				(mid 237.37843 -205.07427)
				(end 237.397798 -205.078076)
			)
			(arc
				(start 238.05896 -205.078076)
				(mid 238.073847 -205.075923)
				(end 238.087408 -205.06944)
			)
			(arc
				(start 238.087408 -205.06944)
				(mid 238.209255 -205.011566)
				(end 238.342678 -204.991716)
			)
			(arc
				(start 238.342678 -204.991716)
				(mid 238.666326 -205.125776)
				(end 238.800386 -205.449424)
			)
			(arc
				(start 238.800386 -205.449424)
				(mid 238.799801 -205.472058)
				(end 238.7981 -205.494636)
			)
			(xy 238.797084 -205.505558) (xy 238.803688 -205.525878)
			(arc
				(start 238.8616 -205.589632)
				(mid 238.87863 -205.601951)
				(end 238.899192 -205.606396)
			)
		)
		(stroke
			(width 0)
			(type solid)
		)
		(fill yes)
		(layer "B.Cu")
		(net "GND")
	)
	(gr_poly
		(pts
			(xy 275.497036 -146.779234) (xy 277.739094 -146.779234) (xy 277.749163 -146.77881) (xy 277.767763 -146.77109)
			(xy 277.775162 -146.764248) (xy 277.934928 -146.604482) (xy 277.941779 -146.597086) (xy 277.949519 -146.578487)
			(xy 277.949914 -146.568414) (xy 277.949914 -146.498818) (xy 277.94938 -146.488829) (xy 277.941673 -146.470391)
			(xy 277.934928 -146.463004) (xy 277.93442 -146.462242) (xy 277.9268 -146.4437) (xy 277.9268 -142.593568)
			(xy 277.926257 -142.583583) (xy 277.918535 -142.56516) (xy 277.911814 -142.557754) (xy 277.909782 -142.555722)
			(xy 277.902384 -142.548876) (xy 277.883785 -142.541145) (xy 277.873714 -142.540736) (xy 274.872958 -142.540736)
			(xy 274.862893 -142.540304) (xy 274.844305 -142.532571) (xy 274.83689 -142.52575) (xy 272.622264 -140.311124)
			(xy 272.614865 -140.304281) (xy 272.596266 -140.296555) (xy 272.586196 -140.296138) (xy 251.943616 -140.296138)
			(xy 251.933553 -140.296577) (xy 251.914975 -140.304317) (xy 251.907548 -140.311124) (xy 251.606304 -140.612368)
			(xy 251.599468 -140.61977) (xy 251.591757 -140.638368) (xy 251.591318 -140.648436) (xy 251.591318 -140.85697)
			(xy 267.812772 -140.85697) (xy 267.816843 -140.801348) (xy 267.828969 -140.746911) (xy 267.848892 -140.69482)
			(xy 267.876188 -140.646185) (xy 267.910274 -140.602042) (xy 267.950423 -140.563333) (xy 267.995781 -140.530882)
			(xy 268.045381 -140.505381) (xy 268.098165 -140.487374) (xy 268.153008 -140.477244) (xy 268.208742 -140.475207)
			(xy 268.264179 -140.481307) (xy 268.318136 -140.495413) (xy 268.369465 -140.517225) (xy 268.417071 -140.546279)
			(xy 268.459939 -140.581954) (xy 268.497156 -140.623491) (xy 268.527929 -140.670004) (xy 268.551601 -140.720501)
			(xy 268.567669 -140.773908) (xy 268.575789 -140.829084) (xy 268.576298 -140.85697) (xy 268.575789 -140.884856)
			(xy 268.567669 -140.940032) (xy 268.551601 -140.993439) (xy 268.534726 -141.029436) (xy 271.791174 -141.029436)
			(xy 271.795245 -140.973814) (xy 271.807371 -140.919377) (xy 271.827294 -140.867286) (xy 271.85459 -140.818651)
			(xy 271.888676 -140.774508) (xy 271.928825 -140.735799) (xy 271.974183 -140.703348) (xy 272.023783 -140.677847)
			(xy 272.076567 -140.65984) (xy 272.13141 -140.64971) (xy 272.187144 -140.647673) (xy 272.242581 -140.653773)
			(xy 272.296538 -140.667879) (xy 272.347867 -140.689691) (xy 272.395473 -140.718745) (xy 272.438341 -140.75442)
			(xy 272.475558 -140.795957) (xy 272.506331 -140.84247) (xy 272.530003 -140.892967) (xy 272.546071 -140.946374)
			(xy 272.554191 -141.00155) (xy 272.5547 -141.029436) (xy 272.554191 -141.057322) (xy 272.546071 -141.112498)
			(xy 272.530003 -141.165905) (xy 272.506331 -141.216402) (xy 272.475558 -141.262915) (xy 272.438341 -141.304452)
			(xy 272.395473 -141.340127) (xy 272.347867 -141.369181) (xy 272.296538 -141.390993) (xy 272.242581 -141.405099)
			(xy 272.187144 -141.411199) (xy 272.13141 -141.409162) (xy 272.076567 -141.399032) (xy 272.023783 -141.381025)
			(xy 271.974183 -141.355524) (xy 271.928825 -141.323073) (xy 271.888676 -141.284364) (xy 271.85459 -141.240221)
			(xy 271.827294 -141.191586) (xy 271.807371 -141.139495) (xy 271.795245 -141.085058) (xy 271.791174 -141.029436)
			(xy 268.534726 -141.029436) (xy 268.527929 -141.043936) (xy 268.497156 -141.090449) (xy 268.459939 -141.131986)
			(xy 268.417071 -141.167661) (xy 268.369465 -141.196715) (xy 268.318136 -141.218527) (xy 268.264179 -141.232633)
			(xy 268.208742 -141.238733) (xy 268.153008 -141.236696) (xy 268.098165 -141.226566) (xy 268.045381 -141.208559)
			(xy 267.995781 -141.183058) (xy 267.950423 -141.150607) (xy 267.910274 -141.111898) (xy 267.876188 -141.067755)
			(xy 267.848892 -141.01912) (xy 267.828969 -140.967029) (xy 267.816843 -140.912592) (xy 267.812772 -140.85697)
			(xy 251.591318 -140.85697) (xy 251.591318 -142.748762) (xy 271.718784 -142.748762) (xy 271.722855 -142.69314)
			(xy 271.734981 -142.638703) (xy 271.754904 -142.586612) (xy 271.7822 -142.537977) (xy 271.816286 -142.493834)
			(xy 271.856435 -142.455125) (xy 271.901793 -142.422674) (xy 271.951393 -142.397173) (xy 272.004177 -142.379166)
			(xy 272.05902 -142.369036) (xy 272.114754 -142.366999) (xy 272.170191 -142.373099) (xy 272.224148 -142.387205)
			(xy 272.275477 -142.409017) (xy 272.323083 -142.438071) (xy 272.365951 -142.473746) (xy 272.403168 -142.515283)
			(xy 272.433941 -142.561796) (xy 272.457613 -142.612293) (xy 272.473681 -142.6657) (xy 272.481801 -142.720876)
			(xy 272.48231 -142.748762) (xy 272.481801 -142.776648) (xy 272.473681 -142.831824) (xy 272.457613 -142.885231)
			(xy 272.433941 -142.935728) (xy 272.403168 -142.982241) (xy 272.365951 -143.023778) (xy 272.323083 -143.059453)
			(xy 272.275477 -143.088507) (xy 272.224148 -143.110319) (xy 272.170191 -143.124425) (xy 272.114754 -143.130525)
			(xy 272.05902 -143.128488) (xy 272.004177 -143.118358) (xy 271.951393 -143.100351) (xy 271.901793 -143.07485)
			(xy 271.856435 -143.042399) (xy 271.816286 -143.00369) (xy 271.7822 -142.959547) (xy 271.754904 -142.910912)
			(xy 271.734981 -142.858821) (xy 271.722855 -142.804384) (xy 271.718784 -142.748762) (xy 251.591318 -142.748762)
			(xy 251.591318 -144.039844) (xy 251.59175 -144.04991) (xy 251.599477 -144.068501) (xy 251.606304 -144.075912)
			(xy 253.106936 -145.576544) (xy 253.114334 -145.583391) (xy 253.132933 -145.591121) (xy 253.143004 -145.59153)
			(xy 255.024382 -145.59153) (xy 255.034445 -145.591969) (xy 255.053025 -145.599707) (xy 255.06045 -145.606516)
			(xy 257.111754 -147.65782) (xy 257.119151 -147.664667) (xy 257.137751 -147.672394) (xy 257.147822 -147.672806)
			(xy 272.920968 -147.672806) (xy 274.603464 -147.672806)
		)
		(stroke
			(width 0)
			(type solid)
		)
		(fill yes)
		(layer "B.Cu")
		(net "P12V_NIC4")
	)
	(gr_poly
		(pts
			(arc
				(start 341.761826 -221.422722)
				(mid 341.781213 -221.418772)
				(end 341.79764 -221.407736)
			)
			(arc
				(start 341.939372 -221.266258)
				(mid 341.955789 -221.255196)
				(end 341.975186 -221.251272)
			)
			(arc
				(start 342.21166 -221.251272)
				(mid 342.231047 -221.255222)
				(end 342.247474 -221.266258)
			)
			(arc
				(start 342.325452 -221.343982)
				(mid 342.341869 -221.355044)
				(end 342.361266 -221.358968)
			)
			(arc
				(start 342.625426 -221.358968)
				(mid 342.644813 -221.355018)
				(end 342.66124 -221.343982)
			)
			(arc
				(start 342.739218 -221.266258)
				(mid 342.755635 -221.255196)
				(end 342.775032 -221.251272)
			)
			(arc
				(start 343.011506 -221.251272)
				(mid 343.030893 -221.255222)
				(end 343.04732 -221.266258)
			)
			(arc
				(start 343.178892 -221.397576)
				(mid 343.195309 -221.408638)
				(end 343.214706 -221.412562)
			)
			(arc
				(start 343.371678 -221.412562)
				(mid 343.391065 -221.408612)
				(end 343.407492 -221.397576)
			)
			(arc
				(start 343.539064 -221.266258)
				(mid 343.555481 -221.255196)
				(end 343.574878 -221.251272)
			)
			(arc
				(start 343.811352 -221.251272)
				(mid 343.830739 -221.255222)
				(end 343.847166 -221.266258)
			)
			(arc
				(start 343.987628 -221.406466)
				(mid 344.004045 -221.417528)
				(end 344.023442 -221.421452)
			)
			(arc
				(start 344.162888 -221.421452)
				(mid 344.182275 -221.417502)
				(end 344.198702 -221.406466)
			)
			(arc
				(start 344.339164 -221.266258)
				(mid 344.355581 -221.255196)
				(end 344.374978 -221.251272)
			)
			(arc
				(start 344.437716 -221.251272)
				(mid 344.455986 -221.247873)
				(end 344.471752 -221.238064)
			)
			(xy 344.529664 -221.184724) (xy 344.537792 -221.167706)
			(arc
				(start 344.538808 -221.158054)
				(mid 344.589099 -221.002122)
				(end 344.703908 -220.885258)
			)
			(xy 344.703908 -220.69171)
			(arc
				(start 344.693748 -220.68155)
				(mid 344.647069 -220.643797)
				(end 344.607388 -220.598746)
			)
			(xy 344.566748 -220.578172) (xy 344.420444 -220.578172)
			(arc
				(start 344.379804 -220.598746)
				(mid 344.093546 -220.743025)
				(end 343.807288 -220.598746)
			)
			(xy 343.766902 -220.578172) (xy 343.60485 -220.578172) (xy 343.546176 -220.486224)
			(arc
				(start 343.546176 -220.32976)
				(mid 343.541453 -220.313668)
				(end 343.531698 -220.300042)
			)
			(arc
				(start 343.422986 -220.191584)
				(mid 343.406569 -220.180522)
				(end 343.387172 -220.176598)
			)
			(arc
				(start 343.199466 -220.176598)
				(mid 343.180079 -220.180548)
				(end 343.163652 -220.191584)
			)
			(xy 343.054686 -220.300296) (xy 343.051384 -220.303852) (xy 343.051384 -220.517466) (xy 342.979502 -220.589348)
			(xy 342.783922 -220.589348) (xy 342.7222 -220.527626) (xy 342.7222 -220.29039)
			(arc
				(start 342.62314 -220.191584)
				(mid 342.606723 -220.180522)
				(end 342.587326 -220.176598)
			)
			(arc
				(start 342.39962 -220.176598)
				(mid 342.380233 -220.180548)
				(end 342.363806 -220.191584)
			)
			(xy 342.25484 -220.300296) (xy 342.252554 -220.302836) (xy 342.252554 -220.521784) (xy 342.195912 -220.578426)
			(xy 342.153494 -220.578426) (xy 341.964772 -220.578426) (xy 341.921084 -220.534738) (xy 341.921084 -220.28912)
			(arc
				(start 341.823294 -220.191584)
				(mid 341.806877 -220.180522)
				(end 341.78748 -220.176598)
			)
			(arc
				(start 341.599774 -220.176598)
				(mid 341.580387 -220.180548)
				(end 341.56396 -220.191584)
			)
			(arc
				(start 341.454994 -220.300296)
				(mid 341.443883 -220.31683)
				(end 341.440008 -220.336364)
			)
			(xy 341.440008 -220.471492) (xy 341.440008 -220.524832) (xy 341.376762 -220.588078) (xy 341.201502 -220.588078)
			(arc
				(start 341.18042 -220.598746)
				(mid 340.894162 -220.743025)
				(end 340.607904 -220.598746)
			)
			(xy 340.567264 -220.578172) (xy 340.42096 -220.578172)
			(arc
				(start 340.38032 -220.598746)
				(mid 340.338124 -220.646327)
				(end 340.288118 -220.685614)
			)
			(arc
				(start 340.288118 -220.888052)
				(mid 340.39999 -221.004313)
				(end 340.4489 -221.158054)
			)
			(xy 340.449916 -221.167706) (xy 340.458044 -221.184724)
			(arc
				(start 340.515956 -221.238064)
				(mid 340.531754 -221.24779)
				(end 340.549992 -221.251272)
			)
			(arc
				(start 340.611968 -221.251272)
				(mid 340.631355 -221.255222)
				(end 340.647782 -221.266258)
			)
			(arc
				(start 340.777068 -221.39529)
				(mid 340.793485 -221.406352)
				(end 340.812882 -221.410276)
			)
			(arc
				(start 340.974426 -221.410276)
				(mid 340.993813 -221.406326)
				(end 341.01024 -221.39529)
			)
			(arc
				(start 341.139526 -221.266258)
				(mid 341.155943 -221.255196)
				(end 341.17534 -221.251272)
			)
			(arc
				(start 341.411814 -221.251272)
				(mid 341.431201 -221.255222)
				(end 341.447628 -221.266258)
			)
			(arc
				(start 341.58936 -221.407736)
				(mid 341.605777 -221.418798)
				(end 341.625174 -221.422722)
			)
		)
		(stroke
			(width 0)
			(type solid)
		)
		(fill yes)
		(layer "B.Cu")
		(net "P3V3_VCC_FPGA_CORE")
	)
	(gr_poly
		(pts
			(xy 301.55642 -288.54527) (xy 301.561233 -288.545149) (xy 301.570692 -288.543362) (xy 301.575216 -288.541714)
			(xy 301.600616 -288.531554) (xy 301.607474 -288.525966) (xy 301.6271 -288.509439) (xy 301.67047 -288.482027)
			(xy 301.717556 -288.461647) (xy 301.767225 -288.448789) (xy 301.818285 -288.44376) (xy 301.869509 -288.446682)
			(xy 301.919665 -288.457485) (xy 301.94377 -288.466276) (xy 301.952406 -288.469832) (xy 302.185578 -288.469832)
			(xy 302.203677 -288.470431) (xy 302.238115 -288.481571) (xy 302.253142 -288.491676) (xy 302.259785 -288.496226)
			(xy 302.275068 -288.501264) (xy 302.283114 -288.501582) (xy 302.316642 -288.501582) (xy 302.324678 -288.501218)
			(xy 302.339941 -288.496169) (xy 302.346614 -288.491676) (xy 302.361633 -288.481554) (xy 302.396076 -288.470411)
			(xy 302.414178 -288.469832) (xy 302.64735 -288.469832) (xy 302.655986 -288.466276) (xy 302.680102 -288.45753)
			(xy 302.730254 -288.44675) (xy 302.781468 -288.44384) (xy 302.832518 -288.44887) (xy 302.88218 -288.46172)
			(xy 302.929263 -288.482082) (xy 302.972638 -288.509467) (xy 302.992282 -288.525966) (xy 302.99914 -288.531554)
			(xy 303.02454 -288.541714) (xy 303.029053 -288.543402) (xy 303.038518 -288.545196) (xy 303.043336 -288.54527)
			(xy 303.45634 -288.54527) (xy 303.461153 -288.545147) (xy 303.470611 -288.543357) (xy 303.475136 -288.541714)
			(xy 303.500282 -288.531808) (xy 303.506886 -288.525966) (xy 303.526789 -288.509176) (xy 303.57085 -288.481431)
			(xy 303.618719 -288.460946) (xy 303.66921 -288.448227) (xy 303.6951 -288.445448) (xy 303.704244 -288.444686)
			(xy 303.720246 -288.437066) (xy 304.048414 -288.108898) (xy 304.055814 -288.102054) (xy 304.074411 -288.094325)
			(xy 304.084482 -288.093912) (xy 305.07305 -288.093912) (xy 305.081432 -288.09315) (xy 305.089036 -288.091633)
			(xy 305.102868 -288.084645) (xy 305.10861 -288.079434) (xy 305.188874 -287.99917) (xy 305.195719 -287.991771)
			(xy 305.203446 -287.973173) (xy 305.20386 -287.963102) (xy 305.20386 -286.257238) (xy 305.203446 -286.247215)
			(xy 305.195782 -286.228692) (xy 305.181607 -286.214517) (xy 305.163083 -286.206853) (xy 305.15306 -286.206438)
			(xy 303.186592 -286.206438) (xy 303.167796 -286.214058) (xy 303.160684 -286.221424) (xy 303.04105 -286.341058)
			(xy 303.040542 -286.341058) (xy 302.939958 -286.441896) (xy 302.93245 -286.450303) (xy 302.924947 -286.471529)
			(xy 302.92548 -286.48279) (xy 302.933354 -286.561022) (xy 302.935083 -286.572242) (xy 302.946806 -286.59165)
			(xy 302.95596 -286.59836) (xy 302.956214 -286.59836) (xy 302.978749 -286.613805) (xy 303.01889 -286.650858)
			(xy 303.052392 -286.694008) (xy 303.078344 -286.742079) (xy 303.096038 -286.793762) (xy 303.104993 -286.847651)
			(xy 303.105566 -286.874966) (xy 303.105056 -286.900953) (xy 303.096926 -286.952288) (xy 303.080865 -287.001718)
			(xy 303.057269 -287.048028) (xy 303.026719 -287.090076) (xy 302.989968 -287.126827) (xy 302.94792 -287.157377)
			(xy 302.90161 -287.180973) (xy 302.85218 -287.197034) (xy 302.800845 -287.205164) (xy 302.748871 -287.205164)
			(xy 302.697536 -287.197034) (xy 302.648106 -287.180973) (xy 302.601796 -287.157377) (xy 302.559748 -287.126827)
			(xy 302.522997 -287.090076) (xy 302.492447 -287.048028) (xy 302.468851 -287.001718) (xy 302.45279 -286.952288)
			(xy 302.44466 -286.900953) (xy 302.44415 -286.874966) (xy 302.444547 -286.85198) (xy 302.450919 -286.806451)
			(xy 302.463534 -286.762243) (xy 302.48215 -286.720208) (xy 302.493934 -286.700468) (xy 302.5013 -286.68853)
			(xy 302.502062 -286.661098) (xy 302.452024 -286.571182) (xy 302.447319 -286.563445) (xy 302.433592 -286.551654)
			(xy 302.416622 -286.545372) (xy 302.407574 -286.54502) (xy 301.218092 -286.54502) (xy 301.208073 -286.545441)
			(xy 301.189563 -286.553114) (xy 301.175398 -286.567286) (xy 301.167736 -286.585801) (xy 301.167292 -286.59582)
			(xy 301.167292 -286.720534) (xy 301.172372 -286.731202) (xy 301.182766 -286.753727) (xy 301.197437 -286.801116)
			(xy 301.204858 -286.850166) (xy 301.204862 -286.899773) (xy 301.197451 -286.948824) (xy 301.182789 -286.996216)
			(xy 301.172372 -287.01873) (xy 301.167292 -287.029398) (xy 301.167292 -287.670494) (xy 301.172372 -287.681162)
			(xy 301.182762 -287.703687) (xy 301.197423 -287.751075) (xy 301.204836 -287.800121) (xy 301.204832 -287.849725)
			(xy 301.204803 -287.849915) (xy 302.45734 -287.849915) (xy 302.45734 -287.799937) (xy 302.465159 -287.750574)
			(xy 302.480603 -287.703042) (xy 302.503293 -287.65851) (xy 302.532669 -287.618077) (xy 302.568009 -287.582737)
			(xy 302.608442 -287.553361) (xy 302.652974 -287.530671) (xy 302.700506 -287.515227) (xy 302.749869 -287.507408)
			(xy 302.799847 -287.507408) (xy 302.84921 -287.515227) (xy 302.896742 -287.530671) (xy 302.941274 -287.553361)
			(xy 302.981707 -287.582737) (xy 303.017047 -287.618077) (xy 303.046423 -287.65851) (xy 303.069113 -287.703042)
			(xy 303.084557 -287.750574) (xy 303.092376 -287.799937) (xy 303.092866 -287.824926) (xy 303.092376 -287.849915)
			(xy 303.084557 -287.899278) (xy 303.069113 -287.94681) (xy 303.046423 -287.991342) (xy 303.017047 -288.031775)
			(xy 302.981707 -288.067115) (xy 302.941274 -288.096491) (xy 302.896742 -288.119181) (xy 302.84921 -288.134625)
			(xy 302.799847 -288.142444) (xy 302.749869 -288.142444) (xy 302.700506 -288.134625) (xy 302.652974 -288.119181)
			(xy 302.608442 -288.096491) (xy 302.568009 -288.067115) (xy 302.532669 -288.031775) (xy 302.503293 -287.991342)
			(xy 302.480603 -287.94681) (xy 302.465159 -287.899278) (xy 302.45734 -287.849915) (xy 301.204803 -287.849915)
			(xy 301.197413 -287.898771) (xy 301.182745 -287.946157) (xy 301.172372 -287.96869) (xy 301.167292 -287.979358)
			(xy 301.167292 -288.364168) (xy 301.167727 -288.374233) (xy 301.175458 -288.39282) (xy 301.182278 -288.400236)
			(xy 301.312326 -288.530284) (xy 301.319725 -288.537128) (xy 301.338323 -288.544856) (xy 301.348394 -288.54527)
		)
		(stroke
			(width 0)
			(type solid)
		)
		(fill yes)
		(layer "B.Cu")
		(net "P1V8_VDDA_PEX2")
	)
	(gr_poly
		(pts
			(xy 464.101942 -398.100042) (xy 464.101441 -398.029227) (xy 464.093428 -397.887824) (xy 464.077428 -397.7471)
			(xy 464.053493 -397.607507) (xy 464.021698 -397.469492) (xy 463.982146 -397.333496) (xy 463.934963 -397.199957)
			(xy 463.880301 -397.0693) (xy 463.818335 -396.941945) (xy 463.749262 -396.8183) (xy 463.673305 -396.698761)
			(xy 463.590707 -396.58371) (xy 463.501732 -396.473517) (xy 463.406666 -396.368533) (xy 463.305812 -396.269097)
			(xy 463.199494 -396.175525) (xy 463.088053 -396.088119) (xy 462.971845 -396.007157) (xy 462.851243 -395.932899)
			(xy 462.726632 -395.865583) (xy 462.598413 -395.805425) (xy 462.466996 -395.752618) (xy 462.332802 -395.707329)
			(xy 462.196261 -395.669706) (xy 462.057809 -395.639867) (xy 461.917892 -395.617909) (xy 461.776956 -395.603903)
			(xy 461.635453 -395.597892) (xy 461.493837 -395.599896) (xy 461.352561 -395.609909) (xy 461.212078 -395.627898)
			(xy 461.072838 -395.653807) (xy 460.935287 -395.687551) (xy 460.799864 -395.729024) (xy 460.667006 -395.778092)
			(xy 460.537136 -395.834597) (xy 460.41067 -395.89836) (xy 460.288015 -395.969175) (xy 460.169562 -396.046816)
			(xy 460.055692 -396.131034) (xy 459.946769 -396.221559) (xy 459.843142 -396.318102) (xy 459.745142 -396.420352)
			(xy 459.653085 -396.527984) (xy 459.567264 -396.640651) (xy 459.487954 -396.757993) (xy 459.415411 -396.879634)
			(xy 459.349865 -397.005184) (xy 459.291527 -397.134241) (xy 459.240585 -397.266393) (xy 459.1972 -397.401214)
			(xy 459.161512 -397.538274) (xy 459.133636 -397.677134) (xy 459.11366 -397.817349) (xy 459.101649 -397.958469)
			(xy 459.097641 -398.100042) (xy 459.539604 -398.100042) (xy 459.543589 -397.971945) (xy 459.555531 -397.844344)
			(xy 459.575383 -397.717732) (xy 459.603067 -397.592599) (xy 459.638478 -397.46943) (xy 459.681477 -397.3487)
			(xy 459.731899 -397.230877) (xy 459.789548 -397.116416) (xy 459.854202 -397.005761) (xy 459.92561 -396.89934)
			(xy 460.003497 -396.797564) (xy 460.08756 -396.700827) (xy 460.177474 -396.609503) (xy 460.272892 -396.523946)
			(xy 460.373445 -396.444486) (xy 460.478743 -396.371431) (xy 460.588379 -396.305064) (xy 460.701929 -396.245642)
			(xy 460.818954 -396.193394) (xy 460.939 -396.148522) (xy 461.061604 -396.1112) (xy 461.186291 -396.081573)
			(xy 461.312579 -396.059755) (xy 461.439979 -396.04583) (xy 461.567998 -396.039853) (xy 461.696142 -396.041846)
			(xy 461.823913 -396.051802) (xy 461.950818 -396.069682) (xy 462.076367 -396.095417) (xy 462.200072 -396.128908)
			(xy 462.321456 -396.170024) (xy 462.440049 -396.218608) (xy 462.555392 -396.27447) (xy 462.667039 -396.337395)
			(xy 462.774558 -396.40714) (xy 462.877534 -396.483434) (xy 462.975566 -396.565982) (xy 463.068277 -396.654465)
			(xy 463.155308 -396.748541) (xy 463.236322 -396.847846) (xy 463.311005 -396.951995) (xy 463.379069 -397.060586)
			(xy 463.440251 -397.173198) (xy 463.494312 -397.289396) (xy 463.541046 -397.408731) (xy 463.58027 -397.530739)
			(xy 463.611832 -397.654951) (xy 463.635612 -397.780884) (xy 463.651516 -397.908052) (xy 463.659484 -398.035963)
			(xy 463.659982 -398.100042) (xy 463.659484 -398.164121) (xy 463.651516 -398.292032) (xy 463.635612 -398.4192)
			(xy 463.611832 -398.545133) (xy 463.58027 -398.669345) (xy 463.541046 -398.791353) (xy 463.494312 -398.910688)
			(xy 463.440251 -399.026886) (xy 463.379069 -399.139498) (xy 463.311005 -399.248089) (xy 463.236322 -399.352238)
			(xy 463.155308 -399.451543) (xy 463.068277 -399.545619) (xy 462.975566 -399.634102) (xy 462.877534 -399.71665)
			(xy 462.774558 -399.792944) (xy 462.667039 -399.862689) (xy 462.555392 -399.925614) (xy 462.440049 -399.981476)
			(xy 462.321456 -400.03006) (xy 462.200072 -400.071176) (xy 462.076367 -400.104667) (xy 461.950818 -400.130402)
			(xy 461.823913 -400.148282) (xy 461.696142 -400.158238) (xy 461.567998 -400.160231) (xy 461.439979 -400.154254)
			(xy 461.312579 -400.140329) (xy 461.186291 -400.118511) (xy 461.061604 -400.088884) (xy 460.939 -400.051562)
			(xy 460.818954 -400.00669) (xy 460.701929 -399.954442) (xy 460.588379 -399.89502) (xy 460.478743 -399.828653)
			(xy 460.373445 -399.755598) (xy 460.272892 -399.676138) (xy 460.177474 -399.590581) (xy 460.08756 -399.499257)
			(xy 460.003497 -399.40252) (xy 459.92561 -399.300744) (xy 459.854202 -399.194323) (xy 459.789548 -399.083668)
			(xy 459.731899 -398.969207) (xy 459.681477 -398.851384) (xy 459.638478 -398.730654) (xy 459.603067 -398.607485)
			(xy 459.575383 -398.482352) (xy 459.555531 -398.35574) (xy 459.543589 -398.228139) (xy 459.539604 -398.100042)
			(xy 459.097641 -398.100042) (xy 459.101649 -398.241615) (xy 459.11366 -398.382735) (xy 459.133636 -398.52295)
			(xy 459.161512 -398.66181) (xy 459.1972 -398.79887) (xy 459.240585 -398.933691) (xy 459.291527 -399.065843)
			(xy 459.349865 -399.1949) (xy 459.415411 -399.32045) (xy 459.487954 -399.442091) (xy 459.567264 -399.559433)
			(xy 459.653085 -399.6721) (xy 459.745142 -399.779732) (xy 459.843142 -399.881982) (xy 459.946769 -399.978525)
			(xy 460.055692 -400.06905) (xy 460.169562 -400.153268) (xy 460.288015 -400.230909) (xy 460.41067 -400.301724)
			(xy 460.537136 -400.365487) (xy 460.667006 -400.421992) (xy 460.799864 -400.47106) (xy 460.935287 -400.512533)
			(xy 461.072838 -400.546277) (xy 461.212078 -400.572186) (xy 461.352561 -400.590175) (xy 461.493837 -400.600188)
			(xy 461.635453 -400.602192) (xy 461.776956 -400.596181) (xy 461.917892 -400.582175) (xy 462.057809 -400.560217)
			(xy 462.196261 -400.530378) (xy 462.332802 -400.492755) (xy 462.466996 -400.447466) (xy 462.598413 -400.394659)
			(xy 462.726632 -400.334501) (xy 462.851243 -400.267185) (xy 462.971845 -400.192927) (xy 463.088053 -400.111965)
			(xy 463.199494 -400.024559) (xy 463.305812 -399.930987) (xy 463.406666 -399.831551) (xy 463.501732 -399.726567)
			(xy 463.590707 -399.616374) (xy 463.673305 -399.501323) (xy 463.749262 -399.381784) (xy 463.818335 -399.258139)
			(xy 463.880301 -399.130784) (xy 463.934963 -399.000127) (xy 463.982146 -398.866588) (xy 464.021698 -398.730592)
			(xy 464.053493 -398.592577) (xy 464.077428 -398.452984) (xy 464.093428 -398.31226) (xy 464.101441 -398.170857)
		)
		(stroke
			(width 0)
			(type solid)
		)
		(fill yes)
		(layer "B.Cu")
		(net "Net_20")
	)
	(gr_poly
		(pts
			(xy 184.189116 -301.471838) (xy 184.198994 -301.471379) (xy 184.217296 -301.463941) (xy 184.224676 -301.45736)
			(xy 184.22493 -301.457106) (xy 184.43829 -301.243746) (xy 184.43956 -301.242476) (xy 184.448196 -301.233332)
			(xy 184.4548 -301.208948) (xy 184.452006 -301.196756) (xy 184.448332 -301.179077) (xy 184.444386 -301.143183)
			(xy 184.444132 -301.125128) (xy 184.444132 -301.124874) (xy 184.444611 -301.099627) (xy 184.452292 -301.049721)
			(xy 184.467471 -301.001562) (xy 184.489795 -300.956271) (xy 184.518746 -300.914901) (xy 184.55365 -300.878413)
			(xy 184.593696 -300.847656) (xy 184.615582 -300.83506) (xy 184.628028 -300.828202) (xy 184.641998 -300.80458)
			(xy 184.641998 -300.495208) (xy 184.628028 -300.471586) (xy 184.615582 -300.464728) (xy 184.593682 -300.452153)
			(xy 184.553634 -300.421392) (xy 184.518729 -300.3849) (xy 184.489777 -300.343525) (xy 184.467453 -300.29823)
			(xy 184.452275 -300.250067) (xy 184.444596 -300.200156) (xy 184.444595 -300.149658) (xy 184.452272 -300.099746)
			(xy 184.467448 -300.051583) (xy 184.48977 -300.006286) (xy 184.51872 -299.96491) (xy 184.553624 -299.928417)
			(xy 184.593671 -299.897655) (xy 184.615582 -299.8851) (xy 184.628028 -299.878242) (xy 184.641998 -299.85462)
			(xy 184.641998 -299.554392) (xy 184.641602 -299.544605) (xy 184.634337 -299.526436) (xy 184.620764 -299.51234)
			(xy 184.612026 -299.50791) (xy 184.58561 -299.496226) (xy 184.564158 -299.480623) (xy 184.526056 -299.443724)
			(xy 184.494336 -299.401213) (xy 184.46981 -299.354182) (xy 184.45311 -299.303839) (xy 184.444663 -299.251475)
			(xy 184.444132 -299.224954) (xy 184.444132 -299.224446) (xy 184.44451 -299.202461) (xy 184.450373 -299.158882)
			(xy 184.455816 -299.137578) (xy 184.455816 -299.137324) (xy 184.457356 -299.130944) (xy 184.457482 -299.117825)
			(xy 184.45607 -299.111416) (xy 184.454191 -299.104931) (xy 184.447502 -299.093207) (xy 184.442862 -299.088302)
			(xy 184.422034 -299.067474) (xy 184.418462 -299.064073) (xy 184.410274 -299.058579) (xy 184.405778 -299.056552)
			(xy 184.396126 -299.052488) (xy 183.880506 -299.052488) (xy 183.865962 -299.052037) (xy 183.837647 -299.04536)
			(xy 183.811571 -299.032462) (xy 183.78908 -299.014011) (xy 183.779922 -299.002704) (xy 183.779668 -299.00245)
			(xy 183.779414 -299.002196) (xy 183.775773 -298.997812) (xy 183.766925 -298.990637) (xy 183.761888 -298.987972)
			(xy 183.756562 -298.985509) (xy 183.745147 -298.982811) (xy 183.739282 -298.982638) (xy 166.26332 -298.982638)
			(xy 166.244524 -298.990258) (xy 166.237412 -298.997624) (xy 166.105332 -299.129704) (xy 166.097966 -299.153326)
			(xy 166.100252 -299.165772) (xy 166.10275 -299.18044) (xy 166.105416 -299.210076) (xy 166.105586 -299.224954)
			(xy 166.105586 -299.225208) (xy 166.105034 -299.25178) (xy 166.096498 -299.304236) (xy 166.079695 -299.354656)
			(xy 166.055055 -299.401744) (xy 166.039546 -299.423328) (xy 166.039292 -299.423582) (xy 166.03472 -299.429932)
			(xy 166.026846 -299.452284) (xy 166.025461 -299.456403) (xy 166.023937 -299.464958) (xy 166.023798 -299.469302)
			(xy 166.023798 -299.930566) (xy 166.023905 -299.934913) (xy 166.025434 -299.943472) (xy 166.026846 -299.947584)
			(xy 166.03472 -299.969936) (xy 166.039292 -299.976286) (xy 166.039546 -299.97654) (xy 166.055064 -299.99812)
			(xy 166.079731 -300.0452) (xy 166.09654 -300.095622) (xy 166.105058 -300.148085) (xy 166.105586 -300.17466)
			(xy 166.105586 -300.175168) (xy 166.105029 -300.201739) (xy 166.096485 -300.25419) (xy 166.084213 -300.290992)
			(xy 166.289228 -300.290992) (xy 166.289228 -300.049946) (xy 166.289659 -300.025949) (xy 166.297132 -299.978541)
			(xy 166.311949 -299.932891) (xy 166.333741 -299.890131) (xy 166.36197 -299.851317) (xy 166.378636 -299.834046)
			(xy 166.558722 -299.65396) (xy 166.576012 -299.637321) (xy 166.614843 -299.609134) (xy 166.657602 -299.587361)
			(xy 166.703239 -299.572537) (xy 166.75063 -299.565027) (xy 166.774622 -299.564552) (xy 183.73979 -299.564552)
			(xy 183.763788 -299.564953) (xy 183.811198 -299.572433) (xy 183.856848 -299.587256) (xy 183.899608 -299.609055)
			(xy 183.93842 -299.637291) (xy 183.95569 -299.65396) (xy 183.95569 -299.654214) (xy 184.19699 -299.895514)
			(xy 184.197244 -299.895514) (xy 184.21388 -299.912807) (xy 184.242067 -299.951637) (xy 184.263841 -299.994396)
			(xy 184.278665 -300.040031) (xy 184.286176 -300.087423) (xy 184.286652 -300.111414) (xy 184.286652 -300.299374)
			(xy 184.286239 -300.323372) (xy 184.278762 -300.370781) (xy 184.263942 -300.416431) (xy 184.242146 -300.459191)
			(xy 184.213912 -300.498004) (xy 184.197244 -300.515274) (xy 184.150762 -300.561756) (xy 184.133438 -300.578358)
			(xy 184.094615 -300.606549) (xy 184.051865 -300.628329) (xy 184.006237 -300.643161) (xy 183.958851 -300.650682)
			(xy 183.934862 -300.651164) (xy 166.6494 -300.651164) (xy 166.625404 -300.650701) (xy 166.577997 -300.643236)
			(xy 166.532348 -300.628427) (xy 166.489587 -300.606642) (xy 166.450772 -300.578419) (xy 166.4335 -300.561756)
			(xy 166.378636 -300.506892) (xy 166.361999 -300.4896) (xy 166.333813 -300.450769) (xy 166.31204 -300.40801)
			(xy 166.297216 -300.362375) (xy 166.289704 -300.314983) (xy 166.289228 -300.290992) (xy 166.084213 -300.290992)
			(xy 166.079674 -300.304604) (xy 166.055029 -300.351686) (xy 166.039546 -300.373288) (xy 166.039292 -300.373542)
			(xy 166.03472 -300.379892) (xy 166.026846 -300.402244) (xy 166.025458 -300.406363) (xy 166.023927 -300.414918)
			(xy 166.023798 -300.419262) (xy 166.023798 -300.880526) (xy 166.023911 -300.884872) (xy 166.025449 -300.893427)
			(xy 166.026846 -300.897544) (xy 166.03472 -300.919896) (xy 166.039292 -300.926246) (xy 166.039546 -300.9265)
			(xy 166.05506 -300.948081) (xy 166.079718 -300.995162) (xy 166.096518 -301.045584) (xy 166.105026 -301.098046)
			(xy 166.105586 -301.12462) (xy 166.105586 -301.125128) (xy 166.105037 -301.152705) (xy 166.095882 -301.207092)
			(xy 166.077815 -301.259202) (xy 166.051339 -301.307584) (xy 166.03472 -301.329598) (xy 166.029386 -301.336456)
			(xy 166.023798 -301.352458) (xy 166.023798 -301.413672) (xy 166.024213 -301.423697) (xy 166.031878 -301.442224)
			(xy 166.046051 -301.456406) (xy 166.064573 -301.464081) (xy 166.074598 -301.464472) (xy 184.028588 -301.464472)
			(xy 184.035954 -301.471838)
		)
		(stroke
			(width 0)
			(type solid)
		)
		(fill yes)
		(layer "B.Cu")
		(net "P0V8_SERDES_VDDA_PEX1")
	)
	(gr_poly
		(pts
			(xy 185.45683 -288.54527) (xy 185.461584 -288.545177) (xy 185.470924 -288.543395) (xy 185.475372 -288.541714)
			(xy 185.500518 -288.531808) (xy 185.507122 -288.52622) (xy 185.526769 -288.509651) (xy 185.570193 -288.482165)
			(xy 185.617344 -288.461723) (xy 185.667089 -288.448816) (xy 185.718231 -288.443755) (xy 185.76954 -288.446661)
			(xy 185.819784 -288.457465) (xy 185.843926 -288.466276) (xy 185.852816 -288.469832) (xy 186.085734 -288.469832)
			(xy 186.103835 -288.470424) (xy 186.138281 -288.481553) (xy 186.153298 -288.491676) (xy 186.159939 -288.496232)
			(xy 186.175222 -288.501284) (xy 186.18327 -288.501582) (xy 186.216798 -288.501582) (xy 186.224836 -288.501225)
			(xy 186.240107 -288.496186) (xy 186.24677 -288.491676) (xy 186.261791 -288.481562) (xy 186.296234 -288.470435)
			(xy 186.314334 -288.469832) (xy 186.547252 -288.469832) (xy 186.556142 -288.466276) (xy 186.580296 -288.457491)
			(xy 186.630536 -288.446655) (xy 186.681848 -288.443726) (xy 186.732995 -288.448775) (xy 186.782744 -288.46168)
			(xy 186.829896 -288.482129) (xy 186.873315 -288.50963) (xy 186.892946 -288.52622) (xy 186.89955 -288.531808)
			(xy 186.924696 -288.541714) (xy 186.92916 -288.543338) (xy 186.93849 -288.545121) (xy 186.943238 -288.54527)
			(xy 187.35675 -288.54527) (xy 187.361504 -288.545176) (xy 187.370842 -288.543389) (xy 187.375292 -288.541714)
			(xy 187.400438 -288.531808) (xy 187.407042 -288.525966) (xy 187.426946 -288.509179) (xy 187.471009 -288.481442)
			(xy 187.518879 -288.460964) (xy 187.56937 -288.448254) (xy 187.595256 -288.445448) (xy 187.6044 -288.444686)
			(xy 187.620402 -288.437066) (xy 187.94857 -288.108898) (xy 187.959492 -288.100516) (xy 187.963556 -288.096706)
			(xy 187.984569 -288.076467) (xy 188.031735 -288.042135) (xy 188.083691 -288.015602) (xy 188.139158 -287.997523)
			(xy 188.196769 -287.988342) (xy 188.225938 -287.98774) (xy 188.85916 -287.98774) (xy 188.869124 -287.987256)
			(xy 188.887553 -287.979674) (xy 188.894974 -287.973008) (xy 189.08903 -287.778952) (xy 189.095877 -287.771554)
			(xy 189.103605 -287.752955) (xy 189.104016 -287.742884) (xy 189.104016 -286.257238) (xy 189.103603 -286.247211)
			(xy 189.095941 -286.228678) (xy 189.081768 -286.21449) (xy 189.063243 -286.206808) (xy 189.053216 -286.206438)
			(xy 187.096908 -286.206438) (xy 187.086838 -286.20686) (xy 187.068235 -286.214577) (xy 187.06084 -286.221424)
			(xy 186.941206 -286.341058) (xy 186.940698 -286.341058) (xy 186.831986 -286.44977) (xy 186.824366 -286.47136)
			(xy 186.825636 -286.48279) (xy 186.83478 -286.572452) (xy 186.846718 -286.59201) (xy 186.85637 -286.59836)
			(xy 186.878908 -286.613803) (xy 186.919054 -286.650854) (xy 186.952561 -286.694003) (xy 186.978515 -286.742074)
			(xy 186.996212 -286.793759) (xy 187.005169 -286.84765) (xy 187.005722 -286.874966) (xy 187.005212 -286.900953)
			(xy 186.997082 -286.952288) (xy 186.981021 -287.001718) (xy 186.957425 -287.048028) (xy 186.926875 -287.090076)
			(xy 186.890124 -287.126827) (xy 186.848076 -287.157377) (xy 186.801766 -287.180973) (xy 186.752336 -287.197034)
			(xy 186.701001 -287.205164) (xy 186.649027 -287.205164) (xy 186.597692 -287.197034) (xy 186.548262 -287.180973)
			(xy 186.501952 -287.157377) (xy 186.459904 -287.126827) (xy 186.423153 -287.090076) (xy 186.392603 -287.048028)
			(xy 186.369007 -287.001718) (xy 186.352946 -286.952288) (xy 186.344816 -286.900953) (xy 186.344306 -286.874966)
			(xy 186.344703 -286.85198) (xy 186.351076 -286.806452) (xy 186.363693 -286.762245) (xy 186.382312 -286.720212)
			(xy 186.39409 -286.700468) (xy 186.394344 -286.700214) (xy 186.398701 -286.692345) (xy 186.402172 -286.674707)
			(xy 186.399391 -286.656948) (xy 186.39536 -286.648906) (xy 186.35218 -286.571182) (xy 186.347473 -286.56345)
			(xy 186.333744 -286.551671) (xy 186.316775 -286.545403) (xy 186.30773 -286.54502) (xy 185.114692 -286.54502)
			(xy 185.105184 -286.546143) (xy 185.087951 -286.55445) (xy 185.074926 -286.568463) (xy 185.067897 -286.586256)
			(xy 185.067448 -286.59582) (xy 185.067448 -286.70885) (xy 185.067574 -286.714496) (xy 185.070013 -286.725519)
			(xy 185.072274 -286.730694) (xy 185.072528 -286.730948) (xy 185.072528 -286.731202) (xy 185.082924 -286.753727)
			(xy 185.097596 -286.801116) (xy 185.105018 -286.850165) (xy 185.105023 -286.899773) (xy 185.09761 -286.948825)
			(xy 185.082946 -286.996216) (xy 185.072528 -287.01873) (xy 185.072528 -287.018984) (xy 185.072274 -287.019238)
			(xy 185.070012 -287.024412) (xy 185.067573 -287.035436) (xy 185.067448 -287.041082) (xy 185.067448 -287.65881)
			(xy 185.06757 -287.664457) (xy 185.070001 -287.675484) (xy 185.072274 -287.680654) (xy 185.072528 -287.680908)
			(xy 185.072528 -287.681162) (xy 185.082919 -287.703687) (xy 185.097583 -287.751074) (xy 185.104996 -287.800121)
			(xy 185.104992 -287.849725) (xy 185.104963 -287.849915) (xy 186.357496 -287.849915) (xy 186.357496 -287.799937)
			(xy 186.365315 -287.750574) (xy 186.380759 -287.703042) (xy 186.403449 -287.65851) (xy 186.432825 -287.618077)
			(xy 186.468165 -287.582737) (xy 186.508598 -287.553361) (xy 186.55313 -287.530671) (xy 186.600662 -287.515227)
			(xy 186.650025 -287.507408) (xy 186.700003 -287.507408) (xy 186.749366 -287.515227) (xy 186.796898 -287.530671)
			(xy 186.84143 -287.553361) (xy 186.881863 -287.582737) (xy 186.917203 -287.618077) (xy 186.946579 -287.65851)
			(xy 186.969269 -287.703042) (xy 186.984713 -287.750574) (xy 186.992532 -287.799937) (xy 186.993022 -287.824926)
			(xy 186.992532 -287.849915) (xy 186.984713 -287.899278) (xy 186.969269 -287.94681) (xy 186.946579 -287.991342)
			(xy 186.917203 -288.031775) (xy 186.881863 -288.067115) (xy 186.84143 -288.096491) (xy 186.796898 -288.119181)
			(xy 186.749366 -288.134625) (xy 186.700003 -288.142444) (xy 186.650025 -288.142444) (xy 186.600662 -288.134625)
			(xy 186.55313 -288.119181) (xy 186.508598 -288.096491) (xy 186.468165 -288.067115) (xy 186.432825 -288.031775)
			(xy 186.403449 -287.991342) (xy 186.380759 -287.94681) (xy 186.365315 -287.899278) (xy 186.357496 -287.849915)
			(xy 185.104963 -287.849915) (xy 185.097572 -287.898772) (xy 185.082902 -287.946157) (xy 185.072528 -287.96869)
			(xy 185.072528 -287.968944) (xy 185.072274 -287.969198) (xy 185.070018 -287.974373) (xy 185.067592 -287.985397)
			(xy 185.067448 -287.991042) (xy 185.067448 -288.364168) (xy 185.067916 -288.374042) (xy 185.075366 -288.392333)
			(xy 185.081926 -288.399728) (xy 185.08218 -288.399982) (xy 185.212482 -288.530284) (xy 185.21299 -288.530792)
			(xy 185.220375 -288.537364) (xy 185.238674 -288.544796) (xy 185.24855 -288.54527)
		)
		(stroke
			(width 0)
			(type solid)
		)
		(fill yes)
		(layer "B.Cu")
		(net "P1V8_VDDA_PEX1")
	)
	(gr_poly
		(pts
			(xy 389.957564 -241.30127)
			(arc
				(start 390.020048 -241.243358)
				(mid 390.032112 -241.226395)
				(end 390.036304 -241.20602)
			)
			(arc
				(start 390.036304 -236.91088)
				(mid 390.032051 -236.890532)
				(end 390.020048 -236.873542)
			)
			(xy 389.957564 -236.81563) (xy 389.937752 -236.808772) (xy 389.927084 -236.809534) (xy 389.89 -236.810804)
			(arc
				(start 388.711186 -236.810804)
				(mid 388.691799 -236.814754)
				(end 388.675372 -236.82579)
			)
			(arc
				(start 388.267448 -237.233968)
				(mid 388.110678 -237.338562)
				(end 387.925818 -237.375192)
			)
			(arc
				(start 387.925818 -237.375192)
				(mid 387.584389 -237.233767)
				(end 387.442964 -236.892338)
			)
			(arc
				(start 387.442964 -236.892338)
				(mid 387.479621 -236.70749)
				(end 387.584188 -236.550708)
			)
			(arc
				(start 388.148576 -235.98632)
				(mid 388.305346 -235.881726)
				(end 388.490206 -235.845096)
			)
			(xy 389.89 -235.845096) (xy 389.927084 -235.846366) (xy 389.937752 -235.847128) (xy 389.957564 -235.84027)
			(arc
				(start 390.020048 -235.782358)
				(mid 390.032112 -235.765395)
				(end 390.036304 -235.74502)
			)
			(arc
				(start 390.036304 -233.364532)
				(mid 390.032471 -233.345175)
				(end 390.021572 -233.328718)
			)
			(arc
				(start 388.399782 -231.706928)
				(mid 388.363879 -231.692093)
				(end 388.3279 -231.706928)
			)
			(arc
				(start 387.183376 -232.851452)
				(mid 387.16937 -232.877443)
				(end 387.1722 -232.906824)
			)
			(xy 387.178296 -232.921302) (xy 387.203696 -232.93832) (xy 387.31825 -232.93832) (xy 387.335776 -232.931208)
			(arc
				(start 387.343142 -232.92435)
				(mid 387.487956 -232.832678)
				(end 387.656324 -232.800652)
			)
			(arc
				(start 387.656324 -232.800652)
				(mid 388.114286 -233.258614)
				(end 387.656324 -233.716576)
			)
			(arc
				(start 387.656324 -233.716576)
				(mid 387.488287 -233.684672)
				(end 387.34365 -233.593386)
			)
			(xy 387.336792 -233.587036)
			(arc
				(start 387.326886 -233.582718)
				(mid 387.31742 -233.579869)
				(end 387.307582 -233.578908)
			)
			(arc
				(start 386.825744 -233.578908)
				(mid 386.807611 -233.596077)
				(end 386.799836 -233.619802)
			)
			(xy 386.799836 -233.75366) (xy 386.800852 -233.763566) (xy 386.802884 -233.773218) (xy 386.805424 -233.781854)
			(arc
				(start 386.806186 -233.783632)
				(mid 386.816098 -233.811925)
				(end 386.82422 -233.840782)
			)
			(arc
				(start 386.82422 -233.840782)
				(mid 386.834905 -233.898767)
				(end 386.838444 -233.957622)
			)
			(arc
				(start 386.838698 -233.963718)
				(mid 386.742936 -234.246651)
				(end 386.4991 -234.41914)
			)
			(arc
				(start 386.498846 -234.41914)
				(mid 386.472972 -234.43751)
				(end 386.463032 -234.467654)
			)
			(arc
				(start 386.463032 -236.763052)
				(mid 386.477911 -236.798973)
				(end 386.513832 -236.813852)
			)
			(xy 386.800598 -236.813852)
			(arc
				(start 387.086602 -236.813852)
				(mid 387.176674 -236.851214)
				(end 387.213856 -236.94136)
			)
			(xy 387.213856 -237.646718)
			(arc
				(start 387.21411 -237.65256)
				(mid 387.206051 -237.697173)
				(end 387.182868 -237.736126)
			)
			(arc
				(start 387.182868 -237.736126)
				(mid 387.177993 -237.742765)
				(end 387.174232 -237.750096)
			)
			(arc
				(start 387.166866 -237.767622)
				(mid 387.164017 -237.777088)
				(end 387.163056 -237.786926)
			)
			(arc
				(start 387.163056 -238.173768)
				(mid 387.155675 -238.25838)
				(end 387.133592 -238.340392)
			)
			(arc
				(start 387.133592 -238.340392)
				(mid 387.087226 -238.43397)
				(end 387.021832 -238.515398)
			)
			(arc
				(start 386.982716 -238.554514)
				(mid 386.949144 -238.584982)
				(end 386.912866 -238.612172)
			)
			(arc
				(start 386.912866 -238.612172)
				(mid 386.890137 -238.626657)
				(end 386.866638 -238.639858)
			)
			(xy 386.861304 -238.642906) (xy 386.852668 -238.650272)
			(arc
				(start 386.849112 -238.655352)
				(mid 386.843407 -238.665758)
				(end 386.840222 -238.677196)
			)
			(arc
				(start 386.82803 -238.757968)
				(mid 386.829971 -238.781383)
				(end 386.842254 -238.801402)
			)
			(arc
				(start 387.005322 -238.96447)
				(mid 387.021856 -238.975581)
				(end 387.04139 -238.979456)
			)
			(arc
				(start 388.130288 -238.979456)
				(mid 388.149811 -238.983357)
				(end 388.166356 -238.994442)
			)
			(arc
				(start 389.04164 -239.869726)
				(mid 389.052751 -239.88626)
				(end 389.056626 -239.905794)
			)
			(arc
				(start 389.056626 -240.994692)
				(mid 389.060527 -241.014215)
				(end 389.071612 -241.03076)
			)
			(arc
				(start 389.331962 -241.29111)
				(mid 389.348379 -241.302172)
				(end 389.367776 -241.306096)
			)
			(xy 389.901176 -241.306096) (xy 389.927084 -241.307366) (xy 389.937752 -241.308128)
		)
		(stroke
			(width 0)
			(type solid)
		)
		(fill yes)
		(layer "B.Cu")
		(net "GND")
	)
	(gr_poly
		(pts
			(xy 417.656518 -288.54527) (xy 417.661331 -288.545149) (xy 417.670791 -288.543363) (xy 417.675314 -288.541714)
			(xy 417.700714 -288.531554) (xy 417.707572 -288.525966) (xy 417.727198 -288.509438) (xy 417.770568 -288.482027)
			(xy 417.817654 -288.461647) (xy 417.867324 -288.448788) (xy 417.918384 -288.443759) (xy 417.969607 -288.446681)
			(xy 418.019764 -288.457484) (xy 418.043868 -288.466276) (xy 418.052504 -288.469832) (xy 418.285676 -288.469832)
			(xy 418.303775 -288.470431) (xy 418.338213 -288.48157) (xy 418.35324 -288.491676) (xy 418.359882 -288.496226)
			(xy 418.375166 -288.501265) (xy 418.383212 -288.501582) (xy 418.41674 -288.501582) (xy 418.424776 -288.501218)
			(xy 418.440039 -288.49617) (xy 418.446712 -288.491676) (xy 418.461731 -288.481554) (xy 418.496174 -288.47041)
			(xy 418.514276 -288.469832) (xy 418.747448 -288.469832) (xy 418.756084 -288.466276) (xy 418.7802 -288.45753)
			(xy 418.830352 -288.44675) (xy 418.881567 -288.443839) (xy 418.932617 -288.448869) (xy 418.982278 -288.461719)
			(xy 419.029362 -288.48208) (xy 419.072738 -288.509465) (xy 419.09238 -288.525966) (xy 419.099238 -288.531554)
			(xy 419.124638 -288.541714) (xy 419.129151 -288.543402) (xy 419.138616 -288.545197) (xy 419.143434 -288.54527)
			(xy 419.556438 -288.54527) (xy 419.561251 -288.545147) (xy 419.570709 -288.543357) (xy 419.575234 -288.541714)
			(xy 419.60038 -288.531808) (xy 419.606984 -288.525966) (xy 419.626887 -288.509176) (xy 419.670948 -288.481431)
			(xy 419.718817 -288.460945) (xy 419.769308 -288.448226) (xy 419.795198 -288.445448) (xy 419.804342 -288.444686)
			(xy 419.820344 -288.437066) (xy 420.148512 -288.108898) (xy 420.155911 -288.102054) (xy 420.174509 -288.094324)
			(xy 420.18458 -288.093912) (xy 420.390066 -288.093912) (xy 420.402714 -288.093246) (xy 420.424991 -288.081262)
			(xy 420.432484 -288.071052) (xy 420.486332 -287.98901) (xy 420.488364 -287.96361) (xy 420.483284 -287.951672)
			(xy 420.474928 -287.931599) (xy 420.463169 -287.889739) (xy 420.457239 -287.846666) (xy 420.456868 -287.824926)
			(xy 420.457358 -287.799937) (xy 420.465177 -287.750574) (xy 420.480621 -287.703042) (xy 420.503311 -287.65851)
			(xy 420.532687 -287.618077) (xy 420.568027 -287.582737) (xy 420.60846 -287.553361) (xy 420.652992 -287.530671)
			(xy 420.700524 -287.515227) (xy 420.749887 -287.507408) (xy 420.799865 -287.507408) (xy 420.849228 -287.515227)
			(xy 420.89676 -287.530671) (xy 420.941292 -287.553361) (xy 420.981725 -287.582737) (xy 421.017065 -287.618077)
			(xy 421.046441 -287.65851) (xy 421.069131 -287.703042) (xy 421.084575 -287.750574) (xy 421.092394 -287.799937)
			(xy 421.092884 -287.824926) (xy 421.092494 -287.846664) (xy 421.086545 -287.889731) (xy 421.074801 -287.931591)
			(xy 421.066468 -287.951672) (xy 421.061388 -287.96361) (xy 421.06342 -287.98901) (xy 421.117268 -288.071052)
			(xy 421.124785 -288.081239) (xy 421.147044 -288.093234) (xy 421.159686 -288.093912) (xy 421.173148 -288.093912)
			(xy 421.183215 -288.093481) (xy 421.201808 -288.085755) (xy 421.209216 -288.078926) (xy 421.288972 -287.99917)
			(xy 421.295817 -287.991771) (xy 421.303545 -287.973173) (xy 421.303958 -287.963102) (xy 421.303958 -286.257238)
			(xy 421.303544 -286.247215) (xy 421.29588 -286.228692) (xy 421.281705 -286.214518) (xy 421.263181 -286.206855)
			(xy 421.253158 -286.206438) (xy 419.28669 -286.206438) (xy 419.267894 -286.214058) (xy 419.260782 -286.221424)
			(xy 419.141148 -286.341058) (xy 419.14064 -286.341058) (xy 419.040056 -286.441896) (xy 419.032548 -286.450304)
			(xy 419.025046 -286.471529) (xy 419.025578 -286.48279) (xy 419.033452 -286.561022) (xy 419.035181 -286.572242)
			(xy 419.046903 -286.59165) (xy 419.056058 -286.59836) (xy 419.056312 -286.59836) (xy 419.078848 -286.613805)
			(xy 419.118989 -286.650858) (xy 419.152491 -286.694008) (xy 419.178442 -286.742078) (xy 419.196137 -286.793762)
			(xy 419.205092 -286.847651) (xy 419.205664 -286.874966) (xy 419.205154 -286.900953) (xy 419.197024 -286.952288)
			(xy 419.180963 -287.001718) (xy 419.157367 -287.048028) (xy 419.126817 -287.090076) (xy 419.090066 -287.126827)
			(xy 419.048018 -287.157377) (xy 419.001708 -287.180973) (xy 418.952278 -287.197034) (xy 418.900943 -287.205164)
			(xy 418.848969 -287.205164) (xy 418.797634 -287.197034) (xy 418.748204 -287.180973) (xy 418.701894 -287.157377)
			(xy 418.659846 -287.126827) (xy 418.623095 -287.090076) (xy 418.592545 -287.048028) (xy 418.568949 -287.001718)
			(xy 418.552888 -286.952288) (xy 418.544758 -286.900953) (xy 418.544248 -286.874966) (xy 418.544646 -286.85198)
			(xy 418.551019 -286.806452) (xy 418.563638 -286.762246) (xy 418.582258 -286.720214) (xy 418.594032 -286.700468)
			(xy 418.601398 -286.68853) (xy 418.60216 -286.661098) (xy 418.552122 -286.571182) (xy 418.547417 -286.563445)
			(xy 418.53369 -286.551655) (xy 418.51672 -286.545373) (xy 418.507672 -286.54502) (xy 417.31819 -286.54502)
			(xy 417.308172 -286.545442) (xy 417.289662 -286.553114) (xy 417.275497 -286.567287) (xy 417.267836 -286.585801)
			(xy 417.26739 -286.59582) (xy 417.26739 -286.720534) (xy 417.27247 -286.731202) (xy 417.282865 -286.753727)
			(xy 417.297535 -286.801116) (xy 417.304956 -286.850166) (xy 417.304961 -286.899773) (xy 417.297549 -286.948824)
			(xy 417.282887 -286.996216) (xy 417.27247 -287.01873) (xy 417.26739 -287.029398) (xy 417.26739 -287.670494)
			(xy 417.27247 -287.681162) (xy 417.28286 -287.703687) (xy 417.297522 -287.751075) (xy 417.304934 -287.800121)
			(xy 417.30493 -287.849725) (xy 417.304901 -287.849915) (xy 418.557438 -287.849915) (xy 418.557438 -287.799937)
			(xy 418.565257 -287.750574) (xy 418.580701 -287.703042) (xy 418.603391 -287.65851) (xy 418.632767 -287.618077)
			(xy 418.668107 -287.582737) (xy 418.70854 -287.553361) (xy 418.753072 -287.530671) (xy 418.800604 -287.515227)
			(xy 418.849967 -287.507408) (xy 418.899945 -287.507408) (xy 418.949308 -287.515227) (xy 418.99684 -287.530671)
			(xy 419.041372 -287.553361) (xy 419.081805 -287.582737) (xy 419.117145 -287.618077) (xy 419.146521 -287.65851)
			(xy 419.169211 -287.703042) (xy 419.184655 -287.750574) (xy 419.192474 -287.799937) (xy 419.192964 -287.824926)
			(xy 419.192474 -287.849915) (xy 419.184655 -287.899278) (xy 419.169211 -287.94681) (xy 419.146521 -287.991342)
			(xy 419.117145 -288.031775) (xy 419.081805 -288.067115) (xy 419.041372 -288.096491) (xy 418.99684 -288.119181)
			(xy 418.949308 -288.134625) (xy 418.899945 -288.142444) (xy 418.849967 -288.142444) (xy 418.800604 -288.134625)
			(xy 418.753072 -288.119181) (xy 418.70854 -288.096491) (xy 418.668107 -288.067115) (xy 418.632767 -288.031775)
			(xy 418.603391 -287.991342) (xy 418.580701 -287.94681) (xy 418.565257 -287.899278) (xy 418.557438 -287.849915)
			(xy 417.304901 -287.849915) (xy 417.297511 -287.898771) (xy 417.282843 -287.946157) (xy 417.27247 -287.96869)
			(xy 417.26739 -287.979358) (xy 417.26739 -288.364168) (xy 417.267825 -288.374233) (xy 417.275556 -288.392821)
			(xy 417.282376 -288.400236) (xy 417.412424 -288.530284) (xy 417.419823 -288.537128) (xy 417.438421 -288.544857)
			(xy 417.448492 -288.54527)
		)
		(stroke
			(width 0)
			(type solid)
		)
		(fill yes)
		(layer "B.Cu")
		(net "P1V8_VDDA_PEX3")
	)
	(gr_poly
		(pts
			(xy 335.075022 -252.067822) (xy 335.085091 -252.067396) (xy 335.103692 -252.059678) (xy 335.11109 -252.052836)
			(xy 335.200498 -251.963428) (xy 335.206602 -251.956886) (xy 335.21418 -251.94069) (xy 335.215705 -251.922874)
			(xy 335.213706 -251.914152) (xy 335.186528 -251.8156) (xy 335.167224 -251.79655) (xy 335.153762 -251.792994)
			(xy 335.12673 -251.785616) (xy 335.075028 -251.764018) (xy 335.027046 -251.735082) (xy 334.983817 -251.699433)
			(xy 334.946274 -251.657839) (xy 334.915225 -251.611196) (xy 334.89134 -251.560509) (xy 334.875134 -251.506872)
			(xy 334.866956 -251.45144) (xy 334.866488 -251.423424) (xy 334.86695 -251.39617) (xy 334.874704 -251.342216)
			(xy 334.890058 -251.289915) (xy 334.912699 -251.240332) (xy 334.942166 -251.194475) (xy 334.97786 -251.15328)
			(xy 335.019053 -251.117583) (xy 335.064907 -251.088112) (xy 335.114489 -251.065468) (xy 335.166789 -251.05011)
			(xy 335.220742 -251.042352) (xy 335.247996 -251.041916) (xy 335.265559 -251.042092) (xy 335.30054 -251.04527)
			(xy 335.317846 -251.048266) (xy 335.329022 -251.050552) (xy 335.350866 -251.04471) (xy 335.4197 -250.98756)
			(xy 335.427948 -250.979954) (xy 335.437429 -250.959651) (xy 335.437988 -250.948444) (xy 335.437988 -250.008898)
			(xy 335.437564 -249.998828) (xy 335.429848 -249.980225) (xy 335.423002 -249.97283) (xy 334.522318 -249.072146)
			(xy 334.514917 -249.065307) (xy 334.496318 -249.057595) (xy 334.48625 -249.05716) (xy 332.600808 -249.05716)
			(xy 332.57617 -249.0724) (xy 332.56982 -249.085862) (xy 332.556261 -249.112853) (xy 332.523086 -249.163331)
			(xy 332.483561 -249.209007) (xy 332.438371 -249.249087) (xy 332.388302 -249.282875) (xy 332.334223 -249.309784)
			(xy 332.277075 -249.329345) (xy 332.21785 -249.34122) (xy 332.157578 -249.345201) (xy 332.097306 -249.34122)
			(xy 332.038081 -249.329345) (xy 331.980933 -249.309784) (xy 331.926854 -249.282875) (xy 331.876785 -249.249087)
			(xy 331.831595 -249.209007) (xy 331.79207 -249.163331) (xy 331.758895 -249.112853) (xy 331.745336 -249.085862)
			(xy 331.738986 -249.0724) (xy 331.714348 -249.05716) (xy 328.696066 -249.05716) (xy 328.687425 -249.057495)
			(xy 328.671128 -249.063241) (xy 328.657683 -249.074097) (xy 328.652886 -249.08129) (xy 328.637868 -249.10461)
			(xy 328.602159 -249.147052) (xy 328.560684 -249.18388) (xy 328.514316 -249.214318) (xy 328.464032 -249.237726)
			(xy 328.410889 -249.25361) (xy 328.356007 -249.261637) (xy 328.300541 -249.261637) (xy 328.245659 -249.25361)
			(xy 328.192516 -249.237726) (xy 328.142232 -249.214318) (xy 328.095864 -249.18388) (xy 328.054389 -249.147052)
			(xy 328.01868 -249.10461) (xy 328.003662 -249.08129) (xy 327.998833 -249.074122) (xy 327.985393 -249.063272)
			(xy 327.969117 -249.057489) (xy 327.960482 -249.05716) (xy 317.340234 -249.05716) (xy 317.33017 -249.056724)
			(xy 317.311587 -249.048988) (xy 317.304166 -249.042174) (xy 310.655716 -242.393724) (xy 310.64888 -242.386322)
			(xy 310.641171 -242.367724) (xy 310.64073 -242.357656) (xy 310.64073 -231.916986) (xy 310.640305 -231.906916)
			(xy 310.632591 -231.888313) (xy 310.625744 -231.880918) (xy 307.12537 -228.380544) (xy 307.117972 -228.373698)
			(xy 307.099373 -228.365967) (xy 307.089302 -228.365558) (xy 301.520098 -228.365558) (xy 301.510029 -228.365983)
			(xy 301.491431 -228.373704) (xy 301.48403 -228.380544) (xy 301.380398 -228.484176) (xy 301.373564 -228.491579)
			(xy 301.365858 -228.510177) (xy 301.365412 -228.520244) (xy 301.365412 -228.88194) (xy 301.362364 -228.885242)
			(xy 301.362364 -229.6287) (xy 301.362851 -229.63871) (xy 301.37051 -229.657208) (xy 301.384661 -229.67137)
			(xy 301.403154 -229.679041) (xy 301.413164 -229.6795) (xy 303.711356 -229.6795) (xy 303.743583 -229.679954)
			(xy 303.807631 -229.687173) (xy 303.870469 -229.701515) (xy 303.931307 -229.722798) (xy 303.989382 -229.750755)
			(xy 304.043963 -229.785036) (xy 304.094365 -229.82521) (xy 304.117502 -229.847648) (xy 304.158904 -229.888796)
			(xy 304.166249 -229.895607) (xy 304.184712 -229.903338) (xy 304.194718 -229.903782) (xy 305.124104 -229.903782)
			(xy 305.134174 -229.904205) (xy 305.152779 -229.911919) (xy 305.160172 -229.918768) (xy 308.545484 -233.30408)
			(xy 308.55232 -233.311482) (xy 308.560027 -233.330081) (xy 308.56047 -233.340148) (xy 308.56047 -244.328188)
			(xy 308.56089 -244.33826) (xy 308.568598 -244.35687) (xy 308.575456 -244.364256) (xy 314.896754 -250.685554)
			(xy 331.662786 -250.685554) (xy 331.663276 -250.655586) (xy 331.671099 -250.596164) (xy 331.686612 -250.538271)
			(xy 331.709548 -250.482898) (xy 331.739515 -250.430992) (xy 331.776002 -250.383442) (xy 331.818382 -250.341062)
			(xy 331.865932 -250.304575) (xy 331.917838 -250.274608) (xy 331.973211 -250.251672) (xy 332.031104 -250.236159)
			(xy 332.090526 -250.228336) (xy 332.150462 -250.228336) (xy 332.209884 -250.236159) (xy 332.267777 -250.251672)
			(xy 332.32315 -250.274608) (xy 332.375056 -250.304575) (xy 332.422606 -250.341062) (xy 332.464986 -250.383442)
			(xy 332.501473 -250.430992) (xy 332.53144 -250.482898) (xy 332.554376 -250.538271) (xy 332.569889 -250.596164)
			(xy 332.577712 -250.655586) (xy 332.578202 -250.685554) (xy 332.577769 -250.714288) (xy 332.570565 -250.771302)
			(xy 332.556278 -250.826966) (xy 332.535132 -250.880402) (xy 332.507461 -250.930769) (xy 332.4737 -250.977274)
			(xy 332.43438 -251.019185) (xy 332.390121 -251.055842) (xy 332.366112 -251.071634) (xy 332.354623 -251.079522)
			(xy 332.336066 -251.100297) (xy 332.323803 -251.125309) (xy 332.318746 -251.152702) (xy 332.321268 -251.180444)
			(xy 332.331183 -251.206476) (xy 332.347756 -251.228867) (xy 332.358492 -251.23775) (xy 332.381156 -251.255933)
			(xy 332.421219 -251.298017) (xy 332.45444 -251.345686) (xy 332.480054 -251.39784) (xy 332.497468 -251.453273)
			(xy 332.506281 -251.510704) (xy 332.506828 -251.539756) (xy 332.506342 -251.567007) (xy 332.498586 -251.620955)
			(xy 332.483231 -251.67325) (xy 332.460589 -251.722827) (xy 332.431123 -251.768677) (xy 332.395432 -251.809868)
			(xy 332.354241 -251.845559) (xy 332.308391 -251.875025) (xy 332.258814 -251.897667) (xy 332.206519 -251.913022)
			(xy 332.152571 -251.920778) (xy 332.098069 -251.920778) (xy 332.044121 -251.913022) (xy 331.991826 -251.897667)
			(xy 331.942249 -251.875025) (xy 331.896399 -251.845559) (xy 331.855208 -251.809868) (xy 331.819517 -251.768677)
			(xy 331.790051 -251.722827) (xy 331.767409 -251.67325) (xy 331.752054 -251.620955) (xy 331.744298 -251.567007)
			(xy 331.743812 -251.539756) (xy 331.744297 -251.511079) (xy 331.752877 -251.454369) (xy 331.76985 -251.399583)
			(xy 331.794836 -251.347957) (xy 331.827269 -251.300653) (xy 331.86642 -251.258739) (xy 331.888592 -251.240544)
			(xy 331.899287 -251.231576) (xy 331.915686 -251.209001) (xy 331.925367 -251.182832) (xy 331.927607 -251.15502)
			(xy 331.92224 -251.127638) (xy 331.909664 -251.10273) (xy 331.890819 -251.082153) (xy 331.879194 -251.074428)
			(xy 331.854737 -251.058731) (xy 331.809622 -251.022096) (xy 331.76951 -250.980043) (xy 331.735046 -250.933248)
			(xy 331.706786 -250.882466) (xy 331.685184 -250.828514) (xy 331.670589 -250.772261) (xy 331.663235 -250.714612)
			(xy 331.662786 -250.685554) (xy 314.896754 -250.685554) (xy 316.264036 -252.052836) (xy 316.271433 -252.059684)
			(xy 316.290032 -252.067415) (xy 316.300104 -252.067822)
		)
		(stroke
			(width 0)
			(type solid)
		)
		(fill yes)
		(layer "B.Cu")
		(net "P5V_AUX")
	)
	(gr_poly
		(pts
			(xy 200.699878 -378.70003) (xy 200.699377 -378.599976) (xy 200.691371 -378.400029) (xy 200.675372 -378.200562)
			(xy 200.651404 -378.001894) (xy 200.619507 -377.804345) (xy 200.579732 -377.60823) (xy 200.532142 -377.413864)
			(xy 200.476814 -377.221557) (xy 200.413836 -377.031618) (xy 200.343309 -376.844351) (xy 200.265346 -376.660055)
			(xy 200.180072 -376.479026) (xy 200.087623 -376.301554) (xy 199.988148 -376.127923) (xy 199.881805 -375.958411)
			(xy 199.768766 -375.79329) (xy 199.64921 -375.632823) (xy 199.52333 -375.477268) (xy 199.391327 -375.326874)
			(xy 199.253413 -375.181882) (xy 199.109808 -375.042524) (xy 198.960742 -374.909023) (xy 198.806454 -374.781593)
			(xy 198.647192 -374.660438) (xy 198.483209 -374.545752) (xy 198.31477 -374.437719) (xy 198.142143 -374.336511)
			(xy 197.965604 -374.242291) (xy 197.785438 -374.15521) (xy 197.601931 -374.075407) (xy 197.415379 -374.00301)
			(xy 197.22608 -373.938135) (xy 197.034336 -373.880885) (xy 196.840455 -373.831353) (xy 196.644748 -373.789618)
			(xy 196.447528 -373.755746) (xy 196.249111 -373.729793) (xy 196.049814 -373.711798) (xy 195.849956 -373.701792)
			(xy 195.649859 -373.69979) (xy 195.449841 -373.705795) (xy 195.250224 -373.719798) (xy 195.051327 -373.741777)
			(xy 194.853468 -373.771696) (xy 194.656965 -373.809507) (xy 194.462132 -373.85515) (xy 194.269282 -373.908551)
			(xy 194.078722 -373.969626) (xy 193.890759 -374.038275) (xy 193.705692 -374.114391) (xy 193.523819 -374.197849)
			(xy 193.345431 -374.288518) (xy 193.170814 -374.386251) (xy 193.000246 -374.490892) (xy 192.834002 -374.602274)
			(xy 192.672347 -374.720218) (xy 192.51554 -374.844536) (xy 192.363833 -374.975027) (xy 192.217469 -375.111484)
			(xy 192.076681 -375.253688) (xy 191.941695 -375.401411) (xy 191.812728 -375.554416) (xy 191.689985 -375.712458)
			(xy 191.573665 -375.875285) (xy 191.463952 -376.042635) (xy 191.361022 -376.214241) (xy 191.265041 -376.389828)
			(xy 191.176161 -376.569114) (xy 191.094526 -376.751813) (xy 191.020267 -376.937632) (xy 190.953501 -377.126273)
			(xy 190.894336 -377.317434) (xy 190.842866 -377.510809) (xy 190.799175 -377.706089) (xy 190.763332 -377.90296)
			(xy 190.735394 -378.101108) (xy 190.715407 -378.300215) (xy 190.703401 -378.499962) (xy 190.699398 -378.70003)
			(xy 190.700735 -378.766865) (xy 193.488053 -378.766865) (xy 193.488053 -378.633195) (xy 193.496123 -378.49977)
			(xy 193.512235 -378.367075) (xy 193.53633 -378.235596) (xy 193.568319 -378.105811) (xy 193.608086 -377.978194)
			(xy 193.655486 -377.853211) (xy 193.710345 -377.731318) (xy 193.772465 -377.61296) (xy 193.841617 -377.498568)
			(xy 193.917549 -377.38856) (xy 193.999986 -377.283338) (xy 194.088625 -377.183285) (xy 194.183143 -377.088767)
			(xy 194.283196 -377.000128) (xy 194.388418 -376.917691) (xy 194.498426 -376.841759) (xy 194.612818 -376.772607)
			(xy 194.731176 -376.710487) (xy 194.853069 -376.655628) (xy 194.978052 -376.608228) (xy 195.105669 -376.568461)
			(xy 195.235454 -376.536472) (xy 195.366933 -376.512377) (xy 195.499628 -376.496265) (xy 195.633053 -376.488195)
			(xy 195.766723 -376.488195) (xy 195.900148 -376.496265) (xy 196.032843 -376.512377) (xy 196.164322 -376.536472)
			(xy 196.294107 -376.568461) (xy 196.421724 -376.608228) (xy 196.546707 -376.655628) (xy 196.6686 -376.710487)
			(xy 196.786958 -376.772607) (xy 196.90135 -376.841759) (xy 197.011358 -376.917691) (xy 197.11658 -377.000128)
			(xy 197.216633 -377.088767) (xy 197.311151 -377.183285) (xy 197.39979 -377.283338) (xy 197.482227 -377.38856)
			(xy 197.558159 -377.498568) (xy 197.627311 -377.61296) (xy 197.689431 -377.731318) (xy 197.74429 -377.853211)
			(xy 197.79169 -377.978194) (xy 197.831457 -378.105811) (xy 197.863446 -378.235596) (xy 197.887541 -378.367075)
			(xy 197.903653 -378.49977) (xy 197.911723 -378.633195) (xy 197.912228 -378.70003) (xy 197.911723 -378.766865)
			(xy 197.903653 -378.90029) (xy 197.887541 -379.032985) (xy 197.863446 -379.164464) (xy 197.831457 -379.294249)
			(xy 197.79169 -379.421866) (xy 197.74429 -379.546849) (xy 197.689431 -379.668742) (xy 197.627311 -379.7871)
			(xy 197.558159 -379.901492) (xy 197.482227 -380.0115) (xy 197.39979 -380.116722) (xy 197.311151 -380.216775)
			(xy 197.216633 -380.311293) (xy 197.11658 -380.399932) (xy 197.011358 -380.482369) (xy 196.90135 -380.558301)
			(xy 196.786958 -380.627453) (xy 196.6686 -380.689573) (xy 196.546707 -380.744432) (xy 196.421724 -380.791832)
			(xy 196.294107 -380.831599) (xy 196.164322 -380.863588) (xy 196.032843 -380.887683) (xy 195.900148 -380.903795)
			(xy 195.766723 -380.911865) (xy 195.633053 -380.911865) (xy 195.499628 -380.903795) (xy 195.366933 -380.887683)
			(xy 195.235454 -380.863588) (xy 195.105669 -380.831599) (xy 194.978052 -380.791832) (xy 194.853069 -380.744432)
			(xy 194.731176 -380.689573) (xy 194.612818 -380.627453) (xy 194.498426 -380.558301) (xy 194.388418 -380.482369)
			(xy 194.283196 -380.399932) (xy 194.183143 -380.311293) (xy 194.088625 -380.216775) (xy 193.999986 -380.116722)
			(xy 193.917549 -380.0115) (xy 193.841617 -379.901492) (xy 193.772465 -379.7871) (xy 193.710345 -379.668742)
			(xy 193.655486 -379.546849) (xy 193.608086 -379.421866) (xy 193.568319 -379.294249) (xy 193.53633 -379.164464)
			(xy 193.512235 -379.032985) (xy 193.496123 -378.90029) (xy 193.488053 -378.766865) (xy 190.700735 -378.766865)
			(xy 190.703401 -378.900098) (xy 190.715407 -379.099845) (xy 190.735394 -379.298952) (xy 190.763332 -379.4971)
			(xy 190.799175 -379.693971) (xy 190.842866 -379.889251) (xy 190.894336 -380.082626) (xy 190.953501 -380.273787)
			(xy 191.020267 -380.462428) (xy 191.094526 -380.648247) (xy 191.176161 -380.830946) (xy 191.265041 -381.010232)
			(xy 191.361022 -381.185819) (xy 191.463952 -381.357425) (xy 191.573665 -381.524775) (xy 191.689985 -381.687602)
			(xy 191.812728 -381.845644) (xy 191.941695 -381.998649) (xy 192.076681 -382.146372) (xy 192.217469 -382.288576)
			(xy 192.363833 -382.425033) (xy 192.51554 -382.555524) (xy 192.672347 -382.679842) (xy 192.834002 -382.797786)
			(xy 193.000246 -382.909168) (xy 193.170814 -383.013809) (xy 193.345431 -383.111542) (xy 193.523819 -383.202211)
			(xy 193.705692 -383.285669) (xy 193.890759 -383.361785) (xy 194.078722 -383.430434) (xy 194.269282 -383.491509)
			(xy 194.462132 -383.54491) (xy 194.656965 -383.590553) (xy 194.853468 -383.628364) (xy 195.051327 -383.658283)
			(xy 195.250224 -383.680262) (xy 195.449841 -383.694265) (xy 195.649859 -383.70027) (xy 195.849956 -383.698268)
			(xy 196.049814 -383.688262) (xy 196.249111 -383.670267) (xy 196.447528 -383.644314) (xy 196.644748 -383.610442)
			(xy 196.840455 -383.568707) (xy 197.034336 -383.519175) (xy 197.22608 -383.461925) (xy 197.415379 -383.39705)
			(xy 197.601931 -383.324653) (xy 197.785438 -383.24485) (xy 197.965604 -383.157769) (xy 198.142143 -383.063549)
			(xy 198.31477 -382.962341) (xy 198.483209 -382.854308) (xy 198.647192 -382.739622) (xy 198.806454 -382.618467)
			(xy 198.960742 -382.491037) (xy 199.109808 -382.357536) (xy 199.253413 -382.218178) (xy 199.391327 -382.073186)
			(xy 199.52333 -381.922792) (xy 199.64921 -381.767237) (xy 199.768766 -381.60677) (xy 199.881805 -381.441649)
			(xy 199.988148 -381.272137) (xy 200.087623 -381.098506) (xy 200.180072 -380.921034) (xy 200.265346 -380.740005)
			(xy 200.343309 -380.555709) (xy 200.413836 -380.368442) (xy 200.476814 -380.178503) (xy 200.532142 -379.986196)
			(xy 200.579732 -379.79183) (xy 200.619507 -379.595715) (xy 200.651404 -379.398166) (xy 200.675372 -379.199498)
			(xy 200.691371 -379.000031) (xy 200.699377 -378.800084)
		)
		(stroke
			(width 0)
			(type solid)
		)
		(fill yes)
		(layer "B.Cu")
		(net "GND")
	)
	(gr_poly
		(pts
			(xy 213.300056 -98.700082) (xy 213.299555 -98.600028) (xy 213.291549 -98.400081) (xy 213.27555 -98.200614)
			(xy 213.251582 -98.001946) (xy 213.219685 -97.804397) (xy 213.17991 -97.608282) (xy 213.13232 -97.413916)
			(xy 213.076992 -97.221609) (xy 213.014014 -97.03167) (xy 212.943487 -96.844403) (xy 212.865524 -96.660107)
			(xy 212.78025 -96.479078) (xy 212.687801 -96.301606) (xy 212.588326 -96.127975) (xy 212.481983 -95.958463)
			(xy 212.368944 -95.793342) (xy 212.249388 -95.632875) (xy 212.123508 -95.47732) (xy 211.991505 -95.326926)
			(xy 211.853591 -95.181934) (xy 211.709986 -95.042576) (xy 211.56092 -94.909075) (xy 211.406632 -94.781645)
			(xy 211.24737 -94.66049) (xy 211.083387 -94.545804) (xy 210.914948 -94.437771) (xy 210.742321 -94.336563)
			(xy 210.565782 -94.242343) (xy 210.385616 -94.155262) (xy 210.202109 -94.075459) (xy 210.015557 -94.003062)
			(xy 209.826258 -93.938187) (xy 209.634514 -93.880937) (xy 209.440633 -93.831405) (xy 209.244926 -93.78967)
			(xy 209.047706 -93.755798) (xy 208.849289 -93.729845) (xy 208.649992 -93.71185) (xy 208.450134 -93.701844)
			(xy 208.250037 -93.699842) (xy 208.050019 -93.705847) (xy 207.850402 -93.71985) (xy 207.651505 -93.741829)
			(xy 207.453646 -93.771748) (xy 207.257143 -93.809559) (xy 207.06231 -93.855202) (xy 206.86946 -93.908603)
			(xy 206.6789 -93.969678) (xy 206.490937 -94.038327) (xy 206.30587 -94.114443) (xy 206.123997 -94.197901)
			(xy 205.945609 -94.28857) (xy 205.770992 -94.386303) (xy 205.600424 -94.490944) (xy 205.43418 -94.602326)
			(xy 205.272525 -94.72027) (xy 205.115718 -94.844588) (xy 204.964011 -94.975079) (xy 204.817647 -95.111536)
			(xy 204.676859 -95.25374) (xy 204.541873 -95.401463) (xy 204.412906 -95.554468) (xy 204.290163 -95.71251)
			(xy 204.173843 -95.875337) (xy 204.06413 -96.042687) (xy 203.9612 -96.214293) (xy 203.865219 -96.38988)
			(xy 203.776339 -96.569166) (xy 203.694704 -96.751865) (xy 203.620445 -96.937684) (xy 203.553679 -97.126325)
			(xy 203.494514 -97.317486) (xy 203.443044 -97.510861) (xy 203.399353 -97.706141) (xy 203.36351 -97.903012)
			(xy 203.335572 -98.10116) (xy 203.315585 -98.300267) (xy 203.303579 -98.500014) (xy 203.299576 -98.700082)
			(xy 203.300913 -98.766917) (xy 206.088231 -98.766917) (xy 206.088231 -98.633247) (xy 206.096301 -98.499822)
			(xy 206.112413 -98.367127) (xy 206.136508 -98.235648) (xy 206.168497 -98.105863) (xy 206.208264 -97.978246)
			(xy 206.255664 -97.853263) (xy 206.310523 -97.73137) (xy 206.372643 -97.613012) (xy 206.441795 -97.49862)
			(xy 206.517727 -97.388612) (xy 206.600164 -97.28339) (xy 206.688803 -97.183337) (xy 206.783321 -97.088819)
			(xy 206.883374 -97.00018) (xy 206.988596 -96.917743) (xy 207.098604 -96.841811) (xy 207.212996 -96.772659)
			(xy 207.331354 -96.710539) (xy 207.453247 -96.65568) (xy 207.57823 -96.60828) (xy 207.705847 -96.568513)
			(xy 207.835632 -96.536524) (xy 207.967111 -96.512429) (xy 208.099806 -96.496317) (xy 208.233231 -96.488247)
			(xy 208.366901 -96.488247) (xy 208.500326 -96.496317) (xy 208.633021 -96.512429) (xy 208.7645 -96.536524)
			(xy 208.894285 -96.568513) (xy 209.021902 -96.60828) (xy 209.146885 -96.65568) (xy 209.268778 -96.710539)
			(xy 209.387136 -96.772659) (xy 209.501528 -96.841811) (xy 209.611536 -96.917743) (xy 209.716758 -97.00018)
			(xy 209.816811 -97.088819) (xy 209.911329 -97.183337) (xy 209.999968 -97.28339) (xy 210.082405 -97.388612)
			(xy 210.158337 -97.49862) (xy 210.227489 -97.613012) (xy 210.289609 -97.73137) (xy 210.344468 -97.853263)
			(xy 210.391868 -97.978246) (xy 210.431635 -98.105863) (xy 210.463624 -98.235648) (xy 210.487719 -98.367127)
			(xy 210.503831 -98.499822) (xy 210.511901 -98.633247) (xy 210.512406 -98.700082) (xy 210.511901 -98.766917)
			(xy 210.503831 -98.900342) (xy 210.487719 -99.033037) (xy 210.463624 -99.164516) (xy 210.431635 -99.294301)
			(xy 210.391868 -99.421918) (xy 210.344468 -99.546901) (xy 210.289609 -99.668794) (xy 210.227489 -99.787152)
			(xy 210.158337 -99.901544) (xy 210.082405 -100.011552) (xy 209.999968 -100.116774) (xy 209.911329 -100.216827)
			(xy 209.816811 -100.311345) (xy 209.716758 -100.399984) (xy 209.611536 -100.482421) (xy 209.501528 -100.558353)
			(xy 209.387136 -100.627505) (xy 209.268778 -100.689625) (xy 209.146885 -100.744484) (xy 209.021902 -100.791884)
			(xy 208.894285 -100.831651) (xy 208.7645 -100.86364) (xy 208.633021 -100.887735) (xy 208.500326 -100.903847)
			(xy 208.366901 -100.911917) (xy 208.233231 -100.911917) (xy 208.099806 -100.903847) (xy 207.967111 -100.887735)
			(xy 207.835632 -100.86364) (xy 207.705847 -100.831651) (xy 207.57823 -100.791884) (xy 207.453247 -100.744484)
			(xy 207.331354 -100.689625) (xy 207.212996 -100.627505) (xy 207.098604 -100.558353) (xy 206.988596 -100.482421)
			(xy 206.883374 -100.399984) (xy 206.783321 -100.311345) (xy 206.688803 -100.216827) (xy 206.600164 -100.116774)
			(xy 206.517727 -100.011552) (xy 206.441795 -99.901544) (xy 206.372643 -99.787152) (xy 206.310523 -99.668794)
			(xy 206.255664 -99.546901) (xy 206.208264 -99.421918) (xy 206.168497 -99.294301) (xy 206.136508 -99.164516)
			(xy 206.112413 -99.033037) (xy 206.096301 -98.900342) (xy 206.088231 -98.766917) (xy 203.300913 -98.766917)
			(xy 203.303579 -98.90015) (xy 203.315585 -99.099897) (xy 203.335572 -99.299004) (xy 203.36351 -99.497152)
			(xy 203.399353 -99.694023) (xy 203.443044 -99.889303) (xy 203.494514 -100.082678) (xy 203.553679 -100.273839)
			(xy 203.620445 -100.46248) (xy 203.694704 -100.648299) (xy 203.776339 -100.830998) (xy 203.865219 -101.010284)
			(xy 203.9612 -101.185871) (xy 204.06413 -101.357477) (xy 204.173843 -101.524827) (xy 204.290163 -101.687654)
			(xy 204.412906 -101.845696) (xy 204.541873 -101.998701) (xy 204.676859 -102.146424) (xy 204.817647 -102.288628)
			(xy 204.964011 -102.425085) (xy 205.115718 -102.555576) (xy 205.272525 -102.679894) (xy 205.43418 -102.797838)
			(xy 205.600424 -102.90922) (xy 205.770992 -103.013861) (xy 205.945609 -103.111594) (xy 206.123997 -103.202263)
			(xy 206.30587 -103.285721) (xy 206.490937 -103.361837) (xy 206.6789 -103.430486) (xy 206.86946 -103.491561)
			(xy 207.06231 -103.544962) (xy 207.257143 -103.590605) (xy 207.453646 -103.628416) (xy 207.651505 -103.658335)
			(xy 207.850402 -103.680314) (xy 208.050019 -103.694317) (xy 208.250037 -103.700322) (xy 208.450134 -103.69832)
			(xy 208.649992 -103.688314) (xy 208.849289 -103.670319) (xy 209.047706 -103.644366) (xy 209.244926 -103.610494)
			(xy 209.440633 -103.568759) (xy 209.634514 -103.519227) (xy 209.826258 -103.461977) (xy 210.015557 -103.397102)
			(xy 210.202109 -103.324705) (xy 210.385616 -103.244902) (xy 210.565782 -103.157821) (xy 210.742321 -103.063601)
			(xy 210.914948 -102.962393) (xy 211.083387 -102.85436) (xy 211.24737 -102.739674) (xy 211.406632 -102.618519)
			(xy 211.56092 -102.491089) (xy 211.709986 -102.357588) (xy 211.853591 -102.21823) (xy 211.991505 -102.073238)
			(xy 212.123508 -101.922844) (xy 212.249388 -101.767289) (xy 212.368944 -101.606822) (xy 212.481983 -101.441701)
			(xy 212.588326 -101.272189) (xy 212.687801 -101.098558) (xy 212.78025 -100.921086) (xy 212.865524 -100.740057)
			(xy 212.943487 -100.555761) (xy 213.014014 -100.368494) (xy 213.076992 -100.178555) (xy 213.13232 -99.986248)
			(xy 213.17991 -99.791882) (xy 213.219685 -99.595767) (xy 213.251582 -99.398218) (xy 213.27555 -99.19955)
			(xy 213.291549 -99.000083) (xy 213.299555 -98.800136)
		)
		(stroke
			(width 0)
			(type solid)
		)
		(fill yes)
		(layer "B.Cu")
		(net "GND")
	)
	(gr_poly
		(pts
			(xy 264.299954 -98.700082) (xy 264.299453 -98.600028) (xy 264.291447 -98.400081) (xy 264.275448 -98.200614)
			(xy 264.25148 -98.001946) (xy 264.219583 -97.804397) (xy 264.179808 -97.608282) (xy 264.132218 -97.413916)
			(xy 264.07689 -97.221609) (xy 264.013912 -97.03167) (xy 263.943385 -96.844403) (xy 263.865422 -96.660107)
			(xy 263.780148 -96.479078) (xy 263.687699 -96.301606) (xy 263.588224 -96.127975) (xy 263.481881 -95.958463)
			(xy 263.368842 -95.793342) (xy 263.249286 -95.632875) (xy 263.123406 -95.47732) (xy 262.991403 -95.326926)
			(xy 262.853489 -95.181934) (xy 262.709884 -95.042576) (xy 262.560818 -94.909075) (xy 262.40653 -94.781645)
			(xy 262.247268 -94.66049) (xy 262.083285 -94.545804) (xy 261.914846 -94.437771) (xy 261.742219 -94.336563)
			(xy 261.56568 -94.242343) (xy 261.385514 -94.155262) (xy 261.202007 -94.075459) (xy 261.015455 -94.003062)
			(xy 260.826156 -93.938187) (xy 260.634412 -93.880937) (xy 260.440531 -93.831405) (xy 260.244824 -93.78967)
			(xy 260.047604 -93.755798) (xy 259.849187 -93.729845) (xy 259.64989 -93.71185) (xy 259.450032 -93.701844)
			(xy 259.249935 -93.699842) (xy 259.049917 -93.705847) (xy 258.8503 -93.71985) (xy 258.651403 -93.741829)
			(xy 258.453544 -93.771748) (xy 258.257041 -93.809559) (xy 258.062208 -93.855202) (xy 257.869358 -93.908603)
			(xy 257.678798 -93.969678) (xy 257.490835 -94.038327) (xy 257.305768 -94.114443) (xy 257.123895 -94.197901)
			(xy 256.945507 -94.28857) (xy 256.77089 -94.386303) (xy 256.600322 -94.490944) (xy 256.434078 -94.602326)
			(xy 256.272423 -94.72027) (xy 256.115616 -94.844588) (xy 255.963909 -94.975079) (xy 255.817545 -95.111536)
			(xy 255.676757 -95.25374) (xy 255.541771 -95.401463) (xy 255.412804 -95.554468) (xy 255.290061 -95.71251)
			(xy 255.173741 -95.875337) (xy 255.064028 -96.042687) (xy 254.961098 -96.214293) (xy 254.865117 -96.38988)
			(xy 254.776237 -96.569166) (xy 254.694602 -96.751865) (xy 254.620343 -96.937684) (xy 254.553577 -97.126325)
			(xy 254.494412 -97.317486) (xy 254.442942 -97.510861) (xy 254.399251 -97.706141) (xy 254.363408 -97.903012)
			(xy 254.33547 -98.10116) (xy 254.315483 -98.300267) (xy 254.303477 -98.500014) (xy 254.299474 -98.700082)
			(xy 254.300811 -98.766917) (xy 257.088129 -98.766917) (xy 257.088129 -98.633247) (xy 257.096199 -98.499822)
			(xy 257.112311 -98.367127) (xy 257.136406 -98.235648) (xy 257.168395 -98.105863) (xy 257.208162 -97.978246)
			(xy 257.255562 -97.853263) (xy 257.310421 -97.73137) (xy 257.372541 -97.613012) (xy 257.441693 -97.49862)
			(xy 257.517625 -97.388612) (xy 257.600062 -97.28339) (xy 257.688701 -97.183337) (xy 257.783219 -97.088819)
			(xy 257.883272 -97.00018) (xy 257.988494 -96.917743) (xy 258.098502 -96.841811) (xy 258.212894 -96.772659)
			(xy 258.331252 -96.710539) (xy 258.453145 -96.65568) (xy 258.578128 -96.60828) (xy 258.705745 -96.568513)
			(xy 258.83553 -96.536524) (xy 258.967009 -96.512429) (xy 259.099704 -96.496317) (xy 259.233129 -96.488247)
			(xy 259.366799 -96.488247) (xy 259.500224 -96.496317) (xy 259.632919 -96.512429) (xy 259.764398 -96.536524)
			(xy 259.894183 -96.568513) (xy 260.0218 -96.60828) (xy 260.146783 -96.65568) (xy 260.268676 -96.710539)
			(xy 260.387034 -96.772659) (xy 260.501426 -96.841811) (xy 260.611434 -96.917743) (xy 260.716656 -97.00018)
			(xy 260.816709 -97.088819) (xy 260.911227 -97.183337) (xy 260.999866 -97.28339) (xy 261.082303 -97.388612)
			(xy 261.158235 -97.49862) (xy 261.227387 -97.613012) (xy 261.289507 -97.73137) (xy 261.344366 -97.853263)
			(xy 261.391766 -97.978246) (xy 261.431533 -98.105863) (xy 261.463522 -98.235648) (xy 261.487617 -98.367127)
			(xy 261.503729 -98.499822) (xy 261.511799 -98.633247) (xy 261.512304 -98.700082) (xy 261.511799 -98.766917)
			(xy 261.503729 -98.900342) (xy 261.487617 -99.033037) (xy 261.463522 -99.164516) (xy 261.431533 -99.294301)
			(xy 261.391766 -99.421918) (xy 261.344366 -99.546901) (xy 261.289507 -99.668794) (xy 261.227387 -99.787152)
			(xy 261.158235 -99.901544) (xy 261.082303 -100.011552) (xy 260.999866 -100.116774) (xy 260.911227 -100.216827)
			(xy 260.816709 -100.311345) (xy 260.716656 -100.399984) (xy 260.611434 -100.482421) (xy 260.501426 -100.558353)
			(xy 260.387034 -100.627505) (xy 260.268676 -100.689625) (xy 260.146783 -100.744484) (xy 260.0218 -100.791884)
			(xy 259.894183 -100.831651) (xy 259.764398 -100.86364) (xy 259.632919 -100.887735) (xy 259.500224 -100.903847)
			(xy 259.366799 -100.911917) (xy 259.233129 -100.911917) (xy 259.099704 -100.903847) (xy 258.967009 -100.887735)
			(xy 258.83553 -100.86364) (xy 258.705745 -100.831651) (xy 258.578128 -100.791884) (xy 258.453145 -100.744484)
			(xy 258.331252 -100.689625) (xy 258.212894 -100.627505) (xy 258.098502 -100.558353) (xy 257.988494 -100.482421)
			(xy 257.883272 -100.399984) (xy 257.783219 -100.311345) (xy 257.688701 -100.216827) (xy 257.600062 -100.116774)
			(xy 257.517625 -100.011552) (xy 257.441693 -99.901544) (xy 257.372541 -99.787152) (xy 257.310421 -99.668794)
			(xy 257.255562 -99.546901) (xy 257.208162 -99.421918) (xy 257.168395 -99.294301) (xy 257.136406 -99.164516)
			(xy 257.112311 -99.033037) (xy 257.096199 -98.900342) (xy 257.088129 -98.766917) (xy 254.300811 -98.766917)
			(xy 254.303477 -98.90015) (xy 254.315483 -99.099897) (xy 254.33547 -99.299004) (xy 254.363408 -99.497152)
			(xy 254.399251 -99.694023) (xy 254.442942 -99.889303) (xy 254.494412 -100.082678) (xy 254.553577 -100.273839)
			(xy 254.620343 -100.46248) (xy 254.694602 -100.648299) (xy 254.776237 -100.830998) (xy 254.865117 -101.010284)
			(xy 254.961098 -101.185871) (xy 255.064028 -101.357477) (xy 255.173741 -101.524827) (xy 255.290061 -101.687654)
			(xy 255.412804 -101.845696) (xy 255.541771 -101.998701) (xy 255.676757 -102.146424) (xy 255.817545 -102.288628)
			(xy 255.963909 -102.425085) (xy 256.115616 -102.555576) (xy 256.272423 -102.679894) (xy 256.434078 -102.797838)
			(xy 256.600322 -102.90922) (xy 256.77089 -103.013861) (xy 256.945507 -103.111594) (xy 257.123895 -103.202263)
			(xy 257.305768 -103.285721) (xy 257.490835 -103.361837) (xy 257.678798 -103.430486) (xy 257.869358 -103.491561)
			(xy 258.062208 -103.544962) (xy 258.257041 -103.590605) (xy 258.453544 -103.628416) (xy 258.651403 -103.658335)
			(xy 258.8503 -103.680314) (xy 259.049917 -103.694317) (xy 259.249935 -103.700322) (xy 259.450032 -103.69832)
			(xy 259.64989 -103.688314) (xy 259.849187 -103.670319) (xy 260.047604 -103.644366) (xy 260.244824 -103.610494)
			(xy 260.440531 -103.568759) (xy 260.634412 -103.519227) (xy 260.826156 -103.461977) (xy 261.015455 -103.397102)
			(xy 261.202007 -103.324705) (xy 261.385514 -103.244902) (xy 261.56568 -103.157821) (xy 261.742219 -103.063601)
			(xy 261.914846 -102.962393) (xy 262.083285 -102.85436) (xy 262.247268 -102.739674) (xy 262.40653 -102.618519)
			(xy 262.560818 -102.491089) (xy 262.709884 -102.357588) (xy 262.853489 -102.21823) (xy 262.991403 -102.073238)
			(xy 263.123406 -101.922844) (xy 263.249286 -101.767289) (xy 263.368842 -101.606822) (xy 263.481881 -101.441701)
			(xy 263.588224 -101.272189) (xy 263.687699 -101.098558) (xy 263.780148 -100.921086) (xy 263.865422 -100.740057)
			(xy 263.943385 -100.555761) (xy 264.013912 -100.368494) (xy 264.07689 -100.178555) (xy 264.132218 -99.986248)
			(xy 264.179808 -99.791882) (xy 264.219583 -99.595767) (xy 264.25148 -99.398218) (xy 264.275448 -99.19955)
			(xy 264.291447 -99.000083) (xy 264.299453 -98.800136)
		)
		(stroke
			(width 0)
			(type solid)
		)
		(fill yes)
		(layer "B.Cu")
		(net "GND")
	)
	(gr_poly
		(pts
			(xy 276.899878 -378.70003) (xy 276.899377 -378.599976) (xy 276.891371 -378.400029) (xy 276.875372 -378.200562)
			(xy 276.851404 -378.001894) (xy 276.819507 -377.804345) (xy 276.779732 -377.60823) (xy 276.732142 -377.413864)
			(xy 276.676814 -377.221557) (xy 276.613836 -377.031618) (xy 276.543309 -376.844351) (xy 276.465346 -376.660055)
			(xy 276.380072 -376.479026) (xy 276.287623 -376.301554) (xy 276.188148 -376.127923) (xy 276.081805 -375.958411)
			(xy 275.968766 -375.79329) (xy 275.84921 -375.632823) (xy 275.72333 -375.477268) (xy 275.591327 -375.326874)
			(xy 275.453413 -375.181882) (xy 275.309808 -375.042524) (xy 275.160742 -374.909023) (xy 275.006454 -374.781593)
			(xy 274.847192 -374.660438) (xy 274.683209 -374.545752) (xy 274.51477 -374.437719) (xy 274.342143 -374.336511)
			(xy 274.165604 -374.242291) (xy 273.985438 -374.15521) (xy 273.801931 -374.075407) (xy 273.615379 -374.00301)
			(xy 273.42608 -373.938135) (xy 273.234336 -373.880885) (xy 273.040455 -373.831353) (xy 272.844748 -373.789618)
			(xy 272.647528 -373.755746) (xy 272.449111 -373.729793) (xy 272.249814 -373.711798) (xy 272.049956 -373.701792)
			(xy 271.849859 -373.69979) (xy 271.649841 -373.705795) (xy 271.450224 -373.719798) (xy 271.251327 -373.741777)
			(xy 271.053468 -373.771696) (xy 270.856965 -373.809507) (xy 270.662132 -373.85515) (xy 270.469282 -373.908551)
			(xy 270.278722 -373.969626) (xy 270.090759 -374.038275) (xy 269.905692 -374.114391) (xy 269.723819 -374.197849)
			(xy 269.545431 -374.288518) (xy 269.370814 -374.386251) (xy 269.200246 -374.490892) (xy 269.034002 -374.602274)
			(xy 268.872347 -374.720218) (xy 268.71554 -374.844536) (xy 268.563833 -374.975027) (xy 268.417469 -375.111484)
			(xy 268.276681 -375.253688) (xy 268.141695 -375.401411) (xy 268.012728 -375.554416) (xy 267.889985 -375.712458)
			(xy 267.773665 -375.875285) (xy 267.663952 -376.042635) (xy 267.561022 -376.214241) (xy 267.465041 -376.389828)
			(xy 267.376161 -376.569114) (xy 267.294526 -376.751813) (xy 267.220267 -376.937632) (xy 267.153501 -377.126273)
			(xy 267.094336 -377.317434) (xy 267.042866 -377.510809) (xy 266.999175 -377.706089) (xy 266.963332 -377.90296)
			(xy 266.935394 -378.101108) (xy 266.915407 -378.300215) (xy 266.903401 -378.499962) (xy 266.899398 -378.70003)
			(xy 266.900735 -378.766865) (xy 269.688053 -378.766865) (xy 269.688053 -378.633195) (xy 269.696123 -378.49977)
			(xy 269.712235 -378.367075) (xy 269.73633 -378.235596) (xy 269.768319 -378.105811) (xy 269.808086 -377.978194)
			(xy 269.855486 -377.853211) (xy 269.910345 -377.731318) (xy 269.972465 -377.61296) (xy 270.041617 -377.498568)
			(xy 270.117549 -377.38856) (xy 270.199986 -377.283338) (xy 270.288625 -377.183285) (xy 270.383143 -377.088767)
			(xy 270.483196 -377.000128) (xy 270.588418 -376.917691) (xy 270.698426 -376.841759) (xy 270.812818 -376.772607)
			(xy 270.931176 -376.710487) (xy 271.053069 -376.655628) (xy 271.178052 -376.608228) (xy 271.305669 -376.568461)
			(xy 271.435454 -376.536472) (xy 271.566933 -376.512377) (xy 271.699628 -376.496265) (xy 271.833053 -376.488195)
			(xy 271.966723 -376.488195) (xy 272.100148 -376.496265) (xy 272.232843 -376.512377) (xy 272.364322 -376.536472)
			(xy 272.494107 -376.568461) (xy 272.621724 -376.608228) (xy 272.746707 -376.655628) (xy 272.8686 -376.710487)
			(xy 272.986958 -376.772607) (xy 273.10135 -376.841759) (xy 273.211358 -376.917691) (xy 273.31658 -377.000128)
			(xy 273.416633 -377.088767) (xy 273.511151 -377.183285) (xy 273.59979 -377.283338) (xy 273.682227 -377.38856)
			(xy 273.758159 -377.498568) (xy 273.827311 -377.61296) (xy 273.889431 -377.731318) (xy 273.94429 -377.853211)
			(xy 273.99169 -377.978194) (xy 274.031457 -378.105811) (xy 274.063446 -378.235596) (xy 274.087541 -378.367075)
			(xy 274.103653 -378.49977) (xy 274.111723 -378.633195) (xy 274.112228 -378.70003) (xy 274.111723 -378.766865)
			(xy 274.103653 -378.90029) (xy 274.087541 -379.032985) (xy 274.063446 -379.164464) (xy 274.031457 -379.294249)
			(xy 273.99169 -379.421866) (xy 273.94429 -379.546849) (xy 273.889431 -379.668742) (xy 273.827311 -379.7871)
			(xy 273.758159 -379.901492) (xy 273.682227 -380.0115) (xy 273.59979 -380.116722) (xy 273.511151 -380.216775)
			(xy 273.416633 -380.311293) (xy 273.31658 -380.399932) (xy 273.211358 -380.482369) (xy 273.10135 -380.558301)
			(xy 272.986958 -380.627453) (xy 272.8686 -380.689573) (xy 272.746707 -380.744432) (xy 272.621724 -380.791832)
			(xy 272.494107 -380.831599) (xy 272.364322 -380.863588) (xy 272.232843 -380.887683) (xy 272.100148 -380.903795)
			(xy 271.966723 -380.911865) (xy 271.833053 -380.911865) (xy 271.699628 -380.903795) (xy 271.566933 -380.887683)
			(xy 271.435454 -380.863588) (xy 271.305669 -380.831599) (xy 271.178052 -380.791832) (xy 271.053069 -380.744432)
			(xy 270.931176 -380.689573) (xy 270.812818 -380.627453) (xy 270.698426 -380.558301) (xy 270.588418 -380.482369)
			(xy 270.483196 -380.399932) (xy 270.383143 -380.311293) (xy 270.288625 -380.216775) (xy 270.199986 -380.116722)
			(xy 270.117549 -380.0115) (xy 270.041617 -379.901492) (xy 269.972465 -379.7871) (xy 269.910345 -379.668742)
			(xy 269.855486 -379.546849) (xy 269.808086 -379.421866) (xy 269.768319 -379.294249) (xy 269.73633 -379.164464)
			(xy 269.712235 -379.032985) (xy 269.696123 -378.90029) (xy 269.688053 -378.766865) (xy 266.900735 -378.766865)
			(xy 266.903401 -378.900098) (xy 266.915407 -379.099845) (xy 266.935394 -379.298952) (xy 266.963332 -379.4971)
			(xy 266.999175 -379.693971) (xy 267.042866 -379.889251) (xy 267.094336 -380.082626) (xy 267.153501 -380.273787)
			(xy 267.220267 -380.462428) (xy 267.294526 -380.648247) (xy 267.376161 -380.830946) (xy 267.465041 -381.010232)
			(xy 267.561022 -381.185819) (xy 267.663952 -381.357425) (xy 267.773665 -381.524775) (xy 267.889985 -381.687602)
			(xy 268.012728 -381.845644) (xy 268.141695 -381.998649) (xy 268.276681 -382.146372) (xy 268.417469 -382.288576)
			(xy 268.563833 -382.425033) (xy 268.71554 -382.555524) (xy 268.872347 -382.679842) (xy 269.034002 -382.797786)
			(xy 269.200246 -382.909168) (xy 269.370814 -383.013809) (xy 269.545431 -383.111542) (xy 269.723819 -383.202211)
			(xy 269.905692 -383.285669) (xy 270.090759 -383.361785) (xy 270.278722 -383.430434) (xy 270.469282 -383.491509)
			(xy 270.662132 -383.54491) (xy 270.856965 -383.590553) (xy 271.053468 -383.628364) (xy 271.251327 -383.658283)
			(xy 271.450224 -383.680262) (xy 271.649841 -383.694265) (xy 271.849859 -383.70027) (xy 272.049956 -383.698268)
			(xy 272.249814 -383.688262) (xy 272.449111 -383.670267) (xy 272.647528 -383.644314) (xy 272.844748 -383.610442)
			(xy 273.040455 -383.568707) (xy 273.234336 -383.519175) (xy 273.42608 -383.461925) (xy 273.615379 -383.39705)
			(xy 273.801931 -383.324653) (xy 273.985438 -383.24485) (xy 274.165604 -383.157769) (xy 274.342143 -383.063549)
			(xy 274.51477 -382.962341) (xy 274.683209 -382.854308) (xy 274.847192 -382.739622) (xy 275.006454 -382.618467)
			(xy 275.160742 -382.491037) (xy 275.309808 -382.357536) (xy 275.453413 -382.218178) (xy 275.591327 -382.073186)
			(xy 275.72333 -381.922792) (xy 275.84921 -381.767237) (xy 275.968766 -381.60677) (xy 276.081805 -381.441649)
			(xy 276.188148 -381.272137) (xy 276.287623 -381.098506) (xy 276.380072 -380.921034) (xy 276.465346 -380.740005)
			(xy 276.543309 -380.555709) (xy 276.613836 -380.368442) (xy 276.676814 -380.178503) (xy 276.732142 -379.986196)
			(xy 276.779732 -379.79183) (xy 276.819507 -379.595715) (xy 276.851404 -379.398166) (xy 276.875372 -379.199498)
			(xy 276.891371 -379.000031) (xy 276.899377 -378.800084)
		)
		(stroke
			(width 0)
			(type solid)
		)
		(fill yes)
		(layer "B.Cu")
		(net "GND")
	)
	(gr_poly
		(pts
			(xy 34.145474 -320.900044) (xy 34.144975 -320.805249) (xy 34.136982 -320.615827) (xy 34.121011 -320.42691)
			(xy 34.097091 -320.238835) (xy 34.065263 -320.051935) (xy 34.025584 -319.866543) (xy 33.978125 -319.682988)
			(xy 33.92297 -319.501598) (xy 33.860218 -319.322694) (xy 33.789979 -319.146594) (xy 33.712379 -318.973612)
			(xy 33.627556 -318.804055) (xy 33.53566 -318.638224) (xy 33.436855 -318.476415) (xy 33.331316 -318.318916)
			(xy 33.219232 -318.166005) (xy 33.100801 -318.017955) (xy 32.976234 -317.87503) (xy 32.845753 -317.737483)
			(xy 32.709589 -317.605559) (xy 32.567985 -317.479492) (xy 32.421192 -317.359507) (xy 32.269471 -317.245817)
			(xy 32.113093 -317.138624) (xy 31.952334 -317.038118) (xy 31.787482 -316.944479) (xy 31.618828 -316.857873)
			(xy 31.446674 -316.778454) (xy 31.271325 -316.706363) (xy 31.093092 -316.641728) (xy 30.912293 -316.584664)
			(xy 30.729249 -316.535272) (xy 30.544286 -316.493641) (xy 30.357732 -316.459845) (xy 30.169919 -316.433943)
			(xy 29.981181 -316.415981) (xy 29.791854 -316.405993) (xy 29.602274 -316.403994) (xy 29.412778 -316.409989)
			(xy 29.223703 -316.423967) (xy 29.035386 -316.445904) (xy 28.848161 -316.47576) (xy 28.662361 -316.513482)
			(xy 28.478317 -316.559003) (xy 28.296355 -316.612243) (xy 28.116799 -316.673106) (xy 27.939969 -316.741484)
			(xy 27.766178 -316.817256) (xy 27.595736 -316.900287) (xy 27.428946 -316.99043) (xy 27.266105 -317.087524)
			(xy 27.107501 -317.191396) (xy 26.953417 -317.301862) (xy 26.804127 -317.418726) (xy 26.659897 -317.541779)
			(xy 26.520982 -317.670803) (xy 26.387629 -317.805568) (xy 26.260077 -317.945836) (xy 26.138551 -318.091356)
			(xy 26.023268 -318.241869) (xy 25.914432 -318.397109) (xy 25.812238 -318.556799) (xy 25.716866 -318.720655)
			(xy 25.628487 -318.888386) (xy 25.547257 -319.059694) (xy 25.473321 -319.234273) (xy 25.406811 -319.411815)
			(xy 25.347844 -319.592002) (xy 25.296526 -319.774515) (xy 25.252947 -319.95903) (xy 25.217186 -320.145217)
			(xy 25.189306 -320.332746) (xy 25.169355 -320.521284) (xy 25.157371 -320.710496) (xy 25.153374 -320.900044)
			(xy 26.880575 -320.900044) (xy 26.884567 -320.751408) (xy 26.896532 -320.603201) (xy 26.916434 -320.455849)
			(xy 26.944217 -320.309779) (xy 26.979801 -320.16541) (xy 27.023083 -320.023159) (xy 27.073937 -319.883437)
			(xy 27.132219 -319.746645) (xy 27.197759 -319.61318) (xy 27.270368 -319.483424) (xy 27.349837 -319.357753)
			(xy 27.435938 -319.236529) (xy 27.528421 -319.120101) (xy 27.62702 -319.008806) (xy 27.731452 -318.902963)
			(xy 27.841414 -318.802878) (xy 27.956589 -318.70884) (xy 28.076646 -318.62112) (xy 28.201239 -318.539971)
			(xy 28.330008 -318.465626) (xy 28.462582 -318.3983) (xy 28.598578 -318.338188) (xy 28.737605 -318.285462)
			(xy 28.879262 -318.240274) (xy 29.02314 -318.202756) (xy 29.168825 -318.173014) (xy 29.315896 -318.151135)
			(xy 29.463929 -318.137182) (xy 29.612498 -318.131195) (xy 29.761174 -318.133191) (xy 29.909529 -318.143164)
			(xy 30.057134 -318.161087) (xy 30.203565 -318.186907) (xy 30.348399 -318.220549) (xy 30.491217 -318.261917)
			(xy 30.63161 -318.310891) (xy 30.769171 -318.367331) (xy 30.903505 -318.431073) (xy 31.034224 -318.501934)
			(xy 31.16095 -318.579709) (xy 31.283319 -318.664174) (xy 31.400978 -318.755086) (xy 31.513587 -318.852182)
			(xy 31.620822 -318.955183) (xy 31.722374 -319.063792) (xy 31.81795 -319.177694) (xy 31.907274 -319.296563)
			(xy 31.990089 -319.420055) (xy 32.066156 -319.547814) (xy 32.135255 -319.679472) (xy 32.197188 -319.81465)
			(xy 32.251776 -319.952956) (xy 32.298861 -320.093994) (xy 32.338308 -320.237355) (xy 32.370003 -320.382627)
			(xy 32.393854 -320.529391) (xy 32.409794 -320.677224) (xy 32.417775 -320.825699) (xy 32.418274 -320.900044)
			(xy 32.417775 -320.974389) (xy 32.409794 -321.122864) (xy 32.393854 -321.270697) (xy 32.370003 -321.417461)
			(xy 32.338308 -321.562733) (xy 32.298861 -321.706094) (xy 32.251776 -321.847132) (xy 32.197188 -321.985438)
			(xy 32.135255 -322.120616) (xy 32.066156 -322.252274) (xy 31.990089 -322.380033) (xy 31.907274 -322.503525)
			(xy 31.81795 -322.622394) (xy 31.722374 -322.736296) (xy 31.620822 -322.844905) (xy 31.513587 -322.947906)
			(xy 31.400978 -323.045002) (xy 31.283319 -323.135914) (xy 31.16095 -323.220379) (xy 31.034224 -323.298154)
			(xy 30.903505 -323.369015) (xy 30.769171 -323.432757) (xy 30.63161 -323.489197) (xy 30.491217 -323.538171)
			(xy 30.348399 -323.579539) (xy 30.203565 -323.613181) (xy 30.057134 -323.639001) (xy 29.909529 -323.656924)
			(xy 29.761174 -323.666897) (xy 29.612498 -323.668893) (xy 29.463929 -323.662906) (xy 29.315896 -323.648953)
			(xy 29.168825 -323.627074) (xy 29.02314 -323.597332) (xy 28.879262 -323.559814) (xy 28.737605 -323.514626)
			(xy 28.598578 -323.4619) (xy 28.462582 -323.401788) (xy 28.330008 -323.334462) (xy 28.201239 -323.260117)
			(xy 28.076646 -323.178968) (xy 27.956589 -323.091248) (xy 27.841414 -322.99721) (xy 27.731452 -322.897125)
			(xy 27.62702 -322.791282) (xy 27.528421 -322.679987) (xy 27.435938 -322.563559) (xy 27.349837 -322.442335)
			(xy 27.270368 -322.316664) (xy 27.197759 -322.186908) (xy 27.132219 -322.053443) (xy 27.073937 -321.916651)
			(xy 27.023083 -321.776929) (xy 26.979801 -321.634678) (xy 26.944217 -321.490309) (xy 26.916434 -321.344239)
			(xy 26.896532 -321.196887) (xy 26.884567 -321.04868) (xy 26.880575 -320.900044) (xy 25.153374 -320.900044)
			(xy 25.157371 -321.089592) (xy 25.169355 -321.278804) (xy 25.189306 -321.467342) (xy 25.217186 -321.654871)
			(xy 25.252947 -321.841058) (xy 25.296526 -322.025573) (xy 25.347844 -322.208086) (xy 25.406811 -322.388273)
			(xy 25.473321 -322.565815) (xy 25.547257 -322.740394) (xy 25.628487 -322.911702) (xy 25.716866 -323.079433)
			(xy 25.812238 -323.243289) (xy 25.914432 -323.402979) (xy 26.023268 -323.558219) (xy 26.138551 -323.708732)
			(xy 26.260077 -323.854252) (xy 26.387629 -323.99452) (xy 26.520982 -324.129285) (xy 26.659897 -324.258309)
			(xy 26.804127 -324.381362) (xy 26.953417 -324.498226) (xy 27.107501 -324.608692) (xy 27.266105 -324.712564)
			(xy 27.428946 -324.809658) (xy 27.595736 -324.899801) (xy 27.766178 -324.982832) (xy 27.939969 -325.058604)
			(xy 28.116799 -325.126982) (xy 28.296355 -325.187845) (xy 28.478317 -325.241085) (xy 28.662361 -325.286606)
			(xy 28.848161 -325.324328) (xy 29.035386 -325.354184) (xy 29.223703 -325.376121) (xy 29.412778 -325.390099)
			(xy 29.602274 -325.396094) (xy 29.791854 -325.394095) (xy 29.981181 -325.384107) (xy 30.169919 -325.366145)
			(xy 30.357732 -325.340243) (xy 30.544286 -325.306447) (xy 30.729249 -325.264816) (xy 30.912293 -325.215424)
			(xy 31.093092 -325.15836) (xy 31.271325 -325.093725) (xy 31.446674 -325.021634) (xy 31.618828 -324.942215)
			(xy 31.787482 -324.855609) (xy 31.952334 -324.76197) (xy 32.113093 -324.661464) (xy 32.269471 -324.554271)
			(xy 32.421192 -324.440581) (xy 32.567985 -324.320596) (xy 32.709589 -324.194529) (xy 32.845753 -324.062605)
			(xy 32.976234 -323.925058) (xy 33.100801 -323.782133) (xy 33.219232 -323.634083) (xy 33.331316 -323.481172)
			(xy 33.436855 -323.323673) (xy 33.53566 -323.161864) (xy 33.627556 -322.996033) (xy 33.712379 -322.826476)
			(xy 33.789979 -322.653494) (xy 33.860218 -322.477394) (xy 33.92297 -322.29849) (xy 33.978125 -322.1171)
			(xy 34.025584 -321.933545) (xy 34.065263 -321.748153) (xy 34.097091 -321.561253) (xy 34.121011 -321.373178)
			(xy 34.136982 -321.184261) (xy 34.144975 -320.994839)
		)
		(stroke
			(width 0)
			(type solid)
		)
		(fill yes)
		(layer "B.Cu")
		(net "GND")
	)
	(gr_poly
		(pts
			(xy 34.145474 -270.89989) (xy 34.144975 -270.805095) (xy 34.136982 -270.615673) (xy 34.121011 -270.426756)
			(xy 34.097091 -270.238681) (xy 34.065263 -270.051781) (xy 34.025584 -269.866389) (xy 33.978125 -269.682834)
			(xy 33.92297 -269.501444) (xy 33.860218 -269.32254) (xy 33.789979 -269.14644) (xy 33.712379 -268.973458)
			(xy 33.627556 -268.803901) (xy 33.53566 -268.63807) (xy 33.436855 -268.476261) (xy 33.331316 -268.318762)
			(xy 33.219232 -268.165851) (xy 33.100801 -268.017801) (xy 32.976234 -267.874876) (xy 32.845753 -267.737329)
			(xy 32.709589 -267.605405) (xy 32.567985 -267.479338) (xy 32.421192 -267.359353) (xy 32.269471 -267.245663)
			(xy 32.113093 -267.13847) (xy 31.952334 -267.037964) (xy 31.787482 -266.944325) (xy 31.618828 -266.857719)
			(xy 31.446674 -266.7783) (xy 31.271325 -266.706209) (xy 31.093092 -266.641574) (xy 30.912293 -266.58451)
			(xy 30.729249 -266.535118) (xy 30.544286 -266.493487) (xy 30.357732 -266.459691) (xy 30.169919 -266.433789)
			(xy 29.981181 -266.415827) (xy 29.791854 -266.405839) (xy 29.602274 -266.40384) (xy 29.412778 -266.409835)
			(xy 29.223703 -266.423813) (xy 29.035386 -266.44575) (xy 28.848161 -266.475606) (xy 28.662361 -266.513328)
			(xy 28.478317 -266.558849) (xy 28.296355 -266.612089) (xy 28.116799 -266.672952) (xy 27.939969 -266.74133)
			(xy 27.766178 -266.817102) (xy 27.595736 -266.900133) (xy 27.428946 -266.990276) (xy 27.266105 -267.08737)
			(xy 27.107501 -267.191242) (xy 26.953417 -267.301708) (xy 26.804127 -267.418572) (xy 26.659897 -267.541625)
			(xy 26.520982 -267.670649) (xy 26.387629 -267.805414) (xy 26.260077 -267.945682) (xy 26.138551 -268.091202)
			(xy 26.023268 -268.241715) (xy 25.914432 -268.396955) (xy 25.812238 -268.556645) (xy 25.716866 -268.720501)
			(xy 25.628487 -268.888232) (xy 25.547257 -269.05954) (xy 25.473321 -269.234119) (xy 25.406811 -269.411661)
			(xy 25.347844 -269.591848) (xy 25.296526 -269.774361) (xy 25.252947 -269.958876) (xy 25.217186 -270.145063)
			(xy 25.189306 -270.332592) (xy 25.169355 -270.52113) (xy 25.157371 -270.710342) (xy 25.153374 -270.89989)
			(xy 26.880575 -270.89989) (xy 26.884567 -270.751254) (xy 26.896532 -270.603047) (xy 26.916434 -270.455695)
			(xy 26.944217 -270.309625) (xy 26.979801 -270.165256) (xy 27.023083 -270.023005) (xy 27.073937 -269.883283)
			(xy 27.132219 -269.746491) (xy 27.197759 -269.613026) (xy 27.270368 -269.48327) (xy 27.349837 -269.357599)
			(xy 27.435938 -269.236375) (xy 27.528421 -269.119947) (xy 27.62702 -269.008652) (xy 27.731452 -268.902809)
			(xy 27.841414 -268.802724) (xy 27.956589 -268.708686) (xy 28.076646 -268.620966) (xy 28.201239 -268.539817)
			(xy 28.330008 -268.465472) (xy 28.462582 -268.398146) (xy 28.598578 -268.338034) (xy 28.737605 -268.285308)
			(xy 28.879262 -268.24012) (xy 29.02314 -268.202602) (xy 29.168825 -268.17286) (xy 29.315896 -268.150981)
			(xy 29.463929 -268.137028) (xy 29.612498 -268.131041) (xy 29.761174 -268.133037) (xy 29.909529 -268.14301)
			(xy 30.057134 -268.160933) (xy 30.203565 -268.186753) (xy 30.348399 -268.220395) (xy 30.491217 -268.261763)
			(xy 30.63161 -268.310737) (xy 30.769171 -268.367177) (xy 30.903505 -268.430919) (xy 31.034224 -268.50178)
			(xy 31.16095 -268.579555) (xy 31.283319 -268.66402) (xy 31.400978 -268.754932) (xy 31.513587 -268.852028)
			(xy 31.620822 -268.955029) (xy 31.722374 -269.063638) (xy 31.81795 -269.17754) (xy 31.907274 -269.296409)
			(xy 31.990089 -269.419901) (xy 32.066156 -269.54766) (xy 32.135255 -269.679318) (xy 32.197188 -269.814496)
			(xy 32.251776 -269.952802) (xy 32.298861 -270.09384) (xy 32.338308 -270.237201) (xy 32.370003 -270.382473)
			(xy 32.393854 -270.529237) (xy 32.409794 -270.67707) (xy 32.417775 -270.825545) (xy 32.418274 -270.89989)
			(xy 32.417775 -270.974235) (xy 32.409794 -271.12271) (xy 32.393854 -271.270543) (xy 32.370003 -271.417307)
			(xy 32.338308 -271.562579) (xy 32.298861 -271.70594) (xy 32.251776 -271.846978) (xy 32.197188 -271.985284)
			(xy 32.135255 -272.120462) (xy 32.066156 -272.25212) (xy 31.990089 -272.379879) (xy 31.907274 -272.503371)
			(xy 31.81795 -272.62224) (xy 31.722374 -272.736142) (xy 31.620822 -272.844751) (xy 31.513587 -272.947752)
			(xy 31.400978 -273.044848) (xy 31.283319 -273.13576) (xy 31.16095 -273.220225) (xy 31.034224 -273.298)
			(xy 30.903505 -273.368861) (xy 30.769171 -273.432603) (xy 30.63161 -273.489043) (xy 30.491217 -273.538017)
			(xy 30.348399 -273.579385) (xy 30.203565 -273.613027) (xy 30.057134 -273.638847) (xy 29.909529 -273.65677)
			(xy 29.761174 -273.666743) (xy 29.612498 -273.668739) (xy 29.463929 -273.662752) (xy 29.315896 -273.648799)
			(xy 29.168825 -273.62692) (xy 29.02314 -273.597178) (xy 28.879262 -273.55966) (xy 28.737605 -273.514472)
			(xy 28.598578 -273.461746) (xy 28.462582 -273.401634) (xy 28.330008 -273.334308) (xy 28.201239 -273.259963)
			(xy 28.076646 -273.178814) (xy 27.956589 -273.091094) (xy 27.841414 -272.997056) (xy 27.731452 -272.896971)
			(xy 27.62702 -272.791128) (xy 27.528421 -272.679833) (xy 27.435938 -272.563405) (xy 27.349837 -272.442181)
			(xy 27.270368 -272.31651) (xy 27.197759 -272.186754) (xy 27.132219 -272.053289) (xy 27.073937 -271.916497)
			(xy 27.023083 -271.776775) (xy 26.979801 -271.634524) (xy 26.944217 -271.490155) (xy 26.916434 -271.344085)
			(xy 26.896532 -271.196733) (xy 26.884567 -271.048526) (xy 26.880575 -270.89989) (xy 25.153374 -270.89989)
			(xy 25.157371 -271.089438) (xy 25.169355 -271.27865) (xy 25.189306 -271.467188) (xy 25.217186 -271.654717)
			(xy 25.252947 -271.840904) (xy 25.296526 -272.025419) (xy 25.347844 -272.207932) (xy 25.406811 -272.388119)
			(xy 25.473321 -272.565661) (xy 25.547257 -272.74024) (xy 25.628487 -272.911548) (xy 25.716866 -273.079279)
			(xy 25.812238 -273.243135) (xy 25.914432 -273.402825) (xy 26.023268 -273.558065) (xy 26.138551 -273.708578)
			(xy 26.260077 -273.854098) (xy 26.387629 -273.994366) (xy 26.520982 -274.129131) (xy 26.659897 -274.258155)
			(xy 26.804127 -274.381208) (xy 26.953417 -274.498072) (xy 27.107501 -274.608538) (xy 27.266105 -274.71241)
			(xy 27.428946 -274.809504) (xy 27.595736 -274.899647) (xy 27.766178 -274.982678) (xy 27.939969 -275.05845)
			(xy 28.116799 -275.126828) (xy 28.296355 -275.187691) (xy 28.478317 -275.240931) (xy 28.662361 -275.286452)
			(xy 28.848161 -275.324174) (xy 29.035386 -275.35403) (xy 29.223703 -275.375967) (xy 29.412778 -275.389945)
			(xy 29.602274 -275.39594) (xy 29.791854 -275.393941) (xy 29.981181 -275.383953) (xy 30.169919 -275.365991)
			(xy 30.357732 -275.340089) (xy 30.544286 -275.306293) (xy 30.729249 -275.264662) (xy 30.912293 -275.21527)
			(xy 31.093092 -275.158206) (xy 31.271325 -275.093571) (xy 31.446674 -275.02148) (xy 31.618828 -274.942061)
			(xy 31.787482 -274.855455) (xy 31.952334 -274.761816) (xy 32.113093 -274.66131) (xy 32.269471 -274.554117)
			(xy 32.421192 -274.440427) (xy 32.567985 -274.320442) (xy 32.709589 -274.194375) (xy 32.845753 -274.062451)
			(xy 32.976234 -273.924904) (xy 33.100801 -273.781979) (xy 33.219232 -273.633929) (xy 33.331316 -273.481018)
			(xy 33.436855 -273.323519) (xy 33.53566 -273.16171) (xy 33.627556 -272.995879) (xy 33.712379 -272.826322)
			(xy 33.789979 -272.65334) (xy 33.860218 -272.47724) (xy 33.92297 -272.298336) (xy 33.978125 -272.116946)
			(xy 34.025584 -271.933391) (xy 34.065263 -271.747999) (xy 34.097091 -271.561099) (xy 34.121011 -271.373024)
			(xy 34.136982 -271.184107) (xy 34.144975 -270.994685)
		)
		(stroke
			(width 0)
			(type solid)
		)
		(fill yes)
		(layer "B.Cu")
		(net "GND")
	)
	(gr_poly
		(pts
			(xy 94.145608 -320.900044) (xy 94.145109 -320.805249) (xy 94.137116 -320.615827) (xy 94.121145 -320.42691)
			(xy 94.097225 -320.238835) (xy 94.065397 -320.051935) (xy 94.025718 -319.866543) (xy 93.978259 -319.682988)
			(xy 93.923104 -319.501598) (xy 93.860352 -319.322694) (xy 93.790113 -319.146594) (xy 93.712513 -318.973612)
			(xy 93.62769 -318.804055) (xy 93.535794 -318.638224) (xy 93.436989 -318.476415) (xy 93.33145 -318.318916)
			(xy 93.219366 -318.166005) (xy 93.100935 -318.017955) (xy 92.976368 -317.87503) (xy 92.845887 -317.737483)
			(xy 92.709723 -317.605559) (xy 92.568119 -317.479492) (xy 92.421326 -317.359507) (xy 92.269605 -317.245817)
			(xy 92.113227 -317.138624) (xy 91.952468 -317.038118) (xy 91.787616 -316.944479) (xy 91.618962 -316.857873)
			(xy 91.446808 -316.778454) (xy 91.271459 -316.706363) (xy 91.093226 -316.641728) (xy 90.912427 -316.584664)
			(xy 90.729383 -316.535272) (xy 90.54442 -316.493641) (xy 90.357866 -316.459845) (xy 90.170053 -316.433943)
			(xy 89.981315 -316.415981) (xy 89.791988 -316.405993) (xy 89.602408 -316.403994) (xy 89.412912 -316.409989)
			(xy 89.223837 -316.423967) (xy 89.03552 -316.445904) (xy 88.848295 -316.47576) (xy 88.662495 -316.513482)
			(xy 88.478451 -316.559003) (xy 88.296489 -316.612243) (xy 88.116933 -316.673106) (xy 87.940103 -316.741484)
			(xy 87.766312 -316.817256) (xy 87.59587 -316.900287) (xy 87.42908 -316.99043) (xy 87.266239 -317.087524)
			(xy 87.107635 -317.191396) (xy 86.953551 -317.301862) (xy 86.804261 -317.418726) (xy 86.660031 -317.541779)
			(xy 86.521116 -317.670803) (xy 86.387763 -317.805568) (xy 86.260211 -317.945836) (xy 86.138685 -318.091356)
			(xy 86.023402 -318.241869) (xy 85.914566 -318.397109) (xy 85.812372 -318.556799) (xy 85.717 -318.720655)
			(xy 85.628621 -318.888386) (xy 85.547391 -319.059694) (xy 85.473455 -319.234273) (xy 85.406945 -319.411815)
			(xy 85.347978 -319.592002) (xy 85.29666 -319.774515) (xy 85.253081 -319.95903) (xy 85.21732 -320.145217)
			(xy 85.18944 -320.332746) (xy 85.169489 -320.521284) (xy 85.157505 -320.710496) (xy 85.153508 -320.900044)
			(xy 86.880709 -320.900044) (xy 86.884701 -320.751408) (xy 86.896666 -320.603201) (xy 86.916568 -320.455849)
			(xy 86.944351 -320.309779) (xy 86.979935 -320.16541) (xy 87.023217 -320.023159) (xy 87.074071 -319.883437)
			(xy 87.132353 -319.746645) (xy 87.197893 -319.61318) (xy 87.270502 -319.483424) (xy 87.349971 -319.357753)
			(xy 87.436072 -319.236529) (xy 87.528555 -319.120101) (xy 87.627154 -319.008806) (xy 87.731586 -318.902963)
			(xy 87.841548 -318.802878) (xy 87.956723 -318.70884) (xy 88.07678 -318.62112) (xy 88.201373 -318.539971)
			(xy 88.330142 -318.465626) (xy 88.462716 -318.3983) (xy 88.598712 -318.338188) (xy 88.737739 -318.285462)
			(xy 88.879396 -318.240274) (xy 89.023274 -318.202756) (xy 89.168959 -318.173014) (xy 89.31603 -318.151135)
			(xy 89.464063 -318.137182) (xy 89.612632 -318.131195) (xy 89.761308 -318.133191) (xy 89.909663 -318.143164)
			(xy 90.057268 -318.161087) (xy 90.203699 -318.186907) (xy 90.348533 -318.220549) (xy 90.491351 -318.261917)
			(xy 90.631744 -318.310891) (xy 90.769305 -318.367331) (xy 90.903639 -318.431073) (xy 91.034358 -318.501934)
			(xy 91.161084 -318.579709) (xy 91.283453 -318.664174) (xy 91.401112 -318.755086) (xy 91.513721 -318.852182)
			(xy 91.620956 -318.955183) (xy 91.722508 -319.063792) (xy 91.818084 -319.177694) (xy 91.907408 -319.296563)
			(xy 91.990223 -319.420055) (xy 92.06629 -319.547814) (xy 92.135389 -319.679472) (xy 92.197322 -319.81465)
			(xy 92.25191 -319.952956) (xy 92.298995 -320.093994) (xy 92.338442 -320.237355) (xy 92.370137 -320.382627)
			(xy 92.393988 -320.529391) (xy 92.409928 -320.677224) (xy 92.417909 -320.825699) (xy 92.418408 -320.900044)
			(xy 92.417909 -320.974389) (xy 92.409928 -321.122864) (xy 92.393988 -321.270697) (xy 92.370137 -321.417461)
			(xy 92.338442 -321.562733) (xy 92.298995 -321.706094) (xy 92.25191 -321.847132) (xy 92.197322 -321.985438)
			(xy 92.135389 -322.120616) (xy 92.06629 -322.252274) (xy 91.990223 -322.380033) (xy 91.907408 -322.503525)
			(xy 91.818084 -322.622394) (xy 91.722508 -322.736296) (xy 91.620956 -322.844905) (xy 91.513721 -322.947906)
			(xy 91.401112 -323.045002) (xy 91.283453 -323.135914) (xy 91.161084 -323.220379) (xy 91.034358 -323.298154)
			(xy 90.903639 -323.369015) (xy 90.769305 -323.432757) (xy 90.631744 -323.489197) (xy 90.491351 -323.538171)
			(xy 90.348533 -323.579539) (xy 90.203699 -323.613181) (xy 90.057268 -323.639001) (xy 89.909663 -323.656924)
			(xy 89.761308 -323.666897) (xy 89.612632 -323.668893) (xy 89.464063 -323.662906) (xy 89.31603 -323.648953)
			(xy 89.168959 -323.627074) (xy 89.023274 -323.597332) (xy 88.879396 -323.559814) (xy 88.737739 -323.514626)
			(xy 88.598712 -323.4619) (xy 88.462716 -323.401788) (xy 88.330142 -323.334462) (xy 88.201373 -323.260117)
			(xy 88.07678 -323.178968) (xy 87.956723 -323.091248) (xy 87.841548 -322.99721) (xy 87.731586 -322.897125)
			(xy 87.627154 -322.791282) (xy 87.528555 -322.679987) (xy 87.436072 -322.563559) (xy 87.349971 -322.442335)
			(xy 87.270502 -322.316664) (xy 87.197893 -322.186908) (xy 87.132353 -322.053443) (xy 87.074071 -321.916651)
			(xy 87.023217 -321.776929) (xy 86.979935 -321.634678) (xy 86.944351 -321.490309) (xy 86.916568 -321.344239)
			(xy 86.896666 -321.196887) (xy 86.884701 -321.04868) (xy 86.880709 -320.900044) (xy 85.153508 -320.900044)
			(xy 85.157505 -321.089592) (xy 85.169489 -321.278804) (xy 85.18944 -321.467342) (xy 85.21732 -321.654871)
			(xy 85.253081 -321.841058) (xy 85.29666 -322.025573) (xy 85.347978 -322.208086) (xy 85.406945 -322.388273)
			(xy 85.473455 -322.565815) (xy 85.547391 -322.740394) (xy 85.628621 -322.911702) (xy 85.717 -323.079433)
			(xy 85.812372 -323.243289) (xy 85.914566 -323.402979) (xy 86.023402 -323.558219) (xy 86.138685 -323.708732)
			(xy 86.260211 -323.854252) (xy 86.387763 -323.99452) (xy 86.521116 -324.129285) (xy 86.660031 -324.258309)
			(xy 86.804261 -324.381362) (xy 86.953551 -324.498226) (xy 87.107635 -324.608692) (xy 87.266239 -324.712564)
			(xy 87.42908 -324.809658) (xy 87.59587 -324.899801) (xy 87.766312 -324.982832) (xy 87.940103 -325.058604)
			(xy 88.116933 -325.126982) (xy 88.296489 -325.187845) (xy 88.478451 -325.241085) (xy 88.662495 -325.286606)
			(xy 88.848295 -325.324328) (xy 89.03552 -325.354184) (xy 89.223837 -325.376121) (xy 89.412912 -325.390099)
			(xy 89.602408 -325.396094) (xy 89.791988 -325.394095) (xy 89.981315 -325.384107) (xy 90.170053 -325.366145)
			(xy 90.357866 -325.340243) (xy 90.54442 -325.306447) (xy 90.729383 -325.264816) (xy 90.912427 -325.215424)
			(xy 91.093226 -325.15836) (xy 91.271459 -325.093725) (xy 91.446808 -325.021634) (xy 91.618962 -324.942215)
			(xy 91.787616 -324.855609) (xy 91.952468 -324.76197) (xy 92.113227 -324.661464) (xy 92.269605 -324.554271)
			(xy 92.421326 -324.440581) (xy 92.568119 -324.320596) (xy 92.709723 -324.194529) (xy 92.845887 -324.062605)
			(xy 92.976368 -323.925058) (xy 93.100935 -323.782133) (xy 93.219366 -323.634083) (xy 93.33145 -323.481172)
			(xy 93.436989 -323.323673) (xy 93.535794 -323.161864) (xy 93.62769 -322.996033) (xy 93.712513 -322.826476)
			(xy 93.790113 -322.653494) (xy 93.860352 -322.477394) (xy 93.923104 -322.29849) (xy 93.978259 -322.1171)
			(xy 94.025718 -321.933545) (xy 94.065397 -321.748153) (xy 94.097225 -321.561253) (xy 94.121145 -321.373178)
			(xy 94.137116 -321.184261) (xy 94.145109 -320.994839)
		)
		(stroke
			(width 0)
			(type solid)
		)
		(fill yes)
		(layer "B.Cu")
		(net "GND")
	)
	(gr_poly
		(pts
			(xy 94.145608 -270.89989) (xy 94.145109 -270.805095) (xy 94.137116 -270.615673) (xy 94.121145 -270.426756)
			(xy 94.097225 -270.238681) (xy 94.065397 -270.051781) (xy 94.025718 -269.866389) (xy 93.978259 -269.682834)
			(xy 93.923104 -269.501444) (xy 93.860352 -269.32254) (xy 93.790113 -269.14644) (xy 93.712513 -268.973458)
			(xy 93.62769 -268.803901) (xy 93.535794 -268.63807) (xy 93.436989 -268.476261) (xy 93.33145 -268.318762)
			(xy 93.219366 -268.165851) (xy 93.100935 -268.017801) (xy 92.976368 -267.874876) (xy 92.845887 -267.737329)
			(xy 92.709723 -267.605405) (xy 92.568119 -267.479338) (xy 92.421326 -267.359353) (xy 92.269605 -267.245663)
			(xy 92.113227 -267.13847) (xy 91.952468 -267.037964) (xy 91.787616 -266.944325) (xy 91.618962 -266.857719)
			(xy 91.446808 -266.7783) (xy 91.271459 -266.706209) (xy 91.093226 -266.641574) (xy 90.912427 -266.58451)
			(xy 90.729383 -266.535118) (xy 90.54442 -266.493487) (xy 90.357866 -266.459691) (xy 90.170053 -266.433789)
			(xy 89.981315 -266.415827) (xy 89.791988 -266.405839) (xy 89.602408 -266.40384) (xy 89.412912 -266.409835)
			(xy 89.223837 -266.423813) (xy 89.03552 -266.44575) (xy 88.848295 -266.475606) (xy 88.662495 -266.513328)
			(xy 88.478451 -266.558849) (xy 88.296489 -266.612089) (xy 88.116933 -266.672952) (xy 87.940103 -266.74133)
			(xy 87.766312 -266.817102) (xy 87.59587 -266.900133) (xy 87.42908 -266.990276) (xy 87.266239 -267.08737)
			(xy 87.107635 -267.191242) (xy 86.953551 -267.301708) (xy 86.804261 -267.418572) (xy 86.660031 -267.541625)
			(xy 86.521116 -267.670649) (xy 86.387763 -267.805414) (xy 86.260211 -267.945682) (xy 86.138685 -268.091202)
			(xy 86.023402 -268.241715) (xy 85.914566 -268.396955) (xy 85.812372 -268.556645) (xy 85.717 -268.720501)
			(xy 85.628621 -268.888232) (xy 85.547391 -269.05954) (xy 85.473455 -269.234119) (xy 85.406945 -269.411661)
			(xy 85.347978 -269.591848) (xy 85.29666 -269.774361) (xy 85.253081 -269.958876) (xy 85.21732 -270.145063)
			(xy 85.18944 -270.332592) (xy 85.169489 -270.52113) (xy 85.157505 -270.710342) (xy 85.153508 -270.89989)
			(xy 86.880709 -270.89989) (xy 86.884701 -270.751254) (xy 86.896666 -270.603047) (xy 86.916568 -270.455695)
			(xy 86.944351 -270.309625) (xy 86.979935 -270.165256) (xy 87.023217 -270.023005) (xy 87.074071 -269.883283)
			(xy 87.132353 -269.746491) (xy 87.197893 -269.613026) (xy 87.270502 -269.48327) (xy 87.349971 -269.357599)
			(xy 87.436072 -269.236375) (xy 87.528555 -269.119947) (xy 87.627154 -269.008652) (xy 87.731586 -268.902809)
			(xy 87.841548 -268.802724) (xy 87.956723 -268.708686) (xy 88.07678 -268.620966) (xy 88.201373 -268.539817)
			(xy 88.330142 -268.465472) (xy 88.462716 -268.398146) (xy 88.598712 -268.338034) (xy 88.737739 -268.285308)
			(xy 88.879396 -268.24012) (xy 89.023274 -268.202602) (xy 89.168959 -268.17286) (xy 89.31603 -268.150981)
			(xy 89.464063 -268.137028) (xy 89.612632 -268.131041) (xy 89.761308 -268.133037) (xy 89.909663 -268.14301)
			(xy 90.057268 -268.160933) (xy 90.203699 -268.186753) (xy 90.348533 -268.220395) (xy 90.491351 -268.261763)
			(xy 90.631744 -268.310737) (xy 90.769305 -268.367177) (xy 90.903639 -268.430919) (xy 91.034358 -268.50178)
			(xy 91.161084 -268.579555) (xy 91.283453 -268.66402) (xy 91.401112 -268.754932) (xy 91.513721 -268.852028)
			(xy 91.620956 -268.955029) (xy 91.722508 -269.063638) (xy 91.818084 -269.17754) (xy 91.907408 -269.296409)
			(xy 91.990223 -269.419901) (xy 92.06629 -269.54766) (xy 92.135389 -269.679318) (xy 92.197322 -269.814496)
			(xy 92.25191 -269.952802) (xy 92.298995 -270.09384) (xy 92.338442 -270.237201) (xy 92.370137 -270.382473)
			(xy 92.393988 -270.529237) (xy 92.409928 -270.67707) (xy 92.417909 -270.825545) (xy 92.418408 -270.89989)
			(xy 92.417909 -270.974235) (xy 92.409928 -271.12271) (xy 92.393988 -271.270543) (xy 92.370137 -271.417307)
			(xy 92.338442 -271.562579) (xy 92.298995 -271.70594) (xy 92.25191 -271.846978) (xy 92.197322 -271.985284)
			(xy 92.135389 -272.120462) (xy 92.06629 -272.25212) (xy 91.990223 -272.379879) (xy 91.907408 -272.503371)
			(xy 91.818084 -272.62224) (xy 91.722508 -272.736142) (xy 91.620956 -272.844751) (xy 91.513721 -272.947752)
			(xy 91.401112 -273.044848) (xy 91.283453 -273.13576) (xy 91.161084 -273.220225) (xy 91.034358 -273.298)
			(xy 90.903639 -273.368861) (xy 90.769305 -273.432603) (xy 90.631744 -273.489043) (xy 90.491351 -273.538017)
			(xy 90.348533 -273.579385) (xy 90.203699 -273.613027) (xy 90.057268 -273.638847) (xy 89.909663 -273.65677)
			(xy 89.761308 -273.666743) (xy 89.612632 -273.668739) (xy 89.464063 -273.662752) (xy 89.31603 -273.648799)
			(xy 89.168959 -273.62692) (xy 89.023274 -273.597178) (xy 88.879396 -273.55966) (xy 88.737739 -273.514472)
			(xy 88.598712 -273.461746) (xy 88.462716 -273.401634) (xy 88.330142 -273.334308) (xy 88.201373 -273.259963)
			(xy 88.07678 -273.178814) (xy 87.956723 -273.091094) (xy 87.841548 -272.997056) (xy 87.731586 -272.896971)
			(xy 87.627154 -272.791128) (xy 87.528555 -272.679833) (xy 87.436072 -272.563405) (xy 87.349971 -272.442181)
			(xy 87.270502 -272.31651) (xy 87.197893 -272.186754) (xy 87.132353 -272.053289) (xy 87.074071 -271.916497)
			(xy 87.023217 -271.776775) (xy 86.979935 -271.634524) (xy 86.944351 -271.490155) (xy 86.916568 -271.344085)
			(xy 86.896666 -271.196733) (xy 86.884701 -271.048526) (xy 86.880709 -270.89989) (xy 85.153508 -270.89989)
			(xy 85.157505 -271.089438) (xy 85.169489 -271.27865) (xy 85.18944 -271.467188) (xy 85.21732 -271.654717)
			(xy 85.253081 -271.840904) (xy 85.29666 -272.025419) (xy 85.347978 -272.207932) (xy 85.406945 -272.388119)
			(xy 85.473455 -272.565661) (xy 85.547391 -272.74024) (xy 85.628621 -272.911548) (xy 85.717 -273.079279)
			(xy 85.812372 -273.243135) (xy 85.914566 -273.402825) (xy 86.023402 -273.558065) (xy 86.138685 -273.708578)
			(xy 86.260211 -273.854098) (xy 86.387763 -273.994366) (xy 86.521116 -274.129131) (xy 86.660031 -274.258155)
			(xy 86.804261 -274.381208) (xy 86.953551 -274.498072) (xy 87.107635 -274.608538) (xy 87.266239 -274.71241)
			(xy 87.42908 -274.809504) (xy 87.59587 -274.899647) (xy 87.766312 -274.982678) (xy 87.940103 -275.05845)
			(xy 88.116933 -275.126828) (xy 88.296489 -275.187691) (xy 88.478451 -275.240931) (xy 88.662495 -275.286452)
			(xy 88.848295 -275.324174) (xy 89.03552 -275.35403) (xy 89.223837 -275.375967) (xy 89.412912 -275.389945)
			(xy 89.602408 -275.39594) (xy 89.791988 -275.393941) (xy 89.981315 -275.383953) (xy 90.170053 -275.365991)
			(xy 90.357866 -275.340089) (xy 90.54442 -275.306293) (xy 90.729383 -275.264662) (xy 90.912427 -275.21527)
			(xy 91.093226 -275.158206) (xy 91.271459 -275.093571) (xy 91.446808 -275.02148) (xy 91.618962 -274.942061)
			(xy 91.787616 -274.855455) (xy 91.952468 -274.761816) (xy 92.113227 -274.66131) (xy 92.269605 -274.554117)
			(xy 92.421326 -274.440427) (xy 92.568119 -274.320442) (xy 92.709723 -274.194375) (xy 92.845887 -274.062451)
			(xy 92.976368 -273.924904) (xy 93.100935 -273.781979) (xy 93.219366 -273.633929) (xy 93.33145 -273.481018)
			(xy 93.436989 -273.323519) (xy 93.535794 -273.16171) (xy 93.62769 -272.995879) (xy 93.712513 -272.826322)
			(xy 93.790113 -272.65334) (xy 93.860352 -272.47724) (xy 93.923104 -272.298336) (xy 93.978259 -272.116946)
			(xy 94.025718 -271.933391) (xy 94.065397 -271.747999) (xy 94.097225 -271.561099) (xy 94.121145 -271.373024)
			(xy 94.137116 -271.184107) (xy 94.145109 -270.994685)
		)
		(stroke
			(width 0)
			(type solid)
		)
		(fill yes)
		(layer "B.Cu")
		(net "GND")
	)
	(gr_poly
		(pts
			(xy 150.245572 -320.900044) (xy 150.245073 -320.805249) (xy 150.23708 -320.615827) (xy 150.221109 -320.42691)
			(xy 150.197189 -320.238835) (xy 150.165361 -320.051935) (xy 150.125682 -319.866543) (xy 150.078223 -319.682988)
			(xy 150.023068 -319.501598) (xy 149.960316 -319.322694) (xy 149.890077 -319.146594) (xy 149.812477 -318.973612)
			(xy 149.727654 -318.804055) (xy 149.635758 -318.638224) (xy 149.536953 -318.476415) (xy 149.431414 -318.318916)
			(xy 149.31933 -318.166005) (xy 149.200899 -318.017955) (xy 149.076332 -317.87503) (xy 148.945851 -317.737483)
			(xy 148.809687 -317.605559) (xy 148.668083 -317.479492) (xy 148.52129 -317.359507) (xy 148.369569 -317.245817)
			(xy 148.213191 -317.138624) (xy 148.052432 -317.038118) (xy 147.88758 -316.944479) (xy 147.718926 -316.857873)
			(xy 147.546772 -316.778454) (xy 147.371423 -316.706363) (xy 147.19319 -316.641728) (xy 147.012391 -316.584664)
			(xy 146.829347 -316.535272) (xy 146.644384 -316.493641) (xy 146.45783 -316.459845) (xy 146.270017 -316.433943)
			(xy 146.081279 -316.415981) (xy 145.891952 -316.405993) (xy 145.702372 -316.403994) (xy 145.512876 -316.409989)
			(xy 145.323801 -316.423967) (xy 145.135484 -316.445904) (xy 144.948259 -316.47576) (xy 144.762459 -316.513482)
			(xy 144.578415 -316.559003) (xy 144.396453 -316.612243) (xy 144.216897 -316.673106) (xy 144.040067 -316.741484)
			(xy 143.866276 -316.817256) (xy 143.695834 -316.900287) (xy 143.529044 -316.99043) (xy 143.366203 -317.087524)
			(xy 143.207599 -317.191396) (xy 143.053515 -317.301862) (xy 142.904225 -317.418726) (xy 142.759995 -317.541779)
			(xy 142.62108 -317.670803) (xy 142.487727 -317.805568) (xy 142.360175 -317.945836) (xy 142.238649 -318.091356)
			(xy 142.123366 -318.241869) (xy 142.01453 -318.397109) (xy 141.912336 -318.556799) (xy 141.816964 -318.720655)
			(xy 141.728585 -318.888386) (xy 141.647355 -319.059694) (xy 141.573419 -319.234273) (xy 141.506909 -319.411815)
			(xy 141.447942 -319.592002) (xy 141.396624 -319.774515) (xy 141.353045 -319.95903) (xy 141.317284 -320.145217)
			(xy 141.289404 -320.332746) (xy 141.269453 -320.521284) (xy 141.257469 -320.710496) (xy 141.253472 -320.900044)
			(xy 142.980673 -320.900044) (xy 142.984665 -320.751408) (xy 142.99663 -320.603201) (xy 143.016532 -320.455849)
			(xy 143.044315 -320.309779) (xy 143.079899 -320.16541) (xy 143.123181 -320.023159) (xy 143.174035 -319.883437)
			(xy 143.232317 -319.746645) (xy 143.297857 -319.61318) (xy 143.370466 -319.483424) (xy 143.449935 -319.357753)
			(xy 143.536036 -319.236529) (xy 143.628519 -319.120101) (xy 143.727118 -319.008806) (xy 143.83155 -318.902963)
			(xy 143.941512 -318.802878) (xy 144.056687 -318.70884) (xy 144.176744 -318.62112) (xy 144.301337 -318.539971)
			(xy 144.430106 -318.465626) (xy 144.56268 -318.3983) (xy 144.698676 -318.338188) (xy 144.837703 -318.285462)
			(xy 144.97936 -318.240274) (xy 145.123238 -318.202756) (xy 145.268923 -318.173014) (xy 145.415994 -318.151135)
			(xy 145.564027 -318.137182) (xy 145.712596 -318.131195) (xy 145.861272 -318.133191) (xy 146.009627 -318.143164)
			(xy 146.157232 -318.161087) (xy 146.303663 -318.186907) (xy 146.448497 -318.220549) (xy 146.591315 -318.261917)
			(xy 146.731708 -318.310891) (xy 146.869269 -318.367331) (xy 147.003603 -318.431073) (xy 147.134322 -318.501934)
			(xy 147.261048 -318.579709) (xy 147.383417 -318.664174) (xy 147.501076 -318.755086) (xy 147.613685 -318.852182)
			(xy 147.72092 -318.955183) (xy 147.822472 -319.063792) (xy 147.918048 -319.177694) (xy 148.007372 -319.296563)
			(xy 148.090187 -319.420055) (xy 148.166254 -319.547814) (xy 148.235353 -319.679472) (xy 148.297286 -319.81465)
			(xy 148.351874 -319.952956) (xy 148.398959 -320.093994) (xy 148.438406 -320.237355) (xy 148.470101 -320.382627)
			(xy 148.493952 -320.529391) (xy 148.509892 -320.677224) (xy 148.517873 -320.825699) (xy 148.518372 -320.900044)
			(xy 148.517873 -320.974389) (xy 148.509892 -321.122864) (xy 148.493952 -321.270697) (xy 148.470101 -321.417461)
			(xy 148.438406 -321.562733) (xy 148.398959 -321.706094) (xy 148.351874 -321.847132) (xy 148.297286 -321.985438)
			(xy 148.235353 -322.120616) (xy 148.166254 -322.252274) (xy 148.090187 -322.380033) (xy 148.007372 -322.503525)
			(xy 147.918048 -322.622394) (xy 147.822472 -322.736296) (xy 147.72092 -322.844905) (xy 147.613685 -322.947906)
			(xy 147.501076 -323.045002) (xy 147.383417 -323.135914) (xy 147.261048 -323.220379) (xy 147.134322 -323.298154)
			(xy 147.003603 -323.369015) (xy 146.869269 -323.432757) (xy 146.731708 -323.489197) (xy 146.591315 -323.538171)
			(xy 146.448497 -323.579539) (xy 146.303663 -323.613181) (xy 146.157232 -323.639001) (xy 146.009627 -323.656924)
			(xy 145.861272 -323.666897) (xy 145.712596 -323.668893) (xy 145.564027 -323.662906) (xy 145.415994 -323.648953)
			(xy 145.268923 -323.627074) (xy 145.123238 -323.597332) (xy 144.97936 -323.559814) (xy 144.837703 -323.514626)
			(xy 144.698676 -323.4619) (xy 144.56268 -323.401788) (xy 144.430106 -323.334462) (xy 144.301337 -323.260117)
			(xy 144.176744 -323.178968) (xy 144.056687 -323.091248) (xy 143.941512 -322.99721) (xy 143.83155 -322.897125)
			(xy 143.727118 -322.791282) (xy 143.628519 -322.679987) (xy 143.536036 -322.563559) (xy 143.449935 -322.442335)
			(xy 143.370466 -322.316664) (xy 143.297857 -322.186908) (xy 143.232317 -322.053443) (xy 143.174035 -321.916651)
			(xy 143.123181 -321.776929) (xy 143.079899 -321.634678) (xy 143.044315 -321.490309) (xy 143.016532 -321.344239)
			(xy 142.99663 -321.196887) (xy 142.984665 -321.04868) (xy 142.980673 -320.900044) (xy 141.253472 -320.900044)
			(xy 141.257469 -321.089592) (xy 141.269453 -321.278804) (xy 141.289404 -321.467342) (xy 141.317284 -321.654871)
			(xy 141.353045 -321.841058) (xy 141.396624 -322.025573) (xy 141.447942 -322.208086) (xy 141.506909 -322.388273)
			(xy 141.573419 -322.565815) (xy 141.647355 -322.740394) (xy 141.728585 -322.911702) (xy 141.816964 -323.079433)
			(xy 141.912336 -323.243289) (xy 142.01453 -323.402979) (xy 142.123366 -323.558219) (xy 142.238649 -323.708732)
			(xy 142.360175 -323.854252) (xy 142.487727 -323.99452) (xy 142.62108 -324.129285) (xy 142.759995 -324.258309)
			(xy 142.904225 -324.381362) (xy 143.053515 -324.498226) (xy 143.207599 -324.608692) (xy 143.366203 -324.712564)
			(xy 143.529044 -324.809658) (xy 143.695834 -324.899801) (xy 143.866276 -324.982832) (xy 144.040067 -325.058604)
			(xy 144.216897 -325.126982) (xy 144.396453 -325.187845) (xy 144.578415 -325.241085) (xy 144.762459 -325.286606)
			(xy 144.948259 -325.324328) (xy 145.135484 -325.354184) (xy 145.323801 -325.376121) (xy 145.512876 -325.390099)
			(xy 145.702372 -325.396094) (xy 145.891952 -325.394095) (xy 146.081279 -325.384107) (xy 146.270017 -325.366145)
			(xy 146.45783 -325.340243) (xy 146.644384 -325.306447) (xy 146.829347 -325.264816) (xy 147.012391 -325.215424)
			(xy 147.19319 -325.15836) (xy 147.371423 -325.093725) (xy 147.546772 -325.021634) (xy 147.718926 -324.942215)
			(xy 147.88758 -324.855609) (xy 148.052432 -324.76197) (xy 148.213191 -324.661464) (xy 148.369569 -324.554271)
			(xy 148.52129 -324.440581) (xy 148.668083 -324.320596) (xy 148.809687 -324.194529) (xy 148.945851 -324.062605)
			(xy 149.076332 -323.925058) (xy 149.200899 -323.782133) (xy 149.31933 -323.634083) (xy 149.431414 -323.481172)
			(xy 149.536953 -323.323673) (xy 149.635758 -323.161864) (xy 149.727654 -322.996033) (xy 149.812477 -322.826476)
			(xy 149.890077 -322.653494) (xy 149.960316 -322.477394) (xy 150.023068 -322.29849) (xy 150.078223 -322.1171)
			(xy 150.125682 -321.933545) (xy 150.165361 -321.748153) (xy 150.197189 -321.561253) (xy 150.221109 -321.373178)
			(xy 150.23708 -321.184261) (xy 150.245073 -320.994839)
		)
		(stroke
			(width 0)
			(type solid)
		)
		(fill yes)
		(layer "B.Cu")
		(net "GND")
	)
	(gr_poly
		(pts
			(xy 150.245572 -270.89989) (xy 150.245073 -270.805095) (xy 150.23708 -270.615673) (xy 150.221109 -270.426756)
			(xy 150.197189 -270.238681) (xy 150.165361 -270.051781) (xy 150.125682 -269.866389) (xy 150.078223 -269.682834)
			(xy 150.023068 -269.501444) (xy 149.960316 -269.32254) (xy 149.890077 -269.14644) (xy 149.812477 -268.973458)
			(xy 149.727654 -268.803901) (xy 149.635758 -268.63807) (xy 149.536953 -268.476261) (xy 149.431414 -268.318762)
			(xy 149.31933 -268.165851) (xy 149.200899 -268.017801) (xy 149.076332 -267.874876) (xy 148.945851 -267.737329)
			(xy 148.809687 -267.605405) (xy 148.668083 -267.479338) (xy 148.52129 -267.359353) (xy 148.369569 -267.245663)
			(xy 148.213191 -267.13847) (xy 148.052432 -267.037964) (xy 147.88758 -266.944325) (xy 147.718926 -266.857719)
			(xy 147.546772 -266.7783) (xy 147.371423 -266.706209) (xy 147.19319 -266.641574) (xy 147.012391 -266.58451)
			(xy 146.829347 -266.535118) (xy 146.644384 -266.493487) (xy 146.45783 -266.459691) (xy 146.270017 -266.433789)
			(xy 146.081279 -266.415827) (xy 145.891952 -266.405839) (xy 145.702372 -266.40384) (xy 145.512876 -266.409835)
			(xy 145.323801 -266.423813) (xy 145.135484 -266.44575) (xy 144.948259 -266.475606) (xy 144.762459 -266.513328)
			(xy 144.578415 -266.558849) (xy 144.396453 -266.612089) (xy 144.216897 -266.672952) (xy 144.040067 -266.74133)
			(xy 143.866276 -266.817102) (xy 143.695834 -266.900133) (xy 143.529044 -266.990276) (xy 143.366203 -267.08737)
			(xy 143.207599 -267.191242) (xy 143.053515 -267.301708) (xy 142.904225 -267.418572) (xy 142.759995 -267.541625)
			(xy 142.62108 -267.670649) (xy 142.487727 -267.805414) (xy 142.360175 -267.945682) (xy 142.238649 -268.091202)
			(xy 142.123366 -268.241715) (xy 142.01453 -268.396955) (xy 141.912336 -268.556645) (xy 141.816964 -268.720501)
			(xy 141.728585 -268.888232) (xy 141.647355 -269.05954) (xy 141.573419 -269.234119) (xy 141.506909 -269.411661)
			(xy 141.447942 -269.591848) (xy 141.396624 -269.774361) (xy 141.353045 -269.958876) (xy 141.317284 -270.145063)
			(xy 141.289404 -270.332592) (xy 141.269453 -270.52113) (xy 141.257469 -270.710342) (xy 141.253472 -270.89989)
			(xy 142.980673 -270.89989) (xy 142.984665 -270.751254) (xy 142.99663 -270.603047) (xy 143.016532 -270.455695)
			(xy 143.044315 -270.309625) (xy 143.079899 -270.165256) (xy 143.123181 -270.023005) (xy 143.174035 -269.883283)
			(xy 143.232317 -269.746491) (xy 143.297857 -269.613026) (xy 143.370466 -269.48327) (xy 143.449935 -269.357599)
			(xy 143.536036 -269.236375) (xy 143.628519 -269.119947) (xy 143.727118 -269.008652) (xy 143.83155 -268.902809)
			(xy 143.941512 -268.802724) (xy 144.056687 -268.708686) (xy 144.176744 -268.620966) (xy 144.301337 -268.539817)
			(xy 144.430106 -268.465472) (xy 144.56268 -268.398146) (xy 144.698676 -268.338034) (xy 144.837703 -268.285308)
			(xy 144.97936 -268.24012) (xy 145.123238 -268.202602) (xy 145.268923 -268.17286) (xy 145.415994 -268.150981)
			(xy 145.564027 -268.137028) (xy 145.712596 -268.131041) (xy 145.861272 -268.133037) (xy 146.009627 -268.14301)
			(xy 146.157232 -268.160933) (xy 146.303663 -268.186753) (xy 146.448497 -268.220395) (xy 146.591315 -268.261763)
			(xy 146.731708 -268.310737) (xy 146.869269 -268.367177) (xy 147.003603 -268.430919) (xy 147.134322 -268.50178)
			(xy 147.261048 -268.579555) (xy 147.383417 -268.66402) (xy 147.501076 -268.754932) (xy 147.613685 -268.852028)
			(xy 147.72092 -268.955029) (xy 147.822472 -269.063638) (xy 147.918048 -269.17754) (xy 148.007372 -269.296409)
			(xy 148.090187 -269.419901) (xy 148.166254 -269.54766) (xy 148.235353 -269.679318) (xy 148.297286 -269.814496)
			(xy 148.351874 -269.952802) (xy 148.398959 -270.09384) (xy 148.438406 -270.237201) (xy 148.470101 -270.382473)
			(xy 148.493952 -270.529237) (xy 148.509892 -270.67707) (xy 148.517873 -270.825545) (xy 148.518372 -270.89989)
			(xy 148.517873 -270.974235) (xy 148.509892 -271.12271) (xy 148.493952 -271.270543) (xy 148.470101 -271.417307)
			(xy 148.438406 -271.562579) (xy 148.398959 -271.70594) (xy 148.351874 -271.846978) (xy 148.297286 -271.985284)
			(xy 148.235353 -272.120462) (xy 148.166254 -272.25212) (xy 148.090187 -272.379879) (xy 148.007372 -272.503371)
			(xy 147.918048 -272.62224) (xy 147.822472 -272.736142) (xy 147.72092 -272.844751) (xy 147.613685 -272.947752)
			(xy 147.501076 -273.044848) (xy 147.383417 -273.13576) (xy 147.261048 -273.220225) (xy 147.134322 -273.298)
			(xy 147.003603 -273.368861) (xy 146.869269 -273.432603) (xy 146.731708 -273.489043) (xy 146.591315 -273.538017)
			(xy 146.448497 -273.579385) (xy 146.303663 -273.613027) (xy 146.157232 -273.638847) (xy 146.009627 -273.65677)
			(xy 145.861272 -273.666743) (xy 145.712596 -273.668739) (xy 145.564027 -273.662752) (xy 145.415994 -273.648799)
			(xy 145.268923 -273.62692) (xy 145.123238 -273.597178) (xy 144.97936 -273.55966) (xy 144.837703 -273.514472)
			(xy 144.698676 -273.461746) (xy 144.56268 -273.401634) (xy 144.430106 -273.334308) (xy 144.301337 -273.259963)
			(xy 144.176744 -273.178814) (xy 144.056687 -273.091094) (xy 143.941512 -272.997056) (xy 143.83155 -272.896971)
			(xy 143.727118 -272.791128) (xy 143.628519 -272.679833) (xy 143.536036 -272.563405) (xy 143.449935 -272.442181)
			(xy 143.370466 -272.31651) (xy 143.297857 -272.186754) (xy 143.232317 -272.053289) (xy 143.174035 -271.916497)
			(xy 143.123181 -271.776775) (xy 143.079899 -271.634524) (xy 143.044315 -271.490155) (xy 143.016532 -271.344085)
			(xy 142.99663 -271.196733) (xy 142.984665 -271.048526) (xy 142.980673 -270.89989) (xy 141.253472 -270.89989)
			(xy 141.257469 -271.089438) (xy 141.269453 -271.27865) (xy 141.289404 -271.467188) (xy 141.317284 -271.654717)
			(xy 141.353045 -271.840904) (xy 141.396624 -272.025419) (xy 141.447942 -272.207932) (xy 141.506909 -272.388119)
			(xy 141.573419 -272.565661) (xy 141.647355 -272.74024) (xy 141.728585 -272.911548) (xy 141.816964 -273.079279)
			(xy 141.912336 -273.243135) (xy 142.01453 -273.402825) (xy 142.123366 -273.558065) (xy 142.238649 -273.708578)
			(xy 142.360175 -273.854098) (xy 142.487727 -273.994366) (xy 142.62108 -274.129131) (xy 142.759995 -274.258155)
			(xy 142.904225 -274.381208) (xy 143.053515 -274.498072) (xy 143.207599 -274.608538) (xy 143.366203 -274.71241)
			(xy 143.529044 -274.809504) (xy 143.695834 -274.899647) (xy 143.866276 -274.982678) (xy 144.040067 -275.05845)
			(xy 144.216897 -275.126828) (xy 144.396453 -275.187691) (xy 144.578415 -275.240931) (xy 144.762459 -275.286452)
			(xy 144.948259 -275.324174) (xy 145.135484 -275.35403) (xy 145.323801 -275.375967) (xy 145.512876 -275.389945)
			(xy 145.702372 -275.39594) (xy 145.891952 -275.393941) (xy 146.081279 -275.383953) (xy 146.270017 -275.365991)
			(xy 146.45783 -275.340089) (xy 146.644384 -275.306293) (xy 146.829347 -275.264662) (xy 147.012391 -275.21527)
			(xy 147.19319 -275.158206) (xy 147.371423 -275.093571) (xy 147.546772 -275.02148) (xy 147.718926 -274.942061)
			(xy 147.88758 -274.855455) (xy 148.052432 -274.761816) (xy 148.213191 -274.66131) (xy 148.369569 -274.554117)
			(xy 148.52129 -274.440427) (xy 148.668083 -274.320442) (xy 148.809687 -274.194375) (xy 148.945851 -274.062451)
			(xy 149.076332 -273.924904) (xy 149.200899 -273.781979) (xy 149.31933 -273.633929) (xy 149.431414 -273.481018)
			(xy 149.536953 -273.323519) (xy 149.635758 -273.16171) (xy 149.727654 -272.995879) (xy 149.812477 -272.826322)
			(xy 149.890077 -272.65334) (xy 149.960316 -272.47724) (xy 150.023068 -272.298336) (xy 150.078223 -272.116946)
			(xy 150.125682 -271.933391) (xy 150.165361 -271.747999) (xy 150.197189 -271.561099) (xy 150.221109 -271.373024)
			(xy 150.23708 -271.184107) (xy 150.245073 -270.994685)
		)
		(stroke
			(width 0)
			(type solid)
		)
		(fill yes)
		(layer "B.Cu")
		(net "GND")
	)
	(gr_poly
		(pts
			(xy 210.245452 -320.900044) (xy 210.244953 -320.805249) (xy 210.23696 -320.615827) (xy 210.220989 -320.42691)
			(xy 210.197069 -320.238835) (xy 210.165241 -320.051935) (xy 210.125562 -319.866543) (xy 210.078103 -319.682988)
			(xy 210.022948 -319.501598) (xy 209.960196 -319.322694) (xy 209.889957 -319.146594) (xy 209.812357 -318.973612)
			(xy 209.727534 -318.804055) (xy 209.635638 -318.638224) (xy 209.536833 -318.476415) (xy 209.431294 -318.318916)
			(xy 209.31921 -318.166005) (xy 209.200779 -318.017955) (xy 209.076212 -317.87503) (xy 208.945731 -317.737483)
			(xy 208.809567 -317.605559) (xy 208.667963 -317.479492) (xy 208.52117 -317.359507) (xy 208.369449 -317.245817)
			(xy 208.213071 -317.138624) (xy 208.052312 -317.038118) (xy 207.88746 -316.944479) (xy 207.718806 -316.857873)
			(xy 207.546652 -316.778454) (xy 207.371303 -316.706363) (xy 207.19307 -316.641728) (xy 207.012271 -316.584664)
			(xy 206.829227 -316.535272) (xy 206.644264 -316.493641) (xy 206.45771 -316.459845) (xy 206.269897 -316.433943)
			(xy 206.081159 -316.415981) (xy 205.891832 -316.405993) (xy 205.702252 -316.403994) (xy 205.512756 -316.409989)
			(xy 205.323681 -316.423967) (xy 205.135364 -316.445904) (xy 204.948139 -316.47576) (xy 204.762339 -316.513482)
			(xy 204.578295 -316.559003) (xy 204.396333 -316.612243) (xy 204.216777 -316.673106) (xy 204.039947 -316.741484)
			(xy 203.866156 -316.817256) (xy 203.695714 -316.900287) (xy 203.528924 -316.99043) (xy 203.366083 -317.087524)
			(xy 203.207479 -317.191396) (xy 203.053395 -317.301862) (xy 202.904105 -317.418726) (xy 202.759875 -317.541779)
			(xy 202.62096 -317.670803) (xy 202.487607 -317.805568) (xy 202.360055 -317.945836) (xy 202.238529 -318.091356)
			(xy 202.123246 -318.241869) (xy 202.01441 -318.397109) (xy 201.912216 -318.556799) (xy 201.816844 -318.720655)
			(xy 201.728465 -318.888386) (xy 201.647235 -319.059694) (xy 201.573299 -319.234273) (xy 201.506789 -319.411815)
			(xy 201.447822 -319.592002) (xy 201.396504 -319.774515) (xy 201.352925 -319.95903) (xy 201.317164 -320.145217)
			(xy 201.289284 -320.332746) (xy 201.269333 -320.521284) (xy 201.257349 -320.710496) (xy 201.253352 -320.900044)
			(xy 202.980553 -320.900044) (xy 202.984545 -320.751408) (xy 202.99651 -320.603201) (xy 203.016412 -320.455849)
			(xy 203.044195 -320.309779) (xy 203.079779 -320.16541) (xy 203.123061 -320.023159) (xy 203.173915 -319.883437)
			(xy 203.232197 -319.746645) (xy 203.297737 -319.61318) (xy 203.370346 -319.483424) (xy 203.449815 -319.357753)
			(xy 203.535916 -319.236529) (xy 203.628399 -319.120101) (xy 203.726998 -319.008806) (xy 203.83143 -318.902963)
			(xy 203.941392 -318.802878) (xy 204.056567 -318.70884) (xy 204.176624 -318.62112) (xy 204.301217 -318.539971)
			(xy 204.429986 -318.465626) (xy 204.56256 -318.3983) (xy 204.698556 -318.338188) (xy 204.837583 -318.285462)
			(xy 204.97924 -318.240274) (xy 205.123118 -318.202756) (xy 205.268803 -318.173014) (xy 205.415874 -318.151135)
			(xy 205.563907 -318.137182) (xy 205.712476 -318.131195) (xy 205.861152 -318.133191) (xy 206.009507 -318.143164)
			(xy 206.157112 -318.161087) (xy 206.303543 -318.186907) (xy 206.448377 -318.220549) (xy 206.591195 -318.261917)
			(xy 206.731588 -318.310891) (xy 206.869149 -318.367331) (xy 207.003483 -318.431073) (xy 207.134202 -318.501934)
			(xy 207.260928 -318.579709) (xy 207.383297 -318.664174) (xy 207.500956 -318.755086) (xy 207.613565 -318.852182)
			(xy 207.7208 -318.955183) (xy 207.822352 -319.063792) (xy 207.917928 -319.177694) (xy 208.007252 -319.296563)
			(xy 208.090067 -319.420055) (xy 208.166134 -319.547814) (xy 208.235233 -319.679472) (xy 208.297166 -319.81465)
			(xy 208.351754 -319.952956) (xy 208.398839 -320.093994) (xy 208.438286 -320.237355) (xy 208.469981 -320.382627)
			(xy 208.493832 -320.529391) (xy 208.509772 -320.677224) (xy 208.517753 -320.825699) (xy 208.518252 -320.900044)
			(xy 208.517753 -320.974389) (xy 208.509772 -321.122864) (xy 208.493832 -321.270697) (xy 208.469981 -321.417461)
			(xy 208.438286 -321.562733) (xy 208.398839 -321.706094) (xy 208.351754 -321.847132) (xy 208.297166 -321.985438)
			(xy 208.235233 -322.120616) (xy 208.166134 -322.252274) (xy 208.090067 -322.380033) (xy 208.007252 -322.503525)
			(xy 207.917928 -322.622394) (xy 207.822352 -322.736296) (xy 207.7208 -322.844905) (xy 207.613565 -322.947906)
			(xy 207.500956 -323.045002) (xy 207.383297 -323.135914) (xy 207.260928 -323.220379) (xy 207.134202 -323.298154)
			(xy 207.003483 -323.369015) (xy 206.869149 -323.432757) (xy 206.731588 -323.489197) (xy 206.591195 -323.538171)
			(xy 206.448377 -323.579539) (xy 206.303543 -323.613181) (xy 206.157112 -323.639001) (xy 206.009507 -323.656924)
			(xy 205.861152 -323.666897) (xy 205.712476 -323.668893) (xy 205.563907 -323.662906) (xy 205.415874 -323.648953)
			(xy 205.268803 -323.627074) (xy 205.123118 -323.597332) (xy 204.97924 -323.559814) (xy 204.837583 -323.514626)
			(xy 204.698556 -323.4619) (xy 204.56256 -323.401788) (xy 204.429986 -323.334462) (xy 204.301217 -323.260117)
			(xy 204.176624 -323.178968) (xy 204.056567 -323.091248) (xy 203.941392 -322.99721) (xy 203.83143 -322.897125)
			(xy 203.726998 -322.791282) (xy 203.628399 -322.679987) (xy 203.535916 -322.563559) (xy 203.449815 -322.442335)
			(xy 203.370346 -322.316664) (xy 203.297737 -322.186908) (xy 203.232197 -322.053443) (xy 203.173915 -321.916651)
			(xy 203.123061 -321.776929) (xy 203.079779 -321.634678) (xy 203.044195 -321.490309) (xy 203.016412 -321.344239)
			(xy 202.99651 -321.196887) (xy 202.984545 -321.04868) (xy 202.980553 -320.900044) (xy 201.253352 -320.900044)
			(xy 201.257349 -321.089592) (xy 201.269333 -321.278804) (xy 201.289284 -321.467342) (xy 201.317164 -321.654871)
			(xy 201.352925 -321.841058) (xy 201.396504 -322.025573) (xy 201.447822 -322.208086) (xy 201.506789 -322.388273)
			(xy 201.573299 -322.565815) (xy 201.647235 -322.740394) (xy 201.728465 -322.911702) (xy 201.816844 -323.079433)
			(xy 201.912216 -323.243289) (xy 202.01441 -323.402979) (xy 202.123246 -323.558219) (xy 202.238529 -323.708732)
			(xy 202.360055 -323.854252) (xy 202.487607 -323.99452) (xy 202.62096 -324.129285) (xy 202.759875 -324.258309)
			(xy 202.904105 -324.381362) (xy 203.053395 -324.498226) (xy 203.207479 -324.608692) (xy 203.366083 -324.712564)
			(xy 203.528924 -324.809658) (xy 203.695714 -324.899801) (xy 203.866156 -324.982832) (xy 204.039947 -325.058604)
			(xy 204.216777 -325.126982) (xy 204.396333 -325.187845) (xy 204.578295 -325.241085) (xy 204.762339 -325.286606)
			(xy 204.948139 -325.324328) (xy 205.135364 -325.354184) (xy 205.323681 -325.376121) (xy 205.512756 -325.390099)
			(xy 205.702252 -325.396094) (xy 205.891832 -325.394095) (xy 206.081159 -325.384107) (xy 206.269897 -325.366145)
			(xy 206.45771 -325.340243) (xy 206.644264 -325.306447) (xy 206.829227 -325.264816) (xy 207.012271 -325.215424)
			(xy 207.19307 -325.15836) (xy 207.371303 -325.093725) (xy 207.546652 -325.021634) (xy 207.718806 -324.942215)
			(xy 207.88746 -324.855609) (xy 208.052312 -324.76197) (xy 208.213071 -324.661464) (xy 208.369449 -324.554271)
			(xy 208.52117 -324.440581) (xy 208.667963 -324.320596) (xy 208.809567 -324.194529) (xy 208.945731 -324.062605)
			(xy 209.076212 -323.925058) (xy 209.200779 -323.782133) (xy 209.31921 -323.634083) (xy 209.431294 -323.481172)
			(xy 209.536833 -323.323673) (xy 209.635638 -323.161864) (xy 209.727534 -322.996033) (xy 209.812357 -322.826476)
			(xy 209.889957 -322.653494) (xy 209.960196 -322.477394) (xy 210.022948 -322.29849) (xy 210.078103 -322.1171)
			(xy 210.125562 -321.933545) (xy 210.165241 -321.748153) (xy 210.197069 -321.561253) (xy 210.220989 -321.373178)
			(xy 210.23696 -321.184261) (xy 210.244953 -320.994839)
		)
		(stroke
			(width 0)
			(type solid)
		)
		(fill yes)
		(layer "B.Cu")
		(net "GND")
	)
	(gr_poly
		(pts
			(xy 210.245452 -270.89989) (xy 210.244953 -270.805095) (xy 210.23696 -270.615673) (xy 210.220989 -270.426756)
			(xy 210.197069 -270.238681) (xy 210.165241 -270.051781) (xy 210.125562 -269.866389) (xy 210.078103 -269.682834)
			(xy 210.022948 -269.501444) (xy 209.960196 -269.32254) (xy 209.889957 -269.14644) (xy 209.812357 -268.973458)
			(xy 209.727534 -268.803901) (xy 209.635638 -268.63807) (xy 209.536833 -268.476261) (xy 209.431294 -268.318762)
			(xy 209.31921 -268.165851) (xy 209.200779 -268.017801) (xy 209.076212 -267.874876) (xy 208.945731 -267.737329)
			(xy 208.809567 -267.605405) (xy 208.667963 -267.479338) (xy 208.52117 -267.359353) (xy 208.369449 -267.245663)
			(xy 208.213071 -267.13847) (xy 208.052312 -267.037964) (xy 207.88746 -266.944325) (xy 207.718806 -266.857719)
			(xy 207.546652 -266.7783) (xy 207.371303 -266.706209) (xy 207.19307 -266.641574) (xy 207.012271 -266.58451)
			(xy 206.829227 -266.535118) (xy 206.644264 -266.493487) (xy 206.45771 -266.459691) (xy 206.269897 -266.433789)
			(xy 206.081159 -266.415827) (xy 205.891832 -266.405839) (xy 205.702252 -266.40384) (xy 205.512756 -266.409835)
			(xy 205.323681 -266.423813) (xy 205.135364 -266.44575) (xy 204.948139 -266.475606) (xy 204.762339 -266.513328)
			(xy 204.578295 -266.558849) (xy 204.396333 -266.612089) (xy 204.216777 -266.672952) (xy 204.039947 -266.74133)
			(xy 203.866156 -266.817102) (xy 203.695714 -266.900133) (xy 203.528924 -266.990276) (xy 203.366083 -267.08737)
			(xy 203.207479 -267.191242) (xy 203.053395 -267.301708) (xy 202.904105 -267.418572) (xy 202.759875 -267.541625)
			(xy 202.62096 -267.670649) (xy 202.487607 -267.805414) (xy 202.360055 -267.945682) (xy 202.238529 -268.091202)
			(xy 202.123246 -268.241715) (xy 202.01441 -268.396955) (xy 201.912216 -268.556645) (xy 201.816844 -268.720501)
			(xy 201.728465 -268.888232) (xy 201.647235 -269.05954) (xy 201.573299 -269.234119) (xy 201.506789 -269.411661)
			(xy 201.447822 -269.591848) (xy 201.396504 -269.774361) (xy 201.352925 -269.958876) (xy 201.317164 -270.145063)
			(xy 201.289284 -270.332592) (xy 201.269333 -270.52113) (xy 201.257349 -270.710342) (xy 201.253352 -270.89989)
			(xy 202.980553 -270.89989) (xy 202.984545 -270.751254) (xy 202.99651 -270.603047) (xy 203.016412 -270.455695)
			(xy 203.044195 -270.309625) (xy 203.079779 -270.165256) (xy 203.123061 -270.023005) (xy 203.173915 -269.883283)
			(xy 203.232197 -269.746491) (xy 203.297737 -269.613026) (xy 203.370346 -269.48327) (xy 203.449815 -269.357599)
			(xy 203.535916 -269.236375) (xy 203.628399 -269.119947) (xy 203.726998 -269.008652) (xy 203.83143 -268.902809)
			(xy 203.941392 -268.802724) (xy 204.056567 -268.708686) (xy 204.176624 -268.620966) (xy 204.301217 -268.539817)
			(xy 204.429986 -268.465472) (xy 204.56256 -268.398146) (xy 204.698556 -268.338034) (xy 204.837583 -268.285308)
			(xy 204.97924 -268.24012) (xy 205.123118 -268.202602) (xy 205.268803 -268.17286) (xy 205.415874 -268.150981)
			(xy 205.563907 -268.137028) (xy 205.712476 -268.131041) (xy 205.861152 -268.133037) (xy 206.009507 -268.14301)
			(xy 206.157112 -268.160933) (xy 206.303543 -268.186753) (xy 206.448377 -268.220395) (xy 206.591195 -268.261763)
			(xy 206.731588 -268.310737) (xy 206.869149 -268.367177) (xy 207.003483 -268.430919) (xy 207.134202 -268.50178)
			(xy 207.260928 -268.579555) (xy 207.383297 -268.66402) (xy 207.500956 -268.754932) (xy 207.613565 -268.852028)
			(xy 207.7208 -268.955029) (xy 207.822352 -269.063638) (xy 207.917928 -269.17754) (xy 208.007252 -269.296409)
			(xy 208.090067 -269.419901) (xy 208.166134 -269.54766) (xy 208.235233 -269.679318) (xy 208.297166 -269.814496)
			(xy 208.351754 -269.952802) (xy 208.398839 -270.09384) (xy 208.438286 -270.237201) (xy 208.469981 -270.382473)
			(xy 208.493832 -270.529237) (xy 208.509772 -270.67707) (xy 208.517753 -270.825545) (xy 208.518252 -270.89989)
			(xy 208.517753 -270.974235) (xy 208.509772 -271.12271) (xy 208.493832 -271.270543) (xy 208.469981 -271.417307)
			(xy 208.438286 -271.562579) (xy 208.398839 -271.70594) (xy 208.351754 -271.846978) (xy 208.297166 -271.985284)
			(xy 208.235233 -272.120462) (xy 208.166134 -272.25212) (xy 208.090067 -272.379879) (xy 208.007252 -272.503371)
			(xy 207.917928 -272.62224) (xy 207.822352 -272.736142) (xy 207.7208 -272.844751) (xy 207.613565 -272.947752)
			(xy 207.500956 -273.044848) (xy 207.383297 -273.13576) (xy 207.260928 -273.220225) (xy 207.134202 -273.298)
			(xy 207.003483 -273.368861) (xy 206.869149 -273.432603) (xy 206.731588 -273.489043) (xy 206.591195 -273.538017)
			(xy 206.448377 -273.579385) (xy 206.303543 -273.613027) (xy 206.157112 -273.638847) (xy 206.009507 -273.65677)
			(xy 205.861152 -273.666743) (xy 205.712476 -273.668739) (xy 205.563907 -273.662752) (xy 205.415874 -273.648799)
			(xy 205.268803 -273.62692) (xy 205.123118 -273.597178) (xy 204.97924 -273.55966) (xy 204.837583 -273.514472)
			(xy 204.698556 -273.461746) (xy 204.56256 -273.401634) (xy 204.429986 -273.334308) (xy 204.301217 -273.259963)
			(xy 204.176624 -273.178814) (xy 204.056567 -273.091094) (xy 203.941392 -272.997056) (xy 203.83143 -272.896971)
			(xy 203.726998 -272.791128) (xy 203.628399 -272.679833) (xy 203.535916 -272.563405) (xy 203.449815 -272.442181)
			(xy 203.370346 -272.31651) (xy 203.297737 -272.186754) (xy 203.232197 -272.053289) (xy 203.173915 -271.916497)
			(xy 203.123061 -271.776775) (xy 203.079779 -271.634524) (xy 203.044195 -271.490155) (xy 203.016412 -271.344085)
			(xy 202.99651 -271.196733) (xy 202.984545 -271.048526) (xy 202.980553 -270.89989) (xy 201.253352 -270.89989)
			(xy 201.257349 -271.089438) (xy 201.269333 -271.27865) (xy 201.289284 -271.467188) (xy 201.317164 -271.654717)
			(xy 201.352925 -271.840904) (xy 201.396504 -272.025419) (xy 201.447822 -272.207932) (xy 201.506789 -272.388119)
			(xy 201.573299 -272.565661) (xy 201.647235 -272.74024) (xy 201.728465 -272.911548) (xy 201.816844 -273.079279)
			(xy 201.912216 -273.243135) (xy 202.01441 -273.402825) (xy 202.123246 -273.558065) (xy 202.238529 -273.708578)
			(xy 202.360055 -273.854098) (xy 202.487607 -273.994366) (xy 202.62096 -274.129131) (xy 202.759875 -274.258155)
			(xy 202.904105 -274.381208) (xy 203.053395 -274.498072) (xy 203.207479 -274.608538) (xy 203.366083 -274.71241)
			(xy 203.528924 -274.809504) (xy 203.695714 -274.899647) (xy 203.866156 -274.982678) (xy 204.039947 -275.05845)
			(xy 204.216777 -275.126828) (xy 204.396333 -275.187691) (xy 204.578295 -275.240931) (xy 204.762339 -275.286452)
			(xy 204.948139 -275.324174) (xy 205.135364 -275.35403) (xy 205.323681 -275.375967) (xy 205.512756 -275.389945)
			(xy 205.702252 -275.39594) (xy 205.891832 -275.393941) (xy 206.081159 -275.383953) (xy 206.269897 -275.365991)
			(xy 206.45771 -275.340089) (xy 206.644264 -275.306293) (xy 206.829227 -275.264662) (xy 207.012271 -275.21527)
			(xy 207.19307 -275.158206) (xy 207.371303 -275.093571) (xy 207.546652 -275.02148) (xy 207.718806 -274.942061)
			(xy 207.88746 -274.855455) (xy 208.052312 -274.761816) (xy 208.213071 -274.66131) (xy 208.369449 -274.554117)
			(xy 208.52117 -274.440427) (xy 208.667963 -274.320442) (xy 208.809567 -274.194375) (xy 208.945731 -274.062451)
			(xy 209.076212 -273.924904) (xy 209.200779 -273.781979) (xy 209.31921 -273.633929) (xy 209.431294 -273.481018)
			(xy 209.536833 -273.323519) (xy 209.635638 -273.16171) (xy 209.727534 -272.995879) (xy 209.812357 -272.826322)
			(xy 209.889957 -272.65334) (xy 209.960196 -272.47724) (xy 210.022948 -272.298336) (xy 210.078103 -272.116946)
			(xy 210.125562 -271.933391) (xy 210.165241 -271.747999) (xy 210.197069 -271.561099) (xy 210.220989 -271.373024)
			(xy 210.23696 -271.184107) (xy 210.244953 -270.994685)
		)
		(stroke
			(width 0)
			(type solid)
		)
		(fill yes)
		(layer "B.Cu")
		(net "GND")
	)
	(gr_poly
		(pts
			(xy 266.34567 -320.900044) (xy 266.345171 -320.805249) (xy 266.337178 -320.615827) (xy 266.321207 -320.42691)
			(xy 266.297287 -320.238835) (xy 266.265459 -320.051935) (xy 266.22578 -319.866543) (xy 266.178321 -319.682988)
			(xy 266.123166 -319.501598) (xy 266.060414 -319.322694) (xy 265.990175 -319.146594) (xy 265.912575 -318.973612)
			(xy 265.827752 -318.804055) (xy 265.735856 -318.638224) (xy 265.637051 -318.476415) (xy 265.531512 -318.318916)
			(xy 265.419428 -318.166005) (xy 265.300997 -318.017955) (xy 265.17643 -317.87503) (xy 265.045949 -317.737483)
			(xy 264.909785 -317.605559) (xy 264.768181 -317.479492) (xy 264.621388 -317.359507) (xy 264.469667 -317.245817)
			(xy 264.313289 -317.138624) (xy 264.15253 -317.038118) (xy 263.987678 -316.944479) (xy 263.819024 -316.857873)
			(xy 263.64687 -316.778454) (xy 263.471521 -316.706363) (xy 263.293288 -316.641728) (xy 263.112489 -316.584664)
			(xy 262.929445 -316.535272) (xy 262.744482 -316.493641) (xy 262.557928 -316.459845) (xy 262.370115 -316.433943)
			(xy 262.181377 -316.415981) (xy 261.99205 -316.405993) (xy 261.80247 -316.403994) (xy 261.612974 -316.409989)
			(xy 261.423899 -316.423967) (xy 261.235582 -316.445904) (xy 261.048357 -316.47576) (xy 260.862557 -316.513482)
			(xy 260.678513 -316.559003) (xy 260.496551 -316.612243) (xy 260.316995 -316.673106) (xy 260.140165 -316.741484)
			(xy 259.966374 -316.817256) (xy 259.795932 -316.900287) (xy 259.629142 -316.99043) (xy 259.466301 -317.087524)
			(xy 259.307697 -317.191396) (xy 259.153613 -317.301862) (xy 259.004323 -317.418726) (xy 258.860093 -317.541779)
			(xy 258.721178 -317.670803) (xy 258.587825 -317.805568) (xy 258.460273 -317.945836) (xy 258.338747 -318.091356)
			(xy 258.223464 -318.241869) (xy 258.114628 -318.397109) (xy 258.012434 -318.556799) (xy 257.917062 -318.720655)
			(xy 257.828683 -318.888386) (xy 257.747453 -319.059694) (xy 257.673517 -319.234273) (xy 257.607007 -319.411815)
			(xy 257.54804 -319.592002) (xy 257.496722 -319.774515) (xy 257.453143 -319.95903) (xy 257.417382 -320.145217)
			(xy 257.389502 -320.332746) (xy 257.369551 -320.521284) (xy 257.357567 -320.710496) (xy 257.35357 -320.900044)
			(xy 259.080771 -320.900044) (xy 259.084763 -320.751408) (xy 259.096728 -320.603201) (xy 259.11663 -320.455849)
			(xy 259.144413 -320.309779) (xy 259.179997 -320.16541) (xy 259.223279 -320.023159) (xy 259.274133 -319.883437)
			(xy 259.332415 -319.746645) (xy 259.397955 -319.61318) (xy 259.470564 -319.483424) (xy 259.550033 -319.357753)
			(xy 259.636134 -319.236529) (xy 259.728617 -319.120101) (xy 259.827216 -319.008806) (xy 259.931648 -318.902963)
			(xy 260.04161 -318.802878) (xy 260.156785 -318.70884) (xy 260.276842 -318.62112) (xy 260.401435 -318.539971)
			(xy 260.530204 -318.465626) (xy 260.662778 -318.3983) (xy 260.798774 -318.338188) (xy 260.937801 -318.285462)
			(xy 261.079458 -318.240274) (xy 261.223336 -318.202756) (xy 261.369021 -318.173014) (xy 261.516092 -318.151135)
			(xy 261.664125 -318.137182) (xy 261.812694 -318.131195) (xy 261.96137 -318.133191) (xy 262.109725 -318.143164)
			(xy 262.25733 -318.161087) (xy 262.403761 -318.186907) (xy 262.548595 -318.220549) (xy 262.691413 -318.261917)
			(xy 262.831806 -318.310891) (xy 262.969367 -318.367331) (xy 263.103701 -318.431073) (xy 263.23442 -318.501934)
			(xy 263.361146 -318.579709) (xy 263.483515 -318.664174) (xy 263.601174 -318.755086) (xy 263.713783 -318.852182)
			(xy 263.821018 -318.955183) (xy 263.92257 -319.063792) (xy 264.018146 -319.177694) (xy 264.10747 -319.296563)
			(xy 264.190285 -319.420055) (xy 264.266352 -319.547814) (xy 264.335451 -319.679472) (xy 264.397384 -319.81465)
			(xy 264.451972 -319.952956) (xy 264.499057 -320.093994) (xy 264.538504 -320.237355) (xy 264.570199 -320.382627)
			(xy 264.59405 -320.529391) (xy 264.60999 -320.677224) (xy 264.617971 -320.825699) (xy 264.61847 -320.900044)
			(xy 264.617971 -320.974389) (xy 264.60999 -321.122864) (xy 264.59405 -321.270697) (xy 264.570199 -321.417461)
			(xy 264.538504 -321.562733) (xy 264.499057 -321.706094) (xy 264.451972 -321.847132) (xy 264.397384 -321.985438)
			(xy 264.335451 -322.120616) (xy 264.266352 -322.252274) (xy 264.190285 -322.380033) (xy 264.10747 -322.503525)
			(xy 264.018146 -322.622394) (xy 263.92257 -322.736296) (xy 263.821018 -322.844905) (xy 263.713783 -322.947906)
			(xy 263.601174 -323.045002) (xy 263.483515 -323.135914) (xy 263.361146 -323.220379) (xy 263.23442 -323.298154)
			(xy 263.103701 -323.369015) (xy 262.969367 -323.432757) (xy 262.831806 -323.489197) (xy 262.691413 -323.538171)
			(xy 262.548595 -323.579539) (xy 262.403761 -323.613181) (xy 262.25733 -323.639001) (xy 262.109725 -323.656924)
			(xy 261.96137 -323.666897) (xy 261.812694 -323.668893) (xy 261.664125 -323.662906) (xy 261.516092 -323.648953)
			(xy 261.369021 -323.627074) (xy 261.223336 -323.597332) (xy 261.079458 -323.559814) (xy 260.937801 -323.514626)
			(xy 260.798774 -323.4619) (xy 260.662778 -323.401788) (xy 260.530204 -323.334462) (xy 260.401435 -323.260117)
			(xy 260.276842 -323.178968) (xy 260.156785 -323.091248) (xy 260.04161 -322.99721) (xy 259.931648 -322.897125)
			(xy 259.827216 -322.791282) (xy 259.728617 -322.679987) (xy 259.636134 -322.563559) (xy 259.550033 -322.442335)
			(xy 259.470564 -322.316664) (xy 259.397955 -322.186908) (xy 259.332415 -322.053443) (xy 259.274133 -321.916651)
			(xy 259.223279 -321.776929) (xy 259.179997 -321.634678) (xy 259.144413 -321.490309) (xy 259.11663 -321.344239)
			(xy 259.096728 -321.196887) (xy 259.084763 -321.04868) (xy 259.080771 -320.900044) (xy 257.35357 -320.900044)
			(xy 257.357567 -321.089592) (xy 257.369551 -321.278804) (xy 257.389502 -321.467342) (xy 257.417382 -321.654871)
			(xy 257.453143 -321.841058) (xy 257.496722 -322.025573) (xy 257.54804 -322.208086) (xy 257.607007 -322.388273)
			(xy 257.673517 -322.565815) (xy 257.747453 -322.740394) (xy 257.828683 -322.911702) (xy 257.917062 -323.079433)
			(xy 258.012434 -323.243289) (xy 258.114628 -323.402979) (xy 258.223464 -323.558219) (xy 258.338747 -323.708732)
			(xy 258.460273 -323.854252) (xy 258.587825 -323.99452) (xy 258.721178 -324.129285) (xy 258.860093 -324.258309)
			(xy 259.004323 -324.381362) (xy 259.153613 -324.498226) (xy 259.307697 -324.608692) (xy 259.466301 -324.712564)
			(xy 259.629142 -324.809658) (xy 259.795932 -324.899801) (xy 259.966374 -324.982832) (xy 260.140165 -325.058604)
			(xy 260.316995 -325.126982) (xy 260.496551 -325.187845) (xy 260.678513 -325.241085) (xy 260.862557 -325.286606)
			(xy 261.048357 -325.324328) (xy 261.235582 -325.354184) (xy 261.423899 -325.376121) (xy 261.612974 -325.390099)
			(xy 261.80247 -325.396094) (xy 261.99205 -325.394095) (xy 262.181377 -325.384107) (xy 262.370115 -325.366145)
			(xy 262.557928 -325.340243) (xy 262.744482 -325.306447) (xy 262.929445 -325.264816) (xy 263.112489 -325.215424)
			(xy 263.293288 -325.15836) (xy 263.471521 -325.093725) (xy 263.64687 -325.021634) (xy 263.819024 -324.942215)
			(xy 263.987678 -324.855609) (xy 264.15253 -324.76197) (xy 264.313289 -324.661464) (xy 264.469667 -324.554271)
			(xy 264.621388 -324.440581) (xy 264.768181 -324.320596) (xy 264.909785 -324.194529) (xy 265.045949 -324.062605)
			(xy 265.17643 -323.925058) (xy 265.300997 -323.782133) (xy 265.419428 -323.634083) (xy 265.531512 -323.481172)
			(xy 265.637051 -323.323673) (xy 265.735856 -323.161864) (xy 265.827752 -322.996033) (xy 265.912575 -322.826476)
			(xy 265.990175 -322.653494) (xy 266.060414 -322.477394) (xy 266.123166 -322.29849) (xy 266.178321 -322.1171)
			(xy 266.22578 -321.933545) (xy 266.265459 -321.748153) (xy 266.297287 -321.561253) (xy 266.321207 -321.373178)
			(xy 266.337178 -321.184261) (xy 266.345171 -320.994839)
		)
		(stroke
			(width 0)
			(type solid)
		)
		(fill yes)
		(layer "B.Cu")
		(net "GND")
	)
	(gr_poly
		(pts
			(xy 266.34567 -270.89989) (xy 266.345171 -270.805095) (xy 266.337178 -270.615673) (xy 266.321207 -270.426756)
			(xy 266.297287 -270.238681) (xy 266.265459 -270.051781) (xy 266.22578 -269.866389) (xy 266.178321 -269.682834)
			(xy 266.123166 -269.501444) (xy 266.060414 -269.32254) (xy 265.990175 -269.14644) (xy 265.912575 -268.973458)
			(xy 265.827752 -268.803901) (xy 265.735856 -268.63807) (xy 265.637051 -268.476261) (xy 265.531512 -268.318762)
			(xy 265.419428 -268.165851) (xy 265.300997 -268.017801) (xy 265.17643 -267.874876) (xy 265.045949 -267.737329)
			(xy 264.909785 -267.605405) (xy 264.768181 -267.479338) (xy 264.621388 -267.359353) (xy 264.469667 -267.245663)
			(xy 264.313289 -267.13847) (xy 264.15253 -267.037964) (xy 263.987678 -266.944325) (xy 263.819024 -266.857719)
			(xy 263.64687 -266.7783) (xy 263.471521 -266.706209) (xy 263.293288 -266.641574) (xy 263.112489 -266.58451)
			(xy 262.929445 -266.535118) (xy 262.744482 -266.493487) (xy 262.557928 -266.459691) (xy 262.370115 -266.433789)
			(xy 262.181377 -266.415827) (xy 261.99205 -266.405839) (xy 261.80247 -266.40384) (xy 261.612974 -266.409835)
			(xy 261.423899 -266.423813) (xy 261.235582 -266.44575) (xy 261.048357 -266.475606) (xy 260.862557 -266.513328)
			(xy 260.678513 -266.558849) (xy 260.496551 -266.612089) (xy 260.316995 -266.672952) (xy 260.140165 -266.74133)
			(xy 259.966374 -266.817102) (xy 259.795932 -266.900133) (xy 259.629142 -266.990276) (xy 259.466301 -267.08737)
			(xy 259.307697 -267.191242) (xy 259.153613 -267.301708) (xy 259.004323 -267.418572) (xy 258.860093 -267.541625)
			(xy 258.721178 -267.670649) (xy 258.587825 -267.805414) (xy 258.460273 -267.945682) (xy 258.338747 -268.091202)
			(xy 258.223464 -268.241715) (xy 258.114628 -268.396955) (xy 258.012434 -268.556645) (xy 257.917062 -268.720501)
			(xy 257.828683 -268.888232) (xy 257.747453 -269.05954) (xy 257.673517 -269.234119) (xy 257.607007 -269.411661)
			(xy 257.54804 -269.591848) (xy 257.496722 -269.774361) (xy 257.453143 -269.958876) (xy 257.417382 -270.145063)
			(xy 257.389502 -270.332592) (xy 257.369551 -270.52113) (xy 257.357567 -270.710342) (xy 257.35357 -270.89989)
			(xy 259.080771 -270.89989) (xy 259.084763 -270.751254) (xy 259.096728 -270.603047) (xy 259.11663 -270.455695)
			(xy 259.144413 -270.309625) (xy 259.179997 -270.165256) (xy 259.223279 -270.023005) (xy 259.274133 -269.883283)
			(xy 259.332415 -269.746491) (xy 259.397955 -269.613026) (xy 259.470564 -269.48327) (xy 259.550033 -269.357599)
			(xy 259.636134 -269.236375) (xy 259.728617 -269.119947) (xy 259.827216 -269.008652) (xy 259.931648 -268.902809)
			(xy 260.04161 -268.802724) (xy 260.156785 -268.708686) (xy 260.276842 -268.620966) (xy 260.401435 -268.539817)
			(xy 260.530204 -268.465472) (xy 260.662778 -268.398146) (xy 260.798774 -268.338034) (xy 260.937801 -268.285308)
			(xy 261.079458 -268.24012) (xy 261.223336 -268.202602) (xy 261.369021 -268.17286) (xy 261.516092 -268.150981)
			(xy 261.664125 -268.137028) (xy 261.812694 -268.131041) (xy 261.96137 -268.133037) (xy 262.109725 -268.14301)
			(xy 262.25733 -268.160933) (xy 262.403761 -268.186753) (xy 262.548595 -268.220395) (xy 262.691413 -268.261763)
			(xy 262.831806 -268.310737) (xy 262.969367 -268.367177) (xy 263.103701 -268.430919) (xy 263.23442 -268.50178)
			(xy 263.361146 -268.579555) (xy 263.483515 -268.66402) (xy 263.601174 -268.754932) (xy 263.713783 -268.852028)
			(xy 263.821018 -268.955029) (xy 263.92257 -269.063638) (xy 264.018146 -269.17754) (xy 264.10747 -269.296409)
			(xy 264.190285 -269.419901) (xy 264.266352 -269.54766) (xy 264.335451 -269.679318) (xy 264.397384 -269.814496)
			(xy 264.451972 -269.952802) (xy 264.499057 -270.09384) (xy 264.538504 -270.237201) (xy 264.570199 -270.382473)
			(xy 264.59405 -270.529237) (xy 264.60999 -270.67707) (xy 264.617971 -270.825545) (xy 264.61847 -270.89989)
			(xy 264.617971 -270.974235) (xy 264.60999 -271.12271) (xy 264.59405 -271.270543) (xy 264.570199 -271.417307)
			(xy 264.538504 -271.562579) (xy 264.499057 -271.70594) (xy 264.451972 -271.846978) (xy 264.397384 -271.985284)
			(xy 264.335451 -272.120462) (xy 264.266352 -272.25212) (xy 264.190285 -272.379879) (xy 264.10747 -272.503371)
			(xy 264.018146 -272.62224) (xy 263.92257 -272.736142) (xy 263.821018 -272.844751) (xy 263.713783 -272.947752)
			(xy 263.601174 -273.044848) (xy 263.483515 -273.13576) (xy 263.361146 -273.220225) (xy 263.23442 -273.298)
			(xy 263.103701 -273.368861) (xy 262.969367 -273.432603) (xy 262.831806 -273.489043) (xy 262.691413 -273.538017)
			(xy 262.548595 -273.579385) (xy 262.403761 -273.613027) (xy 262.25733 -273.638847) (xy 262.109725 -273.65677)
			(xy 261.96137 -273.666743) (xy 261.812694 -273.668739) (xy 261.664125 -273.662752) (xy 261.516092 -273.648799)
			(xy 261.369021 -273.62692) (xy 261.223336 -273.597178) (xy 261.079458 -273.55966) (xy 260.937801 -273.514472)
			(xy 260.798774 -273.461746) (xy 260.662778 -273.401634) (xy 260.530204 -273.334308) (xy 260.401435 -273.259963)
			(xy 260.276842 -273.178814) (xy 260.156785 -273.091094) (xy 260.04161 -272.997056) (xy 259.931648 -272.896971)
			(xy 259.827216 -272.791128) (xy 259.728617 -272.679833) (xy 259.636134 -272.563405) (xy 259.550033 -272.442181)
			(xy 259.470564 -272.31651) (xy 259.397955 -272.186754) (xy 259.332415 -272.053289) (xy 259.274133 -271.916497)
			(xy 259.223279 -271.776775) (xy 259.179997 -271.634524) (xy 259.144413 -271.490155) (xy 259.11663 -271.344085)
			(xy 259.096728 -271.196733) (xy 259.084763 -271.048526) (xy 259.080771 -270.89989) (xy 257.35357 -270.89989)
			(xy 257.357567 -271.089438) (xy 257.369551 -271.27865) (xy 257.389502 -271.467188) (xy 257.417382 -271.654717)
			(xy 257.453143 -271.840904) (xy 257.496722 -272.025419) (xy 257.54804 -272.207932) (xy 257.607007 -272.388119)
			(xy 257.673517 -272.565661) (xy 257.747453 -272.74024) (xy 257.828683 -272.911548) (xy 257.917062 -273.079279)
			(xy 258.012434 -273.243135) (xy 258.114628 -273.402825) (xy 258.223464 -273.558065) (xy 258.338747 -273.708578)
			(xy 258.460273 -273.854098) (xy 258.587825 -273.994366) (xy 258.721178 -274.129131) (xy 258.860093 -274.258155)
			(xy 259.004323 -274.381208) (xy 259.153613 -274.498072) (xy 259.307697 -274.608538) (xy 259.466301 -274.71241)
			(xy 259.629142 -274.809504) (xy 259.795932 -274.899647) (xy 259.966374 -274.982678) (xy 260.140165 -275.05845)
			(xy 260.316995 -275.126828) (xy 260.496551 -275.187691) (xy 260.678513 -275.240931) (xy 260.862557 -275.286452)
			(xy 261.048357 -275.324174) (xy 261.235582 -275.35403) (xy 261.423899 -275.375967) (xy 261.612974 -275.389945)
			(xy 261.80247 -275.39594) (xy 261.99205 -275.393941) (xy 262.181377 -275.383953) (xy 262.370115 -275.365991)
			(xy 262.557928 -275.340089) (xy 262.744482 -275.306293) (xy 262.929445 -275.264662) (xy 263.112489 -275.21527)
			(xy 263.293288 -275.158206) (xy 263.471521 -275.093571) (xy 263.64687 -275.02148) (xy 263.819024 -274.942061)
			(xy 263.987678 -274.855455) (xy 264.15253 -274.761816) (xy 264.313289 -274.66131) (xy 264.469667 -274.554117)
			(xy 264.621388 -274.440427) (xy 264.768181 -274.320442) (xy 264.909785 -274.194375) (xy 265.045949 -274.062451)
			(xy 265.17643 -273.924904) (xy 265.300997 -273.781979) (xy 265.419428 -273.633929) (xy 265.531512 -273.481018)
			(xy 265.637051 -273.323519) (xy 265.735856 -273.16171) (xy 265.827752 -272.995879) (xy 265.912575 -272.826322)
			(xy 265.990175 -272.65334) (xy 266.060414 -272.47724) (xy 266.123166 -272.298336) (xy 266.178321 -272.116946)
			(xy 266.22578 -271.933391) (xy 266.265459 -271.747999) (xy 266.297287 -271.561099) (xy 266.321207 -271.373024)
			(xy 266.337178 -271.184107) (xy 266.345171 -270.994685)
		)
		(stroke
			(width 0)
			(type solid)
		)
		(fill yes)
		(layer "B.Cu")
		(net "GND")
	)
	(gr_poly
		(pts
			(xy 326.34555 -320.900044) (xy 326.345051 -320.805249) (xy 326.337058 -320.615827) (xy 326.321087 -320.42691)
			(xy 326.297167 -320.238835) (xy 326.265339 -320.051935) (xy 326.22566 -319.866543) (xy 326.178201 -319.682988)
			(xy 326.123046 -319.501598) (xy 326.060294 -319.322694) (xy 325.990055 -319.146594) (xy 325.912455 -318.973612)
			(xy 325.827632 -318.804055) (xy 325.735736 -318.638224) (xy 325.636931 -318.476415) (xy 325.531392 -318.318916)
			(xy 325.419308 -318.166005) (xy 325.300877 -318.017955) (xy 325.17631 -317.87503) (xy 325.045829 -317.737483)
			(xy 324.909665 -317.605559) (xy 324.768061 -317.479492) (xy 324.621268 -317.359507) (xy 324.469547 -317.245817)
			(xy 324.313169 -317.138624) (xy 324.15241 -317.038118) (xy 323.987558 -316.944479) (xy 323.818904 -316.857873)
			(xy 323.64675 -316.778454) (xy 323.471401 -316.706363) (xy 323.293168 -316.641728) (xy 323.112369 -316.584664)
			(xy 322.929325 -316.535272) (xy 322.744362 -316.493641) (xy 322.557808 -316.459845) (xy 322.369995 -316.433943)
			(xy 322.181257 -316.415981) (xy 321.99193 -316.405993) (xy 321.80235 -316.403994) (xy 321.612854 -316.409989)
			(xy 321.423779 -316.423967) (xy 321.235462 -316.445904) (xy 321.048237 -316.47576) (xy 320.862437 -316.513482)
			(xy 320.678393 -316.559003) (xy 320.496431 -316.612243) (xy 320.316875 -316.673106) (xy 320.140045 -316.741484)
			(xy 319.966254 -316.817256) (xy 319.795812 -316.900287) (xy 319.629022 -316.99043) (xy 319.466181 -317.087524)
			(xy 319.307577 -317.191396) (xy 319.153493 -317.301862) (xy 319.004203 -317.418726) (xy 318.859973 -317.541779)
			(xy 318.721058 -317.670803) (xy 318.587705 -317.805568) (xy 318.460153 -317.945836) (xy 318.338627 -318.091356)
			(xy 318.223344 -318.241869) (xy 318.114508 -318.397109) (xy 318.012314 -318.556799) (xy 317.916942 -318.720655)
			(xy 317.828563 -318.888386) (xy 317.747333 -319.059694) (xy 317.673397 -319.234273) (xy 317.606887 -319.411815)
			(xy 317.54792 -319.592002) (xy 317.496602 -319.774515) (xy 317.453023 -319.95903) (xy 317.417262 -320.145217)
			(xy 317.389382 -320.332746) (xy 317.369431 -320.521284) (xy 317.357447 -320.710496) (xy 317.35345 -320.900044)
			(xy 319.080651 -320.900044) (xy 319.084643 -320.751408) (xy 319.096608 -320.603201) (xy 319.11651 -320.455849)
			(xy 319.144293 -320.309779) (xy 319.179877 -320.16541) (xy 319.223159 -320.023159) (xy 319.274013 -319.883437)
			(xy 319.332295 -319.746645) (xy 319.397835 -319.61318) (xy 319.470444 -319.483424) (xy 319.549913 -319.357753)
			(xy 319.636014 -319.236529) (xy 319.728497 -319.120101) (xy 319.827096 -319.008806) (xy 319.931528 -318.902963)
			(xy 320.04149 -318.802878) (xy 320.156665 -318.70884) (xy 320.276722 -318.62112) (xy 320.401315 -318.539971)
			(xy 320.530084 -318.465626) (xy 320.662658 -318.3983) (xy 320.798654 -318.338188) (xy 320.937681 -318.285462)
			(xy 321.079338 -318.240274) (xy 321.223216 -318.202756) (xy 321.368901 -318.173014) (xy 321.515972 -318.151135)
			(xy 321.664005 -318.137182) (xy 321.812574 -318.131195) (xy 321.96125 -318.133191) (xy 322.109605 -318.143164)
			(xy 322.25721 -318.161087) (xy 322.403641 -318.186907) (xy 322.548475 -318.220549) (xy 322.691293 -318.261917)
			(xy 322.831686 -318.310891) (xy 322.969247 -318.367331) (xy 323.103581 -318.431073) (xy 323.2343 -318.501934)
			(xy 323.361026 -318.579709) (xy 323.483395 -318.664174) (xy 323.601054 -318.755086) (xy 323.713663 -318.852182)
			(xy 323.820898 -318.955183) (xy 323.92245 -319.063792) (xy 324.018026 -319.177694) (xy 324.10735 -319.296563)
			(xy 324.190165 -319.420055) (xy 324.266232 -319.547814) (xy 324.335331 -319.679472) (xy 324.397264 -319.81465)
			(xy 324.451852 -319.952956) (xy 324.498937 -320.093994) (xy 324.538384 -320.237355) (xy 324.570079 -320.382627)
			(xy 324.59393 -320.529391) (xy 324.60987 -320.677224) (xy 324.617851 -320.825699) (xy 324.61835 -320.900044)
			(xy 324.617851 -320.974389) (xy 324.60987 -321.122864) (xy 324.59393 -321.270697) (xy 324.570079 -321.417461)
			(xy 324.538384 -321.562733) (xy 324.498937 -321.706094) (xy 324.451852 -321.847132) (xy 324.397264 -321.985438)
			(xy 324.335331 -322.120616) (xy 324.266232 -322.252274) (xy 324.190165 -322.380033) (xy 324.10735 -322.503525)
			(xy 324.018026 -322.622394) (xy 323.92245 -322.736296) (xy 323.820898 -322.844905) (xy 323.713663 -322.947906)
			(xy 323.601054 -323.045002) (xy 323.483395 -323.135914) (xy 323.361026 -323.220379) (xy 323.2343 -323.298154)
			(xy 323.103581 -323.369015) (xy 322.969247 -323.432757) (xy 322.831686 -323.489197) (xy 322.691293 -323.538171)
			(xy 322.548475 -323.579539) (xy 322.403641 -323.613181) (xy 322.25721 -323.639001) (xy 322.109605 -323.656924)
			(xy 321.96125 -323.666897) (xy 321.812574 -323.668893) (xy 321.664005 -323.662906) (xy 321.515972 -323.648953)
			(xy 321.368901 -323.627074) (xy 321.223216 -323.597332) (xy 321.079338 -323.559814) (xy 320.937681 -323.514626)
			(xy 320.798654 -323.4619) (xy 320.662658 -323.401788) (xy 320.530084 -323.334462) (xy 320.401315 -323.260117)
			(xy 320.276722 -323.178968) (xy 320.156665 -323.091248) (xy 320.04149 -322.99721) (xy 319.931528 -322.897125)
			(xy 319.827096 -322.791282) (xy 319.728497 -322.679987) (xy 319.636014 -322.563559) (xy 319.549913 -322.442335)
			(xy 319.470444 -322.316664) (xy 319.397835 -322.186908) (xy 319.332295 -322.053443) (xy 319.274013 -321.916651)
			(xy 319.223159 -321.776929) (xy 319.179877 -321.634678) (xy 319.144293 -321.490309) (xy 319.11651 -321.344239)
			(xy 319.096608 -321.196887) (xy 319.084643 -321.04868) (xy 319.080651 -320.900044) (xy 317.35345 -320.900044)
			(xy 317.357447 -321.089592) (xy 317.369431 -321.278804) (xy 317.389382 -321.467342) (xy 317.417262 -321.654871)
			(xy 317.453023 -321.841058) (xy 317.496602 -322.025573) (xy 317.54792 -322.208086) (xy 317.606887 -322.388273)
			(xy 317.673397 -322.565815) (xy 317.747333 -322.740394) (xy 317.828563 -322.911702) (xy 317.916942 -323.079433)
			(xy 318.012314 -323.243289) (xy 318.114508 -323.402979) (xy 318.223344 -323.558219) (xy 318.338627 -323.708732)
			(xy 318.460153 -323.854252) (xy 318.587705 -323.99452) (xy 318.721058 -324.129285) (xy 318.859973 -324.258309)
			(xy 319.004203 -324.381362) (xy 319.153493 -324.498226) (xy 319.307577 -324.608692) (xy 319.466181 -324.712564)
			(xy 319.629022 -324.809658) (xy 319.795812 -324.899801) (xy 319.966254 -324.982832) (xy 320.140045 -325.058604)
			(xy 320.316875 -325.126982) (xy 320.496431 -325.187845) (xy 320.678393 -325.241085) (xy 320.862437 -325.286606)
			(xy 321.048237 -325.324328) (xy 321.235462 -325.354184) (xy 321.423779 -325.376121) (xy 321.612854 -325.390099)
			(xy 321.80235 -325.396094) (xy 321.99193 -325.394095) (xy 322.181257 -325.384107) (xy 322.369995 -325.366145)
			(xy 322.557808 -325.340243) (xy 322.744362 -325.306447) (xy 322.929325 -325.264816) (xy 323.112369 -325.215424)
			(xy 323.293168 -325.15836) (xy 323.471401 -325.093725) (xy 323.64675 -325.021634) (xy 323.818904 -324.942215)
			(xy 323.987558 -324.855609) (xy 324.15241 -324.76197) (xy 324.313169 -324.661464) (xy 324.469547 -324.554271)
			(xy 324.621268 -324.440581) (xy 324.768061 -324.320596) (xy 324.909665 -324.194529) (xy 325.045829 -324.062605)
			(xy 325.17631 -323.925058) (xy 325.300877 -323.782133) (xy 325.419308 -323.634083) (xy 325.531392 -323.481172)
			(xy 325.636931 -323.323673) (xy 325.735736 -323.161864) (xy 325.827632 -322.996033) (xy 325.912455 -322.826476)
			(xy 325.990055 -322.653494) (xy 326.060294 -322.477394) (xy 326.123046 -322.29849) (xy 326.178201 -322.1171)
			(xy 326.22566 -321.933545) (xy 326.265339 -321.748153) (xy 326.297167 -321.561253) (xy 326.321087 -321.373178)
			(xy 326.337058 -321.184261) (xy 326.345051 -320.994839)
		)
		(stroke
			(width 0)
			(type solid)
		)
		(fill yes)
		(layer "B.Cu")
		(net "GND")
	)
	(gr_poly
		(pts
			(xy 326.34555 -270.89989) (xy 326.345051 -270.805095) (xy 326.337058 -270.615673) (xy 326.321087 -270.426756)
			(xy 326.297167 -270.238681) (xy 326.265339 -270.051781) (xy 326.22566 -269.866389) (xy 326.178201 -269.682834)
			(xy 326.123046 -269.501444) (xy 326.060294 -269.32254) (xy 325.990055 -269.14644) (xy 325.912455 -268.973458)
			(xy 325.827632 -268.803901) (xy 325.735736 -268.63807) (xy 325.636931 -268.476261) (xy 325.531392 -268.318762)
			(xy 325.419308 -268.165851) (xy 325.300877 -268.017801) (xy 325.17631 -267.874876) (xy 325.045829 -267.737329)
			(xy 324.909665 -267.605405) (xy 324.768061 -267.479338) (xy 324.621268 -267.359353) (xy 324.469547 -267.245663)
			(xy 324.313169 -267.13847) (xy 324.15241 -267.037964) (xy 323.987558 -266.944325) (xy 323.818904 -266.857719)
			(xy 323.64675 -266.7783) (xy 323.471401 -266.706209) (xy 323.293168 -266.641574) (xy 323.112369 -266.58451)
			(xy 322.929325 -266.535118) (xy 322.744362 -266.493487) (xy 322.557808 -266.459691) (xy 322.369995 -266.433789)
			(xy 322.181257 -266.415827) (xy 321.99193 -266.405839) (xy 321.80235 -266.40384) (xy 321.612854 -266.409835)
			(xy 321.423779 -266.423813) (xy 321.235462 -266.44575) (xy 321.048237 -266.475606) (xy 320.862437 -266.513328)
			(xy 320.678393 -266.558849) (xy 320.496431 -266.612089) (xy 320.316875 -266.672952) (xy 320.140045 -266.74133)
			(xy 319.966254 -266.817102) (xy 319.795812 -266.900133) (xy 319.629022 -266.990276) (xy 319.466181 -267.08737)
			(xy 319.307577 -267.191242) (xy 319.153493 -267.301708) (xy 319.004203 -267.418572) (xy 318.859973 -267.541625)
			(xy 318.721058 -267.670649) (xy 318.587705 -267.805414) (xy 318.460153 -267.945682) (xy 318.338627 -268.091202)
			(xy 318.223344 -268.241715) (xy 318.114508 -268.396955) (xy 318.012314 -268.556645) (xy 317.916942 -268.720501)
			(xy 317.828563 -268.888232) (xy 317.747333 -269.05954) (xy 317.673397 -269.234119) (xy 317.606887 -269.411661)
			(xy 317.54792 -269.591848) (xy 317.496602 -269.774361) (xy 317.453023 -269.958876) (xy 317.417262 -270.145063)
			(xy 317.389382 -270.332592) (xy 317.369431 -270.52113) (xy 317.357447 -270.710342) (xy 317.35345 -270.89989)
			(xy 319.080651 -270.89989) (xy 319.084643 -270.751254) (xy 319.096608 -270.603047) (xy 319.11651 -270.455695)
			(xy 319.144293 -270.309625) (xy 319.179877 -270.165256) (xy 319.223159 -270.023005) (xy 319.274013 -269.883283)
			(xy 319.332295 -269.746491) (xy 319.397835 -269.613026) (xy 319.470444 -269.48327) (xy 319.549913 -269.357599)
			(xy 319.636014 -269.236375) (xy 319.728497 -269.119947) (xy 319.827096 -269.008652) (xy 319.931528 -268.902809)
			(xy 320.04149 -268.802724) (xy 320.156665 -268.708686) (xy 320.276722 -268.620966) (xy 320.401315 -268.539817)
			(xy 320.530084 -268.465472) (xy 320.662658 -268.398146) (xy 320.798654 -268.338034) (xy 320.937681 -268.285308)
			(xy 321.079338 -268.24012) (xy 321.223216 -268.202602) (xy 321.368901 -268.17286) (xy 321.515972 -268.150981)
			(xy 321.664005 -268.137028) (xy 321.812574 -268.131041) (xy 321.96125 -268.133037) (xy 322.109605 -268.14301)
			(xy 322.25721 -268.160933) (xy 322.403641 -268.186753) (xy 322.548475 -268.220395) (xy 322.691293 -268.261763)
			(xy 322.831686 -268.310737) (xy 322.969247 -268.367177) (xy 323.103581 -268.430919) (xy 323.2343 -268.50178)
			(xy 323.361026 -268.579555) (xy 323.483395 -268.66402) (xy 323.601054 -268.754932) (xy 323.713663 -268.852028)
			(xy 323.820898 -268.955029) (xy 323.92245 -269.063638) (xy 324.018026 -269.17754) (xy 324.10735 -269.296409)
			(xy 324.190165 -269.419901) (xy 324.266232 -269.54766) (xy 324.335331 -269.679318) (xy 324.397264 -269.814496)
			(xy 324.451852 -269.952802) (xy 324.498937 -270.09384) (xy 324.538384 -270.237201) (xy 324.570079 -270.382473)
			(xy 324.59393 -270.529237) (xy 324.60987 -270.67707) (xy 324.617851 -270.825545) (xy 324.61835 -270.89989)
			(xy 324.617851 -270.974235) (xy 324.60987 -271.12271) (xy 324.59393 -271.270543) (xy 324.570079 -271.417307)
			(xy 324.538384 -271.562579) (xy 324.498937 -271.70594) (xy 324.451852 -271.846978) (xy 324.397264 -271.985284)
			(xy 324.335331 -272.120462) (xy 324.266232 -272.25212) (xy 324.190165 -272.379879) (xy 324.10735 -272.503371)
			(xy 324.018026 -272.62224) (xy 323.92245 -272.736142) (xy 323.820898 -272.844751) (xy 323.713663 -272.947752)
			(xy 323.601054 -273.044848) (xy 323.483395 -273.13576) (xy 323.361026 -273.220225) (xy 323.2343 -273.298)
			(xy 323.103581 -273.368861) (xy 322.969247 -273.432603) (xy 322.831686 -273.489043) (xy 322.691293 -273.538017)
			(xy 322.548475 -273.579385) (xy 322.403641 -273.613027) (xy 322.25721 -273.638847) (xy 322.109605 -273.65677)
			(xy 321.96125 -273.666743) (xy 321.812574 -273.668739) (xy 321.664005 -273.662752) (xy 321.515972 -273.648799)
			(xy 321.368901 -273.62692) (xy 321.223216 -273.597178) (xy 321.079338 -273.55966) (xy 320.937681 -273.514472)
			(xy 320.798654 -273.461746) (xy 320.662658 -273.401634) (xy 320.530084 -273.334308) (xy 320.401315 -273.259963)
			(xy 320.276722 -273.178814) (xy 320.156665 -273.091094) (xy 320.04149 -272.997056) (xy 319.931528 -272.896971)
			(xy 319.827096 -272.791128) (xy 319.728497 -272.679833) (xy 319.636014 -272.563405) (xy 319.549913 -272.442181)
			(xy 319.470444 -272.31651) (xy 319.397835 -272.186754) (xy 319.332295 -272.053289) (xy 319.274013 -271.916497)
			(xy 319.223159 -271.776775) (xy 319.179877 -271.634524) (xy 319.144293 -271.490155) (xy 319.11651 -271.344085)
			(xy 319.096608 -271.196733) (xy 319.084643 -271.048526) (xy 319.080651 -270.89989) (xy 317.35345 -270.89989)
			(xy 317.357447 -271.089438) (xy 317.369431 -271.27865) (xy 317.389382 -271.467188) (xy 317.417262 -271.654717)
			(xy 317.453023 -271.840904) (xy 317.496602 -272.025419) (xy 317.54792 -272.207932) (xy 317.606887 -272.388119)
			(xy 317.673397 -272.565661) (xy 317.747333 -272.74024) (xy 317.828563 -272.911548) (xy 317.916942 -273.079279)
			(xy 318.012314 -273.243135) (xy 318.114508 -273.402825) (xy 318.223344 -273.558065) (xy 318.338627 -273.708578)
			(xy 318.460153 -273.854098) (xy 318.587705 -273.994366) (xy 318.721058 -274.129131) (xy 318.859973 -274.258155)
			(xy 319.004203 -274.381208) (xy 319.153493 -274.498072) (xy 319.307577 -274.608538) (xy 319.466181 -274.71241)
			(xy 319.629022 -274.809504) (xy 319.795812 -274.899647) (xy 319.966254 -274.982678) (xy 320.140045 -275.05845)
			(xy 320.316875 -275.126828) (xy 320.496431 -275.187691) (xy 320.678393 -275.240931) (xy 320.862437 -275.286452)
			(xy 321.048237 -275.324174) (xy 321.235462 -275.35403) (xy 321.423779 -275.375967) (xy 321.612854 -275.389945)
			(xy 321.80235 -275.39594) (xy 321.99193 -275.393941) (xy 322.181257 -275.383953) (xy 322.369995 -275.365991)
			(xy 322.557808 -275.340089) (xy 322.744362 -275.306293) (xy 322.929325 -275.264662) (xy 323.112369 -275.21527)
			(xy 323.293168 -275.158206) (xy 323.471401 -275.093571) (xy 323.64675 -275.02148) (xy 323.818904 -274.942061)
			(xy 323.987558 -274.855455) (xy 324.15241 -274.761816) (xy 324.313169 -274.66131) (xy 324.469547 -274.554117)
			(xy 324.621268 -274.440427) (xy 324.768061 -274.320442) (xy 324.909665 -274.194375) (xy 325.045829 -274.062451)
			(xy 325.17631 -273.924904) (xy 325.300877 -273.781979) (xy 325.419308 -273.633929) (xy 325.531392 -273.481018)
			(xy 325.636931 -273.323519) (xy 325.735736 -273.16171) (xy 325.827632 -272.995879) (xy 325.912455 -272.826322)
			(xy 325.990055 -272.65334) (xy 326.060294 -272.47724) (xy 326.123046 -272.298336) (xy 326.178201 -272.116946)
			(xy 326.22566 -271.933391) (xy 326.265339 -271.747999) (xy 326.297167 -271.561099) (xy 326.321087 -271.373024)
			(xy 326.337058 -271.184107) (xy 326.345051 -270.994685)
		)
		(stroke
			(width 0)
			(type solid)
		)
		(fill yes)
		(layer "B.Cu")
		(net "GND")
	)
	(gr_poly
		(pts
			(xy 382.445514 -320.900044) (xy 382.445015 -320.805249) (xy 382.437022 -320.615827) (xy 382.421051 -320.42691)
			(xy 382.397131 -320.238835) (xy 382.365303 -320.051935) (xy 382.325624 -319.866543) (xy 382.278165 -319.682988)
			(xy 382.22301 -319.501598) (xy 382.160258 -319.322694) (xy 382.090019 -319.146594) (xy 382.012419 -318.973612)
			(xy 381.927596 -318.804055) (xy 381.8357 -318.638224) (xy 381.736895 -318.476415) (xy 381.631356 -318.318916)
			(xy 381.519272 -318.166005) (xy 381.400841 -318.017955) (xy 381.276274 -317.87503) (xy 381.145793 -317.737483)
			(xy 381.009629 -317.605559) (xy 380.868025 -317.479492) (xy 380.721232 -317.359507) (xy 380.569511 -317.245817)
			(xy 380.413133 -317.138624) (xy 380.252374 -317.038118) (xy 380.087522 -316.944479) (xy 379.918868 -316.857873)
			(xy 379.746714 -316.778454) (xy 379.571365 -316.706363) (xy 379.393132 -316.641728) (xy 379.212333 -316.584664)
			(xy 379.029289 -316.535272) (xy 378.844326 -316.493641) (xy 378.657772 -316.459845) (xy 378.469959 -316.433943)
			(xy 378.281221 -316.415981) (xy 378.091894 -316.405993) (xy 377.902314 -316.403994) (xy 377.712818 -316.409989)
			(xy 377.523743 -316.423967) (xy 377.335426 -316.445904) (xy 377.148201 -316.47576) (xy 376.962401 -316.513482)
			(xy 376.778357 -316.559003) (xy 376.596395 -316.612243) (xy 376.416839 -316.673106) (xy 376.240009 -316.741484)
			(xy 376.066218 -316.817256) (xy 375.895776 -316.900287) (xy 375.728986 -316.99043) (xy 375.566145 -317.087524)
			(xy 375.407541 -317.191396) (xy 375.253457 -317.301862) (xy 375.104167 -317.418726) (xy 374.959937 -317.541779)
			(xy 374.821022 -317.670803) (xy 374.687669 -317.805568) (xy 374.560117 -317.945836) (xy 374.438591 -318.091356)
			(xy 374.323308 -318.241869) (xy 374.214472 -318.397109) (xy 374.112278 -318.556799) (xy 374.016906 -318.720655)
			(xy 373.928527 -318.888386) (xy 373.847297 -319.059694) (xy 373.773361 -319.234273) (xy 373.706851 -319.411815)
			(xy 373.647884 -319.592002) (xy 373.596566 -319.774515) (xy 373.552987 -319.95903) (xy 373.517226 -320.145217)
			(xy 373.489346 -320.332746) (xy 373.469395 -320.521284) (xy 373.457411 -320.710496) (xy 373.453414 -320.900044)
			(xy 375.180615 -320.900044) (xy 375.184607 -320.751408) (xy 375.196572 -320.603201) (xy 375.216474 -320.455849)
			(xy 375.244257 -320.309779) (xy 375.279841 -320.16541) (xy 375.323123 -320.023159) (xy 375.373977 -319.883437)
			(xy 375.432259 -319.746645) (xy 375.497799 -319.61318) (xy 375.570408 -319.483424) (xy 375.649877 -319.357753)
			(xy 375.735978 -319.236529) (xy 375.828461 -319.120101) (xy 375.92706 -319.008806) (xy 376.031492 -318.902963)
			(xy 376.141454 -318.802878) (xy 376.256629 -318.70884) (xy 376.376686 -318.62112) (xy 376.501279 -318.539971)
			(xy 376.630048 -318.465626) (xy 376.762622 -318.3983) (xy 376.898618 -318.338188) (xy 377.037645 -318.285462)
			(xy 377.179302 -318.240274) (xy 377.32318 -318.202756) (xy 377.468865 -318.173014) (xy 377.615936 -318.151135)
			(xy 377.763969 -318.137182) (xy 377.912538 -318.131195) (xy 378.061214 -318.133191) (xy 378.209569 -318.143164)
			(xy 378.357174 -318.161087) (xy 378.503605 -318.186907) (xy 378.648439 -318.220549) (xy 378.791257 -318.261917)
			(xy 378.93165 -318.310891) (xy 379.069211 -318.367331) (xy 379.203545 -318.431073) (xy 379.334264 -318.501934)
			(xy 379.46099 -318.579709) (xy 379.583359 -318.664174) (xy 379.701018 -318.755086) (xy 379.813627 -318.852182)
			(xy 379.920862 -318.955183) (xy 380.022414 -319.063792) (xy 380.11799 -319.177694) (xy 380.207314 -319.296563)
			(xy 380.290129 -319.420055) (xy 380.366196 -319.547814) (xy 380.435295 -319.679472) (xy 380.497228 -319.81465)
			(xy 380.551816 -319.952956) (xy 380.598901 -320.093994) (xy 380.638348 -320.237355) (xy 380.670043 -320.382627)
			(xy 380.693894 -320.529391) (xy 380.709834 -320.677224) (xy 380.717815 -320.825699) (xy 380.718314 -320.900044)
			(xy 380.717815 -320.974389) (xy 380.709834 -321.122864) (xy 380.693894 -321.270697) (xy 380.670043 -321.417461)
			(xy 380.638348 -321.562733) (xy 380.598901 -321.706094) (xy 380.551816 -321.847132) (xy 380.497228 -321.985438)
			(xy 380.435295 -322.120616) (xy 380.366196 -322.252274) (xy 380.290129 -322.380033) (xy 380.207314 -322.503525)
			(xy 380.11799 -322.622394) (xy 380.022414 -322.736296) (xy 379.920862 -322.844905) (xy 379.813627 -322.947906)
			(xy 379.701018 -323.045002) (xy 379.583359 -323.135914) (xy 379.46099 -323.220379) (xy 379.334264 -323.298154)
			(xy 379.203545 -323.369015) (xy 379.069211 -323.432757) (xy 378.93165 -323.489197) (xy 378.791257 -323.538171)
			(xy 378.648439 -323.579539) (xy 378.503605 -323.613181) (xy 378.357174 -323.639001) (xy 378.209569 -323.656924)
			(xy 378.061214 -323.666897) (xy 377.912538 -323.668893) (xy 377.763969 -323.662906) (xy 377.615936 -323.648953)
			(xy 377.468865 -323.627074) (xy 377.32318 -323.597332) (xy 377.179302 -323.559814) (xy 377.037645 -323.514626)
			(xy 376.898618 -323.4619) (xy 376.762622 -323.401788) (xy 376.630048 -323.334462) (xy 376.501279 -323.260117)
			(xy 376.376686 -323.178968) (xy 376.256629 -323.091248) (xy 376.141454 -322.99721) (xy 376.031492 -322.897125)
			(xy 375.92706 -322.791282) (xy 375.828461 -322.679987) (xy 375.735978 -322.563559) (xy 375.649877 -322.442335)
			(xy 375.570408 -322.316664) (xy 375.497799 -322.186908) (xy 375.432259 -322.053443) (xy 375.373977 -321.916651)
			(xy 375.323123 -321.776929) (xy 375.279841 -321.634678) (xy 375.244257 -321.490309) (xy 375.216474 -321.344239)
			(xy 375.196572 -321.196887) (xy 375.184607 -321.04868) (xy 375.180615 -320.900044) (xy 373.453414 -320.900044)
			(xy 373.457411 -321.089592) (xy 373.469395 -321.278804) (xy 373.489346 -321.467342) (xy 373.517226 -321.654871)
			(xy 373.552987 -321.841058) (xy 373.596566 -322.025573) (xy 373.647884 -322.208086) (xy 373.706851 -322.388273)
			(xy 373.773361 -322.565815) (xy 373.847297 -322.740394) (xy 373.928527 -322.911702) (xy 374.016906 -323.079433)
			(xy 374.112278 -323.243289) (xy 374.214472 -323.402979) (xy 374.323308 -323.558219) (xy 374.438591 -323.708732)
			(xy 374.560117 -323.854252) (xy 374.687669 -323.99452) (xy 374.821022 -324.129285) (xy 374.959937 -324.258309)
			(xy 375.104167 -324.381362) (xy 375.253457 -324.498226) (xy 375.407541 -324.608692) (xy 375.566145 -324.712564)
			(xy 375.728986 -324.809658) (xy 375.895776 -324.899801) (xy 376.066218 -324.982832) (xy 376.240009 -325.058604)
			(xy 376.416839 -325.126982) (xy 376.596395 -325.187845) (xy 376.778357 -325.241085) (xy 376.962401 -325.286606)
			(xy 377.148201 -325.324328) (xy 377.335426 -325.354184) (xy 377.523743 -325.376121) (xy 377.712818 -325.390099)
			(xy 377.902314 -325.396094) (xy 378.091894 -325.394095) (xy 378.281221 -325.384107) (xy 378.469959 -325.366145)
			(xy 378.657772 -325.340243) (xy 378.844326 -325.306447) (xy 379.029289 -325.264816) (xy 379.212333 -325.215424)
			(xy 379.393132 -325.15836) (xy 379.571365 -325.093725) (xy 379.746714 -325.021634) (xy 379.918868 -324.942215)
			(xy 380.087522 -324.855609) (xy 380.252374 -324.76197) (xy 380.413133 -324.661464) (xy 380.569511 -324.554271)
			(xy 380.721232 -324.440581) (xy 380.868025 -324.320596) (xy 381.009629 -324.194529) (xy 381.145793 -324.062605)
			(xy 381.276274 -323.925058) (xy 381.400841 -323.782133) (xy 381.519272 -323.634083) (xy 381.631356 -323.481172)
			(xy 381.736895 -323.323673) (xy 381.8357 -323.161864) (xy 381.927596 -322.996033) (xy 382.012419 -322.826476)
			(xy 382.090019 -322.653494) (xy 382.160258 -322.477394) (xy 382.22301 -322.29849) (xy 382.278165 -322.1171)
			(xy 382.325624 -321.933545) (xy 382.365303 -321.748153) (xy 382.397131 -321.561253) (xy 382.421051 -321.373178)
			(xy 382.437022 -321.184261) (xy 382.445015 -320.994839)
		)
		(stroke
			(width 0)
			(type solid)
		)
		(fill yes)
		(layer "B.Cu")
		(net "GND")
	)
	(gr_poly
		(pts
			(xy 382.445514 -270.89989) (xy 382.445015 -270.805095) (xy 382.437022 -270.615673) (xy 382.421051 -270.426756)
			(xy 382.397131 -270.238681) (xy 382.365303 -270.051781) (xy 382.325624 -269.866389) (xy 382.278165 -269.682834)
			(xy 382.22301 -269.501444) (xy 382.160258 -269.32254) (xy 382.090019 -269.14644) (xy 382.012419 -268.973458)
			(xy 381.927596 -268.803901) (xy 381.8357 -268.63807) (xy 381.736895 -268.476261) (xy 381.631356 -268.318762)
			(xy 381.519272 -268.165851) (xy 381.400841 -268.017801) (xy 381.276274 -267.874876) (xy 381.145793 -267.737329)
			(xy 381.009629 -267.605405) (xy 380.868025 -267.479338) (xy 380.721232 -267.359353) (xy 380.569511 -267.245663)
			(xy 380.413133 -267.13847) (xy 380.252374 -267.037964) (xy 380.087522 -266.944325) (xy 379.918868 -266.857719)
			(xy 379.746714 -266.7783) (xy 379.571365 -266.706209) (xy 379.393132 -266.641574) (xy 379.212333 -266.58451)
			(xy 379.029289 -266.535118) (xy 378.844326 -266.493487) (xy 378.657772 -266.459691) (xy 378.469959 -266.433789)
			(xy 378.281221 -266.415827) (xy 378.091894 -266.405839) (xy 377.902314 -266.40384) (xy 377.712818 -266.409835)
			(xy 377.523743 -266.423813) (xy 377.335426 -266.44575) (xy 377.148201 -266.475606) (xy 376.962401 -266.513328)
			(xy 376.778357 -266.558849) (xy 376.596395 -266.612089) (xy 376.416839 -266.672952) (xy 376.240009 -266.74133)
			(xy 376.066218 -266.817102) (xy 375.895776 -266.900133) (xy 375.728986 -266.990276) (xy 375.566145 -267.08737)
			(xy 375.407541 -267.191242) (xy 375.253457 -267.301708) (xy 375.104167 -267.418572) (xy 374.959937 -267.541625)
			(xy 374.821022 -267.670649) (xy 374.687669 -267.805414) (xy 374.560117 -267.945682) (xy 374.438591 -268.091202)
			(xy 374.323308 -268.241715) (xy 374.214472 -268.396955) (xy 374.112278 -268.556645) (xy 374.016906 -268.720501)
			(xy 373.928527 -268.888232) (xy 373.847297 -269.05954) (xy 373.773361 -269.234119) (xy 373.706851 -269.411661)
			(xy 373.647884 -269.591848) (xy 373.596566 -269.774361) (xy 373.552987 -269.958876) (xy 373.517226 -270.145063)
			(xy 373.489346 -270.332592) (xy 373.469395 -270.52113) (xy 373.457411 -270.710342) (xy 373.453414 -270.89989)
			(xy 375.180615 -270.89989) (xy 375.184607 -270.751254) (xy 375.196572 -270.603047) (xy 375.216474 -270.455695)
			(xy 375.244257 -270.309625) (xy 375.279841 -270.165256) (xy 375.323123 -270.023005) (xy 375.373977 -269.883283)
			(xy 375.432259 -269.746491) (xy 375.497799 -269.613026) (xy 375.570408 -269.48327) (xy 375.649877 -269.357599)
			(xy 375.735978 -269.236375) (xy 375.828461 -269.119947) (xy 375.92706 -269.008652) (xy 376.031492 -268.902809)
			(xy 376.141454 -268.802724) (xy 376.256629 -268.708686) (xy 376.376686 -268.620966) (xy 376.501279 -268.539817)
			(xy 376.630048 -268.465472) (xy 376.762622 -268.398146) (xy 376.898618 -268.338034) (xy 377.037645 -268.285308)
			(xy 377.179302 -268.24012) (xy 377.32318 -268.202602) (xy 377.468865 -268.17286) (xy 377.615936 -268.150981)
			(xy 377.763969 -268.137028) (xy 377.912538 -268.131041) (xy 378.061214 -268.133037) (xy 378.209569 -268.14301)
			(xy 378.357174 -268.160933) (xy 378.503605 -268.186753) (xy 378.648439 -268.220395) (xy 378.791257 -268.261763)
			(xy 378.93165 -268.310737) (xy 379.069211 -268.367177) (xy 379.203545 -268.430919) (xy 379.334264 -268.50178)
			(xy 379.46099 -268.579555) (xy 379.583359 -268.66402) (xy 379.701018 -268.754932) (xy 379.813627 -268.852028)
			(xy 379.920862 -268.955029) (xy 380.022414 -269.063638) (xy 380.11799 -269.17754) (xy 380.207314 -269.296409)
			(xy 380.290129 -269.419901) (xy 380.366196 -269.54766) (xy 380.435295 -269.679318) (xy 380.497228 -269.814496)
			(xy 380.551816 -269.952802) (xy 380.598901 -270.09384) (xy 380.638348 -270.237201) (xy 380.670043 -270.382473)
			(xy 380.693894 -270.529237) (xy 380.709834 -270.67707) (xy 380.717815 -270.825545) (xy 380.718314 -270.89989)
			(xy 380.717815 -270.974235) (xy 380.709834 -271.12271) (xy 380.693894 -271.270543) (xy 380.670043 -271.417307)
			(xy 380.638348 -271.562579) (xy 380.598901 -271.70594) (xy 380.551816 -271.846978) (xy 380.497228 -271.985284)
			(xy 380.435295 -272.120462) (xy 380.366196 -272.25212) (xy 380.290129 -272.379879) (xy 380.207314 -272.503371)
			(xy 380.11799 -272.62224) (xy 380.022414 -272.736142) (xy 379.920862 -272.844751) (xy 379.813627 -272.947752)
			(xy 379.701018 -273.044848) (xy 379.583359 -273.13576) (xy 379.46099 -273.220225) (xy 379.334264 -273.298)
			(xy 379.203545 -273.368861) (xy 379.069211 -273.432603) (xy 378.93165 -273.489043) (xy 378.791257 -273.538017)
			(xy 378.648439 -273.579385) (xy 378.503605 -273.613027) (xy 378.357174 -273.638847) (xy 378.209569 -273.65677)
			(xy 378.061214 -273.666743) (xy 377.912538 -273.668739) (xy 377.763969 -273.662752) (xy 377.615936 -273.648799)
			(xy 377.468865 -273.62692) (xy 377.32318 -273.597178) (xy 377.179302 -273.55966) (xy 377.037645 -273.514472)
			(xy 376.898618 -273.461746) (xy 376.762622 -273.401634) (xy 376.630048 -273.334308) (xy 376.501279 -273.259963)
			(xy 376.376686 -273.178814) (xy 376.256629 -273.091094) (xy 376.141454 -272.997056) (xy 376.031492 -272.896971)
			(xy 375.92706 -272.791128) (xy 375.828461 -272.679833) (xy 375.735978 -272.563405) (xy 375.649877 -272.442181)
			(xy 375.570408 -272.31651) (xy 375.497799 -272.186754) (xy 375.432259 -272.053289) (xy 375.373977 -271.916497)
			(xy 375.323123 -271.776775) (xy 375.279841 -271.634524) (xy 375.244257 -271.490155) (xy 375.216474 -271.344085)
			(xy 375.196572 -271.196733) (xy 375.184607 -271.048526) (xy 375.180615 -270.89989) (xy 373.453414 -270.89989)
			(xy 373.457411 -271.089438) (xy 373.469395 -271.27865) (xy 373.489346 -271.467188) (xy 373.517226 -271.654717)
			(xy 373.552987 -271.840904) (xy 373.596566 -272.025419) (xy 373.647884 -272.207932) (xy 373.706851 -272.388119)
			(xy 373.773361 -272.565661) (xy 373.847297 -272.74024) (xy 373.928527 -272.911548) (xy 374.016906 -273.079279)
			(xy 374.112278 -273.243135) (xy 374.214472 -273.402825) (xy 374.323308 -273.558065) (xy 374.438591 -273.708578)
			(xy 374.560117 -273.854098) (xy 374.687669 -273.994366) (xy 374.821022 -274.129131) (xy 374.959937 -274.258155)
			(xy 375.104167 -274.381208) (xy 375.253457 -274.498072) (xy 375.407541 -274.608538) (xy 375.566145 -274.71241)
			(xy 375.728986 -274.809504) (xy 375.895776 -274.899647) (xy 376.066218 -274.982678) (xy 376.240009 -275.05845)
			(xy 376.416839 -275.126828) (xy 376.596395 -275.187691) (xy 376.778357 -275.240931) (xy 376.962401 -275.286452)
			(xy 377.148201 -275.324174) (xy 377.335426 -275.35403) (xy 377.523743 -275.375967) (xy 377.712818 -275.389945)
			(xy 377.902314 -275.39594) (xy 378.091894 -275.393941) (xy 378.281221 -275.383953) (xy 378.469959 -275.365991)
			(xy 378.657772 -275.340089) (xy 378.844326 -275.306293) (xy 379.029289 -275.264662) (xy 379.212333 -275.21527)
			(xy 379.393132 -275.158206) (xy 379.571365 -275.093571) (xy 379.746714 -275.02148) (xy 379.918868 -274.942061)
			(xy 380.087522 -274.855455) (xy 380.252374 -274.761816) (xy 380.413133 -274.66131) (xy 380.569511 -274.554117)
			(xy 380.721232 -274.440427) (xy 380.868025 -274.320442) (xy 381.009629 -274.194375) (xy 381.145793 -274.062451)
			(xy 381.276274 -273.924904) (xy 381.400841 -273.781979) (xy 381.519272 -273.633929) (xy 381.631356 -273.481018)
			(xy 381.736895 -273.323519) (xy 381.8357 -273.16171) (xy 381.927596 -272.995879) (xy 382.012419 -272.826322)
			(xy 382.090019 -272.65334) (xy 382.160258 -272.47724) (xy 382.22301 -272.298336) (xy 382.278165 -272.116946)
			(xy 382.325624 -271.933391) (xy 382.365303 -271.747999) (xy 382.397131 -271.561099) (xy 382.421051 -271.373024)
			(xy 382.437022 -271.184107) (xy 382.445015 -270.994685)
		)
		(stroke
			(width 0)
			(type solid)
		)
		(fill yes)
		(layer "B.Cu")
		(net "GND")
	)
	(gr_poly
		(pts
			(xy 442.445648 -320.900044) (xy 442.445149 -320.805249) (xy 442.437156 -320.615827) (xy 442.421185 -320.42691)
			(xy 442.397265 -320.238835) (xy 442.365437 -320.051935) (xy 442.325758 -319.866543) (xy 442.278299 -319.682988)
			(xy 442.223144 -319.501598) (xy 442.160392 -319.322694) (xy 442.090153 -319.146594) (xy 442.012553 -318.973612)
			(xy 441.92773 -318.804055) (xy 441.835834 -318.638224) (xy 441.737029 -318.476415) (xy 441.63149 -318.318916)
			(xy 441.519406 -318.166005) (xy 441.400975 -318.017955) (xy 441.276408 -317.87503) (xy 441.145927 -317.737483)
			(xy 441.009763 -317.605559) (xy 440.868159 -317.479492) (xy 440.721366 -317.359507) (xy 440.569645 -317.245817)
			(xy 440.413267 -317.138624) (xy 440.252508 -317.038118) (xy 440.087656 -316.944479) (xy 439.919002 -316.857873)
			(xy 439.746848 -316.778454) (xy 439.571499 -316.706363) (xy 439.393266 -316.641728) (xy 439.212467 -316.584664)
			(xy 439.029423 -316.535272) (xy 438.84446 -316.493641) (xy 438.657906 -316.459845) (xy 438.470093 -316.433943)
			(xy 438.281355 -316.415981) (xy 438.092028 -316.405993) (xy 437.902448 -316.403994) (xy 437.712952 -316.409989)
			(xy 437.523877 -316.423967) (xy 437.33556 -316.445904) (xy 437.148335 -316.47576) (xy 436.962535 -316.513482)
			(xy 436.778491 -316.559003) (xy 436.596529 -316.612243) (xy 436.416973 -316.673106) (xy 436.240143 -316.741484)
			(xy 436.066352 -316.817256) (xy 435.89591 -316.900287) (xy 435.72912 -316.99043) (xy 435.566279 -317.087524)
			(xy 435.407675 -317.191396) (xy 435.253591 -317.301862) (xy 435.104301 -317.418726) (xy 434.960071 -317.541779)
			(xy 434.821156 -317.670803) (xy 434.687803 -317.805568) (xy 434.560251 -317.945836) (xy 434.438725 -318.091356)
			(xy 434.323442 -318.241869) (xy 434.214606 -318.397109) (xy 434.112412 -318.556799) (xy 434.01704 -318.720655)
			(xy 433.928661 -318.888386) (xy 433.847431 -319.059694) (xy 433.773495 -319.234273) (xy 433.706985 -319.411815)
			(xy 433.648018 -319.592002) (xy 433.5967 -319.774515) (xy 433.553121 -319.95903) (xy 433.51736 -320.145217)
			(xy 433.48948 -320.332746) (xy 433.469529 -320.521284) (xy 433.457545 -320.710496) (xy 433.453548 -320.900044)
			(xy 435.180749 -320.900044) (xy 435.184741 -320.751408) (xy 435.196706 -320.603201) (xy 435.216608 -320.455849)
			(xy 435.244391 -320.309779) (xy 435.279975 -320.16541) (xy 435.323257 -320.023159) (xy 435.374111 -319.883437)
			(xy 435.432393 -319.746645) (xy 435.497933 -319.61318) (xy 435.570542 -319.483424) (xy 435.650011 -319.357753)
			(xy 435.736112 -319.236529) (xy 435.828595 -319.120101) (xy 435.927194 -319.008806) (xy 436.031626 -318.902963)
			(xy 436.141588 -318.802878) (xy 436.256763 -318.70884) (xy 436.37682 -318.62112) (xy 436.501413 -318.539971)
			(xy 436.630182 -318.465626) (xy 436.762756 -318.3983) (xy 436.898752 -318.338188) (xy 437.037779 -318.285462)
			(xy 437.179436 -318.240274) (xy 437.323314 -318.202756) (xy 437.468999 -318.173014) (xy 437.61607 -318.151135)
			(xy 437.764103 -318.137182) (xy 437.912672 -318.131195) (xy 438.061348 -318.133191) (xy 438.209703 -318.143164)
			(xy 438.357308 -318.161087) (xy 438.503739 -318.186907) (xy 438.648573 -318.220549) (xy 438.791391 -318.261917)
			(xy 438.931784 -318.310891) (xy 439.069345 -318.367331) (xy 439.203679 -318.431073) (xy 439.334398 -318.501934)
			(xy 439.461124 -318.579709) (xy 439.583493 -318.664174) (xy 439.701152 -318.755086) (xy 439.813761 -318.852182)
			(xy 439.920996 -318.955183) (xy 440.022548 -319.063792) (xy 440.118124 -319.177694) (xy 440.207448 -319.296563)
			(xy 440.290263 -319.420055) (xy 440.36633 -319.547814) (xy 440.435429 -319.679472) (xy 440.497362 -319.81465)
			(xy 440.55195 -319.952956) (xy 440.599035 -320.093994) (xy 440.638482 -320.237355) (xy 440.670177 -320.382627)
			(xy 440.694028 -320.529391) (xy 440.709968 -320.677224) (xy 440.717949 -320.825699) (xy 440.718448 -320.900044)
			(xy 440.717949 -320.974389) (xy 440.709968 -321.122864) (xy 440.694028 -321.270697) (xy 440.670177 -321.417461)
			(xy 440.638482 -321.562733) (xy 440.599035 -321.706094) (xy 440.55195 -321.847132) (xy 440.497362 -321.985438)
			(xy 440.435429 -322.120616) (xy 440.36633 -322.252274) (xy 440.290263 -322.380033) (xy 440.207448 -322.503525)
			(xy 440.118124 -322.622394) (xy 440.022548 -322.736296) (xy 439.920996 -322.844905) (xy 439.813761 -322.947906)
			(xy 439.701152 -323.045002) (xy 439.583493 -323.135914) (xy 439.461124 -323.220379) (xy 439.334398 -323.298154)
			(xy 439.203679 -323.369015) (xy 439.069345 -323.432757) (xy 438.931784 -323.489197) (xy 438.791391 -323.538171)
			(xy 438.648573 -323.579539) (xy 438.503739 -323.613181) (xy 438.357308 -323.639001) (xy 438.209703 -323.656924)
			(xy 438.061348 -323.666897) (xy 437.912672 -323.668893) (xy 437.764103 -323.662906) (xy 437.61607 -323.648953)
			(xy 437.468999 -323.627074) (xy 437.323314 -323.597332) (xy 437.179436 -323.559814) (xy 437.037779 -323.514626)
			(xy 436.898752 -323.4619) (xy 436.762756 -323.401788) (xy 436.630182 -323.334462) (xy 436.501413 -323.260117)
			(xy 436.37682 -323.178968) (xy 436.256763 -323.091248) (xy 436.141588 -322.99721) (xy 436.031626 -322.897125)
			(xy 435.927194 -322.791282) (xy 435.828595 -322.679987) (xy 435.736112 -322.563559) (xy 435.650011 -322.442335)
			(xy 435.570542 -322.316664) (xy 435.497933 -322.186908) (xy 435.432393 -322.053443) (xy 435.374111 -321.916651)
			(xy 435.323257 -321.776929) (xy 435.279975 -321.634678) (xy 435.244391 -321.490309) (xy 435.216608 -321.344239)
			(xy 435.196706 -321.196887) (xy 435.184741 -321.04868) (xy 435.180749 -320.900044) (xy 433.453548 -320.900044)
			(xy 433.457545 -321.089592) (xy 433.469529 -321.278804) (xy 433.48948 -321.467342) (xy 433.51736 -321.654871)
			(xy 433.553121 -321.841058) (xy 433.5967 -322.025573) (xy 433.648018 -322.208086) (xy 433.706985 -322.388273)
			(xy 433.773495 -322.565815) (xy 433.847431 -322.740394) (xy 433.928661 -322.911702) (xy 434.01704 -323.079433)
			(xy 434.112412 -323.243289) (xy 434.214606 -323.402979) (xy 434.323442 -323.558219) (xy 434.438725 -323.708732)
			(xy 434.560251 -323.854252) (xy 434.687803 -323.99452) (xy 434.821156 -324.129285) (xy 434.960071 -324.258309)
			(xy 435.104301 -324.381362) (xy 435.253591 -324.498226) (xy 435.407675 -324.608692) (xy 435.566279 -324.712564)
			(xy 435.72912 -324.809658) (xy 435.89591 -324.899801) (xy 436.066352 -324.982832) (xy 436.240143 -325.058604)
			(xy 436.416973 -325.126982) (xy 436.596529 -325.187845) (xy 436.778491 -325.241085) (xy 436.962535 -325.286606)
			(xy 437.148335 -325.324328) (xy 437.33556 -325.354184) (xy 437.523877 -325.376121) (xy 437.712952 -325.390099)
			(xy 437.902448 -325.396094) (xy 438.092028 -325.394095) (xy 438.281355 -325.384107) (xy 438.470093 -325.366145)
			(xy 438.657906 -325.340243) (xy 438.84446 -325.306447) (xy 439.029423 -325.264816) (xy 439.212467 -325.215424)
			(xy 439.393266 -325.15836) (xy 439.571499 -325.093725) (xy 439.746848 -325.021634) (xy 439.919002 -324.942215)
			(xy 440.087656 -324.855609) (xy 440.252508 -324.76197) (xy 440.413267 -324.661464) (xy 440.569645 -324.554271)
			(xy 440.721366 -324.440581) (xy 440.868159 -324.320596) (xy 441.009763 -324.194529) (xy 441.145927 -324.062605)
			(xy 441.276408 -323.925058) (xy 441.400975 -323.782133) (xy 441.519406 -323.634083) (xy 441.63149 -323.481172)
			(xy 441.737029 -323.323673) (xy 441.835834 -323.161864) (xy 441.92773 -322.996033) (xy 442.012553 -322.826476)
			(xy 442.090153 -322.653494) (xy 442.160392 -322.477394) (xy 442.223144 -322.29849) (xy 442.278299 -322.1171)
			(xy 442.325758 -321.933545) (xy 442.365437 -321.748153) (xy 442.397265 -321.561253) (xy 442.421185 -321.373178)
			(xy 442.437156 -321.184261) (xy 442.445149 -320.994839)
		)
		(stroke
			(width 0)
			(type solid)
		)
		(fill yes)
		(layer "B.Cu")
		(net "GND")
	)
	(gr_poly
		(pts
			(xy 442.445648 -270.89989) (xy 442.445149 -270.805095) (xy 442.437156 -270.615673) (xy 442.421185 -270.426756)
			(xy 442.397265 -270.238681) (xy 442.365437 -270.051781) (xy 442.325758 -269.866389) (xy 442.278299 -269.682834)
			(xy 442.223144 -269.501444) (xy 442.160392 -269.32254) (xy 442.090153 -269.14644) (xy 442.012553 -268.973458)
			(xy 441.92773 -268.803901) (xy 441.835834 -268.63807) (xy 441.737029 -268.476261) (xy 441.63149 -268.318762)
			(xy 441.519406 -268.165851) (xy 441.400975 -268.017801) (xy 441.276408 -267.874876) (xy 441.145927 -267.737329)
			(xy 441.009763 -267.605405) (xy 440.868159 -267.479338) (xy 440.721366 -267.359353) (xy 440.569645 -267.245663)
			(xy 440.413267 -267.13847) (xy 440.252508 -267.037964) (xy 440.087656 -266.944325) (xy 439.919002 -266.857719)
			(xy 439.746848 -266.7783) (xy 439.571499 -266.706209) (xy 439.393266 -266.641574) (xy 439.212467 -266.58451)
			(xy 439.029423 -266.535118) (xy 438.84446 -266.493487) (xy 438.657906 -266.459691) (xy 438.470093 -266.433789)
			(xy 438.281355 -266.415827) (xy 438.092028 -266.405839) (xy 437.902448 -266.40384) (xy 437.712952 -266.409835)
			(xy 437.523877 -266.423813) (xy 437.33556 -266.44575) (xy 437.148335 -266.475606) (xy 436.962535 -266.513328)
			(xy 436.778491 -266.558849) (xy 436.596529 -266.612089) (xy 436.416973 -266.672952) (xy 436.240143 -266.74133)
			(xy 436.066352 -266.817102) (xy 435.89591 -266.900133) (xy 435.72912 -266.990276) (xy 435.566279 -267.08737)
			(xy 435.407675 -267.191242) (xy 435.253591 -267.301708) (xy 435.104301 -267.418572) (xy 434.960071 -267.541625)
			(xy 434.821156 -267.670649) (xy 434.687803 -267.805414) (xy 434.560251 -267.945682) (xy 434.438725 -268.091202)
			(xy 434.323442 -268.241715) (xy 434.214606 -268.396955) (xy 434.112412 -268.556645) (xy 434.01704 -268.720501)
			(xy 433.928661 -268.888232) (xy 433.847431 -269.05954) (xy 433.773495 -269.234119) (xy 433.706985 -269.411661)
			(xy 433.648018 -269.591848) (xy 433.5967 -269.774361) (xy 433.553121 -269.958876) (xy 433.51736 -270.145063)
			(xy 433.48948 -270.332592) (xy 433.469529 -270.52113) (xy 433.457545 -270.710342) (xy 433.453548 -270.89989)
			(xy 435.180749 -270.89989) (xy 435.184741 -270.751254) (xy 435.196706 -270.603047) (xy 435.216608 -270.455695)
			(xy 435.244391 -270.309625) (xy 435.279975 -270.165256) (xy 435.323257 -270.023005) (xy 435.374111 -269.883283)
			(xy 435.432393 -269.746491) (xy 435.497933 -269.613026) (xy 435.570542 -269.48327) (xy 435.650011 -269.357599)
			(xy 435.736112 -269.236375) (xy 435.828595 -269.119947) (xy 435.927194 -269.008652) (xy 436.031626 -268.902809)
			(xy 436.141588 -268.802724) (xy 436.256763 -268.708686) (xy 436.37682 -268.620966) (xy 436.501413 -268.539817)
			(xy 436.630182 -268.465472) (xy 436.762756 -268.398146) (xy 436.898752 -268.338034) (xy 437.037779 -268.285308)
			(xy 437.179436 -268.24012) (xy 437.323314 -268.202602) (xy 437.468999 -268.17286) (xy 437.61607 -268.150981)
			(xy 437.764103 -268.137028) (xy 437.912672 -268.131041) (xy 438.061348 -268.133037) (xy 438.209703 -268.14301)
			(xy 438.357308 -268.160933) (xy 438.503739 -268.186753) (xy 438.648573 -268.220395) (xy 438.791391 -268.261763)
			(xy 438.931784 -268.310737) (xy 439.069345 -268.367177) (xy 439.203679 -268.430919) (xy 439.334398 -268.50178)
			(xy 439.461124 -268.579555) (xy 439.583493 -268.66402) (xy 439.701152 -268.754932) (xy 439.813761 -268.852028)
			(xy 439.920996 -268.955029) (xy 440.022548 -269.063638) (xy 440.118124 -269.17754) (xy 440.207448 -269.296409)
			(xy 440.290263 -269.419901) (xy 440.36633 -269.54766) (xy 440.435429 -269.679318) (xy 440.497362 -269.814496)
			(xy 440.55195 -269.952802) (xy 440.599035 -270.09384) (xy 440.638482 -270.237201) (xy 440.670177 -270.382473)
			(xy 440.694028 -270.529237) (xy 440.709968 -270.67707) (xy 440.717949 -270.825545) (xy 440.718448 -270.89989)
			(xy 440.717949 -270.974235) (xy 440.709968 -271.12271) (xy 440.694028 -271.270543) (xy 440.670177 -271.417307)
			(xy 440.638482 -271.562579) (xy 440.599035 -271.70594) (xy 440.55195 -271.846978) (xy 440.497362 -271.985284)
			(xy 440.435429 -272.120462) (xy 440.36633 -272.25212) (xy 440.290263 -272.379879) (xy 440.207448 -272.503371)
			(xy 440.118124 -272.62224) (xy 440.022548 -272.736142) (xy 439.920996 -272.844751) (xy 439.813761 -272.947752)
			(xy 439.701152 -273.044848) (xy 439.583493 -273.13576) (xy 439.461124 -273.220225) (xy 439.334398 -273.298)
			(xy 439.203679 -273.368861) (xy 439.069345 -273.432603) (xy 438.931784 -273.489043) (xy 438.791391 -273.538017)
			(xy 438.648573 -273.579385) (xy 438.503739 -273.613027) (xy 438.357308 -273.638847) (xy 438.209703 -273.65677)
			(xy 438.061348 -273.666743) (xy 437.912672 -273.668739) (xy 437.764103 -273.662752) (xy 437.61607 -273.648799)
			(xy 437.468999 -273.62692) (xy 437.323314 -273.597178) (xy 437.179436 -273.55966) (xy 437.037779 -273.514472)
			(xy 436.898752 -273.461746) (xy 436.762756 -273.401634) (xy 436.630182 -273.334308) (xy 436.501413 -273.259963)
			(xy 436.37682 -273.178814) (xy 436.256763 -273.091094) (xy 436.141588 -272.997056) (xy 436.031626 -272.896971)
			(xy 435.927194 -272.791128) (xy 435.828595 -272.679833) (xy 435.736112 -272.563405) (xy 435.650011 -272.442181)
			(xy 435.570542 -272.31651) (xy 435.497933 -272.186754) (xy 435.432393 -272.053289) (xy 435.374111 -271.916497)
			(xy 435.323257 -271.776775) (xy 435.279975 -271.634524) (xy 435.244391 -271.490155) (xy 435.216608 -271.344085)
			(xy 435.196706 -271.196733) (xy 435.184741 -271.048526) (xy 435.180749 -270.89989) (xy 433.453548 -270.89989)
			(xy 433.457545 -271.089438) (xy 433.469529 -271.27865) (xy 433.48948 -271.467188) (xy 433.51736 -271.654717)
			(xy 433.553121 -271.840904) (xy 433.5967 -272.025419) (xy 433.648018 -272.207932) (xy 433.706985 -272.388119)
			(xy 433.773495 -272.565661) (xy 433.847431 -272.74024) (xy 433.928661 -272.911548) (xy 434.01704 -273.079279)
			(xy 434.112412 -273.243135) (xy 434.214606 -273.402825) (xy 434.323442 -273.558065) (xy 434.438725 -273.708578)
			(xy 434.560251 -273.854098) (xy 434.687803 -273.994366) (xy 434.821156 -274.129131) (xy 434.960071 -274.258155)
			(xy 435.104301 -274.381208) (xy 435.253591 -274.498072) (xy 435.407675 -274.608538) (xy 435.566279 -274.71241)
			(xy 435.72912 -274.809504) (xy 435.89591 -274.899647) (xy 436.066352 -274.982678) (xy 436.240143 -275.05845)
			(xy 436.416973 -275.126828) (xy 436.596529 -275.187691) (xy 436.778491 -275.240931) (xy 436.962535 -275.286452)
			(xy 437.148335 -275.324174) (xy 437.33556 -275.35403) (xy 437.523877 -275.375967) (xy 437.712952 -275.389945)
			(xy 437.902448 -275.39594) (xy 438.092028 -275.393941) (xy 438.281355 -275.383953) (xy 438.470093 -275.365991)
			(xy 438.657906 -275.340089) (xy 438.84446 -275.306293) (xy 439.029423 -275.264662) (xy 439.212467 -275.21527)
			(xy 439.393266 -275.158206) (xy 439.571499 -275.093571) (xy 439.746848 -275.02148) (xy 439.919002 -274.942061)
			(xy 440.087656 -274.855455) (xy 440.252508 -274.761816) (xy 440.413267 -274.66131) (xy 440.569645 -274.554117)
			(xy 440.721366 -274.440427) (xy 440.868159 -274.320442) (xy 441.009763 -274.194375) (xy 441.145927 -274.062451)
			(xy 441.276408 -273.924904) (xy 441.400975 -273.781979) (xy 441.519406 -273.633929) (xy 441.63149 -273.481018)
			(xy 441.737029 -273.323519) (xy 441.835834 -273.16171) (xy 441.92773 -272.995879) (xy 442.012553 -272.826322)
			(xy 442.090153 -272.65334) (xy 442.160392 -272.47724) (xy 442.223144 -272.298336) (xy 442.278299 -272.116946)
			(xy 442.325758 -271.933391) (xy 442.365437 -271.747999) (xy 442.397265 -271.561099) (xy 442.421185 -271.373024)
			(xy 442.437156 -271.184107) (xy 442.445149 -270.994685)
		)
		(stroke
			(width 0)
			(type solid)
		)
		(fill yes)
		(layer "B.Cu")
		(net "GND")
	)
	(gr_poly
		(pts
			(xy 232.311194 -211.88426) (xy 232.311194 -210.592416) (xy 232.302558 -210.592416) (xy 232.271095 -210.59192)
			(xy 232.208665 -210.584028) (xy 232.147716 -210.568374) (xy 232.08921 -210.545206) (xy 232.034069 -210.514888)
			(xy 231.983162 -210.477898) (xy 231.937292 -210.434819) (xy 231.897183 -210.386332) (xy 231.863467 -210.3332)
			(xy 231.836675 -210.276262) (xy 231.817231 -210.216415) (xy 231.80544 -210.154603) (xy 231.801489 -210.0918)
			(xy 231.80544 -210.028997) (xy 231.817231 -209.967185) (xy 231.836675 -209.907338) (xy 231.863467 -209.8504)
			(xy 231.897183 -209.797268) (xy 231.937292 -209.748781) (xy 231.983162 -209.705702) (xy 232.034069 -209.668712)
			(xy 232.08921 -209.638394) (xy 232.147716 -209.615226) (xy 232.208665 -209.599572) (xy 232.271095 -209.59168)
			(xy 232.302558 -209.591148) (xy 232.336252 -209.591697) (xy 232.403029 -209.600747) (xy 232.435654 -209.609182)
			(xy 232.472484 -209.577686) (xy 232.480507 -209.570114) (xy 232.489725 -209.550097) (xy 232.490264 -209.539078)
			(xy 232.490264 -207.737456) (xy 232.482644 -207.718914) (xy 232.480612 -207.716882) (xy 232.480612 -207.433164)
			(xy 232.481042 -207.423097) (xy 232.488767 -207.404503) (xy 232.495598 -207.397096) (xy 232.833672 -207.059022)
			(xy 232.841073 -207.052185) (xy 232.859672 -207.044473) (xy 232.86974 -207.044036) (xy 233.437176 -207.044036)
			(xy 233.447239 -207.043597) (xy 233.465817 -207.035856) (xy 233.473244 -207.02905) (xy 233.684572 -206.817722)
			(xy 233.691409 -206.810321) (xy 233.69912 -206.791722) (xy 233.699558 -206.781654) (xy 233.699558 -205.972918)
			(xy 233.699998 -205.962856) (xy 233.70774 -205.944278) (xy 233.714544 -205.93685) (xy 233.761788 -205.889606)
			(xy 233.768138 -205.878938) (xy 233.769916 -205.873096) (xy 233.778158 -205.84782) (xy 233.800665 -205.799658)
			(xy 233.82964 -205.755085) (xy 233.864522 -205.714966) (xy 233.904635 -205.680078) (xy 233.949203 -205.651096)
			(xy 233.997362 -205.62858) (xy 234.022646 -205.620366) (xy 234.028488 -205.618588) (xy 234.039156 -205.612238)
			(xy 234.637072 -205.014322) (xy 234.643909 -205.006921) (xy 234.65162 -204.988322) (xy 234.652058 -204.978254)
			(xy 234.652058 -203.229972) (xy 234.651628 -203.219905) (xy 234.643902 -203.201312) (xy 234.637072 -203.193904)
			(xy 234.580176 -203.137008) (xy 234.569 -203.130658) (xy 234.562396 -203.128626) (xy 234.539637 -203.122013)
			(xy 234.495836 -203.10391) (xy 234.454616 -203.080516) (xy 234.435396 -203.06665) (xy 234.428656 -203.06198)
			(xy 234.41311 -203.056794) (xy 234.404916 -203.05649) (xy 233.41584 -203.05649) (xy 233.405774 -203.056924)
			(xy 233.387185 -203.064652) (xy 233.379772 -203.071476) (xy 233.295444 -203.155804) (xy 233.288593 -203.163201)
			(xy 233.280853 -203.181799) (xy 233.280458 -203.191872) (xy 233.280458 -204.203808) (xy 233.280032 -204.213877)
			(xy 233.272311 -204.232475) (xy 233.265472 -204.239876) (xy 232.442258 -205.06309) (xy 232.438448 -205.070964)
			(xy 232.429878 -205.087713) (xy 232.408041 -205.118348) (xy 232.381438 -205.144949) (xy 232.350802 -205.166785)
			(xy 232.334054 -205.175358) (xy 232.32618 -205.179168) (xy 232.178098 -205.32725) (xy 232.170702 -205.334102)
			(xy 232.152103 -205.341843) (xy 232.14203 -205.342236) (xy 231.143048 -205.342236) (xy 231.132983 -205.342669)
			(xy 231.114395 -205.350401) (xy 231.10698 -205.357222) (xy 230.782622 -205.68158) (xy 230.775822 -205.688929)
			(xy 230.768115 -205.707392) (xy 230.767636 -205.717394) (xy 230.767636 -206.236316) (xy 231.701846 -206.236316)
			(xy 231.705917 -206.180694) (xy 231.718043 -206.126257) (xy 231.737966 -206.074166) (xy 231.765262 -206.025531)
			(xy 231.799348 -205.981388) (xy 231.839497 -205.942679) (xy 231.884855 -205.910228) (xy 231.934455 -205.884727)
			(xy 231.987239 -205.86672) (xy 232.042082 -205.85659) (xy 232.097816 -205.854553) (xy 232.153253 -205.860653)
			(xy 232.20721 -205.874759) (xy 232.258539 -205.896571) (xy 232.306145 -205.925625) (xy 232.349013 -205.9613)
			(xy 232.38623 -206.002837) (xy 232.417003 -206.04935) (xy 232.434517 -206.08671) (xy 232.739944 -206.08671)
			(xy 232.744015 -206.031088) (xy 232.756141 -205.976651) (xy 232.776064 -205.92456) (xy 232.80336 -205.875925)
			(xy 232.837446 -205.831782) (xy 232.877595 -205.793073) (xy 232.922953 -205.760622) (xy 232.972553 -205.735121)
			(xy 233.025337 -205.717114) (xy 233.08018 -205.706984) (xy 233.135914 -205.704947) (xy 233.191351 -205.711047)
			(xy 233.245308 -205.725153) (xy 233.296637 -205.746965) (xy 233.344243 -205.776019) (xy 233.387111 -205.811694)
			(xy 233.424328 -205.853231) (xy 233.455101 -205.899744) (xy 233.478773 -205.950241) (xy 233.494841 -206.003648)
			(xy 233.502961 -206.058824) (xy 233.50347 -206.08671) (xy 233.502961 -206.114596) (xy 233.494841 -206.169772)
			(xy 233.478773 -206.223179) (xy 233.455101 -206.273676) (xy 233.424328 -206.320189) (xy 233.387111 -206.361726)
			(xy 233.344243 -206.397401) (xy 233.296637 -206.426455) (xy 233.245308 -206.448267) (xy 233.191351 -206.462373)
			(xy 233.135914 -206.468473) (xy 233.08018 -206.466436) (xy 233.025337 -206.456306) (xy 232.972553 -206.438299)
			(xy 232.922953 -206.412798) (xy 232.877595 -206.380347) (xy 232.837446 -206.341638) (xy 232.80336 -206.297495)
			(xy 232.776064 -206.24886) (xy 232.756141 -206.196769) (xy 232.744015 -206.142332) (xy 232.739944 -206.08671)
			(xy 232.434517 -206.08671) (xy 232.440675 -206.099847) (xy 232.456743 -206.153254) (xy 232.464863 -206.20843)
			(xy 232.465372 -206.236316) (xy 232.464863 -206.264202) (xy 232.456743 -206.319378) (xy 232.440675 -206.372785)
			(xy 232.417003 -206.423282) (xy 232.38623 -206.469795) (xy 232.349013 -206.511332) (xy 232.306145 -206.547007)
			(xy 232.258539 -206.576061) (xy 232.20721 -206.597873) (xy 232.153253 -206.611979) (xy 232.097816 -206.618079)
			(xy 232.042082 -206.616042) (xy 231.987239 -206.605912) (xy 231.934455 -206.587905) (xy 231.884855 -206.562404)
			(xy 231.839497 -206.529953) (xy 231.799348 -206.491244) (xy 231.765262 -206.447101) (xy 231.737966 -206.398466)
			(xy 231.718043 -206.346375) (xy 231.705917 -206.291938) (xy 231.701846 -206.236316) (xy 230.767636 -206.236316)
			(xy 230.767636 -206.859632) (xy 230.77551 -206.878428) (xy 230.775764 -206.878682) (xy 231.198928 -206.878682)
			(xy 231.208996 -206.87911) (xy 231.227595 -206.886829) (xy 231.234996 -206.893668) (xy 231.303322 -206.961994)
			(xy 231.310178 -206.969388) (xy 231.317927 -206.987987) (xy 231.318308 -206.998062) (xy 231.318308 -207.252824)
			(xy 231.369108 -207.303624) (xy 231.369108 -207.550258) (xy 231.368514 -207.573428) (xy 231.359057 -207.618795)
			(xy 231.340608 -207.661306) (xy 231.327706 -207.68056) (xy 231.32288 -207.68691) (xy 231.318308 -207.701896)
			(xy 231.318308 -207.9879) (xy 231.317885 -207.99797) (xy 231.310172 -208.016576) (xy 231.303322 -208.023968)
			(xy 231.299766 -208.027524) (xy 231.293416 -208.038192) (xy 231.291638 -208.044034) (xy 231.283576 -208.068035)
			(xy 231.260877 -208.113288) (xy 231.231222 -208.15432) (xy 231.21366 -208.172558) (xy 230.952548 -208.433924)
			(xy 230.9457 -208.441321) (xy 230.937967 -208.45992) (xy 230.937562 -208.469992) (xy 230.937562 -210.596988)
			(xy 230.940356 -210.608418) (xy 230.94315 -210.613752) (xy 230.954245 -210.636675) (xy 230.970952 -210.684782)
			(xy 230.981134 -210.73468) (xy 230.983282 -210.760056) (xy 230.98379 -210.769454) (xy 230.991156 -210.78571)
			(xy 231.304338 -211.098892) (xy 231.311192 -211.106287) (xy 231.31894 -211.124886) (xy 231.319324 -211.13496)
			(xy 231.319324 -211.80933) (xy 231.319753 -211.819397) (xy 231.327478 -211.837992) (xy 231.33431 -211.845398)
			(xy 231.402128 -211.913216) (xy 231.409524 -211.920067) (xy 231.428123 -211.927805) (xy 231.438196 -211.928202)
			(xy 232.267252 -211.928202)
		)
		(stroke
			(width 0)
			(type solid)
		)
		(fill yes)
		(layer "B.Cu")
		(net "P3V3_AUX")
	)
	(gr_poly
		(pts
			(arc
				(start 231.506014 -216.16924)
				(mid 231.519458 -216.167289)
				(end 231.531922 -216.161874)
			)
			(xy 231.544114 -216.154508)
			(arc
				(start 231.54767 -216.14765)
				(mid 231.679025 -216.002181)
				(end 231.867456 -215.94826)
			)
			(xy 231.869488 -215.94826)
			(arc
				(start 231.876346 -215.94826)
				(mid 231.906967 -215.950259)
				(end 231.937306 -215.954864)
			)
			(xy 231.939592 -215.955372) (xy 231.94772 -215.956134)
			(arc
				(start 231.949244 -215.956388)
				(mid 231.968601 -215.952555)
				(end 231.985058 -215.941656)
			)
			(arc
				(start 232.061512 -215.865202)
				(mid 232.070145 -215.853367)
				(end 232.074974 -215.839548)
			)
			(xy 232.074974 -215.83904) (xy 232.07599 -215.829642)
			(arc
				(start 232.07599 -215.619076)
				(mid 232.074578 -215.607183)
				(end 232.070402 -215.595962)
			)
			(arc
				(start 232.070402 -215.595962)
				(mid 232.066526 -215.589673)
				(end 232.061766 -215.584024)
			)
			(xy 231.895396 -215.417654) (xy 231.891332 -215.413336)
			(arc
				(start 231.820974 -215.342978)
				(mid 231.809863 -215.326444)
				(end 231.805988 -215.30691)
			)
			(arc
				(start 231.805988 -215.30183)
				(mid 231.804971 -215.291714)
				(end 231.801924 -215.282018)
			)
			(xy 231.798114 -215.272874) (xy 231.794304 -215.269064) (xy 231.725978 -215.22436) (xy 231.676448 -215.192356)
			(xy 231.676448 -215.01608) (xy 231.767126 -214.95766) (xy 231.782112 -214.95766) (xy 231.791002 -214.94877)
			(arc
				(start 231.795828 -214.943182)
				(mid 231.803381 -214.928766)
				(end 231.805988 -214.912702)
			)
			(arc
				(start 231.805988 -214.867744)
				(mid 231.809889 -214.848221)
				(end 231.820974 -214.831676)
			)
			(xy 231.995218 -214.657686) (xy 232.020618 -214.632032) (xy 232.021126 -214.631524) (xy 232.028492 -214.624158)
			(xy 232.029254 -214.62365)
			(arc
				(start 232.062274 -214.59063)
				(mid 232.071533 -214.576772)
				(end 232.075736 -214.560658)
			)
			(xy 232.07599 -214.555832)
			(arc
				(start 232.07599 -213.339934)
				(mid 232.075461 -213.332095)
				(end 232.073704 -213.32444)
			)
			(arc
				(start 232.069386 -213.311232)
				(mid 232.066405 -213.303831)
				(end 232.062274 -213.297008)
			)
			(arc
				(start 232.062274 -213.297008)
				(mid 231.998338 -213.17015)
				(end 231.976422 -213.0298)
			)
			(xy 231.976422 -213.029292)
			(arc
				(start 231.976422 -213.02345)
				(mid 231.98207 -212.958069)
				(end 231.996996 -212.894164)
			)
			(xy 231.999282 -212.886798) (xy 231.999536 -212.87359)
			(arc
				(start 231.997758 -212.866732)
				(mid 231.992722 -212.854162)
				(end 231.98455 -212.843364)
			)
			(arc
				(start 231.59212 -212.450934)
				(mid 231.586122 -212.445874)
				(end 231.57942 -212.44179)
			)
			(arc
				(start 231.57942 -212.44179)
				(mid 231.568193 -212.437635)
				(end 231.556306 -212.436202)
			)
			(arc
				(start 231.025954 -212.436202)
				(mid 231.014061 -212.437614)
				(end 231.00284 -212.44179)
			)
			(arc
				(start 231.00284 -212.44179)
				(mid 230.996131 -212.445864)
				(end 230.99014 -212.450934)
			)
			(arc
				(start 230.95331 -212.487764)
				(mid 230.943584 -212.50141)
				(end 230.938832 -212.517482)
			)
			(xy 230.938832 -212.654388) (xy 230.915718 -212.66912) (xy 230.915464 -212.669374) (xy 230.891842 -212.684614)
			(xy 230.878888 -212.692996)
			(arc
				(start 230.866188 -212.701124)
				(mid 230.855056 -212.714119)
				(end 230.848916 -212.73008)
			)
			(xy 230.8479 -212.74024)
			(arc
				(start 230.8479 -213.559898)
				(mid 230.843999 -213.579421)
				(end 230.832914 -213.595966)
			)
			(arc
				(start 230.621078 -213.807802)
				(mid 230.613617 -213.817208)
				(end 230.608632 -213.828122)
			)
			(xy 230.605076 -213.839552)
			(arc
				(start 230.606854 -213.85149)
				(mid 230.609889 -213.877701)
				(end 230.610918 -213.904068)
			)
			(arc
				(start 230.610918 -213.907116)
				(mid 230.509354 -214.148142)
				(end 230.26751 -214.24773)
			)
			(arc
				(start 230.26751 -214.24773)
				(mid 230.113706 -214.211392)
				(end 229.992428 -214.110062)
			)
			(xy 229.990142 -214.107268) (xy 229.97922 -214.098632) (xy 229.968552 -214.09025)
			(arc
				(start 229.964234 -214.088218)
				(mid 229.944868 -214.07946)
				(end 229.926134 -214.069422)
			)
			(arc
				(start 229.926134 -214.069422)
				(mid 229.896196 -214.049611)
				(end 229.86873 -214.026496)
			)
			(arc
				(start 229.86873 -214.026496)
				(mid 229.854436 -214.018244)
				(end 229.83825 -214.015066)
			)
			(xy 229.022148 -214.015066) (xy 229.008178 -214.017098) (xy 228.982016 -214.04326) (xy 228.978206 -214.051388)
			(arc
				(start 228.978206 -214.051642)
				(mid 228.938719 -214.115519)
				(end 228.886258 -214.169244)
			)
			(arc
				(start 228.886258 -214.169244)
				(mid 228.858283 -214.190019)
				(end 228.828346 -214.207852)
			)
			(xy 228.82733 -214.211662) (xy 228.825806 -214.2236) (xy 228.825806 -214.385144) (xy 228.827584 -214.397844)
			(arc
				(start 228.828346 -214.400892)
				(mid 228.888516 -214.441378)
				(end 228.938836 -214.493602)
			)
			(xy 228.953568 -214.512398) (xy 228.961696 -214.51316) (xy 228.979222 -214.51316) (xy 228.979476 -214.512652)
			(xy 229.155752 -214.512652) (xy 229.161086 -214.52078) (xy 229.174548 -214.522812) (xy 229.76078 -214.522812)
			(xy 229.770686 -214.518494) (xy 229.771956 -214.517732) (xy 229.77221 -214.517732) (xy 229.776782 -214.5157)
			(xy 229.779068 -214.512144) (xy 229.957122 -214.512144)
			(arc
				(start 229.997 -214.492586)
				(mid 230.279602 -214.361148)
				(end 230.552244 -214.512144)
			)
			(xy 230.555038 -214.512652) (xy 230.728012 -214.512652) (xy 230.755698 -214.512652) (xy 230.769922 -214.53475)
			(xy 230.770684 -214.53602) (xy 230.814372 -214.603584) (xy 230.814372 -214.618316) (xy 230.823516 -214.627714)
			(arc
				(start 230.829104 -214.63254)
				(mid 230.84352 -214.640093)
				(end 230.859584 -214.6427)
			)
			(arc
				(start 230.890572 -214.6427)
				(mid 230.910095 -214.646601)
				(end 230.92664 -214.657686)
			)
			(arc
				(start 231.123998 -214.855044)
				(mid 231.135109 -214.871578)
				(end 231.138984 -214.891112)
			)
			(arc
				(start 231.138984 -215.14308)
				(mid 231.140826 -215.156383)
				(end 231.146096 -215.168734)
			)
			(arc
				(start 231.174036 -215.177878)
				(mid 231.410738 -215.504268)
				(end 231.174036 -215.830658)
			)
			(arc
				(start 231.146096 -215.839802)
				(mid 231.140834 -215.852155)
				(end 231.138984 -215.865456)
			)
			(arc
				(start 231.138984 -215.94318)
				(mid 231.140826 -215.956483)
				(end 231.146096 -215.968834)
			)
			(arc
				(start 231.174036 -215.977978)
				(mid 231.287075 -216.040484)
				(end 231.369108 -216.140284)
			)
			(xy 231.370886 -216.143078) (xy 231.415336 -216.170002) (xy 231.418892 -216.170002)
		)
		(stroke
			(width 0)
			(type solid)
		)
		(fill yes)
		(layer "B.Cu")
		(net "GND")
	)
	(gr_poly
		(pts
			(xy 138.94308 -293.661846) (xy 138.950192 -293.65448)
			(arc
				(start 139.267946 -293.336726)
				(mid 139.279057 -293.320192)
				(end 139.282932 -293.300658)
			)
			(xy 139.282932 -285.519622) (xy 139.275312 -285.500826) (xy 139.267946 -285.493714) (xy 139.109958 -285.335726)
			(xy 139.102846 -285.32836) (xy 139.08405 -285.32074)
			(arc
				(start 133.300724 -285.32074)
				(mid 133.281201 -285.316839)
				(end 133.264656 -285.305754)
			)
			(arc
				(start 132.605526 -284.646624)
				(mid 132.594415 -284.63009)
				(end 132.59054 -284.610556)
			)
			(arc
				(start 132.59054 -282.893008)
				(mid 132.58693 -282.874452)
				(end 132.576824 -282.858464)
			)
			(arc
				(start 132.576824 -282.858464)
				(mid 132.54324 -282.812396)
				(end 132.522214 -282.759404)
			)
			(arc
				(start 132.522214 -282.75915)
				(mid 132.517083 -282.74654)
				(end 132.508752 -282.735782)
			)
			(arc
				(start 132.47243 -282.69946)
				(mid 132.455896 -282.688349)
				(end 132.436362 -282.684474)
			)
			(arc
				(start 132.361178 -282.684474)
				(mid 132.341957 -282.680593)
				(end 132.325618 -282.669742)
			)
			(xy 132.325364 -282.669488)
			(arc
				(start 132.316982 -282.66136)
				(mid 132.300715 -282.650799)
				(end 132.281676 -282.647136)
			)
			(xy 130.79857 -282.647136) (xy 130.792728 -282.652978)
			(arc
				(start 130.792728 -284.865064)
				(mid 130.788827 -284.884587)
				(end 130.777742 -284.901132)
			)
			(arc
				(start 130.692144 -284.98673)
				(mid 130.67561 -284.997841)
				(end 130.656076 -285.001716)
			)
			(arc
				(start 127.633476 -285.001716)
				(mid 127.613953 -284.997815)
				(end 127.597408 -284.98673)
			)
			(arc
				(start 127.586486 -284.975808)
				(mid 127.569952 -284.964697)
				(end 127.550418 -284.960822)
			)
			(xy 126.98984 -284.960822) (xy 126.85903 -285.091632) (xy 126.85903 -286.204152)
			(arc
				(start 127.144526 -286.489902)
				(mid 127.155588 -286.506319)
				(end 127.159512 -286.525716)
			)
			(arc
				(start 127.159512 -286.883856)
				(mid 127.155562 -286.903243)
				(end 127.144526 -286.91967)
			)
			(xy 126.891542 -287.172654) (xy 126.806452 -287.257744)
			(arc
				(start 126.004828 -287.257744)
				(mid 125.988411 -287.268806)
				(end 125.969014 -287.27273)
			)
			(arc
				(start 125.610874 -287.27273)
				(mid 125.591487 -287.26878)
				(end 125.57506 -287.257744)
			)
			(arc
				(start 124.88926 -286.571944)
				(mid 124.878198 -286.555527)
				(end 124.874274 -286.53613)
			)
			(xy 124.874274 -285.821628) (xy 124.874274 -285.054802)
			(arc
				(start 124.780294 -284.960822)
				(mid 124.760771 -284.956921)
				(end 124.744226 -284.945836)
			)
			(arc
				(start 124.445014 -284.646624)
				(mid 124.433903 -284.63009)
				(end 124.430028 -284.610556)
			)
			(arc
				(start 124.430028 -282.890722)
				(mid 124.426351 -282.871999)
				(end 124.416058 -282.855924)
			)
			(arc
				(start 124.416058 -282.855924)
				(mid 124.382644 -282.810708)
				(end 124.361448 -282.758642)
			)
			(xy 124.35967 -282.752038) (xy 124.353066 -282.740608) (xy 124.323602 -282.711144) (xy 124.31649 -282.703778)
			(xy 124.297694 -282.696158)
			(arc
				(start 124.121672 -282.696158)
				(mid 124.102285 -282.692208)
				(end 124.085858 -282.681172)
			)
			(xy 124.066554 -282.662122) (xy 124.066046 -282.661614)
			(arc
				(start 124.065792 -282.66136)
				(mid 124.049525 -282.650799)
				(end 124.030486 -282.647136)
			)
			(xy 122.638058 -282.647136) (xy 122.632216 -282.652978)
			(arc
				(start 122.632216 -284.865064)
				(mid 122.628315 -284.884587)
				(end 122.61723 -284.901132)
			)
			(arc
				(start 122.531632 -284.98673)
				(mid 122.515098 -284.997841)
				(end 122.495564 -285.001716)
			)
			(arc
				(start 118.827804 -285.001716)
				(mid 118.808281 -285.005617)
				(end 118.791736 -285.016702)
			)
			(arc
				(start 118.695724 -285.112714)
				(mid 118.67919 -285.123825)
				(end 118.659656 -285.1277)
			)
			(arc
				(start 116.485416 -285.1277)
				(mid 116.465893 -285.123799)
				(end 116.449348 -285.112714)
			)
			(arc
				(start 115.946428 -284.609794)
				(mid 115.935317 -284.59326)
				(end 115.931442 -284.573726)
			)
			(arc
				(start 115.931442 -282.97632)
				(mid 115.927541 -282.956797)
				(end 115.916456 -282.940252)
			)
			(xy 115.638326 -282.662122) (xy 115.631214 -282.654756) (xy 115.612418 -282.647136) (xy 114.139472 -282.647136)
			(xy 114.13363 -282.652978)
			(arc
				(start 114.13363 -284.865064)
				(mid 114.129729 -284.884587)
				(end 114.118644 -284.901132)
			)
			(arc
				(start 114.033046 -284.98673)
				(mid 114.016512 -284.997841)
				(end 113.996978 -285.001716)
			)
			(arc
				(start 110.974378 -285.001716)
				(mid 110.954855 -284.997815)
				(end 110.93831 -284.98673)
			)
			(arc
				(start 110.927388 -284.975808)
				(mid 110.910854 -284.964697)
				(end 110.89132 -284.960822)
			)
			(xy 110.426246 -284.960822) (xy 110.266988 -285.12008) (xy 110.266988 -286.26435) (xy 110.442248 -286.43961)
			(xy 110.442248 -286.881062)
			(arc
				(start 110.423706 -286.899604)
				(mid 110.419756 -286.918991)
				(end 110.40872 -286.935418)
			)
			(xy 110.155736 -287.188402) (xy 110.086902 -287.257236)
			(arc
				(start 109.269276 -287.257236)
				(mid 109.252859 -287.268298)
				(end 109.233462 -287.272222)
			)
			(arc
				(start 108.875322 -287.272222)
				(mid 108.855935 -287.268272)
				(end 108.839508 -287.257236)
			)
			(arc
				(start 108.24337 -286.661098)
				(mid 108.232308 -286.644681)
				(end 108.228384 -286.625284)
			)
			(xy 108.228384 -285.797498) (xy 108.228384 -285.036514)
			(arc
				(start 108.152692 -284.960822)
				(mid 108.133169 -284.956921)
				(end 108.116624 -284.945836)
			)
			(arc
				(start 107.785916 -284.615128)
				(mid 107.774805 -284.598594)
				(end 107.77093 -284.57906)
			)
			(arc
				(start 107.77093 -282.913582)
				(mid 107.767029 -282.894059)
				(end 107.755944 -282.877514)
			)
			(arc
				(start 107.540552 -282.662122)
				(mid 107.524018 -282.651011)
				(end 107.504484 -282.647136)
			)
			(xy 105.97896 -282.647136) (xy 105.973118 -282.652978)
			(arc
				(start 105.973118 -284.865064)
				(mid 105.969217 -284.884587)
				(end 105.958132 -284.901132)
			)
			(arc
				(start 105.872534 -284.98673)
				(mid 105.856 -284.997841)
				(end 105.836466 -285.001716)
			)
			(arc
				(start 102.813866 -285.001716)
				(mid 102.794343 -284.997815)
				(end 102.777798 -284.98673)
			)
			(arc
				(start 102.766876 -284.975808)
				(mid 102.750342 -284.964697)
				(end 102.730808 -284.960822)
			)
			(arc
				(start 102.2096 -284.960822)
				(mid 102.190077 -284.964723)
				(end 102.173532 -284.975808)
			)
			(arc
				(start 102.029514 -285.119826)
				(mid 102.018403 -285.13636)
				(end 102.014528 -285.155894)
			)
			(arc
				(start 102.014528 -287.846262)
				(mid 102.016711 -287.86125)
				(end 102.023164 -287.874964)
			)
			(arc
				(start 102.023164 -287.874964)
				(mid 102.619612 -289.819814)
				(end 102.023418 -291.76472)
			)
			(xy 102.023164 -291.764974) (xy 102.018846 -291.771578)
			(arc
				(start 102.01656 -291.778944)
				(mid 102.015021 -291.78611)
				(end 102.014528 -291.793422)
			)
			(arc
				(start 102.014528 -293.472362)
				(mid 102.018429 -293.491885)
				(end 102.029514 -293.50843)
			)
			(arc
				(start 102.175564 -293.65448)
				(mid 102.192098 -293.665591)
				(end 102.211632 -293.669466)
			)
			(xy 138.924284 -293.669466)
		)
		(stroke
			(width 0)
			(type solid)
		)
		(fill yes)
		(layer "B.Cu")
		(net "GND")
	)
	(gr_poly
		(pts
			(arc
				(start 235.197904 -413.08528)
				(mid 235.217427 -413.081379)
				(end 235.233972 -413.070294)
			)
			(arc
				(start 235.786422 -412.517844)
				(mid 235.797533 -412.50131)
				(end 235.801408 -412.481776)
			)
			(arc
				(start 235.801408 -402.553932)
				(mid 235.805309 -402.534409)
				(end 235.816394 -402.517864)
			)
			(arc
				(start 239.479582 -398.854676)
				(mid 239.496116 -398.843565)
				(end 239.51565 -398.83969)
			)
			(arc
				(start 243.146072 -398.83969)
				(mid 243.165595 -398.835789)
				(end 243.18214 -398.824704)
			)
			(arc
				(start 243.88064 -398.126204)
				(mid 243.891751 -398.10967)
				(end 243.895626 -398.090136)
			)
			(arc
				(start 243.895626 -391.287508)
				(mid 243.899527 -391.267985)
				(end 243.910612 -391.25144)
			)
			(arc
				(start 245.242842 -389.91921)
				(mid 245.259376 -389.908099)
				(end 245.27891 -389.904224)
			)
			(arc
				(start 258.730496 -389.904224)
				(mid 258.750019 -389.900323)
				(end 258.766564 -389.889238)
			)
			(arc
				(start 261.831836 -386.823966)
				(mid 261.842947 -386.807432)
				(end 261.846822 -386.787898)
			)
			(arc
				(start 261.846822 -379.294136)
				(mid 261.842921 -379.274613)
				(end 261.831836 -379.258068)
			)
			(arc
				(start 261.595362 -379.021594)
				(mid 261.578828 -379.010483)
				(end 261.559294 -379.006608)
			)
			(arc
				(start 240.831624 -379.006608)
				(mid 240.812101 -379.010509)
				(end 240.795556 -379.021594)
			)
			(arc
				(start 239.945418 -379.871732)
				(mid 239.928884 -379.882843)
				(end 239.90935 -379.886718)
			)
			(arc
				(start 237.11027 -379.886718)
				(mid 237.090747 -379.882817)
				(end 237.074202 -379.871732)
			)
			(arc
				(start 232.94594 -375.74347)
				(mid 232.934829 -375.726936)
				(end 232.930954 -375.707402)
			)
			(arc
				(start 232.930954 -372.092728)
				(mid 232.927053 -372.073205)
				(end 232.915968 -372.05666)
			)
			(arc
				(start 232.187242 -371.327934)
				(mid 232.176131 -371.3114)
				(end 232.172256 -371.291866)
			)
			(arc
				(start 232.172256 -371.023134)
				(mid 232.168355 -371.003611)
				(end 232.15727 -370.987066)
			)
			(arc
				(start 232.019094 -370.84889)
				(mid 232.007983 -370.832356)
				(end 232.004108 -370.812822)
			)
			(arc
				(start 232.004108 -367.40973)
				(mid 232.000207 -367.390207)
				(end 231.989122 -367.373662)
			)
			(arc
				(start 231.95661 -367.34115)
				(mid 231.940076 -367.330039)
				(end 231.920542 -367.326164)
			)
			(arc
				(start 228.646736 -367.326164)
				(mid 228.627213 -367.330065)
				(end 228.610668 -367.34115)
			)
			(xy 228.60762 -367.344198)
			(arc
				(start 228.60762 -370.799868)
				(mid 228.603719 -370.819391)
				(end 228.592634 -370.835936)
			)
			(arc
				(start 228.428296 -371.000274)
				(mid 228.417185 -371.016808)
				(end 228.41331 -371.036342)
			)
			(arc
				(start 228.41331 -371.455188)
				(mid 228.409409 -371.474711)
				(end 228.398324 -371.491256)
			)
			(arc
				(start 226.91217 -372.97741)
				(mid 226.901059 -372.993944)
				(end 226.897184 -373.013478)
			)
			(arc
				(start 226.897184 -374.370854)
				(mid 226.893283 -374.390377)
				(end 226.882198 -374.406922)
			)
			(arc
				(start 225.537268 -375.751852)
				(mid 225.520734 -375.762963)
				(end 225.5012 -375.766838)
			)
			(arc
				(start 223.629474 -375.766838)
				(mid 223.609951 -375.762937)
				(end 223.593406 -375.751852)
			)
			(arc
				(start 221.543626 -373.702072)
				(mid 221.532515 -373.685538)
				(end 221.52864 -373.666004)
			)
			(arc
				(start 221.52864 -371.066822)
				(mid 221.524739 -371.047299)
				(end 221.513654 -371.030754)
			)
			(arc
				(start 221.337632 -370.854732)
				(mid 221.326521 -370.838198)
				(end 221.322646 -370.818664)
			)
			(arc
				(start 221.322646 -367.47069)
				(mid 221.318745 -367.451167)
				(end 221.30766 -367.434622)
			)
			(arc
				(start 221.255082 -367.382044)
				(mid 221.238548 -367.370933)
				(end 221.219014 -367.367058)
			)
			(arc
				(start 217.950542 -367.367058)
				(mid 217.931019 -367.370959)
				(end 217.914474 -367.382044)
			)
			(xy 217.909902 -367.386616) (xy 217.902282 -367.405158)
			(arc
				(start 217.902282 -370.800376)
				(mid 217.898381 -370.819899)
				(end 217.887296 -370.836444)
			)
			(arc
				(start 216.498424 -372.225316)
				(mid 216.48189 -372.236427)
				(end 216.462356 -372.240302)
			)
			(arc
				(start 210.63966 -372.240302)
				(mid 210.620137 -372.236401)
				(end 210.603592 -372.225316)
			)
			(arc
				(start 208.79816 -370.419884)
				(mid 208.781626 -370.408773)
				(end 208.762092 -370.404898)
			)
			(arc
				(start 208.200752 -370.404898)
				(mid 208.181229 -370.400997)
				(end 208.164684 -370.389912)
			)
			(arc
				(start 208.110328 -370.335556)
				(mid 208.099217 -370.319022)
				(end 208.095342 -370.299488)
			)
			(arc
				(start 208.095342 -367.551208)
				(mid 208.091441 -367.531685)
				(end 208.080356 -367.51514)
			)
			(arc
				(start 207.934306 -367.36909)
				(mid 207.917772 -367.357979)
				(end 207.898238 -367.354104)
			)
			(arc
				(start 205.361032 -367.354104)
				(mid 205.325111 -367.368983)
				(end 205.310232 -367.404904)
			)
			(xy 205.310232 -367.533174)
			(arc
				(start 205.312264 -367.547144)
				(mid 205.327545 -367.654078)
				(end 205.312264 -367.761012)
			)
			(xy 205.310232 -367.774982)
			(arc
				(start 205.310232 -368.527076)
				(mid 205.306331 -368.546599)
				(end 205.295246 -368.563144)
			)
			(arc
				(start 205.228952 -368.629438)
				(mid 205.213951 -368.664335)
				(end 205.227428 -368.699796)
			)
			(arc
				(start 205.227428 -368.699796)
				(mid 205.27347 -368.761588)
				(end 205.306168 -368.831368)
			)
			(arc
				(start 205.306168 -368.831368)
				(mid 205.311063 -368.841568)
				(end 205.318106 -368.850418)
			)
			(arc
				(start 205.353666 -368.885978)
				(mid 205.364777 -368.902512)
				(end 205.368652 -368.922046)
			)
			(arc
				(start 205.368652 -370.864638)
				(mid 205.364751 -370.884161)
				(end 205.353666 -370.900706)
			)
			(arc
				(start 204.817726 -371.4369)
				(mid 204.806615 -371.453434)
				(end 204.80274 -371.472968)
			)
			(arc
				(start 204.80274 -372.76024)
				(mid 204.808877 -372.784193)
				(end 204.8256 -372.802404)
			)
			(xy 204.90688 -372.856506) (xy 204.93228 -372.858538)
			(arc
				(start 204.944218 -372.853458)
				(mid 205.032145 -372.825971)
				(end 205.123796 -372.816628)
			)
			(arc
				(start 205.124304 -372.816628)
				(mid 205.447952 -372.950688)
				(end 205.582012 -373.274336)
			)
			(arc
				(start 205.582012 -373.274336)
				(mid 205.453208 -373.592642)
				(end 205.13929 -373.73179)
			)
			(arc
				(start 205.139036 -373.73179)
				(mid 205.120759 -373.735982)
				(end 205.105254 -373.746522)
			)
			(arc
				(start 204.993494 -373.858282)
				(mid 204.923426 -373.91131)
				(end 204.841602 -373.943372)
			)
			(xy 204.824584 -373.947436) (xy 204.80274 -373.974868)
			(arc
				(start 204.80274 -374.509284)
				(mid 204.806641 -374.528807)
				(end 204.817726 -374.545352)
			)
			(arc
				(start 204.893672 -374.621298)
				(mid 204.904783 -374.637832)
				(end 204.908658 -374.657366)
			)
			(arc
				(start 204.908658 -386.862574)
				(mid 204.912559 -386.882097)
				(end 204.923644 -386.898642)
			)
			(arc
				(start 207.444848 -389.419846)
				(mid 207.455959 -389.43638)
				(end 207.459834 -389.455914)
			)
			(arc
				(start 207.459834 -411.614112)
				(mid 207.463735 -411.633635)
				(end 207.47482 -411.65018)
			)
			(arc
				(start 208.894934 -413.070294)
				(mid 208.911468 -413.081405)
				(end 208.931002 -413.08528)
			)
		)
		(stroke
			(width 0)
			(type solid)
		)
		(fill yes)
		(layer "B.Cu")
		(net "P12V_STBY")
	)
	(gr_poly
		(pts
			(xy 371.694456 -293.661846) (xy 371.701568 -293.65448)
			(arc
				(start 371.9703 -293.385748)
				(mid 371.981411 -293.369214)
				(end 371.985286 -293.34968)
			)
			(xy 371.985286 -285.48965) (xy 371.977666 -285.470854) (xy 371.9703 -285.463742)
			(arc
				(start 371.842284 -285.335726)
				(mid 371.82575 -285.324615)
				(end 371.806216 -285.32074)
			)
			(arc
				(start 365.50092 -285.32074)
				(mid 365.481397 -285.316839)
				(end 365.464852 -285.305754)
			)
			(arc
				(start 364.805722 -284.646624)
				(mid 364.794611 -284.63009)
				(end 364.790736 -284.610556)
			)
			(arc
				(start 364.790736 -282.899358)
				(mid 364.788553 -282.88437)
				(end 364.7821 -282.870656)
			)
			(arc
				(start 364.77575 -282.863036)
				(mid 364.753488 -282.837128)
				(end 364.735364 -282.808172)
			)
			(xy 364.731808 -282.801314)
			(arc
				(start 364.592616 -282.662122)
				(mid 364.576082 -282.651011)
				(end 364.556548 -282.647136)
			)
			(xy 362.998766 -282.647136) (xy 362.992924 -282.652978)
			(arc
				(start 362.992924 -284.865064)
				(mid 362.989023 -284.884587)
				(end 362.977938 -284.901132)
			)
			(arc
				(start 362.89234 -284.98673)
				(mid 362.875806 -284.997841)
				(end 362.856272 -285.001716)
			)
			(arc
				(start 359.833672 -285.001716)
				(mid 359.814149 -284.997815)
				(end 359.797604 -284.98673)
			)
			(xy 359.786682 -284.975808) (xy 359.77957 -284.968442) (xy 359.760774 -284.960822) (xy 359.22585 -284.960822)
			(xy 359.12806 -285.058612) (xy 359.12806 -286.237172)
			(arc
				(start 359.414826 -286.524192)
				(mid 359.425888 -286.540609)
				(end 359.429812 -286.560006)
			)
			(arc
				(start 359.429812 -286.918146)
				(mid 359.425862 -286.937533)
				(end 359.414826 -286.95396)
			)
			(xy 359.074466 -287.29432)
			(arc
				(start 358.208834 -287.29432)
				(mid 358.192417 -287.305382)
				(end 358.17302 -287.309306)
			)
			(arc
				(start 357.81488 -287.309306)
				(mid 357.795493 -287.305356)
				(end 357.779066 -287.29432)
			)
			(arc
				(start 357.152448 -286.667702)
				(mid 357.141386 -286.651285)
				(end 357.137462 -286.631888)
			)
			(xy 357.137462 -285.117794)
			(arc
				(start 356.98049 -284.960822)
				(mid 356.960967 -284.956921)
				(end 356.944422 -284.945836)
			)
			(arc
				(start 356.64521 -284.646624)
				(mid 356.634099 -284.63009)
				(end 356.630224 -284.610556)
			)
			(arc
				(start 356.630224 -282.91155)
				(mid 356.6291 -282.901172)
				(end 356.625906 -282.89123)
			)
			(xy 356.613968 -282.864306)
			(arc
				(start 356.60711 -282.857448)
				(mid 356.568089 -282.805659)
				(end 356.545388 -282.744926)
			)
			(xy 356.543864 -282.73756) (xy 356.537006 -282.725114) (xy 356.49154 -282.679648) (xy 356.484428 -282.672282)
			(xy 356.465632 -282.664662)
			(arc
				(start 356.447598 -282.664662)
				(mid 356.432875 -282.662405)
				(end 356.419404 -282.656026)
			)
			(xy 356.413054 -282.651708) (xy 356.398576 -282.647136) (xy 354.838254 -282.647136) (xy 354.832412 -282.652978)
			(arc
				(start 354.832412 -284.865064)
				(mid 354.828511 -284.884587)
				(end 354.817426 -284.901132)
			)
			(arc
				(start 354.731828 -284.98673)
				(mid 354.715294 -284.997841)
				(end 354.69576 -285.001716)
			)
			(arc
				(start 351.028 -285.001716)
				(mid 351.008477 -285.005617)
				(end 350.991932 -285.016702)
			)
			(xy 350.888808 -285.119826) (xy 350.881442 -285.126938) (xy 350.881188 -285.1277) (xy 348.66453 -285.1277)
			(arc
				(start 348.146624 -284.609794)
				(mid 348.135513 -284.59326)
				(end 348.131638 -284.573726)
			)
			(arc
				(start 348.131638 -282.895294)
				(mid 348.130707 -282.885863)
				(end 348.128082 -282.876752)
			)
			(xy 348.118176 -282.85186)
			(arc
				(start 348.112588 -282.845256)
				(mid 348.086155 -282.807533)
				(end 348.067884 -282.765246)
			)
			(arc
				(start 348.067122 -282.76296)
				(mid 348.062149 -282.750678)
				(end 348.054168 -282.7401)
			)
			(xy 347.97619 -282.662122) (xy 347.969078 -282.654756) (xy 347.950282 -282.647136) (xy 346.339668 -282.647136)
			(xy 346.333826 -282.652978)
			(arc
				(start 346.333826 -284.865064)
				(mid 346.329925 -284.884587)
				(end 346.31884 -284.901132)
			)
			(arc
				(start 346.233242 -284.98673)
				(mid 346.216708 -284.997841)
				(end 346.197174 -285.001716)
			)
			(arc
				(start 343.174574 -285.001716)
				(mid 343.155051 -284.997815)
				(end 343.138506 -284.98673)
			)
			(arc
				(start 343.127584 -284.975808)
				(mid 343.11105 -284.964697)
				(end 343.091516 -284.960822)
			)
			(arc
				(start 342.463374 -284.960822)
				(mid 342.443851 -284.964723)
				(end 342.427306 -284.975808)
			)
			(xy 342.364822 -285.038292) (xy 342.357456 -285.045404) (xy 342.349836 -285.0642)
			(arc
				(start 342.349836 -286.081724)
				(mid 342.353601 -286.100915)
				(end 342.364314 -286.117284)
			)
			(xy 342.563704 -286.316674) (xy 342.631522 -286.384746)
			(arc
				(start 342.643968 -286.397192)
				(mid 342.655079 -286.413726)
				(end 342.658954 -286.43326)
			)
			(arc
				(start 342.658954 -286.759396)
				(mid 342.655053 -286.778919)
				(end 342.643968 -286.795464)
			)
			(arc
				(start 342.413336 -287.026096)
				(mid 342.396802 -287.037207)
				(end 342.377268 -287.041082)
			)
			(xy 342.03005 -287.041082) (xy 342.024208 -287.03524)
			(arc
				(start 341.620602 -287.03524)
				(mid 341.601245 -287.039073)
				(end 341.584788 -287.049972)
			)
			(arc
				(start 341.505286 -287.12922)
				(mid 341.488752 -287.140331)
				(end 341.469218 -287.144206)
			)
			(arc
				(start 341.143082 -287.144206)
				(mid 341.123559 -287.140305)
				(end 341.107014 -287.12922)
			)
			(arc
				(start 340.479634 -286.50184)
				(mid 340.473349 -286.494129)
				(end 340.468712 -286.48533)
			)
			(xy 340.464902 -286.476186)
			(arc
				(start 340.464902 -285.027878)
				(mid 340.461001 -285.008355)
				(end 340.449916 -284.99181)
			)
			(arc
				(start 339.986112 -284.528006)
				(mid 339.975001 -284.511472)
				(end 339.971126 -284.491938)
			)
			(arc
				(start 339.971126 -282.889198)
				(mid 339.97027 -282.880161)
				(end 339.967824 -282.871418)
			)
			(xy 339.95868 -282.84678)
			(arc
				(start 339.953346 -282.840176)
				(mid 339.930417 -282.806147)
				(end 339.913976 -282.768548)
			)
			(arc
				(start 339.913722 -282.767786)
				(mid 339.908781 -282.757168)
				(end 339.90153 -282.747974)
			)
			(xy 339.844888 -282.691332) (xy 339.837776 -282.683966) (xy 339.81898 -282.676346)
			(arc
				(start 339.752178 -282.676346)
				(mid 339.733123 -282.672534)
				(end 339.716872 -282.661868)
			)
			(arc
				(start 339.716364 -282.66136)
				(mid 339.700097 -282.650799)
				(end 339.681058 -282.647136)
			)
			(xy 338.179156 -282.647136) (xy 338.173314 -282.652978)
			(arc
				(start 338.173314 -284.865064)
				(mid 338.169413 -284.884587)
				(end 338.158328 -284.901132)
			)
			(arc
				(start 338.07273 -284.98673)
				(mid 338.056196 -284.997841)
				(end 338.036662 -285.001716)
			)
			(arc
				(start 335.014062 -285.001716)
				(mid 334.994539 -284.997815)
				(end 334.977994 -284.98673)
			)
			(arc
				(start 334.967072 -284.975808)
				(mid 334.950538 -284.964697)
				(end 334.931004 -284.960822)
			)
			(arc
				(start 334.409796 -284.960822)
				(mid 334.390273 -284.964723)
				(end 334.373728 -284.975808)
			)
			(arc
				(start 334.22971 -285.119826)
				(mid 334.218599 -285.13636)
				(end 334.214724 -285.155894)
			)
			(arc
				(start 334.214724 -287.846262)
				(mid 334.216034 -287.857471)
				(end 334.219804 -287.868106)
			)
			(xy 334.22209 -287.872932)
			(arc
				(start 334.224122 -287.87598)
				(mid 334.81987 -289.82073)
				(end 334.22336 -291.765228)
			)
			(xy 334.219296 -291.771324) (xy 334.214978 -291.784786) (xy 334.214724 -291.793422)
			(arc
				(start 334.214724 -293.472362)
				(mid 334.218489 -293.491553)
				(end 334.229202 -293.507922)
			)
			(xy 334.37576 -293.65448)
			(arc
				(start 334.376268 -293.654988)
				(mid 334.392625 -293.66573)
				(end 334.411828 -293.669466)
			)
			(xy 371.67566 -293.669466)
		)
		(stroke
			(width 0)
			(type solid)
		)
		(fill yes)
		(layer "B.Cu")
		(net "GND")
	)
	(gr_poly
		(pts
			(arc
				(start 329.925172 -228.948742)
				(mid 329.944695 -228.944841)
				(end 329.96124 -228.933756)
			)
			(arc
				(start 330.156058 -228.738938)
				(mid 330.167169 -228.722404)
				(end 330.171044 -228.70287)
			)
			(arc
				(start 330.171044 -228.158548)
				(mid 330.174945 -228.139025)
				(end 330.18603 -228.12248)
			)
			(arc
				(start 330.359766 -227.948744)
				(mid 330.3763 -227.937633)
				(end 330.395834 -227.933758)
			)
			(arc
				(start 330.871068 -227.933758)
				(mid 330.890591 -227.929857)
				(end 330.907136 -227.918772)
			)
			(arc
				(start 331.675232 -227.150676)
				(mid 331.691766 -227.139565)
				(end 331.7113 -227.13569)
			)
			(arc
				(start 333.843122 -227.13569)
				(mid 333.862645 -227.131789)
				(end 333.87919 -227.120704)
			)
			(xy 334.134714 -226.86518) (xy 334.142334 -226.843082)
			(arc
				(start 334.14081 -226.831398)
				(mid 334.13873 -226.809343)
				(end 334.138016 -226.787202)
			)
			(arc
				(start 334.138016 -226.786948)
				(mid 334.242318 -226.535142)
				(end 334.494124 -226.43084)
			)
			(arc
				(start 334.494124 -226.43084)
				(mid 334.674578 -226.479948)
				(end 334.805274 -226.61372)
			)
			(arc
				(start 334.805274 -226.61372)
				(mid 334.82393 -226.632871)
				(end 334.849724 -226.639882)
			)
			(arc
				(start 334.93837 -226.639882)
				(mid 334.964153 -226.632853)
				(end 334.98282 -226.61372)
			)
			(arc
				(start 334.98282 -226.61372)
				(mid 335.042293 -226.535133)
				(end 335.120996 -226.475798)
			)
			(arc
				(start 335.120996 -226.475798)
				(mid 335.140147 -226.457142)
				(end 335.147158 -226.431348)
			)
			(arc
				(start 335.147158 -226.342448)
				(mid 335.140129 -226.316665)
				(end 335.120996 -226.297998)
			)
			(arc
				(start 335.120996 -226.297998)
				(mid 334.937972 -225.986848)
				(end 335.120996 -225.675698)
			)
			(arc
				(start 335.120996 -225.675698)
				(mid 335.140147 -225.657042)
				(end 335.147158 -225.631248)
			)
			(arc
				(start 335.147158 -225.542348)
				(mid 335.140129 -225.516565)
				(end 335.120996 -225.497898)
			)
			(arc
				(start 335.120996 -225.497898)
				(mid 334.98703 -225.367275)
				(end 334.937862 -225.186748)
			)
			(arc
				(start 334.937862 -225.186748)
				(mid 334.98697 -225.006294)
				(end 335.120742 -224.875598)
			)
			(arc
				(start 335.120742 -224.875598)
				(mid 335.139893 -224.856942)
				(end 335.146904 -224.831148)
			)
			(arc
				(start 335.146904 -224.742502)
				(mid 335.139875 -224.716719)
				(end 335.120742 -224.698052)
			)
			(arc
				(start 335.120742 -224.698052)
				(mid 335.049965 -224.646224)
				(end 334.993996 -224.578672)
			)
			(arc
				(start 334.993996 -224.578672)
				(mid 334.975633 -224.561579)
				(end 334.951324 -224.555304)
			)
			(arc
				(start 334.837024 -224.555304)
				(mid 334.812681 -224.561516)
				(end 334.794352 -224.578672)
			)
			(arc
				(start 334.794352 -224.578672)
				(mid 334.754362 -224.630094)
				(end 334.705706 -224.673414)
			)
			(arc
				(start 334.705706 -224.673414)
				(mid 334.691356 -224.689835)
				(end 334.685132 -224.710752)
			)
			(xy 334.685132 -224.875344) (xy 334.593184 -224.933764)
			(arc
				(start 334.43799 -224.933764)
				(mid 334.42119 -224.938556)
				(end 334.407002 -224.94875)
			)
			(arc
				(start 334.247998 -225.107754)
				(mid 334.231464 -225.118865)
				(end 334.21193 -225.12274)
			)
			(arc
				(start 333.975456 -225.12274)
				(mid 333.955933 -225.118839)
				(end 333.939388 -225.107754)
			)
			(arc
				(start 333.926942 -225.095308)
				(mid 333.891039 -225.080473)
				(end 333.85506 -225.095308)
			)
			(arc
				(start 333.331312 -225.619056)
				(mid 333.316694 -225.650194)
				(end 333.325216 -225.683572)
			)
			(arc
				(start 333.325216 -225.683572)
				(mid 333.374198 -225.785691)
				(end 333.391002 -225.897694)
			)
			(arc
				(start 333.391002 -225.897694)
				(mid 333.279261 -226.167461)
				(end 333.009494 -226.279202)
			)
			(arc
				(start 333.009494 -226.279202)
				(mid 332.856458 -226.247186)
				(end 332.729078 -226.15652)
			)
			(xy 332.72222 -226.1489)
			(arc
				(start 332.69428 -226.136454)
				(mid 332.684109 -226.133059)
				(end 332.673452 -226.131882)
			)
			(arc
				(start 332.586584 -226.131882)
				(mid 332.567725 -226.135512)
				(end 332.551532 -226.145852)
			)
			(arc
				(start 332.551532 -226.145852)
				(mid 332.429939 -226.2243)
				(end 332.28788 -226.25177)
			)
			(arc
				(start 332.287372 -226.25177)
				(mid 332.182186 -226.23691)
				(end 332.085188 -226.193604)
			)
			(xy 332.07706 -226.18827) (xy 332.059026 -226.184714)
			(arc
				(start 332.028546 -226.190048)
				(mid 332.019195 -226.192601)
				(end 332.010512 -226.196906)
			)
			(xy 332.001622 -226.202494)
			(arc
				(start 331.99578 -226.210368)
				(mid 331.79247 -226.382269)
				(end 331.5335 -226.444048)
			)
			(arc
				(start 331.5335 -226.444048)
				(mid 331.313684 -226.40023)
				(end 331.127354 -226.275646)
			)
			(arc
				(start 331.005688 -226.154234)
				(mid 330.989271 -226.143172)
				(end 330.969874 -226.139248)
			)
			(arc
				(start 330.767182 -226.139248)
				(mid 330.747163 -226.143359)
				(end 330.730352 -226.154996)
			)
			(xy 330.672186 -226.216464) (xy 330.665074 -226.235514) (xy 330.665582 -226.246182) (xy 330.666344 -226.276916)
			(arc
				(start 330.666344 -226.5172)
				(mid 330.498153 -226.923377)
				(end 330.09205 -227.091748)
			)
			(xy 330.08189 -227.091494) (xy 330.071476 -227.09124) (xy 330.05268 -227.09886)
			(arc
				(start 329.993498 -227.156772)
				(mid 329.982338 -227.173423)
				(end 329.978512 -227.193094)
			)
			(arc
				(start 329.978512 -227.328222)
				(mid 329.810395 -227.734219)
				(end 329.404472 -227.902516)
			)
			(arc
				(start 329.403964 -227.902516)
				(mid 329.244834 -227.88004)
				(end 329.098148 -227.814378)
			)
			(arc
				(start 329.089258 -227.81006)
				(mid 328.823936 -227.601472)
				(end 328.723752 -227.2792)
			)
			(arc
				(start 328.723752 -227.00869)
				(mid 328.715145 -226.980651)
				(end 328.69251 -226.961954)
			)
			(xy 328.678032 -226.955858) (xy 328.64806 -226.961954) (xy 327.960482 -227.649532) (xy 327.953116 -227.656644)
			(xy 327.945496 -227.67544)
			(arc
				(start 327.945496 -228.05136)
				(mid 327.949397 -228.070883)
				(end 327.960482 -228.087428)
			)
			(arc
				(start 328.80681 -228.933756)
				(mid 328.823344 -228.944867)
				(end 328.842878 -228.948742)
			)
		)
		(stroke
			(width 0)
			(type solid)
		)
		(fill yes)
		(layer "B.Cu")
		(net "P3V3_FPGA_VCCIO5")
	)
	(gr_poly
		(pts
			(xy 106.199686 -85.46846) (xy 106.209748 -85.46802) (xy 106.228326 -85.460279) (xy 106.235754 -85.453474)
			(xy 106.313224 -85.376004) (xy 106.319906 -85.368593) (xy 106.327486 -85.350158) (xy 106.327956 -85.34019)
			(xy 106.327956 -83.90763) (xy 106.32849 -83.897641) (xy 106.336202 -83.879207) (xy 106.342942 -83.871816)
			(xy 106.628184 -83.586574) (xy 106.63553 -83.579769) (xy 106.653994 -83.572055) (xy 106.663998 -83.571588)
			(xy 110.833154 -83.571588) (xy 110.843145 -83.572117) (xy 110.861591 -83.579817) (xy 110.868968 -83.586574)
			(xy 110.89767 -83.615022) (xy 110.905015 -83.62183) (xy 110.923479 -83.629549) (xy 110.933484 -83.630008)
			(xy 111.134906 -83.630008) (xy 111.144976 -83.630433) (xy 111.163578 -83.638149) (xy 111.170974 -83.644994)
			(xy 111.269272 -83.743292) (xy 111.276123 -83.750689) (xy 111.283864 -83.769287) (xy 111.284258 -83.77936)
			(xy 111.284258 -85.16874) (xy 111.28469 -85.178806) (xy 111.292421 -85.197394) (xy 111.299244 -85.204808)
			(xy 111.430308 -85.335872) (xy 111.437706 -85.34272) (xy 111.456304 -85.350456) (xy 111.466376 -85.350858)
			(xy 112.750346 -85.350858) (xy 112.760412 -85.350425) (xy 112.779 -85.342694) (xy 112.786414 -85.335872)
			(xy 112.892078 -85.230208) (xy 112.898928 -85.222811) (xy 112.906669 -85.204213) (xy 112.907064 -85.19414)
			(xy 112.907064 -82.095848) (xy 112.906556 -82.09534) (xy 112.906556 -81.470754) (xy 112.906556 -80.646016)
			(xy 112.40897 -80.14843) (xy 106.98226 -80.14843) (xy 106.113072 -81.017618) (xy 106.103004 -81.018047)
			(xy 106.084409 -81.02577) (xy 106.077004 -81.032604) (xy 105.428034 -81.681574) (xy 105.420633 -81.688413)
			(xy 105.402035 -81.696127) (xy 105.391966 -81.69656) (xy 105.365804 -81.69656) (xy 105.355818 -81.697098)
			(xy 105.33739 -81.704817) (xy 105.32999 -81.711546) (xy 105.304844 -81.736438) (xy 105.297499 -81.743247)
			(xy 105.279035 -81.750969) (xy 105.26903 -81.751424) (xy 103.657146 -81.751424) (xy 103.647154 -81.750896)
			(xy 103.628708 -81.743197) (xy 103.621332 -81.736438) (xy 103.589074 -81.70418) (xy 103.570532 -81.69656)
			(xy 103.56596 -81.69656) (xy 103.499666 -81.762854) (xy 103.492321 -81.769664) (xy 103.473858 -81.777391)
			(xy 103.463852 -81.77784) (xy 102.52202 -81.77784) (xy 102.51206 -81.77833) (xy 102.493643 -81.785925)
			(xy 102.486206 -81.792572) (xy 102.4697 -81.809078) (xy 108.181884 -81.809078) (xy 108.181884 -81.749142)
			(xy 108.189707 -81.68972) (xy 108.20522 -81.631827) (xy 108.228156 -81.576454) (xy 108.258123 -81.524548)
			(xy 108.29461 -81.476998) (xy 108.33699 -81.434618) (xy 108.38454 -81.398131) (xy 108.436446 -81.368164)
			(xy 108.491819 -81.345228) (xy 108.549712 -81.329715) (xy 108.609134 -81.321892) (xy 108.66907 -81.321892)
			(xy 108.728492 -81.329715) (xy 108.786385 -81.345228) (xy 108.841758 -81.368164) (xy 108.893664 -81.398131)
			(xy 108.941214 -81.434618) (xy 108.983594 -81.476998) (xy 109.020081 -81.524548) (xy 109.050048 -81.576454)
			(xy 109.072984 -81.631827) (xy 109.088497 -81.68972) (xy 109.09632 -81.749142) (xy 109.09681 -81.77911)
			(xy 109.09632 -81.809078) (xy 109.088497 -81.8685) (xy 109.072984 -81.926393) (xy 109.056558 -81.96605)
			(xy 110.455946 -81.96605) (xy 110.455946 -81.906114) (xy 110.463769 -81.846692) (xy 110.479282 -81.788799)
			(xy 110.502218 -81.733426) (xy 110.532185 -81.68152) (xy 110.568672 -81.63397) (xy 110.611052 -81.59159)
			(xy 110.658602 -81.555103) (xy 110.710508 -81.525136) (xy 110.765881 -81.5022) (xy 110.823774 -81.486687)
			(xy 110.883196 -81.478864) (xy 110.943132 -81.478864) (xy 111.002554 -81.486687) (xy 111.060447 -81.5022)
			(xy 111.11582 -81.525136) (xy 111.167726 -81.555103) (xy 111.215276 -81.59159) (xy 111.257656 -81.63397)
			(xy 111.294143 -81.68152) (xy 111.32411 -81.733426) (xy 111.347046 -81.788799) (xy 111.362559 -81.846692)
			(xy 111.370382 -81.906114) (xy 111.370872 -81.936082) (xy 111.370382 -81.96605) (xy 111.362559 -82.025472)
			(xy 111.347046 -82.083365) (xy 111.32411 -82.138738) (xy 111.294143 -82.190644) (xy 111.257656 -82.238194)
			(xy 111.215276 -82.280574) (xy 111.167726 -82.317061) (xy 111.11582 -82.347028) (xy 111.060447 -82.369964)
			(xy 111.002554 -82.385477) (xy 110.943132 -82.3933) (xy 110.883196 -82.3933) (xy 110.823774 -82.385477)
			(xy 110.765881 -82.369964) (xy 110.710508 -82.347028) (xy 110.658602 -82.317061) (xy 110.611052 -82.280574)
			(xy 110.568672 -82.238194) (xy 110.532185 -82.190644) (xy 110.502218 -82.138738) (xy 110.479282 -82.083365)
			(xy 110.463769 -82.025472) (xy 110.455946 -81.96605) (xy 109.056558 -81.96605) (xy 109.050048 -81.981766)
			(xy 109.020081 -82.033672) (xy 108.983594 -82.081222) (xy 108.941214 -82.123602) (xy 108.893664 -82.160089)
			(xy 108.841758 -82.190056) (xy 108.786385 -82.212992) (xy 108.728492 -82.228505) (xy 108.66907 -82.236328)
			(xy 108.609134 -82.236328) (xy 108.549712 -82.228505) (xy 108.491819 -82.212992) (xy 108.436446 -82.190056)
			(xy 108.38454 -82.160089) (xy 108.33699 -82.123602) (xy 108.29461 -82.081222) (xy 108.258123 -82.033672)
			(xy 108.228156 -81.981766) (xy 108.20522 -81.926393) (xy 108.189707 -81.8685) (xy 108.181884 -81.809078)
			(xy 102.4697 -81.809078) (xy 102.413816 -81.864962) (xy 102.406978 -81.872363) (xy 102.399263 -81.890962)
			(xy 102.39883 -81.90103) (xy 102.39883 -82.595462) (xy 111.631966 -82.595462) (xy 111.631966 -82.535526)
			(xy 111.639789 -82.476104) (xy 111.655302 -82.418211) (xy 111.678238 -82.362838) (xy 111.708205 -82.310932)
			(xy 111.744692 -82.263382) (xy 111.787072 -82.221002) (xy 111.834622 -82.184515) (xy 111.886528 -82.154548)
			(xy 111.941901 -82.131612) (xy 111.999794 -82.116099) (xy 112.059216 -82.108276) (xy 112.119152 -82.108276)
			(xy 112.178574 -82.116099) (xy 112.236467 -82.131612) (xy 112.29184 -82.154548) (xy 112.343746 -82.184515)
			(xy 112.391296 -82.221002) (xy 112.433676 -82.263382) (xy 112.470163 -82.310932) (xy 112.50013 -82.362838)
			(xy 112.523066 -82.418211) (xy 112.538579 -82.476104) (xy 112.546402 -82.535526) (xy 112.546892 -82.565494)
			(xy 112.546402 -82.595462) (xy 112.538579 -82.654884) (xy 112.523066 -82.712777) (xy 112.50013 -82.76815)
			(xy 112.470163 -82.820056) (xy 112.433676 -82.867606) (xy 112.391296 -82.909986) (xy 112.343746 -82.946473)
			(xy 112.29184 -82.97644) (xy 112.236467 -82.999376) (xy 112.178574 -83.014889) (xy 112.119152 -83.022712)
			(xy 112.059216 -83.022712) (xy 111.999794 -83.014889) (xy 111.941901 -82.999376) (xy 111.886528 -82.97644)
			(xy 111.834622 -82.946473) (xy 111.787072 -82.909986) (xy 111.744692 -82.867606) (xy 111.708205 -82.820056)
			(xy 111.678238 -82.76815) (xy 111.655302 -82.712777) (xy 111.639789 -82.654884) (xy 111.631966 -82.595462)
			(xy 102.39883 -82.595462) (xy 102.39883 -83.50123) (xy 102.399259 -83.511297) (xy 102.406985 -83.529891)
			(xy 102.413816 -83.537298) (xy 102.53218 -83.655662) (xy 102.539581 -83.6625) (xy 102.55818 -83.670211)
			(xy 102.568248 -83.670648) (xy 104.356916 -83.670648) (xy 104.366984 -83.671075) (xy 104.385579 -83.678799)
			(xy 104.392984 -83.685634) (xy 104.427782 -83.720432) (xy 104.435341 -83.727385) (xy 104.454346 -83.735123)
			(xy 104.464612 -83.735418) (xy 104.548432 -83.73364) (xy 104.567228 -83.725258) (xy 104.57434 -83.717638)
			(xy 104.592453 -83.698696) (xy 104.632975 -83.665458) (xy 104.677666 -83.638082) (xy 104.725686 -83.617083)
			(xy 104.776128 -83.602858) (xy 104.828043 -83.595674) (xy 104.854248 -83.59521) (xy 104.881496 -83.5957)
			(xy 104.935436 -83.603461) (xy 104.987722 -83.61882) (xy 105.037291 -83.641463) (xy 105.083133 -83.670929)
			(xy 105.124316 -83.706618) (xy 105.16 -83.747805) (xy 105.189461 -83.793651) (xy 105.212097 -83.843223)
			(xy 105.227449 -83.895511) (xy 105.235204 -83.949452) (xy 105.235204 -84.003948) (xy 105.227449 -84.057889)
			(xy 105.212097 -84.110177) (xy 105.189461 -84.159749) (xy 105.16 -84.205595) (xy 105.124316 -84.246782)
			(xy 105.083133 -84.282471) (xy 105.037291 -84.311937) (xy 104.987722 -84.33458) (xy 104.935436 -84.349939)
			(xy 104.881496 -84.3577) (xy 104.854248 -84.358226) (xy 104.828049 -84.357796) (xy 104.776142 -84.350634)
			(xy 104.725703 -84.336437) (xy 104.677681 -84.315474) (xy 104.632979 -84.288137) (xy 104.61244 -84.271866)
			(xy 104.605492 -84.266631) (xy 104.58913 -84.26076) (xy 104.571747 -84.260712) (xy 104.563418 -84.26323)
			(xy 104.534462 -84.27339) (xy 104.526251 -84.27664) (xy 104.512555 -84.287765) (xy 104.503482 -84.302899)
			(xy 104.501442 -84.31149) (xy 104.492806 -84.347812) (xy 104.491028 -84.354416) (xy 104.491028 -85.043772)
			(xy 104.491369 -85.052381) (xy 104.497061 -85.068631) (xy 104.507785 -85.082102) (xy 104.514904 -85.086952)
			(xy 104.539326 -85.102824) (xy 104.584326 -85.139805) (xy 104.624271 -85.182196) (xy 104.658516 -85.229311)
			(xy 104.686507 -85.280391) (xy 104.707792 -85.334609) (xy 104.722026 -85.391088) (xy 104.725978 -85.419946)
			(xy 104.726994 -85.428582) (xy 104.73436 -85.443568) (xy 104.744266 -85.453474) (xy 104.751667 -85.460313)
			(xy 104.770265 -85.468027) (xy 104.780334 -85.46846)
		)
		(stroke
			(width 0)
			(type solid)
		)
		(fill yes)
		(layer "B.Cu")
		(net "P3V3_VDD_9ZXL0851_0_7")
	)
	(gr_poly
		(pts
			(xy 280.655522 -397.748506) (xy 280.667296 -397.74948) (xy 280.68965 -397.741917) (xy 280.698448 -397.734028)
			(xy 280.83256 -397.60017) (xy 280.839327 -397.592741) (xy 280.8469 -397.574145) (xy 280.847292 -397.564102)
			(xy 280.847292 -391.206736) (xy 280.846879 -391.196711) (xy 280.839215 -391.178183) (xy 280.825041 -391.164001)
			(xy 280.806517 -391.156327) (xy 280.796492 -391.155936) (xy 278.16048 -391.155936) (xy 278.150412 -391.156364)
			(xy 278.131816 -391.164087) (xy 278.124412 -391.170922) (xy 277.16607 -392.129264) (xy 277.159279 -392.136704)
			(xy 277.151677 -392.155341) (xy 277.151839 -392.175468) (xy 277.155402 -392.18489) (xy 277.198328 -392.285982)
			(xy 277.223982 -392.302746) (xy 277.23973 -392.302492) (xy 277.24735 -392.302492) (xy 277.277317 -392.302985)
			(xy 277.336737 -392.310815) (xy 277.394627 -392.326333) (xy 277.449997 -392.349274) (xy 277.501898 -392.379246)
			(xy 277.549443 -392.415736) (xy 277.591819 -392.458119) (xy 277.628301 -392.505671) (xy 277.658263 -392.557578)
			(xy 277.681194 -392.612952) (xy 277.696702 -392.670845) (xy 277.70452 -392.730266) (xy 277.704518 -392.76045)
			(xy 278.5915 -392.76045) (xy 278.5915 -392.700514) (xy 278.599323 -392.641092) (xy 278.614836 -392.583199)
			(xy 278.637772 -392.527826) (xy 278.667739 -392.47592) (xy 278.704226 -392.42837) (xy 278.746606 -392.38599)
			(xy 278.794156 -392.349503) (xy 278.846062 -392.319536) (xy 278.901435 -392.2966) (xy 278.959328 -392.281087)
			(xy 279.01875 -392.273264) (xy 279.078686 -392.273264) (xy 279.138108 -392.281087) (xy 279.196001 -392.2966)
			(xy 279.251374 -392.319536) (xy 279.30328 -392.349503) (xy 279.35083 -392.38599) (xy 279.39321 -392.42837)
			(xy 279.429697 -392.47592) (xy 279.459664 -392.527826) (xy 279.4826 -392.583199) (xy 279.498113 -392.641092)
			(xy 279.505936 -392.700514) (xy 279.506426 -392.730482) (xy 279.505936 -392.76045) (xy 279.498113 -392.819872)
			(xy 279.4826 -392.877765) (xy 279.459664 -392.933138) (xy 279.429697 -392.985044) (xy 279.39321 -393.032594)
			(xy 279.35083 -393.074974) (xy 279.30328 -393.111461) (xy 279.251374 -393.141428) (xy 279.196001 -393.164364)
			(xy 279.138108 -393.179877) (xy 279.078686 -393.1877) (xy 279.01875 -393.1877) (xy 278.959328 -393.179877)
			(xy 278.901435 -393.164364) (xy 278.846062 -393.141428) (xy 278.794156 -393.111461) (xy 278.746606 -393.074974)
			(xy 278.704226 -393.032594) (xy 278.667739 -392.985044) (xy 278.637772 -392.933138) (xy 278.614836 -392.877765)
			(xy 278.599323 -392.819872) (xy 278.5915 -392.76045) (xy 277.704518 -392.76045) (xy 277.704516 -392.7902)
			(xy 277.696689 -392.849621) (xy 277.681173 -392.907512) (xy 277.658234 -392.962882) (xy 277.628263 -393.014784)
			(xy 277.591775 -393.062331) (xy 277.549393 -393.104708) (xy 277.501843 -393.141191) (xy 277.449937 -393.171156)
			(xy 277.394564 -393.194089) (xy 277.336672 -393.209598) (xy 277.27725 -393.217419) (xy 277.217316 -393.217417)
			(xy 277.157895 -393.209592) (xy 277.100004 -393.194078) (xy 277.044633 -393.171141) (xy 276.99273 -393.141173)
			(xy 276.945182 -393.104686) (xy 276.902803 -393.062306) (xy 276.866318 -393.014757) (xy 276.836352 -392.962852)
			(xy 276.813416 -392.90748) (xy 276.797905 -392.849588) (xy 276.790082 -392.790167) (xy 276.789642 -392.7602)
			(xy 276.789642 -392.75258) (xy 276.789896 -392.736832) (xy 276.773132 -392.711178) (xy 276.67204 -392.668252)
			(xy 276.662612 -392.664725) (xy 276.642499 -392.664584) (xy 276.623864 -392.672152) (xy 276.616414 -392.67892)
			(xy 276.373336 -392.921998) (xy 276.366648 -392.929406) (xy 276.359059 -392.947842) (xy 276.358604 -392.957812)
			(xy 276.358604 -394.762482) (xy 276.700486 -394.762482) (xy 276.704557 -394.70686) (xy 276.716683 -394.652423)
			(xy 276.736606 -394.600332) (xy 276.763902 -394.551697) (xy 276.797988 -394.507554) (xy 276.838137 -394.468845)
			(xy 276.883495 -394.436394) (xy 276.933095 -394.410893) (xy 276.985879 -394.392886) (xy 277.040722 -394.382756)
			(xy 277.096456 -394.380719) (xy 277.151893 -394.386819) (xy 277.20585 -394.400925) (xy 277.257179 -394.422737)
			(xy 277.304785 -394.451791) (xy 277.347653 -394.487466) (xy 277.38487 -394.529003) (xy 277.415643 -394.575516)
			(xy 277.439315 -394.626013) (xy 277.455383 -394.67942) (xy 277.463503 -394.734596) (xy 277.464012 -394.762482)
			(xy 279.240486 -394.762482) (xy 279.244557 -394.70686) (xy 279.256683 -394.652423) (xy 279.276606 -394.600332)
			(xy 279.303902 -394.551697) (xy 279.337988 -394.507554) (xy 279.378137 -394.468845) (xy 279.423495 -394.436394)
			(xy 279.473095 -394.410893) (xy 279.525879 -394.392886) (xy 279.580722 -394.382756) (xy 279.636456 -394.380719)
			(xy 279.691893 -394.386819) (xy 279.74585 -394.400925) (xy 279.797179 -394.422737) (xy 279.844785 -394.451791)
			(xy 279.887653 -394.487466) (xy 279.92487 -394.529003) (xy 279.955643 -394.575516) (xy 279.979315 -394.626013)
			(xy 279.995383 -394.67942) (xy 280.003503 -394.734596) (xy 280.004012 -394.762482) (xy 280.003503 -394.790368)
			(xy 279.995383 -394.845544) (xy 279.979315 -394.898951) (xy 279.955643 -394.949448) (xy 279.92487 -394.995961)
			(xy 279.887653 -395.037498) (xy 279.844785 -395.073173) (xy 279.797179 -395.102227) (xy 279.74585 -395.124039)
			(xy 279.691893 -395.138145) (xy 279.636456 -395.144245) (xy 279.580722 -395.142208) (xy 279.525879 -395.132078)
			(xy 279.473095 -395.114071) (xy 279.423495 -395.08857) (xy 279.378137 -395.056119) (xy 279.337988 -395.01741)
			(xy 279.303902 -394.973267) (xy 279.276606 -394.924632) (xy 279.256683 -394.872541) (xy 279.244557 -394.818104)
			(xy 279.240486 -394.762482) (xy 277.464012 -394.762482) (xy 277.463503 -394.790368) (xy 277.455383 -394.845544)
			(xy 277.439315 -394.898951) (xy 277.415643 -394.949448) (xy 277.38487 -394.995961) (xy 277.347653 -395.037498)
			(xy 277.304785 -395.073173) (xy 277.257179 -395.102227) (xy 277.20585 -395.124039) (xy 277.151893 -395.138145)
			(xy 277.096456 -395.144245) (xy 277.040722 -395.142208) (xy 276.985879 -395.132078) (xy 276.933095 -395.114071)
			(xy 276.883495 -395.08857) (xy 276.838137 -395.056119) (xy 276.797988 -395.01741) (xy 276.763902 -394.973267)
			(xy 276.736606 -394.924632) (xy 276.716683 -394.872541) (xy 276.704557 -394.818104) (xy 276.700486 -394.762482)
			(xy 276.358604 -394.762482) (xy 276.358604 -395.19606) (xy 276.359089 -395.206023) (xy 276.366676 -395.224448)
			(xy 276.373336 -395.231874) (xy 277.246334 -396.104872) (xy 277.263606 -396.112492) (xy 277.273512 -396.112746)
			(xy 277.302822 -396.114178) (xy 277.360745 -396.123583) (xy 277.416991 -396.140314) (xy 277.470637 -396.164098)
			(xy 277.520803 -396.194543) (xy 277.566666 -396.231151) (xy 277.607474 -396.27332) (xy 277.642558 -396.320359)
			(xy 277.671341 -396.371497) (xy 277.693353 -396.425894) (xy 277.70823 -396.482659) (xy 277.715731 -396.540859)
			(xy 277.716108 -396.56283) (xy 278.783016 -396.56283) (xy 278.783016 -396.502894) (xy 278.790839 -396.443472)
			(xy 278.806352 -396.385579) (xy 278.829288 -396.330206) (xy 278.859255 -396.2783) (xy 278.895742 -396.23075)
			(xy 278.938122 -396.18837) (xy 278.985672 -396.151883) (xy 279.037578 -396.121916) (xy 279.092951 -396.09898)
			(xy 279.150844 -396.083467) (xy 279.210266 -396.075644) (xy 279.270202 -396.075644) (xy 279.329624 -396.083467)
			(xy 279.387517 -396.09898) (xy 279.44289 -396.121916) (xy 279.494796 -396.151883) (xy 279.542346 -396.18837)
			(xy 279.584726 -396.23075) (xy 279.621213 -396.2783) (xy 279.65118 -396.330206) (xy 279.674116 -396.385579)
			(xy 279.689629 -396.443472) (xy 279.697452 -396.502894) (xy 279.697942 -396.532862) (xy 279.697452 -396.56283)
			(xy 279.689629 -396.622252) (xy 279.674116 -396.680145) (xy 279.65118 -396.735518) (xy 279.621213 -396.787424)
			(xy 279.584726 -396.834974) (xy 279.542346 -396.877354) (xy 279.494796 -396.913841) (xy 279.44289 -396.943808)
			(xy 279.387517 -396.966744) (xy 279.329624 -396.982257) (xy 279.270202 -396.99008) (xy 279.210266 -396.99008)
			(xy 279.150844 -396.982257) (xy 279.092951 -396.966744) (xy 279.037578 -396.943808) (xy 278.985672 -396.913841)
			(xy 278.938122 -396.877354) (xy 278.895742 -396.834974) (xy 278.859255 -396.787424) (xy 278.829288 -396.735518)
			(xy 278.806352 -396.680145) (xy 278.790839 -396.622252) (xy 278.783016 -396.56283) (xy 277.716108 -396.56283)
			(xy 277.716234 -396.5702) (xy 277.715744 -396.600168) (xy 277.707921 -396.659592) (xy 277.692409 -396.717486)
			(xy 277.669473 -396.772861) (xy 277.639506 -396.824768) (xy 277.60302 -396.87232) (xy 277.560639 -396.914702)
			(xy 277.51309 -396.951191) (xy 277.461184 -396.981161) (xy 277.405811 -397.0041) (xy 277.347918 -397.019616)
			(xy 277.288494 -397.027442) (xy 277.258526 -397.027908) (xy 277.22449 -397.026638) (xy 277.208488 -397.025368)
			(xy 277.18131 -397.041624) (xy 277.134828 -397.142716) (xy 277.130978 -397.152333) (xy 277.130517 -397.173024)
			(xy 277.138251 -397.19222) (xy 277.145242 -397.199866) (xy 277.543768 -397.598392) (xy 277.551176 -397.605082)
			(xy 277.569612 -397.612677) (xy 277.579582 -397.613124) (xy 279.790144 -397.613124) (xy 279.799669 -397.612735)
			(xy 279.817427 -397.605837) (xy 279.824688 -397.599662) (xy 279.845955 -397.580348) (xy 279.892462 -397.546621)
			(xy 279.942823 -397.518977) (xy 279.996247 -397.497852) (xy 280.051895 -397.483578) (xy 280.108891 -397.476379)
			(xy 280.137616 -397.475964) (xy 280.168079 -397.476466) (xy 280.228467 -397.484549) (xy 280.287249 -397.50057)
			(xy 280.343387 -397.524245) (xy 280.395889 -397.555157) (xy 280.443827 -397.59276) (xy 280.486354 -397.636388)
			(xy 280.52272 -397.685272) (xy 280.53792 -397.711676) (xy 280.543762 -397.72209) (xy 280.56332 -397.735552)
		)
		(stroke
			(width 0)
			(type solid)
		)
		(fill yes)
		(layer "B.Cu")
		(net "GND")
	)
	(gr_poly
		(pts
			(arc
				(start 341.80018 -218.985084)
				(mid 341.810965 -218.983926)
				(end 341.821262 -218.980512)
			)
			(arc
				(start 341.821262 -218.980512)
				(mid 341.827801 -218.976789)
				(end 341.833708 -218.97213)
			)
			(xy 341.910416 -218.89593) (xy 341.910416 -218.895676)
			(arc
				(start 341.934038 -218.872308)
				(mid 341.942645 -218.859592)
				(end 341.946992 -218.844876)
			)
			(xy 341.946992 -218.687904) (xy 341.9475 -218.687396)
			(arc
				(start 341.9475 -218.674442)
				(mid 341.951401 -218.654919)
				(end 341.962486 -218.638374)
			)
			(xy 341.992204 -218.608656) (xy 341.992204 -218.608402) (xy 341.999316 -218.60129) (xy 341.999316 -218.59875)
			(xy 342.005158 -218.592908) (xy 342.017096 -218.592908) (xy 342.018112 -218.593924) (xy 342.162384 -218.593924)
			(xy 342.1761 -218.595956) (xy 342.182196 -218.595956)
			(arc
				(start 342.183974 -218.59875)
				(mid 342.191646 -218.60321)
				(end 342.198452 -218.60891)
			)
			(arc
				(start 342.22944 -218.639898)
				(mid 342.240551 -218.656432)
				(end 342.244426 -218.675966)
			)
			(arc
				(start 342.244426 -218.857322)
				(mid 342.248374 -218.865074)
				(end 342.25357 -218.872054)
			)
			(xy 342.277192 -218.89593) (xy 342.277446 -218.89593) (xy 342.354662 -218.972892)
			(arc
				(start 342.35898 -218.976194)
				(mid 342.372659 -218.982808)
				(end 342.387682 -218.985084)
			)
			(arc
				(start 342.600534 -218.985084)
				(mid 342.611319 -218.983926)
				(end 342.621616 -218.980512)
			)
			(arc
				(start 342.621616 -218.980512)
				(mid 342.628155 -218.976789)
				(end 342.634062 -218.97213)
			)
			(xy 342.71077 -218.89593) (xy 342.71077 -218.895676)
			(arc
				(start 342.719152 -218.887548)
				(mid 342.730263 -218.871014)
				(end 342.734138 -218.85148)
			)
			(arc
				(start 342.734138 -218.671648)
				(mid 342.738039 -218.652125)
				(end 342.749124 -218.63558)
			)
			(arc
				(start 342.781128 -218.603576)
				(mid 342.797662 -218.592465)
				(end 342.817196 -218.58859)
			)
			(arc
				(start 342.96858 -218.58859)
				(mid 342.988103 -218.592491)
				(end 343.004648 -218.603576)
			)
			(arc
				(start 343.03716 -218.636088)
				(mid 343.048271 -218.652622)
				(end 343.052146 -218.672156)
			)
			(arc
				(start 343.052146 -218.849194)
				(mid 343.056047 -218.868717)
				(end 343.067132 -218.885262)
			)
			(xy 343.155016 -218.972892)
			(arc
				(start 343.159334 -218.976194)
				(mid 343.173013 -218.982808)
				(end 343.188036 -218.985084)
			)
			(arc
				(start 343.40038 -218.985084)
				(mid 343.410496 -218.984067)
				(end 343.420192 -218.98102)
			)
			(arc
				(start 343.420192 -218.98102)
				(mid 343.427567 -218.977041)
				(end 343.434162 -218.971876)
			)
			(xy 343.449656 -218.956636) (xy 343.510616 -218.89593) (xy 343.510616 -218.895676)
			(arc
				(start 343.519252 -218.887294)
				(mid 343.530363 -218.87076)
				(end 343.534238 -218.851226)
			)
			(arc
				(start 343.534238 -218.675458)
				(mid 343.538139 -218.655935)
				(end 343.549224 -218.63939)
			)
			(arc
				(start 343.590118 -218.598496)
				(mid 343.606652 -218.587385)
				(end 343.626186 -218.58351)
			)
			(arc
				(start 343.779348 -218.58351)
				(mid 343.790818 -218.582257)
				(end 343.8017 -218.57843)
			)
			(xy 343.801954 -218.578176) (xy 343.810082 -218.571318)
			(arc
				(start 343.812622 -218.56827)
				(mid 343.931087 -218.470258)
				(end 344.07983 -218.431364)
			)
			(arc
				(start 344.07983 -218.431364)
				(mid 344.242898 -218.463803)
				(end 344.373454 -218.566746)
			)
			(xy 344.376502 -218.570556) (xy 344.37701 -218.571318) (xy 344.385138 -218.578176) (xy 344.386154 -218.578684)
			(xy 344.405458 -218.588082) (xy 344.40622 -218.588844) (xy 344.408506 -218.58986)
			(arc
				(start 344.417396 -218.59367)
				(mid 344.42493 -218.595382)
				(end 344.432636 -218.595956)
			)
			(arc
				(start 344.559636 -218.595956)
				(mid 344.578993 -218.592123)
				(end 344.59545 -218.581224)
			)
			(xy 344.67165 -218.505024) (xy 344.675968 -218.500706)
			(arc
				(start 344.68054 -218.496134)
				(mid 344.6856 -218.490136)
				(end 344.689684 -218.483434)
			)
			(arc
				(start 344.689684 -218.483434)
				(mid 344.693839 -218.472207)
				(end 344.695272 -218.46032)
			)
			(arc
				(start 344.695272 -218.308936)
				(mid 344.69423 -218.298949)
				(end 344.691208 -218.289378)
			)
			(arc
				(start 344.67546 -218.268804)
				(mid 344.632769 -218.229847)
				(end 344.596974 -218.184476)
			)
			(arc
				(start 344.596974 -218.184476)
				(mid 344.56869 -218.132979)
				(end 344.549222 -218.077542)
			)
			(xy 344.54846 -218.073986) (xy 344.547444 -218.070684) (xy 344.544142 -218.065096) (xy 344.536014 -218.054428)
			(arc
				(start 344.419174 -217.937588)
				(mid 344.413176 -217.932528)
				(end 344.406474 -217.928444)
			)
			(arc
				(start 344.406474 -217.928444)
				(mid 344.395247 -217.924289)
				(end 344.38336 -217.922856)
			)
			(arc
				(start 344.375994 -217.922856)
				(mid 344.365878 -217.921839)
				(end 344.356182 -217.918792)
			)
			(xy 344.347038 -217.914982) (xy 344.314272 -217.882216)
			(arc
				(start 344.22715 -217.795348)
				(mid 344.219439 -217.789063)
				(end 344.21064 -217.784426)
			)
			(arc
				(start 344.21064 -217.784426)
				(mid 344.201174 -217.781577)
				(end 344.191336 -217.780616)
			)
			(arc
				(start 343.996518 -217.780616)
				(mid 343.977131 -217.784566)
				(end 343.960704 -217.795602)
			)
			(xy 343.873836 -217.882216)
			(arc
				(start 343.847928 -217.908124)
				(mid 343.840435 -217.914218)
				(end 343.831926 -217.918792)
			)
			(xy 343.822528 -217.922856)
			(arc
				(start 343.576148 -217.922856)
				(mid 343.566032 -217.921839)
				(end 343.556336 -217.918792)
			)
			(xy 343.547192 -217.914982) (xy 343.514426 -217.882216)
			(arc
				(start 343.427304 -217.795348)
				(mid 343.419593 -217.789063)
				(end 343.410794 -217.784426)
			)
			(arc
				(start 343.410794 -217.784426)
				(mid 343.401328 -217.781577)
				(end 343.39149 -217.780616)
			)
			(arc
				(start 343.196672 -217.780616)
				(mid 343.177285 -217.784566)
				(end 343.160858 -217.795602)
			)
			(xy 343.07399 -217.882216)
			(arc
				(start 343.048082 -217.908124)
				(mid 343.040589 -217.914218)
				(end 343.03208 -217.918792)
			)
			(xy 343.022682 -217.922856)
			(arc
				(start 341.976202 -217.922856)
				(mid 341.966086 -217.921839)
				(end 341.95639 -217.918792)
			)
			(xy 341.947246 -217.914982) (xy 341.91448 -217.882216)
			(arc
				(start 341.897208 -217.865198)
				(mid 341.88088 -217.854321)
				(end 341.861648 -217.850466)
			)
			(arc
				(start 341.526876 -217.850466)
				(mid 341.507353 -217.854367)
				(end 341.490808 -217.865452)
			)
			(arc
				(start 341.448136 -217.908124)
				(mid 341.440643 -217.914218)
				(end 341.432134 -217.918792)
			)
			(xy 341.422736 -217.922856)
			(arc
				(start 341.176356 -217.922856)
				(mid 341.16624 -217.921839)
				(end 341.156544 -217.918792)
			)
			(xy 341.1474 -217.914982)
			(arc
				(start 341.107776 -217.875358)
				(mid 341.091242 -217.864247)
				(end 341.071708 -217.860372)
			)
			(arc
				(start 340.71687 -217.860372)
				(mid 340.697347 -217.864273)
				(end 340.680802 -217.875358)
			)
			(arc
				(start 340.648036 -217.908124)
				(mid 340.640543 -217.914218)
				(end 340.632034 -217.918792)
			)
			(xy 340.622636 -217.922856)
			(arc
				(start 340.549992 -217.922856)
				(mid 340.532695 -217.925983)
				(end 340.51748 -217.934794)
			)
			(arc
				(start 340.46414 -217.983562)
				(mid 340.453778 -217.99809)
				(end 340.449154 -218.015312)
			)
			(xy 340.449154 -218.01709)
			(arc
				(start 340.44763 -218.028774)
				(mid 340.441036 -218.066835)
				(end 340.430358 -218.103958)
			)
			(arc
				(start 340.430358 -218.103958)
				(mid 340.377806 -218.202555)
				(end 340.297262 -218.27998)
			)
			(xy 340.277958 -218.319604) (xy 340.277958 -218.454224) (xy 340.278212 -218.459558)
			(arc
				(start 340.279736 -218.46667)
				(mid 340.282508 -218.474829)
				(end 340.286594 -218.482418)
			)
			(xy 340.29269 -218.490038) (xy 340.297008 -218.494356)
			(arc
				(start 340.30031 -218.496642)
				(mid 340.339516 -218.528938)
				(end 340.373716 -218.566492)
			)
			(xy 340.37397 -218.567) (xy 340.376764 -218.570302) (xy 340.377526 -218.571318) (xy 340.385654 -218.578176)
			(xy 340.387432 -218.578938) (xy 340.405974 -218.588082) (xy 340.406482 -218.58859) (xy 340.410038 -218.590368)
			(xy 340.412578 -218.591638) (xy 340.41334 -218.591892)
			(arc
				(start 340.414864 -218.5924)
				(mid 340.423846 -218.595)
				(end 340.433152 -218.595956)
			)
			(arc
				(start 340.555072 -218.595956)
				(mid 340.564387 -218.595047)
				(end 340.57336 -218.5924)
			)
			(xy 340.60257 -218.578176) (xy 340.610698 -218.571318) (xy 340.611206 -218.570556)
			(arc
				(start 340.614254 -218.566746)
				(mid 340.77547 -218.451381)
				(end 340.97341 -218.44)
			)
			(arc
				(start 340.97341 -218.44)
				(mid 341.085322 -218.486721)
				(end 341.175086 -218.56827)
			)
			(xy 341.177626 -218.571318) (xy 341.185754 -218.578176) (xy 341.209884 -218.590368) (xy 341.211916 -218.591384)
			(xy 341.213186 -218.591892) (xy 341.215472 -218.592908) (xy 341.227918 -218.595956) (xy 341.38235 -218.595956)
			(xy 341.393526 -218.613228) (xy 341.396066 -218.617292) (xy 341.396828 -218.618562) (xy 341.397336 -218.619324)
			(xy 341.43315 -218.675458) (xy 341.43442 -218.67749) (xy 341.435182 -218.67876) (xy 341.441024 -218.687904)
			(arc
				(start 341.441024 -218.838526)
				(mid 341.444151 -218.855823)
				(end 341.452962 -218.871038)
			)
			(xy 341.464138 -218.882468) (xy 341.465154 -218.883484) (xy 341.554816 -218.972892)
			(arc
				(start 341.559134 -218.976194)
				(mid 341.572813 -218.982808)
				(end 341.587836 -218.985084)
			)
		)
		(stroke
			(width 0)
			(type solid)
		)
		(fill yes)
		(layer "B.Cu")
		(net "P3V3_VCC_FPGA_CORE")
	)
	(gr_poly
		(pts
			(xy 243.958872 -77.939138) (xy 247.256808 -74.641202) (xy 247.2563 -74.624438) (xy 247.2563 -74.62393)
			(xy 247.256804 -74.596692) (xy 247.264592 -74.542774) (xy 247.279971 -74.490512) (xy 247.302627 -74.440969)
			(xy 247.332101 -74.395153) (xy 247.367792 -74.353996) (xy 247.408976 -74.318334) (xy 247.454813 -74.288894)
			(xy 247.504372 -74.266273) (xy 247.556645 -74.250933) (xy 247.610569 -74.243184) (xy 247.637808 -74.242676)
			(xy 247.666304 -74.243204) (xy 247.722663 -74.251672) (xy 247.777139 -74.268419) (xy 247.828523 -74.293073)
			(xy 247.875673 -74.325087) (xy 247.917545 -74.36375) (xy 247.93575 -74.385678) (xy 247.94338 -74.394195)
			(xy 247.963957 -74.404101) (xy 247.975374 -74.404728) (xy 255.175258 -74.404728) (xy 255.183761 -74.404366)
			(xy 255.199804 -74.398714) (xy 255.213111 -74.388121) (xy 255.21793 -74.381106) (xy 255.233036 -74.358252)
			(xy 255.268755 -74.316715) (xy 255.310045 -74.280711) (xy 255.356057 -74.250978) (xy 255.405846 -74.228127)
			(xy 255.45839 -74.212628) (xy 255.512611 -74.204798) (xy 255.540002 -74.204322) (xy 255.566238 -74.20476)
			(xy 255.618215 -74.211957) (xy 255.668713 -74.226216) (xy 255.716778 -74.247267) (xy 255.761501 -74.274712)
			(xy 255.802037 -74.308032) (xy 255.820164 -74.327004) (xy 255.821688 -74.328528) (xy 255.8291 -74.335212)
			(xy 255.847533 -74.342809) (xy 255.867471 -74.342809) (xy 255.885904 -74.335212) (xy 255.893316 -74.328528)
			(xy 255.89484 -74.327004) (xy 255.912956 -74.308022) (xy 255.953497 -74.274709) (xy 255.998224 -74.24727)
			(xy 256.046291 -74.226225) (xy 256.096789 -74.211969) (xy 256.148766 -74.204774) (xy 256.175002 -74.204322)
			(xy 256.20002 -74.204717) (xy 256.249627 -74.211264) (xy 256.29795 -74.224245) (xy 256.34416 -74.243437)
			(xy 256.36601 -74.25563) (xy 256.366264 -74.255376) (xy 256.394539 -74.227897) (xy 256.456198 -74.178749)
			(xy 256.522968 -74.136809) (xy 256.594013 -74.102604) (xy 256.668438 -74.076564) (xy 256.74531 -74.059016)
			(xy 256.823663 -74.050181) (xy 256.863088 -74.049636) (xy 259.311902 -74.049636) (xy 259.320603 -74.049286)
			(xy 259.337006 -74.04347) (xy 259.350522 -74.032508) (xy 259.355336 -74.025252) (xy 259.400548 -73.95083)
			(xy 259.404687 -73.943283) (xy 259.408169 -73.926437) (xy 259.405899 -73.909386) (xy 259.402326 -73.901554)
			(xy 259.402326 -73.9013) (xy 259.388967 -73.874127) (xy 259.370068 -73.816606) (xy 259.360495 -73.756821)
			(xy 259.359908 -73.726548) (xy 259.360394 -73.699297) (xy 259.36815 -73.645349) (xy 259.383505 -73.593054)
			(xy 259.406147 -73.543477) (xy 259.435613 -73.497627) (xy 259.471304 -73.456436) (xy 259.512495 -73.420745)
			(xy 259.558345 -73.391279) (xy 259.607922 -73.368637) (xy 259.660217 -73.353282) (xy 259.714165 -73.345526)
			(xy 259.768667 -73.345526) (xy 259.822615 -73.353282) (xy 259.87491 -73.368637) (xy 259.924487 -73.391279)
			(xy 259.970337 -73.420745) (xy 260.011528 -73.456436) (xy 260.047219 -73.497627) (xy 260.076685 -73.543477)
			(xy 260.099327 -73.593054) (xy 260.114682 -73.645349) (xy 260.122438 -73.699297) (xy 260.122924 -73.726548)
			(xy 260.122346 -73.756822) (xy 260.11278 -73.816611) (xy 260.093882 -73.874135) (xy 260.080506 -73.9013)
			(xy 260.080506 -73.901554) (xy 260.076881 -73.909371) (xy 260.07458 -73.926437) (xy 260.078107 -73.943293)
			(xy 260.082284 -73.95083) (xy 260.127496 -74.025252) (xy 260.132321 -74.032498) (xy 260.145828 -74.043463)
			(xy 260.162231 -74.049259) (xy 260.17093 -74.049636) (xy 260.926834 -74.049636) (xy 260.9369 -74.049205)
			(xy 260.95549 -74.041475) (xy 260.962902 -74.03465) (xy 261.017004 -73.980548) (xy 261.023691 -73.973134)
			(xy 261.031295 -73.954696) (xy 261.031304 -73.934752) (xy 261.023718 -73.916306) (xy 261.017004 -73.90892)
			(xy 261.008114 -73.90003) (xy 260.985 -73.892664) (xy 260.973062 -73.894442) (xy 260.958114 -73.89669)
			(xy 260.927979 -73.899106) (xy 260.912864 -73.899268) (xy 260.885617 -73.898779) (xy 260.831679 -73.89102)
			(xy 260.779394 -73.875663) (xy 260.729827 -73.853022) (xy 260.683986 -73.823558) (xy 260.642804 -73.78787)
			(xy 260.60712 -73.746685) (xy 260.577661 -73.700841) (xy 260.555025 -73.651272) (xy 260.539673 -73.598986)
			(xy 260.531918 -73.545047) (xy 260.531918 -73.490553) (xy 260.539673 -73.436614) (xy 260.555025 -73.384328)
			(xy 260.577661 -73.334759) (xy 260.60712 -73.288915) (xy 260.642804 -73.24773) (xy 260.683986 -73.212042)
			(xy 260.729827 -73.182578) (xy 260.779394 -73.159937) (xy 260.831679 -73.14458) (xy 260.885617 -73.136821)
			(xy 260.912864 -73.136252) (xy 260.940601 -73.136754) (xy 260.995489 -73.144794) (xy 261.048634 -73.160697)
			(xy 261.098917 -73.184125) (xy 261.145279 -73.214587) (xy 261.186742 -73.25144) (xy 261.222433 -73.293908)
			(xy 261.251599 -73.341095) (xy 261.273627 -73.392008) (xy 261.288052 -73.445573) (xy 261.291832 -73.473056)
			(xy 261.293356 -73.48728) (xy 261.311644 -73.51014) (xy 261.333488 -73.51776) (xy 261.322008 -73.496396)
			(xy 261.303949 -73.451384) (xy 261.291746 -73.404444) (xy 261.285596 -73.356336) (xy 261.285228 -73.332086)
			(xy 261.285692 -73.304835) (xy 261.293451 -73.250887) (xy 261.308809 -73.198593) (xy 261.331453 -73.149017)
			(xy 261.360921 -73.103168) (xy 261.396616 -73.06198) (xy 261.437808 -73.026291) (xy 261.483661 -72.996829)
			(xy 261.53324 -72.974191) (xy 261.585536 -72.95884) (xy 261.639485 -72.951089) (xy 261.666736 -72.950578)
			(xy 261.693732 -72.951048) (xy 261.747185 -72.958661) (xy 261.799032 -72.97373) (xy 261.848237 -72.995955)
			(xy 261.893821 -73.024891) (xy 261.934872 -73.059962) (xy 261.970571 -73.100468) (xy 261.98576 -73.12279)
			(xy 261.991521 -73.130741) (xy 262.007668 -73.141883) (xy 262.026821 -73.146125) (xy 262.03656 -73.144888)
			(xy 262.065366 -73.140366) (xy 262.123481 -73.135536) (xy 262.152638 -73.135236) (xy 263.051798 -73.135236)
			(xy 263.061846 -73.134813) (xy 263.080405 -73.127109) (xy 263.094594 -73.112879) (xy 263.098788 -73.10374)
			(xy 263.102132 -73.094348) (xy 263.102128 -73.074432) (xy 263.094554 -73.056013) (xy 263.087866 -73.048622)
			(xy 262.913368 -72.87387) (xy 262.905971 -72.867021) (xy 262.887372 -72.859287) (xy 262.8773 -72.858884)
			(xy 259.31495 -72.858884) (xy 259.290159 -72.858426) (xy 259.241188 -72.85067) (xy 259.194035 -72.835343)
			(xy 259.149863 -72.812823) (xy 259.109762 -72.783664) (xy 259.091938 -72.766428) (xy 256.90068 -70.57517)
			(xy 256.893284 -70.568319) (xy 256.874685 -70.560581) (xy 256.864612 -70.560184) (xy 248.5898 -70.560184)
			(xy 248.579729 -70.560607) (xy 248.561123 -70.568319) (xy 248.553732 -70.57517) (xy 247.54307 -71.585832)
			(xy 251.319266 -71.585832) (xy 251.319266 -71.525896) (xy 251.327089 -71.466474) (xy 251.342602 -71.408581)
			(xy 251.365538 -71.353208) (xy 251.395505 -71.301302) (xy 251.431992 -71.253752) (xy 251.474372 -71.211372)
			(xy 251.521922 -71.174885) (xy 251.573828 -71.144918) (xy 251.629201 -71.121982) (xy 251.687094 -71.106469)
			(xy 251.746516 -71.098646) (xy 251.806452 -71.098646) (xy 251.865874 -71.106469) (xy 251.923767 -71.121982)
			(xy 251.97914 -71.144918) (xy 252.031046 -71.174885) (xy 252.078596 -71.211372) (xy 252.120976 -71.253752)
			(xy 252.157463 -71.301302) (xy 252.18743 -71.353208) (xy 252.210366 -71.408581) (xy 252.225879 -71.466474)
			(xy 252.233702 -71.525896) (xy 252.234192 -71.555864) (xy 252.233702 -71.585832) (xy 252.225879 -71.645254)
			(xy 252.223697 -71.653396) (xy 252.82828 -71.653396) (xy 252.82828 -71.59346) (xy 252.836103 -71.534038)
			(xy 252.851616 -71.476145) (xy 252.874552 -71.420772) (xy 252.904519 -71.368866) (xy 252.941006 -71.321316)
			(xy 252.983386 -71.278936) (xy 253.030936 -71.242449) (xy 253.082842 -71.212482) (xy 253.138215 -71.189546)
			(xy 253.196108 -71.174033) (xy 253.25553 -71.16621) (xy 253.315466 -71.16621) (xy 253.374888 -71.174033)
			(xy 253.432781 -71.189546) (xy 253.488154 -71.212482) (xy 253.54006 -71.242449) (xy 253.58761 -71.278936)
			(xy 253.62999 -71.321316) (xy 253.666477 -71.368866) (xy 253.696444 -71.420772) (xy 253.71938 -71.476145)
			(xy 253.734893 -71.534038) (xy 253.742716 -71.59346) (xy 253.743206 -71.623428) (xy 253.742716 -71.653396)
			(xy 253.734893 -71.712818) (xy 253.71938 -71.770711) (xy 253.696444 -71.826084) (xy 253.666477 -71.87799)
			(xy 253.62999 -71.92554) (xy 253.58761 -71.96792) (xy 253.54006 -72.004407) (xy 253.488154 -72.034374)
			(xy 253.432781 -72.05731) (xy 253.374888 -72.072823) (xy 253.315466 -72.080646) (xy 253.25553 -72.080646)
			(xy 253.196108 -72.072823) (xy 253.138215 -72.05731) (xy 253.082842 -72.034374) (xy 253.030936 -72.004407)
			(xy 252.983386 -71.96792) (xy 252.941006 -71.92554) (xy 252.904519 -71.87799) (xy 252.874552 -71.826084)
			(xy 252.851616 -71.770711) (xy 252.836103 -71.712818) (xy 252.82828 -71.653396) (xy 252.223697 -71.653396)
			(xy 252.210366 -71.703147) (xy 252.18743 -71.75852) (xy 252.157463 -71.810426) (xy 252.120976 -71.857976)
			(xy 252.078596 -71.900356) (xy 252.031046 -71.936843) (xy 251.97914 -71.96681) (xy 251.923767 -71.989746)
			(xy 251.865874 -72.005259) (xy 251.806452 -72.013082) (xy 251.746516 -72.013082) (xy 251.687094 -72.005259)
			(xy 251.629201 -71.989746) (xy 251.573828 -71.96681) (xy 251.521922 -71.936843) (xy 251.474372 -71.900356)
			(xy 251.431992 -71.857976) (xy 251.395505 -71.810426) (xy 251.365538 -71.75852) (xy 251.342602 -71.703147)
			(xy 251.327089 -71.645254) (xy 251.319266 -71.585832) (xy 247.54307 -71.585832) (xy 245.21795 -73.910952)
			(xy 245.211106 -73.918351) (xy 245.203383 -73.93695) (xy 245.202964 -73.94702) (xy 245.202964 -75.1586)
			(xy 245.202411 -75.198025) (xy 245.193584 -75.276378) (xy 245.176041 -75.353251) (xy 245.150002 -75.427677)
			(xy 245.115794 -75.49872) (xy 245.073849 -75.565486) (xy 245.024692 -75.627138) (xy 244.997224 -75.655424)
			(xy 243.898166 -76.754482) (xy 243.891325 -76.761882) (xy 243.88361 -76.780481) (xy 243.88318 -76.79055)
			(xy 243.88318 -77.892148) (xy 243.883613 -77.902189) (xy 243.891328 -77.920732) (xy 243.905561 -77.934901)
			(xy 243.914676 -77.939138) (xy 243.9289 -77.945234)
		)
		(stroke
			(width 0)
			(type solid)
		)
		(fill yes)
		(layer "B.Cu")
		(net "GND")
	)
	(gr_poly
		(pts
			(xy 108.254546 -113.518188) (xy 108.25988 -113.512854) (xy 109.765338 -113.512854) (xy 109.775404 -113.512423)
			(xy 109.793994 -113.504693) (xy 109.801406 -113.497868) (xy 110.834424 -112.46485) (xy 110.841282 -112.43818)
			(xy 110.837472 -112.424718) (xy 110.828954 -112.393465) (xy 110.819778 -112.329343) (xy 110.819184 -112.296956)
			(xy 110.819668 -112.266688) (xy 110.827639 -112.206678) (xy 110.84345 -112.148242) (xy 110.866824 -112.0924)
			(xy 110.897353 -112.040125) (xy 110.934506 -111.99233) (xy 110.977634 -111.949848) (xy 111.025984 -111.913421)
			(xy 111.078714 -111.883684) (xy 111.134903 -111.861155) (xy 111.164116 -111.853218) (xy 111.181388 -111.8489)
			(xy 111.20247 -111.821722) (xy 111.20247 -111.001556) (xy 111.176816 -110.9726) (xy 111.157512 -110.970314)
			(xy 111.127477 -110.966346) (xy 111.068739 -110.951504) (xy 111.012472 -110.929042) (xy 110.959662 -110.899352)
			(xy 110.91123 -110.862954) (xy 110.868025 -110.820483) (xy 110.830801 -110.772683) (xy 110.800209 -110.720389)
			(xy 110.776785 -110.664517) (xy 110.760938 -110.606042) (xy 110.752945 -110.545987) (xy 110.752945 -110.485403)
			(xy 110.76094 -110.425348) (xy 110.776788 -110.366873) (xy 110.800214 -110.311001) (xy 110.830807 -110.258708)
			(xy 110.868032 -110.210909) (xy 110.911238 -110.16844) (xy 110.95967 -110.132042) (xy 111.012482 -110.102354)
			(xy 111.068749 -110.079893) (xy 111.127487 -110.065052) (xy 111.157512 -110.060994) (xy 111.176816 -110.058708)
			(xy 111.20247 -110.029752) (xy 111.20247 -96.18345) (xy 111.202037 -96.173384) (xy 111.194307 -96.154796)
			(xy 111.187484 -96.147382) (xy 110.199424 -95.159322) (xy 110.192022 -95.152485) (xy 110.173424 -95.144775)
			(xy 110.163356 -95.144336) (xy 98.380296 -95.144336) (xy 98.370227 -95.144761) (xy 98.351627 -95.15248)
			(xy 98.344228 -95.159322) (xy 98.048572 -95.454978) (xy 98.04173 -95.462377) (xy 98.034013 -95.480976)
			(xy 98.033586 -95.491046) (xy 98.033586 -95.932853) (xy 99.120152 -95.932853) (xy 99.120152 -95.878347)
			(xy 99.127909 -95.824396) (xy 99.143265 -95.772098) (xy 99.165907 -95.722517) (xy 99.195376 -95.676664)
			(xy 99.231069 -95.635471) (xy 99.272262 -95.599777) (xy 99.318115 -95.570308) (xy 99.367696 -95.547666)
			(xy 99.419994 -95.532309) (xy 99.473945 -95.524552) (xy 99.501198 -95.524066) (xy 99.530091 -95.524598)
			(xy 99.587219 -95.533284) (xy 99.642384 -95.550489) (xy 99.694322 -95.575818) (xy 99.741845 -95.608691)
			(xy 99.783865 -95.648357) (xy 99.819422 -95.693907) (xy 99.8477 -95.7443) (xy 99.868054 -95.798382)
			(xy 99.880017 -95.854915) (xy 99.882198 -95.88373) (xy 99.882706 -95.895414) (xy 99.893882 -95.91548)
			(xy 99.977448 -95.97517) (xy 100.000054 -95.97898) (xy 100.01123 -95.975678) (xy 100.041832 -95.96757)
			(xy 100.104544 -95.958904) (xy 100.136198 -95.958406) (xy 100.166166 -95.95888) (xy 100.225588 -95.966703)
			(xy 100.283481 -95.982215) (xy 100.338854 -96.005151) (xy 100.39076 -96.035118) (xy 100.43831 -96.071604)
			(xy 100.480691 -96.113984) (xy 100.517178 -96.161533) (xy 100.547146 -96.213439) (xy 100.570083 -96.268811)
			(xy 100.585596 -96.326704) (xy 100.59342 -96.386126) (xy 100.59342 -96.446062) (xy 100.585598 -96.505484)
			(xy 100.570087 -96.563377) (xy 100.547151 -96.618751) (xy 100.517184 -96.670657) (xy 100.480699 -96.718207)
			(xy 100.438319 -96.760588) (xy 100.39077 -96.797075) (xy 100.338865 -96.827044) (xy 100.283493 -96.849981)
			(xy 100.2256 -96.865495) (xy 100.166178 -96.873319) (xy 100.106242 -96.873321) (xy 100.04682 -96.865499)
			(xy 99.988926 -96.849988) (xy 99.933553 -96.827053) (xy 99.881647 -96.797087) (xy 99.834096 -96.760602)
			(xy 99.791714 -96.718222) (xy 99.755227 -96.670673) (xy 99.725258 -96.618769) (xy 99.70232 -96.563396)
			(xy 99.686806 -96.505504) (xy 99.678981 -96.446082) (xy 99.67849 -96.416114) (xy 99.679252 -96.388682)
			(xy 99.680014 -96.376998) (xy 99.671378 -96.355662) (xy 99.595178 -96.286828) (xy 99.573334 -96.280478)
			(xy 99.56165 -96.282256) (xy 99.546639 -96.284515) (xy 99.516377 -96.286934) (xy 99.501198 -96.287082)
			(xy 99.473945 -96.286648) (xy 99.419994 -96.278891) (xy 99.367696 -96.263534) (xy 99.318115 -96.240892)
			(xy 99.272262 -96.211423) (xy 99.231069 -96.175729) (xy 99.195376 -96.134536) (xy 99.165907 -96.088683)
			(xy 99.143265 -96.039102) (xy 99.127909 -95.986804) (xy 99.120152 -95.932853) (xy 98.033586 -95.932853)
			(xy 98.033586 -96.212152) (xy 98.034094 -96.215454) (xy 98.035778 -96.229809) (xy 98.037556 -96.258659)
			(xy 98.03765 -96.273112) (xy 98.037561 -96.287565) (xy 98.03578 -96.316415) (xy 98.034094 -96.33077)
			(xy 98.033586 -96.334072) (xy 98.033586 -99.095052) (xy 98.034018 -99.105118) (xy 98.041744 -99.12371)
			(xy 98.048572 -99.13112) (xy 98.88474 -99.967288) (xy 98.89214 -99.974129) (xy 98.910738 -99.981851)
			(xy 98.920808 -99.982274) (xy 99.215194 -99.982274) (xy 99.225181 -99.981737) (xy 99.243613 -99.974022)
			(xy 99.251008 -99.967288) (xy 99.38131 -99.836986) (xy 99.388705 -99.830132) (xy 99.407304 -99.822387)
			(xy 99.417378 -99.822) (xy 106.65714 -99.822) (xy 106.667207 -99.822431) (xy 106.685801 -99.830155)
			(xy 106.693208 -99.836986) (xy 107.170982 -100.31476) (xy 107.177821 -100.322161) (xy 107.185536 -100.340759)
			(xy 107.185968 -100.350828) (xy 107.185968 -103.194612) (xy 107.185542 -103.204681) (xy 107.177821 -103.223279)
			(xy 107.170982 -103.23068) (xy 106.31678 -104.084628) (xy 106.310009 -104.092055) (xy 106.302429 -104.110652)
			(xy 106.302048 -104.120696) (xy 106.302048 -108.53674) (xy 106.302531 -108.546703) (xy 106.310117 -108.56513)
			(xy 106.31678 -108.572554) (xy 106.925872 -109.181646) (xy 106.94289 -109.19841) (xy 106.949736 -109.205809)
			(xy 106.957468 -109.224407) (xy 106.957876 -109.234478) (xy 106.957876 -109.502448) (xy 109.338872 -109.502448)
			(xy 109.339362 -109.47248) (xy 109.347185 -109.413058) (xy 109.362698 -109.355165) (xy 109.385634 -109.299792)
			(xy 109.415601 -109.247886) (xy 109.452088 -109.200336) (xy 109.494468 -109.157956) (xy 109.542018 -109.121469)
			(xy 109.593924 -109.091502) (xy 109.649297 -109.068566) (xy 109.70719 -109.053053) (xy 109.766612 -109.04523)
			(xy 109.826548 -109.04523) (xy 109.88597 -109.053053) (xy 109.943863 -109.068566) (xy 109.999236 -109.091502)
			(xy 110.051142 -109.121469) (xy 110.098692 -109.157956) (xy 110.141072 -109.200336) (xy 110.177559 -109.247886)
			(xy 110.207526 -109.299792) (xy 110.230462 -109.355165) (xy 110.245975 -109.413058) (xy 110.253798 -109.47248)
			(xy 110.254288 -109.502448) (xy 110.253869 -109.530203) (xy 110.247127 -109.585302) (xy 110.233783 -109.639185)
			(xy 110.214032 -109.691062) (xy 110.201456 -109.715808) (xy 110.196122 -109.726222) (xy 110.195106 -109.749082)
			(xy 110.236254 -109.843316) (xy 110.25378 -109.858302) (xy 110.264956 -109.86135) (xy 110.291608 -109.869033)
			(xy 110.342525 -109.89103) (xy 110.389718 -109.92017) (xy 110.432193 -109.955839) (xy 110.469053 -109.997284)
			(xy 110.499522 -110.043631) (xy 110.522956 -110.093903) (xy 110.538861 -110.147038) (xy 110.546902 -110.201918)
			(xy 110.547404 -110.22965) (xy 110.546865 -110.257812) (xy 110.53859 -110.313524) (xy 110.522213 -110.367413)
			(xy 110.498091 -110.418309) (xy 110.466747 -110.465105) (xy 110.428862 -110.506783) (xy 110.385261 -110.542438)
			(xy 110.336892 -110.571293) (xy 110.284805 -110.592723) (xy 110.25759 -110.599982) (xy 110.248192 -110.602268)
			(xy 110.232444 -110.613698) (xy 110.18393 -110.688374) (xy 110.180374 -110.707424) (xy 110.181898 -110.716822)
			(xy 110.184849 -110.733878) (xy 110.188029 -110.768348) (xy 110.188248 -110.785656) (xy 110.187762 -110.812907)
			(xy 110.180006 -110.866855) (xy 110.164651 -110.91915) (xy 110.142009 -110.968727) (xy 110.112543 -111.014577)
			(xy 110.076852 -111.055768) (xy 110.035661 -111.091459) (xy 109.989811 -111.120925) (xy 109.940234 -111.143567)
			(xy 109.887939 -111.158922) (xy 109.833991 -111.166678) (xy 109.779489 -111.166678) (xy 109.725541 -111.158922)
			(xy 109.673246 -111.143567) (xy 109.623669 -111.120925) (xy 109.577819 -111.091459) (xy 109.536628 -111.055768)
			(xy 109.500937 -111.014577) (xy 109.471471 -110.968727) (xy 109.448829 -110.91915) (xy 109.433474 -110.866855)
			(xy 109.425718 -110.812907) (xy 109.425232 -110.785656) (xy 109.42575 -110.757493) (xy 109.434024 -110.701779)
			(xy 109.450402 -110.647887) (xy 109.474526 -110.59699) (xy 109.505873 -110.550193) (xy 109.543761 -110.508515)
			(xy 109.587365 -110.472861) (xy 109.635739 -110.444007) (xy 109.68783 -110.422581) (xy 109.715046 -110.415324)
			(xy 109.724444 -110.413038) (xy 109.740192 -110.401608) (xy 109.788706 -110.326932) (xy 109.792262 -110.307882)
			(xy 109.790738 -110.298484) (xy 109.787789 -110.281428) (xy 109.784607 -110.246958) (xy 109.784388 -110.22965)
			(xy 109.784763 -110.206213) (xy 109.79053 -110.159695) (xy 109.801936 -110.11423) (xy 109.810042 -110.092236)
			(xy 109.814106 -110.081314) (xy 109.812328 -110.058708) (xy 109.760512 -109.969808) (xy 109.741462 -109.957108)
			(xy 109.730032 -109.95533) (xy 109.700757 -109.950564) (xy 109.643684 -109.934421) (xy 109.589173 -109.911043)
			(xy 109.538137 -109.88082) (xy 109.491432 -109.84426) (xy 109.44984 -109.801974) (xy 109.414057 -109.754671)
			(xy 109.384682 -109.703143) (xy 109.362208 -109.648253) (xy 109.347011 -109.59092) (xy 109.339345 -109.532104)
			(xy 109.338872 -109.502448) (xy 106.957876 -109.502448) (xy 106.957876 -111.815622) (xy 109.382542 -111.815622)
			(xy 109.382542 -111.755686) (xy 109.390365 -111.696264) (xy 109.405878 -111.638371) (xy 109.428814 -111.582998)
			(xy 109.458781 -111.531092) (xy 109.495268 -111.483542) (xy 109.537648 -111.441162) (xy 109.585198 -111.404675)
			(xy 109.637104 -111.374708) (xy 109.692477 -111.351772) (xy 109.75037 -111.336259) (xy 109.809792 -111.328436)
			(xy 109.869728 -111.328436) (xy 109.92915 -111.336259) (xy 109.987043 -111.351772) (xy 110.042416 -111.374708)
			(xy 110.094322 -111.404675) (xy 110.141872 -111.441162) (xy 110.184252 -111.483542) (xy 110.220739 -111.531092)
			(xy 110.250706 -111.582998) (xy 110.273642 -111.638371) (xy 110.289155 -111.696264) (xy 110.296978 -111.755686)
			(xy 110.297468 -111.785654) (xy 110.296978 -111.815622) (xy 110.289155 -111.875044) (xy 110.273642 -111.932937)
			(xy 110.250706 -111.98831) (xy 110.220739 -112.040216) (xy 110.184252 -112.087766) (xy 110.141872 -112.130146)
			(xy 110.094322 -112.166633) (xy 110.042416 -112.1966) (xy 109.987043 -112.219536) (xy 109.92915 -112.235049)
			(xy 109.869728 -112.242872) (xy 109.809792 -112.242872) (xy 109.75037 -112.235049) (xy 109.692477 -112.219536)
			(xy 109.637104 -112.1966) (xy 109.585198 -112.166633) (xy 109.537648 -112.130146) (xy 109.495268 -112.087766)
			(xy 109.458781 -112.040216) (xy 109.428814 -111.98831) (xy 109.405878 -111.932937) (xy 109.390365 -111.875044)
			(xy 109.382542 -111.815622) (xy 106.957876 -111.815622) (xy 106.957876 -113.504218) (xy 106.96448 -113.510822)
			(xy 106.971879 -113.517664) (xy 106.990478 -113.525382) (xy 107.000548 -113.525808) (xy 108.236004 -113.525808)
		)
		(stroke
			(width 0)
			(type solid)
		)
		(fill yes)
		(layer "B.Cu")
		(net "P12V_AUX")
	)
	(gr_poly
		(pts
			(xy 14.618462 -156.313124) (xy 14.628528 -156.31269) (xy 14.647118 -156.304963) (xy 14.65453 -156.298138)
			(xy 14.758924 -156.193744) (xy 14.76577 -156.186346) (xy 14.773496 -156.167747) (xy 14.77391 -156.157676)
			(xy 14.77391 -148.696426) (xy 14.774347 -148.686362) (xy 14.782081 -148.667778) (xy 14.788896 -148.660358)
			(xy 15.214092 -148.235162) (xy 15.221487 -148.228308) (xy 15.240086 -148.22056) (xy 15.25016 -148.220176)
			(xy 15.887192 -148.220176) (xy 15.898525 -148.219578) (xy 15.918983 -148.209825) (xy 15.926562 -148.20138)
			(xy 15.983712 -148.131022) (xy 15.989046 -148.10867) (xy 15.986506 -148.097494) (xy 15.982572 -148.07779)
			(xy 15.978372 -148.037829) (xy 15.978124 -148.017738) (xy 15.97861 -147.990487) (xy 15.986366 -147.936539)
			(xy 16.001721 -147.884244) (xy 16.024363 -147.834667) (xy 16.053829 -147.788817) (xy 16.08952 -147.747626)
			(xy 16.130711 -147.711935) (xy 16.176561 -147.682469) (xy 16.226138 -147.659827) (xy 16.278433 -147.644472)
			(xy 16.332381 -147.636716) (xy 16.386883 -147.636716) (xy 16.440831 -147.644472) (xy 16.493126 -147.659827)
			(xy 16.542703 -147.682469) (xy 16.588553 -147.711935) (xy 16.629744 -147.747626) (xy 16.665435 -147.788817)
			(xy 16.694901 -147.834667) (xy 16.717543 -147.884244) (xy 16.732898 -147.936539) (xy 16.740654 -147.990487)
			(xy 16.74114 -148.017738) (xy 16.740894 -148.037829) (xy 16.736691 -148.07779) (xy 16.732758 -148.097494)
			(xy 16.730218 -148.10867) (xy 16.735552 -148.131022) (xy 16.792702 -148.20138) (xy 16.800319 -148.209779)
			(xy 16.820752 -148.21954) (xy 16.832072 -148.220176) (xy 22.4917 -148.220176) (xy 22.50177 -148.219752)
			(xy 22.520372 -148.212035) (xy 22.527768 -148.20519) (xy 22.690836 -148.042122) (xy 22.697677 -148.034722)
			(xy 22.705393 -148.016123) (xy 22.705822 -148.006054) (xy 22.705822 -146.714972) (xy 22.705394 -146.704904)
			(xy 22.697675 -146.686304) (xy 22.690836 -146.678904) (xy 22.328378 -146.316446) (xy 22.320981 -146.309598)
			(xy 22.302382 -146.301864) (xy 22.29231 -146.30146) (xy 20.822412 -146.30146) (xy 20.812342 -146.301038)
			(xy 20.793738 -146.293322) (xy 20.786344 -146.286474) (xy 18.923254 -144.423384) (xy 18.916404 -144.415987)
			(xy 18.908667 -144.397389) (xy 18.908268 -144.387316) (xy 18.908268 -141.441424) (xy 18.915634 -141.434058)
			(xy 18.915634 -140.074396) (xy 18.916059 -140.064327) (xy 18.923778 -140.045727) (xy 18.93062 -140.038328)
			(xy 19.348958 -139.61999) (xy 19.356355 -139.613143) (xy 19.374955 -139.605416) (xy 19.385026 -139.605004)
			(xy 20.18792 -139.605004) (xy 20.197989 -139.604577) (xy 20.216588 -139.596858) (xy 20.223988 -139.590018)
			(xy 20.448778 -139.365228) (xy 20.455615 -139.357827) (xy 20.463327 -139.339228) (xy 20.463764 -139.32916)
			(xy 20.463764 -136.35228) (xy 20.463336 -136.342212) (xy 20.455613 -136.323616) (xy 20.448778 -136.316212)
			(xy 20.288758 -136.156192) (xy 20.281357 -136.149353) (xy 20.262759 -136.141635) (xy 20.25269 -136.141206)
			(xy 13.473176 -136.141206) (xy 13.463108 -136.140779) (xy 13.444509 -136.133059) (xy 13.437108 -136.12622)
			(xy 12.957048 -135.64616) (xy 12.94965 -135.639315) (xy 12.931051 -135.63159) (xy 12.92098 -135.631174)
			(xy 12.546076 -135.631174) (xy 12.536007 -135.631601) (xy 12.517407 -135.639318) (xy 12.510008 -135.64616)
			(xy 12.440412 -135.715756) (xy 12.433573 -135.723157) (xy 12.425857 -135.741755) (xy 12.425426 -135.751824)
			(xy 12.425426 -137.848848) (xy 12.425858 -137.858914) (xy 12.433588 -137.877503) (xy 12.440412 -137.884916)
			(xy 12.463272 -137.907776) (xy 12.470673 -137.914614) (xy 12.489272 -137.922326) (xy 12.49934 -137.922762)
			(xy 12.798552 -137.922762) (xy 12.817094 -137.915142) (xy 12.822682 -137.909554) (xy 12.901168 -137.909554)
			(xy 12.911231 -137.909991) (xy 12.929813 -137.917729) (xy 12.937236 -137.92454) (xy 13.191998 -138.179302)
			(xy 13.198844 -138.1867) (xy 13.206579 -138.205298) (xy 13.206984 -138.21537) (xy 13.206984 -139.267692)
			(xy 13.20546 -139.267692) (xy 12.999974 -139.473178) (xy 12.992575 -139.480023) (xy 12.973977 -139.487751)
			(xy 12.963906 -139.488164) (xy 11.19632 -139.488164) (xy 11.186258 -139.488603) (xy 11.16768 -139.496345)
			(xy 11.160252 -139.50315) (xy 10.874756 -139.788646) (xy 10.867911 -139.796044) (xy 10.860184 -139.814643)
			(xy 10.85977 -139.824714) (xy 10.85977 -140.814806) (xy 10.855198 -140.819378) (xy 10.855198 -145.562903)
			(xy 15.978585 -145.562903) (xy 15.978585 -145.508397) (xy 15.986342 -145.454446) (xy 16.001698 -145.402148)
			(xy 16.024341 -145.352568) (xy 16.053809 -145.306714) (xy 16.089503 -145.265522) (xy 16.130696 -145.229828)
			(xy 16.176549 -145.20036) (xy 16.22613 -145.177718) (xy 16.278428 -145.162362) (xy 16.332379 -145.154605)
			(xy 16.359632 -145.154142) (xy 16.385972 -145.154626) (xy 16.438151 -145.161873) (xy 16.488839 -145.176224)
			(xy 16.537072 -145.197407) (xy 16.581935 -145.22502) (xy 16.622577 -145.258539) (xy 16.658224 -145.297326)
			(xy 16.673576 -145.318734) (xy 16.682302 -145.330535) (xy 16.705118 -145.348976) (xy 16.732238 -145.360165)
			(xy 16.76142 -145.363177) (xy 16.790253 -145.357764) (xy 16.816355 -145.344373) (xy 16.83757 -145.32411)
			(xy 16.84528 -145.311622) (xy 16.859992 -145.287097) (xy 16.895591 -145.242338) (xy 16.937471 -145.203394)
			(xy 16.984695 -145.171137) (xy 17.036204 -145.14629) (xy 17.090845 -145.129408) (xy 17.147393 -145.120871)
			(xy 17.175988 -145.12036) (xy 17.203239 -145.120886) (xy 17.257187 -145.128641) (xy 17.309482 -145.143995)
			(xy 17.359059 -145.166635) (xy 17.40491 -145.1961) (xy 17.446101 -145.231791) (xy 17.481793 -145.27298)
			(xy 17.511259 -145.31883) (xy 17.533901 -145.368407) (xy 17.549256 -145.420701) (xy 17.557013 -145.474649)
			(xy 17.557013 -145.529151) (xy 17.549256 -145.583099) (xy 17.533901 -145.635393) (xy 17.511259 -145.68497)
			(xy 17.481793 -145.73082) (xy 17.446101 -145.772009) (xy 17.40491 -145.8077) (xy 17.359059 -145.837165)
			(xy 17.309482 -145.859805) (xy 17.257187 -145.875159) (xy 17.203239 -145.882914) (xy 17.175988 -145.883376)
			(xy 17.149646 -145.882945) (xy 17.097465 -145.875688) (xy 17.046776 -145.861327) (xy 16.998543 -145.840135)
			(xy 16.953681 -145.812514) (xy 16.913041 -145.778989) (xy 16.877395 -145.740195) (xy 16.862044 -145.718784)
			(xy 16.853284 -145.707014) (xy 16.830471 -145.68859) (xy 16.803361 -145.67741) (xy 16.774192 -145.674399)
			(xy 16.74537 -145.679803) (xy 16.719273 -145.693177) (xy 16.698055 -145.713418) (xy 16.69034 -145.725896)
			(xy 16.675621 -145.750416) (xy 16.640022 -145.795174) (xy 16.598143 -145.834117) (xy 16.55092 -145.866375)
			(xy 16.499412 -145.891223) (xy 16.444773 -145.908106) (xy 16.388226 -145.916646) (xy 16.359632 -145.917158)
			(xy 16.332379 -145.916695) (xy 16.278428 -145.908938) (xy 16.22613 -145.893582) (xy 16.176549 -145.87094)
			(xy 16.130696 -145.841472) (xy 16.089503 -145.805778) (xy 16.053809 -145.764586) (xy 16.024341 -145.718732)
			(xy 16.001698 -145.669152) (xy 15.986342 -145.616854) (xy 15.978585 -145.562903) (xy 10.855198 -145.562903)
			(xy 10.855198 -147.18665) (xy 17.837402 -147.18665) (xy 17.841473 -147.131028) (xy 17.853599 -147.076591)
			(xy 17.873522 -147.0245) (xy 17.900818 -146.975865) (xy 17.934904 -146.931722) (xy 17.975053 -146.893013)
			(xy 18.020411 -146.860562) (xy 18.070011 -146.835061) (xy 18.122795 -146.817054) (xy 18.177638 -146.806924)
			(xy 18.233372 -146.804887) (xy 18.288809 -146.810987) (xy 18.342766 -146.825093) (xy 18.394095 -146.846905)
			(xy 18.441701 -146.875959) (xy 18.484569 -146.911634) (xy 18.51432 -146.944838) (xy 19.540964 -146.944838)
			(xy 19.540964 -146.884902) (xy 19.548787 -146.82548) (xy 19.5643 -146.767587) (xy 19.587236 -146.712214)
			(xy 19.617203 -146.660308) (xy 19.65369 -146.612758) (xy 19.69607 -146.570378) (xy 19.74362 -146.533891)
			(xy 19.795526 -146.503924) (xy 19.850899 -146.480988) (xy 19.908792 -146.465475) (xy 19.968214 -146.457652)
			(xy 20.02815 -146.457652) (xy 20.087572 -146.465475) (xy 20.145465 -146.480988) (xy 20.200838 -146.503924)
			(xy 20.252744 -146.533891) (xy 20.300294 -146.570378) (xy 20.342674 -146.612758) (xy 20.379161 -146.660308)
			(xy 20.409128 -146.712214) (xy 20.432064 -146.767587) (xy 20.447577 -146.82548) (xy 20.4554 -146.884902)
			(xy 20.45589 -146.91487) (xy 20.4554 -146.944838) (xy 20.447577 -147.00426) (xy 20.432064 -147.062153)
			(xy 20.41953 -147.092412) (xy 20.919168 -147.092412) (xy 20.919168 -147.032476) (xy 20.926991 -146.973054)
			(xy 20.942504 -146.915161) (xy 20.96544 -146.859788) (xy 20.995407 -146.807882) (xy 21.031894 -146.760332)
			(xy 21.074274 -146.717952) (xy 21.121824 -146.681465) (xy 21.17373 -146.651498) (xy 21.229103 -146.628562)
			(xy 21.286996 -146.613049) (xy 21.346418 -146.605226) (xy 21.406354 -146.605226) (xy 21.465776 -146.613049)
			(xy 21.523669 -146.628562) (xy 21.579042 -146.651498) (xy 21.630948 -146.681465) (xy 21.678498 -146.717952)
			(xy 21.720878 -146.760332) (xy 21.757365 -146.807882) (xy 21.787332 -146.859788) (xy 21.810268 -146.915161)
			(xy 21.825781 -146.973054) (xy 21.833604 -147.032476) (xy 21.834094 -147.062444) (xy 21.833604 -147.092412)
			(xy 21.825781 -147.151834) (xy 21.810268 -147.209727) (xy 21.787332 -147.2651) (xy 21.757365 -147.317006)
			(xy 21.720878 -147.364556) (xy 21.678498 -147.406936) (xy 21.630948 -147.443423) (xy 21.579042 -147.47339)
			(xy 21.523669 -147.496326) (xy 21.465776 -147.511839) (xy 21.406354 -147.519662) (xy 21.346418 -147.519662)
			(xy 21.286996 -147.511839) (xy 21.229103 -147.496326) (xy 21.17373 -147.47339) (xy 21.121824 -147.443423)
			(xy 21.074274 -147.406936) (xy 21.031894 -147.364556) (xy 20.995407 -147.317006) (xy 20.96544 -147.2651)
			(xy 20.942504 -147.209727) (xy 20.926991 -147.151834) (xy 20.919168 -147.092412) (xy 20.41953 -147.092412)
			(xy 20.409128 -147.117526) (xy 20.379161 -147.169432) (xy 20.342674 -147.216982) (xy 20.300294 -147.259362)
			(xy 20.252744 -147.295849) (xy 20.200838 -147.325816) (xy 20.145465 -147.348752) (xy 20.087572 -147.364265)
			(xy 20.02815 -147.372088) (xy 19.968214 -147.372088) (xy 19.908792 -147.364265) (xy 19.850899 -147.348752)
			(xy 19.795526 -147.325816) (xy 19.74362 -147.295849) (xy 19.69607 -147.259362) (xy 19.65369 -147.216982)
			(xy 19.617203 -147.169432) (xy 19.587236 -147.117526) (xy 19.5643 -147.062153) (xy 19.548787 -147.00426)
			(xy 19.540964 -146.944838) (xy 18.51432 -146.944838) (xy 18.521786 -146.953171) (xy 18.552559 -146.999684)
			(xy 18.576231 -147.050181) (xy 18.592299 -147.103588) (xy 18.600419 -147.158764) (xy 18.600928 -147.18665)
			(xy 18.600419 -147.214536) (xy 18.592299 -147.269712) (xy 18.576231 -147.323119) (xy 18.552559 -147.373616)
			(xy 18.521786 -147.420129) (xy 18.484569 -147.461666) (xy 18.441701 -147.497341) (xy 18.394095 -147.526395)
			(xy 18.342766 -147.548207) (xy 18.288809 -147.562313) (xy 18.233372 -147.568413) (xy 18.177638 -147.566376)
			(xy 18.122795 -147.556246) (xy 18.070011 -147.538239) (xy 18.020411 -147.512738) (xy 17.975053 -147.480287)
			(xy 17.934904 -147.441578) (xy 17.900818 -147.397435) (xy 17.873522 -147.3488) (xy 17.853599 -147.296709)
			(xy 17.841473 -147.242272) (xy 17.837402 -147.18665) (xy 10.855198 -147.18665) (xy 10.855198 -156.299154)
			(xy 10.861548 -156.305504) (xy 10.88009 -156.313124)
		)
		(stroke
			(width 0)
			(type solid)
		)
		(fill yes)
		(layer "B.Cu")
		(net "P12V_NIC0_R")
	)
	(gr_poly
		(pts
			(xy 456.554586 -113.518188) (xy 456.55992 -113.512854) (xy 458.065378 -113.512854) (xy 458.075441 -113.512415)
			(xy 458.09402 -113.504676) (xy 458.101446 -113.497868) (xy 459.134464 -112.46485) (xy 459.141322 -112.43818)
			(xy 459.137512 -112.424718) (xy 459.128994 -112.393466) (xy 459.119816 -112.329343) (xy 459.119224 -112.296956)
			(xy 459.119708 -112.266686) (xy 459.127679 -112.206675) (xy 459.143488 -112.148236) (xy 459.166861 -112.092391)
			(xy 459.197389 -112.040113) (xy 459.23454 -111.992314) (xy 459.277666 -111.949827) (xy 459.326015 -111.913395)
			(xy 459.378743 -111.883651) (xy 459.434932 -111.861115) (xy 459.464156 -111.853218) (xy 459.481428 -111.8489)
			(xy 459.50251 -111.821722) (xy 459.50251 -111.001556) (xy 459.476856 -110.9726) (xy 459.457552 -110.970314)
			(xy 459.427515 -110.966348) (xy 459.368773 -110.95151) (xy 459.312502 -110.929051) (xy 459.259687 -110.899363)
			(xy 459.211251 -110.862965) (xy 459.168041 -110.820495) (xy 459.130814 -110.772694) (xy 459.100219 -110.720399)
			(xy 459.076792 -110.664524) (xy 459.060943 -110.606046) (xy 459.052949 -110.545988) (xy 459.05295 -110.485401)
			(xy 459.060945 -110.425344) (xy 459.076796 -110.366866) (xy 459.100224 -110.310992) (xy 459.130819 -110.258697)
			(xy 459.168048 -110.210897) (xy 459.211259 -110.168428) (xy 459.259696 -110.132031) (xy 459.312511 -110.102344)
			(xy 459.368783 -110.079886) (xy 459.427525 -110.06505) (xy 459.457552 -110.060994) (xy 459.476856 -110.058708)
			(xy 459.50251 -110.029752) (xy 459.50251 -96.18345) (xy 459.502078 -96.173384) (xy 459.494352 -96.154791)
			(xy 459.487524 -96.147382) (xy 458.499464 -95.159322) (xy 458.492065 -95.152479) (xy 458.473466 -95.144754)
			(xy 458.463396 -95.144336) (xy 446.680336 -95.144336) (xy 446.670272 -95.144772) (xy 446.651687 -95.152506)
			(xy 446.644268 -95.159322) (xy 446.348612 -95.454978) (xy 446.341777 -95.46238) (xy 446.334069 -95.480979)
			(xy 446.333626 -95.491046) (xy 446.333626 -95.932856) (xy 447.420129 -95.932856) (xy 447.420129 -95.878344)
			(xy 447.427888 -95.824386) (xy 447.443247 -95.772081) (xy 447.465893 -95.722495) (xy 447.495367 -95.676637)
			(xy 447.531067 -95.63544) (xy 447.572267 -95.599744) (xy 447.618128 -95.570275) (xy 447.667717 -95.547633)
			(xy 447.720023 -95.532279) (xy 447.773981 -95.524526) (xy 447.801238 -95.524066) (xy 447.830132 -95.524561)
			(xy 447.887262 -95.533253) (xy 447.942427 -95.550463) (xy 447.994365 -95.575796) (xy 448.041888 -95.608674)
			(xy 448.083908 -95.648344) (xy 448.119464 -95.693898) (xy 448.147742 -95.744294) (xy 448.168095 -95.798378)
			(xy 448.180057 -95.854914) (xy 448.182238 -95.88373) (xy 448.182746 -95.895414) (xy 448.193922 -95.91548)
			(xy 448.277488 -95.97517) (xy 448.300094 -95.97898) (xy 448.31127 -95.975678) (xy 448.34187 -95.967562)
			(xy 448.404583 -95.958902) (xy 448.436238 -95.958406) (xy 448.466202 -95.958922) (xy 448.525618 -95.966749)
			(xy 448.583504 -95.982265) (xy 448.638869 -96.005202) (xy 448.690767 -96.035171) (xy 448.738309 -96.071656)
			(xy 448.780683 -96.114035) (xy 448.817162 -96.161582) (xy 448.847123 -96.213484) (xy 448.870054 -96.268852)
			(xy 448.885562 -96.32674) (xy 448.893381 -96.386156) (xy 448.893379 -96.446085) (xy 448.885554 -96.505501)
			(xy 448.870041 -96.563387) (xy 448.847105 -96.618753) (xy 448.817139 -96.670652) (xy 448.780655 -96.718196)
			(xy 448.738278 -96.760571) (xy 448.690732 -96.797052) (xy 448.638832 -96.827016) (xy 448.583464 -96.849949)
			(xy 448.525577 -96.865459) (xy 448.466161 -96.87328) (xy 448.406232 -96.87328) (xy 448.346816 -96.865457)
			(xy 448.288929 -96.849947) (xy 448.233562 -96.827013) (xy 448.181662 -96.797049) (xy 448.134117 -96.760567)
			(xy 448.09174 -96.718191) (xy 448.055257 -96.670647) (xy 448.025292 -96.618747) (xy 448.002357 -96.563381)
			(xy 447.986845 -96.505494) (xy 447.979021 -96.446078) (xy 447.97853 -96.416114) (xy 447.979292 -96.388682)
			(xy 447.980054 -96.376998) (xy 447.971418 -96.355662) (xy 447.895218 -96.286828) (xy 447.873374 -96.280478)
			(xy 447.86169 -96.282256) (xy 447.84668 -96.284522) (xy 447.816417 -96.286936) (xy 447.801238 -96.287082)
			(xy 447.773981 -96.286674) (xy 447.720023 -96.278921) (xy 447.667717 -96.263567) (xy 447.618128 -96.240925)
			(xy 447.572267 -96.211456) (xy 447.531067 -96.17576) (xy 447.495367 -96.134563) (xy 447.465893 -96.088705)
			(xy 447.443247 -96.039119) (xy 447.427888 -95.986814) (xy 447.420129 -95.932856) (xy 446.333626 -95.932856)
			(xy 446.333626 -96.212152) (xy 446.334134 -96.215454) (xy 446.335817 -96.229809) (xy 446.337596 -96.258659)
			(xy 446.33769 -96.273112) (xy 446.337601 -96.287565) (xy 446.33582 -96.316415) (xy 446.334134 -96.33077)
			(xy 446.333626 -96.334072) (xy 446.333626 -98.048064) (xy 446.334061 -98.058128) (xy 446.341795 -98.076714)
			(xy 446.348612 -98.084132) (xy 447.41211 -99.14763) (xy 447.419453 -99.154446) (xy 447.437916 -99.162186)
			(xy 447.447924 -99.162616) (xy 447.701162 -99.162616) (xy 447.711124 -99.163102) (xy 447.729548 -99.17069)
			(xy 447.736976 -99.177348) (xy 448.350894 -99.791266) (xy 448.357695 -99.798614) (xy 448.365405 -99.817077)
			(xy 448.36588 -99.82708) (xy 448.36588 -99.931474) (xy 448.366295 -99.9415) (xy 448.37396 -99.960029)
			(xy 448.388132 -99.974215) (xy 448.406654 -99.981896) (xy 448.41668 -99.982274) (xy 455.047096 -99.982274)
			(xy 455.057167 -99.982696) (xy 455.075775 -99.990406) (xy 455.083164 -99.99726) (xy 455.29881 -100.212906)
			(xy 455.305665 -100.220301) (xy 455.313412 -100.2389) (xy 455.313796 -100.248974) (xy 455.313796 -103.156258)
			(xy 455.313362 -103.166323) (xy 455.305632 -103.184912) (xy 455.29881 -103.192326) (xy 454.422764 -104.068372)
			(xy 454.415922 -104.075771) (xy 454.408203 -104.09437) (xy 454.407778 -104.10444) (xy 454.407778 -108.34243)
			(xy 454.408206 -108.352498) (xy 454.415926 -108.371097) (xy 454.422764 -108.378498) (xy 454.58253 -108.538264)
			(xy 454.589901 -108.545005) (xy 454.608363 -108.552592) (xy 454.618344 -108.552996) (xy 455.202798 -108.552996)
			(xy 455.212786 -108.553533) (xy 455.231219 -108.561246) (xy 455.238612 -108.567982) (xy 455.914252 -109.243622)
			(xy 455.920927 -109.251035) (xy 455.928493 -109.269471) (xy 455.928984 -109.279436) (xy 455.928984 -109.502448)
			(xy 457.638912 -109.502448) (xy 457.639402 -109.47248) (xy 457.647225 -109.413058) (xy 457.662738 -109.355165)
			(xy 457.685674 -109.299792) (xy 457.715641 -109.247886) (xy 457.752128 -109.200336) (xy 457.794508 -109.157956)
			(xy 457.842058 -109.121469) (xy 457.893964 -109.091502) (xy 457.949337 -109.068566) (xy 458.00723 -109.053053)
			(xy 458.066652 -109.04523) (xy 458.126588 -109.04523) (xy 458.18601 -109.053053) (xy 458.243903 -109.068566)
			(xy 458.299276 -109.091502) (xy 458.351182 -109.121469) (xy 458.398732 -109.157956) (xy 458.441112 -109.200336)
			(xy 458.477599 -109.247886) (xy 458.507566 -109.299792) (xy 458.530502 -109.355165) (xy 458.546015 -109.413058)
			(xy 458.553838 -109.47248) (xy 458.554328 -109.502448) (xy 458.553916 -109.530203) (xy 458.547173 -109.585303)
			(xy 458.533827 -109.639185) (xy 458.514074 -109.691063) (xy 458.501496 -109.715808) (xy 458.496162 -109.726222)
			(xy 458.495146 -109.749082) (xy 458.536294 -109.843316) (xy 458.55382 -109.858302) (xy 458.564996 -109.86135)
			(xy 458.591656 -109.869007) (xy 458.642572 -109.891009) (xy 458.689764 -109.920154) (xy 458.732238 -109.955827)
			(xy 458.769097 -109.997275) (xy 458.799564 -110.043625) (xy 458.822997 -110.093899) (xy 458.838901 -110.147036)
			(xy 458.846942 -110.201917) (xy 458.847444 -110.22965) (xy 458.846874 -110.25781) (xy 458.838601 -110.313519)
			(xy 458.822226 -110.367407) (xy 458.798107 -110.418301) (xy 458.766766 -110.465096) (xy 458.728886 -110.506774)
			(xy 458.68529 -110.542429) (xy 458.636925 -110.571288) (xy 458.584843 -110.592721) (xy 458.55763 -110.599982)
			(xy 458.548232 -110.602268) (xy 458.532484 -110.613698) (xy 458.48397 -110.688374) (xy 458.480414 -110.707424)
			(xy 458.481938 -110.716822) (xy 458.484889 -110.733878) (xy 458.488069 -110.768348) (xy 458.488288 -110.785656)
			(xy 458.487802 -110.812907) (xy 458.480046 -110.866855) (xy 458.464691 -110.91915) (xy 458.442049 -110.968727)
			(xy 458.412583 -111.014577) (xy 458.376892 -111.055768) (xy 458.335701 -111.091459) (xy 458.289851 -111.120925)
			(xy 458.240274 -111.143567) (xy 458.187979 -111.158922) (xy 458.134031 -111.166678) (xy 458.079529 -111.166678)
			(xy 458.025581 -111.158922) (xy 457.973286 -111.143567) (xy 457.923709 -111.120925) (xy 457.877859 -111.091459)
			(xy 457.836668 -111.055768) (xy 457.800977 -111.014577) (xy 457.771511 -110.968727) (xy 457.748869 -110.91915)
			(xy 457.733514 -110.866855) (xy 457.725758 -110.812907) (xy 457.725272 -110.785656) (xy 457.725835 -110.757495)
			(xy 457.734108 -110.701785) (xy 457.750483 -110.647897) (xy 457.774603 -110.597002) (xy 457.805944 -110.550207)
			(xy 457.843825 -110.508529) (xy 457.887423 -110.472874) (xy 457.935789 -110.444016) (xy 457.987873 -110.422584)
			(xy 458.015086 -110.415324) (xy 458.024484 -110.413038) (xy 458.040232 -110.401608) (xy 458.088746 -110.326932)
			(xy 458.092302 -110.307882) (xy 458.090778 -110.298484) (xy 458.087828 -110.281428) (xy 458.084647 -110.246958)
			(xy 458.084428 -110.22965) (xy 458.084807 -110.206213) (xy 458.090573 -110.159695) (xy 458.101977 -110.11423)
			(xy 458.110082 -110.092236) (xy 458.114146 -110.081314) (xy 458.112368 -110.058708) (xy 458.060552 -109.969808)
			(xy 458.041502 -109.957108) (xy 458.030072 -109.95533) (xy 458.000803 -109.950533) (xy 457.943729 -109.934395)
			(xy 457.889218 -109.911021) (xy 457.838182 -109.880802) (xy 457.791476 -109.844245) (xy 457.749883 -109.801963)
			(xy 457.714099 -109.754662) (xy 457.684724 -109.703136) (xy 457.662249 -109.648248) (xy 457.647051 -109.590917)
			(xy 457.639385 -109.532104) (xy 457.638912 -109.502448) (xy 455.928984 -109.502448) (xy 455.928984 -111.815622)
			(xy 457.682582 -111.815622) (xy 457.682582 -111.755686) (xy 457.690405 -111.696264) (xy 457.705918 -111.638371)
			(xy 457.728854 -111.582998) (xy 457.758821 -111.531092) (xy 457.795308 -111.483542) (xy 457.837688 -111.441162)
			(xy 457.885238 -111.404675) (xy 457.937144 -111.374708) (xy 457.992517 -111.351772) (xy 458.05041 -111.336259)
			(xy 458.109832 -111.328436) (xy 458.169768 -111.328436) (xy 458.22919 -111.336259) (xy 458.287083 -111.351772)
			(xy 458.342456 -111.374708) (xy 458.394362 -111.404675) (xy 458.441912 -111.441162) (xy 458.484292 -111.483542)
			(xy 458.520779 -111.531092) (xy 458.550746 -111.582998) (xy 458.573682 -111.638371) (xy 458.589195 -111.696264)
			(xy 458.597018 -111.755686) (xy 458.597508 -111.785654) (xy 458.597018 -111.815622) (xy 458.589195 -111.875044)
			(xy 458.573682 -111.932937) (xy 458.550746 -111.98831) (xy 458.520779 -112.040216) (xy 458.484292 -112.087766)
			(xy 458.441912 -112.130146) (xy 458.394362 -112.166633) (xy 458.342456 -112.1966) (xy 458.287083 -112.219536)
			(xy 458.22919 -112.235049) (xy 458.169768 -112.242872) (xy 458.109832 -112.242872) (xy 458.05041 -112.235049)
			(xy 457.992517 -112.219536) (xy 457.937144 -112.1966) (xy 457.885238 -112.166633) (xy 457.837688 -112.130146)
			(xy 457.795308 -112.087766) (xy 457.758821 -112.040216) (xy 457.728854 -111.98831) (xy 457.705918 -111.932937)
			(xy 457.690405 -111.875044) (xy 457.682582 -111.815622) (xy 455.928984 -111.815622) (xy 455.928984 -113.475008)
			(xy 455.929473 -113.485016) (xy 455.937133 -113.503508) (xy 455.951286 -113.517662) (xy 455.969776 -113.525325)
			(xy 455.979784 -113.525808) (xy 456.536044 -113.525808)
		)
		(stroke
			(width 0)
			(type solid)
		)
		(fill yes)
		(layer "B.Cu")
		(net "P12V_AUX")
	)
	(gr_poly
		(pts
			(arc
				(start 227.94468 -222.131382)
				(mid 227.963236 -222.127772)
				(end 227.979224 -222.117666)
			)
			(arc
				(start 228.10597 -221.99092)
				(mid 228.11637 -221.976014)
				(end 228.120956 -221.958408)
			)
			(xy 228.120956 -221.803468) (xy 228.17963 -221.712536) (xy 228.20376 -221.712536) (xy 228.32822 -221.712536)
			(xy 228.355906 -221.712536) (xy 228.37013 -221.734888) (xy 228.370892 -221.735904) (xy 228.406452 -221.790768)
			(xy 228.408484 -221.794324) (xy 228.41458 -221.803468) (xy 228.41458 -221.814644)
			(arc
				(start 228.41458 -221.955106)
				(mid 228.418481 -221.974629)
				(end 228.429566 -221.991174)
			)
			(xy 228.554788 -222.116396)
			(arc
				(start 228.555296 -222.116904)
				(mid 228.571653 -222.127646)
				(end 228.590856 -222.131382)
			)
			(arc
				(start 228.744272 -222.131382)
				(mid 228.763463 -222.127617)
				(end 228.779832 -222.116904)
			)
			(arc
				(start 228.90607 -221.990666)
				(mid 228.915796 -221.97702)
				(end 228.920548 -221.960948)
			)
			(xy 228.920548 -221.8182) (xy 228.920548 -221.803468) (xy 228.92639 -221.794324) (xy 228.928676 -221.790768)
			(xy 228.96449 -221.73565) (xy 228.966268 -221.73311) (xy 228.979476 -221.712536) (xy 229.003606 -221.712536)
			(xy 229.128066 -221.712536) (xy 229.155752 -221.712536) (xy 229.169976 -221.734888) (xy 229.170738 -221.735904)
			(xy 229.173278 -221.739714) (xy 229.214172 -221.803468)
			(arc
				(start 229.214172 -221.958408)
				(mid 229.218671 -221.976053)
				(end 229.229158 -221.99092)
			)
			(xy 229.354634 -222.116396)
			(arc
				(start 229.355904 -222.117666)
				(mid 229.371872 -222.127821)
				(end 229.390448 -222.131382)
			)
			(arc
				(start 229.544372 -222.131382)
				(mid 229.563563 -222.127617)
				(end 229.579932 -222.116904)
			)
			(arc
				(start 229.70617 -221.990666)
				(mid 229.715896 -221.97702)
				(end 229.720648 -221.960948)
			)
			(xy 229.720648 -221.8182) (xy 229.720648 -221.803468) (xy 229.72649 -221.794324) (xy 229.728776 -221.790768)
			(xy 229.76459 -221.73565) (xy 229.766368 -221.73311) (xy 229.779576 -221.712536) (xy 229.803706 -221.712536)
			(xy 229.928166 -221.712536) (xy 229.955852 -221.712536) (xy 229.970076 -221.734888) (xy 229.970838 -221.735904)
			(xy 229.973378 -221.739714) (xy 230.014272 -221.803468)
			(arc
				(start 230.014272 -221.958408)
				(mid 230.018771 -221.976053)
				(end 230.029258 -221.99092)
			)
			(xy 230.154734 -222.116396)
			(arc
				(start 230.156004 -222.117666)
				(mid 230.171972 -222.127821)
				(end 230.190548 -222.131382)
			)
			(arc
				(start 230.344472 -222.131382)
				(mid 230.363028 -222.127772)
				(end 230.379016 -222.117666)
			)
			(arc
				(start 230.505762 -221.99092)
				(mid 230.516162 -221.976014)
				(end 230.520748 -221.958408)
			)
			(xy 230.520748 -221.803468) (xy 230.579422 -221.712536) (xy 230.603552 -221.712536) (xy 230.728012 -221.712536)
			(xy 230.755698 -221.712536) (xy 230.769922 -221.734888) (xy 230.770684 -221.735904) (xy 230.806244 -221.790768)
			(xy 230.808276 -221.794324) (xy 230.814372 -221.803468) (xy 230.814372 -221.814644)
			(arc
				(start 230.814372 -221.955106)
				(mid 230.818273 -221.974629)
				(end 230.829358 -221.991174)
			)
			(xy 230.95458 -222.116396)
			(arc
				(start 230.955088 -222.116904)
				(mid 230.971445 -222.127646)
				(end 230.990648 -222.131382)
			)
			(arc
				(start 231.453944 -222.131382)
				(mid 231.476681 -222.125882)
				(end 231.494584 -222.110808)
			)
			(xy 231.54132 -222.04807) (xy 231.54513 -222.023432)
			(arc
				(start 231.54132 -222.011748)
				(mid 231.528416 -221.958714)
				(end 231.524048 -221.904306)
			)
			(arc
				(start 231.524048 -221.904052)
				(mid 231.62463 -221.661226)
				(end 231.867456 -221.560644)
			)
			(arc
				(start 231.867456 -221.560644)
				(mid 231.91451 -221.563918)
				(end 231.960674 -221.573598)
			)
			(xy 231.972358 -221.5769) (xy 231.99598 -221.572328)
			(arc
				(start 232.056432 -221.525338)
				(mid 232.070826 -221.507655)
				(end 232.07599 -221.48546)
			)
			(arc
				(start 232.07599 -221.008448)
				(mid 232.072089 -220.988925)
				(end 232.061004 -220.97238)
			)
			(arc
				(start 231.954578 -220.865954)
				(mid 231.939672 -220.855554)
				(end 231.922066 -220.850968)
			)
			(xy 231.767126 -220.850968) (xy 231.676448 -220.792294) (xy 231.676448 -220.616018) (xy 231.6988 -220.60154)
			(xy 231.699562 -220.601032) (xy 231.754426 -220.565472) (xy 231.757982 -220.56344) (xy 231.767126 -220.557344)
			(xy 231.778302 -220.557344)
			(arc
				(start 231.924606 -220.557344)
				(mid 231.940683 -220.552602)
				(end 231.954324 -220.542866)
			)
			(xy 232.061004 -220.436186)
			(arc
				(start 232.061512 -220.435678)
				(mid 232.072254 -220.419321)
				(end 232.07599 -220.400118)
			)
			(arc
				(start 232.07599 -220.208348)
				(mid 232.072089 -220.188825)
				(end 232.061004 -220.17228)
			)
			(arc
				(start 231.954578 -220.065854)
				(mid 231.939672 -220.055454)
				(end 231.922066 -220.050868)
			)
			(xy 231.767126 -220.050868) (xy 231.676448 -219.992194) (xy 231.676448 -219.815918) (xy 231.6988 -219.80144)
			(xy 231.699562 -219.800932) (xy 231.754426 -219.765372) (xy 231.757982 -219.76334) (xy 231.767126 -219.757244)
			(xy 231.778302 -219.757244)
			(arc
				(start 231.924606 -219.757244)
				(mid 231.940683 -219.752502)
				(end 231.954324 -219.742766)
			)
			(xy 232.061004 -219.636086)
			(arc
				(start 232.061512 -219.635578)
				(mid 232.072254 -219.619221)
				(end 232.07599 -219.600018)
			)
			(arc
				(start 232.07599 -218.608402)
				(mid 232.072089 -218.588879)
				(end 232.061004 -218.572334)
			)
			(arc
				(start 231.954832 -218.466162)
				(mid 231.938298 -218.455051)
				(end 231.918764 -218.451176)
			)
			(xy 231.781858 -218.451176) (xy 231.767126 -218.451176) (xy 231.757982 -218.445334) (xy 231.754426 -218.443048)
			(xy 231.709214 -218.413584) (xy 231.676448 -218.392248) (xy 231.676448 -218.215972) (xy 231.767126 -218.157552)
			(arc
				(start 231.92359 -218.157552)
				(mid 231.939578 -218.153144)
				(end 231.953308 -218.143836)
			)
			(xy 231.954324 -218.14282) (xy 232.061004 -218.03614)
			(arc
				(start 232.062274 -218.03487)
				(mid 232.072429 -218.018902)
				(end 232.07599 -218.000326)
			)
			(arc
				(start 232.07599 -217.221816)
				(mid 232.072089 -217.202293)
				(end 232.061004 -217.185748)
			)
			(arc
				(start 232.05694 -217.181684)
				(mid 232.049124 -217.175244)
				(end 232.040176 -217.170508)
			)
			(arc
				(start 232.032302 -217.167206)
				(mid 232.023519 -217.162546)
				(end 232.015792 -217.156284)
			)
			(arc
				(start 231.818434 -216.958926)
				(mid 231.807323 -216.942392)
				(end 231.803448 -216.922858)
			)
			(arc
				(start 231.803448 -216.90203)
				(mid 231.797287 -216.877781)
				(end 231.780334 -216.859358)
			)
			(xy 231.767634 -216.850976) (xy 231.767126 -216.850976) (xy 231.676448 -216.792302) (xy 231.676448 -216.631266)
			(arc
				(start 231.655874 -216.59088)
				(mid 231.596135 -216.53498)
				(end 231.550718 -216.466928)
			)
			(xy 231.544114 -216.454228) (xy 231.519984 -216.439496) (xy 231.40162 -216.43848) (xy 231.377236 -216.452958)
			(arc
				(start 231.370632 -216.465658)
				(mid 231.25737 -216.590524)
				(end 231.098344 -216.646506)
			)
			(xy 231.064816 -216.66327) (xy 231.064562 -216.663524)
			(arc
				(start 231.064562 -216.741248)
				(mid 231.060661 -216.760771)
				(end 231.049576 -216.777316)
			)
			(arc
				(start 231.01046 -216.816432)
				(mid 230.993926 -216.827543)
				(end 230.974392 -216.831418)
			)
			(xy 229.403148 -216.831418) (xy 229.403148 -216.84361)
			(arc
				(start 229.229158 -217.0176)
				(mid 229.219432 -217.031246)
				(end 229.21468 -217.047318)
			)
			(xy 229.21468 -217.190066) (xy 229.21468 -217.204798) (xy 229.208838 -217.213942) (xy 229.206552 -217.217498)
			(xy 229.177088 -217.26271) (xy 229.155752 -217.295476) (xy 228.979476 -217.295476) (xy 228.921056 -217.204798)
			(arc
				(start 228.921056 -217.049858)
				(mid 228.916557 -217.032213)
				(end 228.90607 -217.017346)
			)
			(xy 228.735128 -216.846404) (xy 228.728016 -216.839038) (xy 228.70922 -216.831418)
			(arc
				(start 227.343208 -216.831418)
				(mid 227.323685 -216.835319)
				(end 227.30714 -216.846404)
			)
			(arc
				(start 227.06203 -217.091514)
				(mid 227.019922 -217.12946)
				(end 226.974146 -217.162888)
			)
			(xy 226.964494 -217.169492) (xy 226.95281 -217.188542)
			(arc
				(start 226.943412 -217.278712)
				(mid 226.94614 -217.300943)
				(end 226.958144 -217.31986)
			)
			(arc
				(start 226.98075 -217.342466)
				(mid 226.995656 -217.352866)
				(end 227.013262 -217.357452)
			)
			(xy 227.168202 -217.357452) (xy 227.25888 -217.416126) (xy 227.25888 -217.592402) (xy 227.236528 -217.60688)
			(xy 227.235766 -217.607388) (xy 227.180902 -217.642948) (xy 227.177346 -217.64498) (xy 227.168202 -217.651076)
			(xy 227.157026 -217.651076)
			(arc
				(start 227.010722 -217.651076)
				(mid 226.994645 -217.655818)
				(end 226.981004 -217.665554)
			)
			(xy 226.887532 -217.759026) (xy 226.880166 -217.766138) (xy 226.872546 -217.784934)
			(arc
				(start 226.872546 -218.013026)
				(mid 226.876311 -218.032217)
				(end 226.887024 -218.048586)
			)
			(arc
				(start 226.980496 -218.142058)
				(mid 226.99703 -218.153169)
				(end 227.016564 -218.157044)
			)
			(xy 227.15347 -218.157044) (xy 227.168202 -218.157044) (xy 227.177346 -218.162886) (xy 227.180902 -218.165172)
			(xy 227.226114 -218.194636) (xy 227.25888 -218.215972) (xy 227.25888 -218.392248) (xy 227.168202 -218.450668)
			(arc
				(start 227.011738 -218.450668)
				(mid 226.99575 -218.455076)
				(end 226.98202 -218.464384)
			)
			(xy 226.981004 -218.4654) (xy 226.887532 -218.558872) (xy 226.880166 -218.565984) (xy 226.872546 -218.58478)
			(arc
				(start 226.872546 -218.813126)
				(mid 226.876311 -218.832317)
				(end 226.887024 -218.848686)
			)
			(arc
				(start 226.980496 -218.942158)
				(mid 226.99703 -218.953269)
				(end 227.016564 -218.957144)
			)
			(xy 227.15347 -218.957144) (xy 227.168202 -218.957144) (xy 227.177346 -218.962986) (xy 227.180902 -218.965272)
			(xy 227.226114 -218.994736) (xy 227.25888 -219.016072) (xy 227.25888 -219.192348) (xy 227.168202 -219.250768)
			(arc
				(start 227.011738 -219.250768)
				(mid 226.99575 -219.255176)
				(end 226.98202 -219.264484)
			)
			(xy 226.981004 -219.2655) (xy 226.887532 -219.358972) (xy 226.880166 -219.366084) (xy 226.872546 -219.38488)
			(arc
				(start 226.872546 -220.413326)
				(mid 226.87609 -220.431715)
				(end 226.886008 -220.447616)
			)
			(arc
				(start 226.98075 -220.542358)
				(mid 226.995656 -220.552758)
				(end 227.013262 -220.557344)
			)
			(xy 227.168202 -220.557344) (xy 227.25888 -220.616018) (xy 227.25888 -220.792294) (xy 227.236528 -220.806772)
			(xy 227.235766 -220.80728) (xy 227.180902 -220.84284) (xy 227.177346 -220.844872) (xy 227.168202 -220.850968)
			(xy 227.157026 -220.850968)
			(arc
				(start 227.010722 -220.850968)
				(mid 226.994645 -220.85571)
				(end 226.981004 -220.865446)
			)
			(xy 226.887532 -220.958918) (xy 226.880166 -220.96603) (xy 226.872546 -220.984826)
			(arc
				(start 226.872546 -222.04553)
				(mid 226.876311 -222.064721)
				(end 226.887024 -222.08109)
			)
			(xy 226.92233 -222.116396)
			(arc
				(start 226.922838 -222.116904)
				(mid 226.939195 -222.127646)
				(end 226.958398 -222.131382)
			)
		)
		(stroke
			(width 0)
			(type solid)
		)
		(fill yes)
		(layer "B.Cu")
		(net "GND")
	)
	(gr_poly
		(pts
			(xy 232.46334 -117.643656) (xy 232.469436 -117.63756) (xy 232.469436 -113.368074) (xy 232.469006 -113.358007)
			(xy 232.461278 -113.339416) (xy 232.45445 -113.332006) (xy 231.755442 -112.632998) (xy 231.74804 -112.626161)
			(xy 231.729442 -112.618448) (xy 231.719374 -112.618012) (xy 230.81869 -112.618012) (xy 230.791766 -112.637824)
			(xy 230.78694 -112.65408) (xy 230.77858 -112.679781) (xy 230.755626 -112.72871) (xy 230.726001 -112.773911)
			(xy 230.690296 -112.814482) (xy 230.649226 -112.849612) (xy 230.603611 -112.878598) (xy 230.554364 -112.90086)
			(xy 230.502469 -112.915953) (xy 230.448965 -112.923576) (xy 230.394919 -112.923576) (xy 230.341415 -112.915953)
			(xy 230.28952 -112.90086) (xy 230.240273 -112.878598) (xy 230.194658 -112.849612) (xy 230.153588 -112.814482)
			(xy 230.117883 -112.773911) (xy 230.088258 -112.72871) (xy 230.065304 -112.679781) (xy 230.056944 -112.65408)
			(xy 230.052118 -112.637824) (xy 230.025194 -112.618012) (xy 225.518472 -112.618012) (xy 225.508404 -112.617584)
			(xy 225.489805 -112.609864) (xy 225.482404 -112.603026) (xy 224.338388 -111.45901) (xy 224.331531 -111.451616)
			(xy 224.323779 -111.433017) (xy 224.323402 -111.422942) (xy 224.323402 -109.619796) (xy 224.322386 -109.61878)
			(xy 224.322386 -104.595676) (xy 224.322813 -104.585607) (xy 224.330532 -104.567008) (xy 224.337372 -104.559608)
			(xy 224.817432 -104.079548) (xy 224.824278 -104.07215) (xy 224.832004 -104.053551) (xy 224.832418 -104.04348)
			(xy 224.832418 -103.668576) (xy 224.831991 -103.658507) (xy 224.824273 -103.639907) (xy 224.817432 -103.632508)
			(xy 224.747836 -103.562912) (xy 224.740434 -103.556075) (xy 224.721836 -103.548362) (xy 224.711768 -103.547926)
			(xy 222.614744 -103.547926) (xy 222.604678 -103.547493) (xy 222.586086 -103.539768) (xy 222.578676 -103.53294)
			(xy 222.455232 -103.409496) (xy 222.44783 -103.402661) (xy 222.429232 -103.394952) (xy 222.419164 -103.39451)
			(xy 221.958408 -103.39451) (xy 221.949062 -103.394976) (xy 221.931635 -103.401746) (xy 221.91777 -103.414289)
			(xy 221.913196 -103.42245) (xy 221.865698 -103.515922) (xy 221.867984 -103.544624) (xy 221.87662 -103.556054)
			(xy 221.893978 -103.580745) (xy 221.92151 -103.634454) (xy 221.940248 -103.691824) (xy 221.949727 -103.751429)
			(xy 221.95028 -103.781606) (xy 221.949816 -103.808858) (xy 221.942058 -103.862807) (xy 221.926702 -103.915102)
			(xy 221.904058 -103.96468) (xy 221.87459 -104.01053) (xy 221.838896 -104.05172) (xy 221.797703 -104.08741)
			(xy 221.75185 -104.116875) (xy 221.70227 -104.139513) (xy 221.649973 -104.154866) (xy 221.596024 -104.162619)
			(xy 221.568772 -104.163114) (xy 221.541681 -104.162638) (xy 221.488044 -104.154968) (xy 221.436032 -104.139787)
			(xy 221.386691 -104.1174) (xy 221.341014 -104.088257) (xy 221.299919 -104.052945) (xy 221.264233 -104.012174)
			(xy 221.234675 -103.966764) (xy 221.211839 -103.917629) (xy 221.20352 -103.891842) (xy 221.199964 -103.87965)
			(xy 221.182438 -103.86187) (xy 221.07906 -103.828596) (xy 221.054676 -103.83266) (xy 221.044516 -103.84028)
			(xy 221.02448 -103.855078) (xy 220.981305 -103.879913) (xy 220.935269 -103.89893) (xy 220.887153 -103.911806)
			(xy 220.837772 -103.918323) (xy 220.812868 -103.918766) (xy 220.785618 -103.9183) (xy 220.731673 -103.91054)
			(xy 220.679381 -103.89518) (xy 220.629807 -103.872535) (xy 220.583961 -103.843066) (xy 220.542776 -103.807372)
			(xy 220.50709 -103.766179) (xy 220.477629 -103.720328) (xy 220.454994 -103.67075) (xy 220.439645 -103.618455)
			(xy 220.431894 -103.564508) (xy 220.43136 -103.537258) (xy 220.43263 -103.504746) (xy 220.433646 -103.493824)
			(xy 220.427042 -103.474012) (xy 220.368876 -103.41102) (xy 220.361381 -103.403579) (xy 220.342086 -103.395056)
			(xy 220.331538 -103.39451) (xy 214.804498 -103.39451) (xy 214.792518 -103.395155) (xy 214.771167 -103.406025)
			(xy 214.763604 -103.415338) (xy 214.730376 -103.46071) (xy 214.662809 -103.550629) (xy 214.628476 -103.59517)
			(xy 214.623142 -103.601774) (xy 214.617808 -103.617776) (xy 214.617808 -104.52252) (xy 215.338896 -104.52252)
			(xy 215.338896 -104.462584) (xy 215.346719 -104.403162) (xy 215.362232 -104.345269) (xy 215.385168 -104.289896)
			(xy 215.415135 -104.23799) (xy 215.451622 -104.19044) (xy 215.494002 -104.14806) (xy 215.541552 -104.111573)
			(xy 215.593458 -104.081606) (xy 215.648831 -104.05867) (xy 215.706724 -104.043157) (xy 215.766146 -104.035334)
			(xy 215.826082 -104.035334) (xy 215.885504 -104.043157) (xy 215.943397 -104.05867) (xy 215.99877 -104.081606)
			(xy 216.050676 -104.111573) (xy 216.098226 -104.14806) (xy 216.140606 -104.19044) (xy 216.177093 -104.23799)
			(xy 216.20706 -104.289896) (xy 216.229996 -104.345269) (xy 216.245509 -104.403162) (xy 216.253332 -104.462584)
			(xy 216.253822 -104.492552) (xy 216.253332 -104.52252) (xy 216.245509 -104.581942) (xy 216.229996 -104.639835)
			(xy 216.217462 -104.670094) (xy 216.7171 -104.670094) (xy 216.7171 -104.610158) (xy 216.724923 -104.550736)
			(xy 216.740436 -104.492843) (xy 216.763372 -104.43747) (xy 216.793339 -104.385564) (xy 216.829826 -104.338014)
			(xy 216.872206 -104.295634) (xy 216.919756 -104.259147) (xy 216.971662 -104.22918) (xy 217.027035 -104.206244)
			(xy 217.084928 -104.190731) (xy 217.14435 -104.182908) (xy 217.204286 -104.182908) (xy 217.263708 -104.190731)
			(xy 217.321601 -104.206244) (xy 217.376974 -104.22918) (xy 217.42888 -104.259147) (xy 217.47643 -104.295634)
			(xy 217.51881 -104.338014) (xy 217.542085 -104.368346) (xy 218.571062 -104.368346) (xy 218.575133 -104.312724)
			(xy 218.587259 -104.258287) (xy 218.607182 -104.206196) (xy 218.634478 -104.157561) (xy 218.668564 -104.113418)
			(xy 218.708713 -104.074709) (xy 218.754071 -104.042258) (xy 218.803671 -104.016757) (xy 218.856455 -103.99875)
			(xy 218.911298 -103.98862) (xy 218.967032 -103.986583) (xy 219.022469 -103.992683) (xy 219.076426 -104.006789)
			(xy 219.127755 -104.028601) (xy 219.175361 -104.057655) (xy 219.218229 -104.09333) (xy 219.255446 -104.134867)
			(xy 219.286219 -104.18138) (xy 219.309891 -104.231877) (xy 219.325959 -104.285284) (xy 219.334079 -104.34046)
			(xy 219.334588 -104.368346) (xy 219.334079 -104.396232) (xy 219.325959 -104.451408) (xy 219.309891 -104.504815)
			(xy 219.286219 -104.555312) (xy 219.255446 -104.601825) (xy 219.218229 -104.643362) (xy 219.175361 -104.679037)
			(xy 219.127755 -104.708091) (xy 219.076426 -104.729903) (xy 219.022469 -104.744009) (xy 218.967032 -104.750109)
			(xy 218.911298 -104.748072) (xy 218.856455 -104.737942) (xy 218.803671 -104.719935) (xy 218.754071 -104.694434)
			(xy 218.708713 -104.661983) (xy 218.668564 -104.623274) (xy 218.634478 -104.579131) (xy 218.607182 -104.530496)
			(xy 218.587259 -104.478405) (xy 218.575133 -104.423968) (xy 218.571062 -104.368346) (xy 217.542085 -104.368346)
			(xy 217.555297 -104.385564) (xy 217.585264 -104.43747) (xy 217.6082 -104.492843) (xy 217.623713 -104.550736)
			(xy 217.631536 -104.610158) (xy 217.632026 -104.640126) (xy 217.631536 -104.670094) (xy 217.623713 -104.729516)
			(xy 217.6082 -104.787409) (xy 217.585264 -104.842782) (xy 217.555297 -104.894688) (xy 217.51881 -104.942238)
			(xy 217.47643 -104.984618) (xy 217.42888 -105.021105) (xy 217.376974 -105.051072) (xy 217.321601 -105.074008)
			(xy 217.263708 -105.089521) (xy 217.204286 -105.097344) (xy 217.14435 -105.097344) (xy 217.084928 -105.089521)
			(xy 217.027035 -105.074008) (xy 216.971662 -105.051072) (xy 216.919756 -105.021105) (xy 216.872206 -104.984618)
			(xy 216.829826 -104.942238) (xy 216.793339 -104.894688) (xy 216.763372 -104.842782) (xy 216.740436 -104.787409)
			(xy 216.724923 -104.729516) (xy 216.7171 -104.670094) (xy 216.217462 -104.670094) (xy 216.20706 -104.695208)
			(xy 216.177093 -104.747114) (xy 216.140606 -104.794664) (xy 216.098226 -104.837044) (xy 216.050676 -104.873531)
			(xy 215.99877 -104.903498) (xy 215.943397 -104.926434) (xy 215.885504 -104.941947) (xy 215.826082 -104.94977)
			(xy 215.766146 -104.94977) (xy 215.706724 -104.941947) (xy 215.648831 -104.926434) (xy 215.593458 -104.903498)
			(xy 215.541552 -104.873531) (xy 215.494002 -104.837044) (xy 215.451622 -104.794664) (xy 215.415135 -104.747114)
			(xy 215.385168 -104.695208) (xy 215.362232 -104.639835) (xy 215.346719 -104.581942) (xy 215.338896 -104.52252)
			(xy 214.617808 -104.52252) (xy 214.617808 -105.695496) (xy 214.618231 -105.705566) (xy 214.625945 -105.724171)
			(xy 214.632794 -105.731564) (xy 214.981581 -106.080351) (xy 219.615483 -106.080351) (xy 219.615483 -106.025849)
			(xy 219.62324 -105.971901) (xy 219.638596 -105.919606) (xy 219.661237 -105.870028) (xy 219.690704 -105.824178)
			(xy 219.726397 -105.782988) (xy 219.767588 -105.747297) (xy 219.813439 -105.717831) (xy 219.863017 -105.695191)
			(xy 219.915312 -105.679837) (xy 219.969261 -105.672082) (xy 219.996512 -105.67162) (xy 220.022854 -105.672053)
			(xy 220.075035 -105.67931) (xy 220.125723 -105.69367) (xy 220.173956 -105.714862) (xy 220.218819 -105.742483)
			(xy 220.259459 -105.776008) (xy 220.295105 -105.814801) (xy 220.310456 -105.836212) (xy 220.319216 -105.847982)
			(xy 220.342029 -105.866408) (xy 220.369139 -105.877587) (xy 220.398308 -105.880599) (xy 220.42713 -105.875195)
			(xy 220.453227 -105.86182) (xy 220.474445 -105.841578) (xy 220.48216 -105.8291) (xy 220.496878 -105.804579)
			(xy 220.532477 -105.759821) (xy 220.574356 -105.720878) (xy 220.621579 -105.688621) (xy 220.673087 -105.663773)
			(xy 220.727727 -105.64689) (xy 220.784274 -105.63835) (xy 220.812868 -105.637838) (xy 220.840126 -105.638207)
			(xy 220.894087 -105.645961) (xy 220.946395 -105.661316) (xy 220.995985 -105.68396) (xy 221.041848 -105.71343)
			(xy 221.083049 -105.749128) (xy 221.118751 -105.790327) (xy 221.148225 -105.836187) (xy 221.170873 -105.885775)
			(xy 221.186232 -105.938082) (xy 221.193991 -105.992042) (xy 221.193991 -106.046558) (xy 221.186232 -106.100518)
			(xy 221.170873 -106.152825) (xy 221.148225 -106.202413) (xy 221.118751 -106.248273) (xy 221.083049 -106.289472)
			(xy 221.041848 -106.32517) (xy 220.995985 -106.35464) (xy 220.946395 -106.377284) (xy 220.894087 -106.392639)
			(xy 220.840126 -106.400393) (xy 220.812868 -106.400854) (xy 220.786528 -106.400372) (xy 220.734349 -106.393125)
			(xy 220.683661 -106.378774) (xy 220.635427 -106.35759) (xy 220.590564 -106.329977) (xy 220.549923 -106.296458)
			(xy 220.514276 -106.25767) (xy 220.498924 -106.236262) (xy 220.490198 -106.224461) (xy 220.467381 -106.206021)
			(xy 220.440262 -106.194833) (xy 220.41108 -106.191821) (xy 220.382247 -106.197234) (xy 220.356145 -106.210624)
			(xy 220.33493 -106.230886) (xy 220.32722 -106.243374) (xy 220.312507 -106.267898) (xy 220.276908 -106.312657)
			(xy 220.235028 -106.351601) (xy 220.187804 -106.383858) (xy 220.136295 -106.408706) (xy 220.081655 -106.425588)
			(xy 220.025107 -106.434125) (xy 219.996512 -106.434636) (xy 219.969261 -106.434118) (xy 219.915312 -106.426363)
			(xy 219.863017 -106.411009) (xy 219.813439 -106.388369) (xy 219.767588 -106.358903) (xy 219.726397 -106.323212)
			(xy 219.690704 -106.282022) (xy 219.661237 -106.236172) (xy 219.638596 -106.186594) (xy 219.62324 -106.134299)
			(xy 219.615483 -106.080351) (xy 214.981581 -106.080351) (xy 216.25179 -107.35056) (xy 216.258628 -107.357961)
			(xy 216.266342 -107.37656) (xy 216.266776 -107.386628) (xy 216.266776 -109.199172) (xy 216.259156 -109.217714)
			(xy 216.254838 -109.222032) (xy 216.254838 -115.556538) (xy 216.262458 -115.57508) (xy 216.262712 -115.575334)
			(xy 216.262712 -116.823236) (xy 216.263048 -116.831875) (xy 216.268798 -116.848167) (xy 216.27966 -116.861603)
			(xy 216.286842 -116.866416) (xy 216.310159 -116.881435) (xy 216.352596 -116.917147) (xy 216.389418 -116.958623)
			(xy 216.419851 -117.004991) (xy 216.443253 -117.055275) (xy 216.459132 -117.108417) (xy 216.467155 -117.163296)
			(xy 216.46769 -117.191028) (xy 216.46769 -117.199664) (xy 216.467436 -117.210332) (xy 216.475056 -117.229382)
			(xy 216.881964 -117.63629) (xy 216.889366 -117.643127) (xy 216.907964 -117.65084) (xy 216.918032 -117.651276)
			(xy 232.444798 -117.651276)
		)
		(stroke
			(width 0)
			(type solid)
		)
		(fill yes)
		(layer "B.Cu")
		(net "P12V_NIC3_R")
	)
	(gr_poly
		(pts
			(xy 262.392414 -86.92515) (xy 262.402482 -86.924723) (xy 262.421078 -86.916999) (xy 262.428482 -86.910164)
			(xy 262.82904 -86.509606) (xy 262.835894 -86.502211) (xy 262.84364 -86.483612) (xy 262.844026 -86.473538)
			(xy 262.844026 -86.073742) (xy 262.846566 -86.071202) (xy 262.846566 -81.576418) (xy 262.846127 -81.566355)
			(xy 262.838388 -81.547775) (xy 262.83158 -81.54035) (xy 262.427974 -81.136744) (xy 262.420576 -81.129897)
			(xy 262.401978 -81.122165) (xy 262.391906 -81.121758) (xy 257.352546 -81.121758) (xy 257.037586 -80.806798)
			(xy 257.037586 -78.902814) (xy 257.037209 -78.893642) (xy 257.030736 -78.876479) (xy 257.018593 -78.862732)
			(xy 257.010662 -78.85811) (xy 256.918968 -78.809088) (xy 256.891282 -78.810612) (xy 256.879344 -78.818486)
			(xy 256.855649 -78.833791) (xy 256.804701 -78.858002) (xy 256.750742 -78.874439) (xy 256.69495 -78.882745)
			(xy 256.666746 -78.883256) (xy 256.639488 -78.882796) (xy 256.585525 -78.875044) (xy 256.533215 -78.85969)
			(xy 256.483623 -78.837047) (xy 256.437758 -78.807576) (xy 256.396554 -78.771878) (xy 256.360851 -78.730679)
			(xy 256.331375 -78.684818) (xy 256.308727 -78.635228) (xy 256.293366 -78.58292) (xy 256.285607 -78.528958)
			(xy 256.285607 -78.474442) (xy 256.293366 -78.42048) (xy 256.308727 -78.368172) (xy 256.331375 -78.318582)
			(xy 256.360851 -78.272721) (xy 256.396554 -78.231522) (xy 256.437758 -78.195824) (xy 256.483623 -78.166353)
			(xy 256.533215 -78.14371) (xy 256.585525 -78.128356) (xy 256.639488 -78.120604) (xy 256.666746 -78.12024)
			(xy 256.694949 -78.120752) (xy 256.750738 -78.129067) (xy 256.804695 -78.145509) (xy 256.85564 -78.169719)
			(xy 256.879344 -78.18501) (xy 256.891282 -78.192884) (xy 256.918968 -78.194408) (xy 257.010662 -78.145386)
			(xy 257.01855 -78.14072) (xy 257.030632 -78.126957) (xy 257.037135 -78.109837) (xy 257.037586 -78.100682)
			(xy 257.037586 -76.64069) (xy 257.037234 -76.631961) (xy 257.031351 -76.615526) (xy 257.02025 -76.602054)
			(xy 257.012948 -76.597256) (xy 256.987876 -76.581541) (xy 256.942472 -76.543601) (xy 256.903472 -76.499105)
			(xy 256.87181 -76.44912) (xy 256.848246 -76.394845) (xy 256.833346 -76.337583) (xy 256.829814 -76.308204)
			(xy 256.828798 -76.299314) (xy 256.821432 -76.28382) (xy 256.636774 -76.099162) (xy 256.62943 -76.092349)
			(xy 256.610967 -76.084616) (xy 256.60096 -76.084176) (xy 254.653034 -76.084176) (xy 254.641906 -76.084809)
			(xy 254.621766 -76.094303) (xy 254.614172 -76.102464) (xy 254.556768 -76.171044) (xy 254.550926 -76.19238)
			(xy 254.552958 -76.203556) (xy 254.5557 -76.220056) (xy 254.558626 -76.253379) (xy 254.5588 -76.270104)
			(xy 254.558314 -76.297355) (xy 254.550558 -76.351303) (xy 254.535203 -76.403598) (xy 254.512561 -76.453175)
			(xy 254.483095 -76.499025) (xy 254.447404 -76.540216) (xy 254.406213 -76.575907) (xy 254.360363 -76.605373)
			(xy 254.310786 -76.628015) (xy 254.258491 -76.64337) (xy 254.204543 -76.651126) (xy 254.150041 -76.651126)
			(xy 254.096093 -76.64337) (xy 254.043798 -76.628015) (xy 253.994221 -76.605373) (xy 253.948371 -76.575907)
			(xy 253.90718 -76.540216) (xy 253.871489 -76.499025) (xy 253.842023 -76.453175) (xy 253.819381 -76.403598)
			(xy 253.804026 -76.351303) (xy 253.79627 -76.297355) (xy 253.795784 -76.270104) (xy 253.795962 -76.253379)
			(xy 253.798883 -76.220056) (xy 253.801626 -76.203556) (xy 253.803658 -76.19238) (xy 253.797816 -76.171044)
			(xy 253.740412 -76.102464) (xy 253.732858 -76.094252) (xy 253.712693 -76.084759) (xy 253.70155 -76.084176)
			(xy 248.210324 -76.084176) (xy 248.200273 -76.084681) (xy 248.181712 -76.092402) (xy 248.174256 -76.099162)
			(xy 247.341898 -76.93152) (xy 247.341898 -78.673194) (xy 254.198102 -78.673194) (xy 254.198102 -78.613258)
			(xy 254.205925 -78.553836) (xy 254.221438 -78.495943) (xy 254.244374 -78.44057) (xy 254.274341 -78.388664)
			(xy 254.310828 -78.341114) (xy 254.353208 -78.298734) (xy 254.400758 -78.262247) (xy 254.452664 -78.23228)
			(xy 254.508037 -78.209344) (xy 254.56593 -78.193831) (xy 254.625352 -78.186008) (xy 254.685288 -78.186008)
			(xy 254.74471 -78.193831) (xy 254.802603 -78.209344) (xy 254.857976 -78.23228) (xy 254.909882 -78.262247)
			(xy 254.957432 -78.298734) (xy 254.999812 -78.341114) (xy 255.036299 -78.388664) (xy 255.066266 -78.44057)
			(xy 255.089202 -78.495943) (xy 255.104715 -78.553836) (xy 255.112538 -78.613258) (xy 255.113028 -78.643226)
			(xy 255.112538 -78.673194) (xy 255.104715 -78.732616) (xy 255.089202 -78.790509) (xy 255.066266 -78.845882)
			(xy 255.036299 -78.897788) (xy 254.999812 -78.945338) (xy 254.957432 -78.987718) (xy 254.909882 -79.024205)
			(xy 254.857976 -79.054172) (xy 254.802603 -79.077108) (xy 254.74471 -79.092621) (xy 254.685288 -79.100444)
			(xy 254.625352 -79.100444) (xy 254.56593 -79.092621) (xy 254.508037 -79.077108) (xy 254.452664 -79.054172)
			(xy 254.400758 -79.024205) (xy 254.353208 -78.987718) (xy 254.310828 -78.945338) (xy 254.274341 -78.897788)
			(xy 254.244374 -78.845882) (xy 254.221438 -78.790509) (xy 254.205925 -78.732616) (xy 254.198102 -78.673194)
			(xy 247.341898 -78.673194) (xy 247.341898 -79.809336) (xy 250.3721 -79.809336) (xy 250.3721 -79.7494)
			(xy 250.379923 -79.689978) (xy 250.395436 -79.632085) (xy 250.418372 -79.576712) (xy 250.448339 -79.524806)
			(xy 250.484826 -79.477256) (xy 250.527206 -79.434876) (xy 250.574756 -79.398389) (xy 250.626662 -79.368422)
			(xy 250.682035 -79.345486) (xy 250.739928 -79.329973) (xy 250.79935 -79.32215) (xy 250.859286 -79.32215)
			(xy 250.918708 -79.329973) (xy 250.976601 -79.345486) (xy 251.031974 -79.368422) (xy 251.08388 -79.398389)
			(xy 251.13143 -79.434876) (xy 251.17381 -79.477256) (xy 251.210297 -79.524806) (xy 251.240264 -79.576712)
			(xy 251.2632 -79.632085) (xy 251.278713 -79.689978) (xy 251.286536 -79.7494) (xy 251.287026 -79.779368)
			(xy 251.286536 -79.809336) (xy 251.278713 -79.868758) (xy 251.2632 -79.926651) (xy 251.240264 -79.982024)
			(xy 251.210297 -80.03393) (xy 251.17381 -80.08148) (xy 251.13143 -80.12386) (xy 251.08388 -80.160347)
			(xy 251.031974 -80.190314) (xy 250.976601 -80.21325) (xy 250.918708 -80.228763) (xy 250.859286 -80.236586)
			(xy 250.79935 -80.236586) (xy 250.739928 -80.228763) (xy 250.682035 -80.21325) (xy 250.626662 -80.190314)
			(xy 250.574756 -80.160347) (xy 250.527206 -80.12386) (xy 250.484826 -80.08148) (xy 250.448339 -80.03393)
			(xy 250.418372 -79.982024) (xy 250.395436 -79.926651) (xy 250.379923 -79.868758) (xy 250.3721 -79.809336)
			(xy 247.341898 -79.809336) (xy 247.341898 -80.846418) (xy 251.90499 -80.846418) (xy 251.90499 -80.786482)
			(xy 251.912813 -80.72706) (xy 251.928326 -80.669167) (xy 251.951262 -80.613794) (xy 251.981229 -80.561888)
			(xy 252.017716 -80.514338) (xy 252.060096 -80.471958) (xy 252.107646 -80.435471) (xy 252.159552 -80.405504)
			(xy 252.214925 -80.382568) (xy 252.272818 -80.367055) (xy 252.33224 -80.359232) (xy 252.392176 -80.359232)
			(xy 252.451598 -80.367055) (xy 252.509491 -80.382568) (xy 252.564864 -80.405504) (xy 252.61677 -80.435471)
			(xy 252.66432 -80.471958) (xy 252.7067 -80.514338) (xy 252.743187 -80.561888) (xy 252.773154 -80.613794)
			(xy 252.79609 -80.669167) (xy 252.811603 -80.72706) (xy 252.819426 -80.786482) (xy 252.819704 -80.803492)
			(xy 253.823452 -80.803492) (xy 253.823452 -80.743556) (xy 253.831275 -80.684134) (xy 253.846788 -80.626241)
			(xy 253.869724 -80.570868) (xy 253.899691 -80.518962) (xy 253.936178 -80.471412) (xy 253.978558 -80.429032)
			(xy 254.026108 -80.392545) (xy 254.078014 -80.362578) (xy 254.133387 -80.339642) (xy 254.19128 -80.324129)
			(xy 254.250702 -80.316306) (xy 254.310638 -80.316306) (xy 254.37006 -80.324129) (xy 254.427953 -80.339642)
			(xy 254.483326 -80.362578) (xy 254.535232 -80.392545) (xy 254.582782 -80.429032) (xy 254.625162 -80.471412)
			(xy 254.661649 -80.518962) (xy 254.691616 -80.570868) (xy 254.714552 -80.626241) (xy 254.730065 -80.684134)
			(xy 254.737888 -80.743556) (xy 254.738378 -80.773524) (xy 254.737888 -80.803492) (xy 254.730065 -80.862914)
			(xy 254.714552 -80.920807) (xy 254.691616 -80.97618) (xy 254.661649 -81.028086) (xy 254.625162 -81.075636)
			(xy 254.582782 -81.118016) (xy 254.535232 -81.154503) (xy 254.483326 -81.18447) (xy 254.427953 -81.207406)
			(xy 254.37006 -81.222919) (xy 254.310638 -81.230742) (xy 254.250702 -81.230742) (xy 254.19128 -81.222919)
			(xy 254.133387 -81.207406) (xy 254.078014 -81.18447) (xy 254.026108 -81.154503) (xy 253.978558 -81.118016)
			(xy 253.936178 -81.075636) (xy 253.899691 -81.028086) (xy 253.869724 -80.97618) (xy 253.846788 -80.920807)
			(xy 253.831275 -80.862914) (xy 253.823452 -80.803492) (xy 252.819704 -80.803492) (xy 252.819916 -80.81645)
			(xy 252.819426 -80.846418) (xy 252.811603 -80.90584) (xy 252.79609 -80.963733) (xy 252.773154 -81.019106)
			(xy 252.743187 -81.071012) (xy 252.7067 -81.118562) (xy 252.66432 -81.160942) (xy 252.61677 -81.197429)
			(xy 252.564864 -81.227396) (xy 252.509491 -81.250332) (xy 252.451598 -81.265845) (xy 252.392176 -81.273668)
			(xy 252.33224 -81.273668) (xy 252.272818 -81.265845) (xy 252.214925 -81.250332) (xy 252.159552 -81.227396)
			(xy 252.107646 -81.197429) (xy 252.060096 -81.160942) (xy 252.017716 -81.118562) (xy 251.981229 -81.071012)
			(xy 251.951262 -81.019106) (xy 251.928326 -80.963733) (xy 251.912813 -80.90584) (xy 251.90499 -80.846418)
			(xy 247.341898 -80.846418) (xy 247.341898 -82.17535) (xy 247.34233 -82.185416) (xy 247.350057 -82.204008)
			(xy 247.356884 -82.211418) (xy 247.395492 -82.250026) (xy 247.402886 -82.256882) (xy 247.421485 -82.264631)
			(xy 247.43156 -82.265012) (xy 250.217686 -82.265012) (xy 250.223108 -82.267609) (xy 250.23479 -82.270439)
			(xy 250.2408 -82.2706) (xy 250.267724 -82.2706) (xy 250.269756 -82.269584) (xy 250.77801 -82.269584)
			(xy 250.787907 -82.269062) (xy 250.806198 -82.261478) (xy 250.81357 -82.254852) (xy 250.815856 -82.252566)
			(xy 250.818396 -82.25028) (xy 250.822206 -82.24647) (xy 250.839425 -82.229807) (xy 250.878131 -82.201564)
			(xy 250.920783 -82.179731) (xy 250.966328 -82.164848) (xy 251.013641 -82.157281) (xy 251.037598 -82.156808)
			(xy 251.948188 -82.156808) (xy 251.958218 -82.156364) (xy 251.976784 -82.148781) (xy 251.984256 -82.142076)
			(xy 252.133608 -81.992724) (xy 252.133608 -81.99247) (xy 252.150877 -81.97579) (xy 252.189686 -81.947524)
			(xy 252.232441 -81.925683) (xy 252.278089 -81.910806) (xy 252.325503 -81.90326) (xy 252.349508 -81.902808)
			(xy 253.546102 -81.902808) (xy 253.570177 -81.903283) (xy 253.617724 -81.910884) (xy 253.663491 -81.925849)
			(xy 253.706342 -81.947809) (xy 253.745219 -81.976219) (xy 253.76251 -81.992978) (xy 253.77464 -82.004373)
			(xy 253.803424 -82.021054) (xy 253.83554 -82.029732) (xy 253.852172 -82.030316) (xy 253.85268 -82.030316)
			(xy 253.868838 -82.029853) (xy 253.900125 -82.021769) (xy 253.92838 -82.006088) (xy 253.951793 -81.983814)
			(xy 253.968863 -81.956376) (xy 253.978496 -81.925531) (xy 253.97968 -81.909412) (xy 253.97968 -81.908904)
			(xy 253.98222 -81.860898) (xy 253.982549 -81.856242) (xy 253.984721 -81.847164) (xy 253.986538 -81.842864)
			(xy 254.024892 -81.757012) (xy 254.026863 -81.752805) (xy 254.032098 -81.745132) (xy 254.035306 -81.741772)
			(xy 254.292608 -81.484724) (xy 254.292608 -81.48447) (xy 254.309877 -81.46779) (xy 254.348686 -81.439524)
			(xy 254.391441 -81.417683) (xy 254.437089 -81.402806) (xy 254.484503 -81.39526) (xy 254.508508 -81.394808)
			(xy 256.201926 -81.394808) (xy 256.211911 -81.39535) (xy 256.230336 -81.403071) (xy 256.23774 -81.409794)
			(xy 256.43713 -81.609184) (xy 256.443935 -81.61653) (xy 256.451648 -81.634994) (xy 256.452116 -81.644998)
			(xy 256.452116 -86.773004) (xy 256.45254 -86.783074) (xy 256.460257 -86.801675) (xy 256.467102 -86.809072)
			(xy 256.568194 -86.910164) (xy 256.575591 -86.917015) (xy 256.594189 -86.924758) (xy 256.604262 -86.92515)
		)
		(stroke
			(width 0)
			(type solid)
		)
		(fill yes)
		(layer "B.Cu")
		(net "GND")
	)
	(gr_poly
		(pts
			(arc
				(start 339.99805 -220.528388)
				(mid 340.027458 -220.540041)
				(end 340.057994 -220.531944)
			)
			(arc
				(start 340.149434 -220.472508)
				(mid 340.163746 -220.461236)
				(end 340.17585 -220.447616)
			)
			(arc
				(start 340.204552 -220.408754)
				(mid 340.212575 -220.400233)
				(end 340.222332 -220.393768)
			)
			(arc
				(start 340.31936 -220.344492)
				(mid 340.337978 -220.328371)
				(end 340.346792 -220.305376)
			)
			(xy 340.346792 -220.286326) (xy 340.40572 -220.195648) (xy 340.581996 -220.195648) (xy 340.640416 -220.286326)
			(xy 340.640416 -220.313504) (xy 340.655402 -220.337634)
			(arc
				(start 340.765892 -220.393768)
				(mid 340.775659 -220.400222)
				(end 340.783672 -220.408754)
			)
			(arc
				(start 340.812374 -220.447362)
				(mid 340.894162 -220.488614)
				(end 340.97595 -220.447362)
			)
			(arc
				(start 341.004652 -220.408754)
				(mid 341.012675 -220.400233)
				(end 341.022432 -220.393768)
			)
			(arc
				(start 341.119206 -220.344746)
				(mid 341.139471 -220.325928)
				(end 341.146892 -220.29928)
			)
			(xy 341.146892 -220.286326) (xy 341.20582 -220.195648)
			(arc
				(start 341.220044 -220.195648)
				(mid 341.244822 -220.155795)
				(end 341.275416 -220.12021)
			)
			(arc
				(start 341.384128 -220.011752)
				(mid 341.482935 -219.945609)
				(end 341.59952 -219.922344)
			)
			(arc
				(start 341.787734 -219.922344)
				(mid 341.904283 -219.945696)
				(end 342.003126 -220.011752)
			)
			(arc
				(start 342.057736 -220.066108)
				(mid 342.09355 -220.080943)
				(end 342.129364 -220.066108)
			)
			(arc
				(start 342.183974 -220.011752)
				(mid 342.282781 -219.945609)
				(end 342.399366 -219.922344)
			)
			(arc
				(start 342.58758 -219.922344)
				(mid 342.704129 -219.945696)
				(end 342.802972 -220.011752)
			)
			(arc
				(start 342.857582 -220.066108)
				(mid 342.893396 -220.080943)
				(end 342.92921 -220.066108)
			)
			(arc
				(start 342.98382 -220.011752)
				(mid 343.082627 -219.945609)
				(end 343.199212 -219.922344)
			)
			(arc
				(start 343.387426 -219.922344)
				(mid 343.503975 -219.945696)
				(end 343.602818 -220.011752)
			)
			(arc
				(start 343.71153 -220.119956)
				(mid 343.742125 -220.155673)
				(end 343.766902 -220.195648)
			)
			(xy 343.78138 -220.195648) (xy 343.8398 -220.286326) (xy 343.8398 -220.31325) (xy 343.854786 -220.33738)
			(arc
				(start 343.96553 -220.394022)
				(mid 343.975297 -220.400476)
				(end 343.98331 -220.409008)
			)
			(arc
				(start 344.011758 -220.447362)
				(mid 344.093546 -220.488614)
				(end 344.175334 -220.447362)
			)
			(arc
				(start 344.204036 -220.408754)
				(mid 344.212059 -220.400233)
				(end 344.221816 -220.393768)
			)
			(arc
				(start 344.318844 -220.344492)
				(mid 344.337462 -220.328371)
				(end 344.346276 -220.305376)
			)
			(xy 344.346276 -220.286326) (xy 344.405204 -220.195648) (xy 344.58148 -220.195648) (xy 344.6399 -220.286326)
			(xy 344.6399 -220.313504) (xy 344.654886 -220.337634)
			(arc
				(start 344.765376 -220.393514)
				(mid 344.775143 -220.399968)
				(end 344.783156 -220.4085)
			)
			(arc
				(start 344.811858 -220.447362)
				(mid 344.823071 -220.460181)
				(end 344.836242 -220.470984)
			)
			(xy 344.836496 -220.470984) (xy 344.852498 -220.481652) (xy 344.860118 -220.488002) (xy 344.873072 -220.500956)
			(xy 344.911934 -220.502988)
			(arc
				(start 344.9574 -220.466412)
				(mid 344.965857 -220.458733)
				(end 344.973402 -220.450156)
			)
			(xy 344.97518 -220.44787) (xy 344.992198 -220.427296) (xy 344.998548 -220.420692) (xy 345.039188 -220.386148)
			(xy 345.049602 -220.37929) (xy 345.095322 -220.356684) (xy 345.095322 -220.35643)
			(arc
				(start 345.115388 -220.347286)
				(mid 345.138282 -220.328581)
				(end 345.146884 -220.300296)
			)
			(xy 345.146884 -220.286326) (xy 345.205558 -220.195648)
			(arc
				(start 345.219782 -220.195648)
				(mid 345.243081 -220.157828)
				(end 345.271598 -220.123766)
			)
			(arc
				(start 345.359736 -220.035628)
				(mid 345.37071 -220.019065)
				(end 345.374468 -219.99956)
			)
			(arc
				(start 345.374468 -219.961714)
				(mid 345.372536 -219.947839)
				(end 345.366848 -219.935044)
			)
			(arc
				(start 345.366594 -219.934536)
				(mid 345.330915 -219.856172)
				(end 345.318588 -219.77096)
			)
			(arc
				(start 345.318588 -219.40393)
				(mid 345.331114 -219.318421)
				(end 345.367102 -219.239846)
			)
			(xy 345.367102 -219.239338) (xy 345.370912 -219.233496) (xy 345.374976 -219.21978)
			(arc
				(start 345.374976 -219.174314)
				(mid 345.371192 -219.15482)
				(end 345.360244 -219.138246)
			)
			(arc
				(start 345.27617 -219.054172)
				(mid 345.245425 -219.01848)
				(end 345.220544 -218.97848)
			)
			(xy 345.205812 -218.97848) (xy 345.147392 -218.887802) (xy 345.147392 -218.858338) (xy 345.130374 -218.833192)
			(xy 345.11615 -218.82735) (xy 345.094052 -218.81719) (xy 345.093798 -218.816936) (xy 345.04884 -218.79433)
			(xy 345.038934 -218.787726) (xy 344.998548 -218.753436) (xy 344.992198 -218.746832) (xy 344.97518 -218.726258)
			(arc
				(start 344.973402 -218.724226)
				(mid 344.963374 -218.713133)
				(end 344.951812 -218.703652)
			)
			(xy 344.951304 -218.703398)
			(arc
				(start 344.916252 -218.679014)
				(mid 344.882788 -218.670139)
				(end 344.851482 -218.684856)
			)
			(arc
				(start 344.775028 -218.76131)
				(mid 344.727255 -218.800146)
				(end 344.672666 -218.82862)
			)
			(arc
				(start 344.672666 -218.82862)
				(mid 344.651074 -218.844799)
				(end 344.640916 -218.869768)
			)
			(xy 344.640916 -218.887802) (xy 344.581988 -218.97848) (xy 344.405712 -218.97848) (xy 344.347292 -218.887802)
			(xy 344.347292 -218.858084) (xy 344.330274 -218.832938) (xy 344.316304 -218.827096) (xy 344.315796 -218.827096)
			(xy 344.295222 -218.817698) (xy 344.295222 -218.817444) (xy 344.249502 -218.794838) (xy 344.239088 -218.78798)
			(xy 344.198448 -218.753436) (xy 344.192098 -218.746832) (xy 344.17508 -218.726258)
			(arc
				(start 344.173556 -218.724226)
				(mid 344.093546 -218.685387)
				(end 344.013536 -218.724226)
			)
			(xy 344.012012 -218.726258) (xy 343.994994 -218.746832) (xy 343.988644 -218.753436) (xy 343.948004 -218.78798)
			(xy 343.93759 -218.794838) (xy 343.89187 -218.817444) (xy 343.89187 -218.817698) (xy 343.871804 -218.826842)
			(xy 343.85758 -218.832684) (xy 343.840816 -218.85783) (xy 343.840816 -218.887802) (xy 343.782142 -218.97848)
			(xy 343.781888 -218.97848) (xy 343.773506 -218.991434) (xy 343.766648 -218.999816)
			(arc
				(start 343.616026 -219.14993)
				(mid 343.517248 -219.21621)
				(end 343.400634 -219.239592)
			)
			(arc
				(start 343.187782 -219.239592)
				(mid 343.07994 -219.219815)
				(end 342.986106 -219.163138)
			)
			(xy 342.977724 -219.155772) (xy 342.975692 -219.15374)
			(arc
				(start 342.929972 -219.10802)
				(mid 342.894158 -219.093259)
				(end 342.858344 -219.10802)
			)
			(arc
				(start 342.81618 -219.14993)
				(mid 342.717402 -219.21621)
				(end 342.600788 -219.239592)
			)
			(arc
				(start 342.387428 -219.239592)
				(mid 342.279586 -219.219815)
				(end 342.185752 -219.163138)
			)
			(xy 342.171274 -219.150184) (xy 342.17102 -219.150184)
			(arc
				(start 342.129618 -219.108528)
				(mid 342.09373 -219.093438)
				(end 342.057736 -219.108274)
			)
			(arc
				(start 342.015826 -219.14993)
				(mid 341.917048 -219.21621)
				(end 341.800434 -219.239592)
			)
			(arc
				(start 341.587582 -219.239592)
				(mid 341.47974 -219.219815)
				(end 341.385906 -219.163138)
			)
			(xy 341.371428 -219.150184) (xy 341.371174 -219.150184) (xy 341.27567 -219.053664)
			(arc
				(start 341.275416 -219.053664)
				(mid 341.245096 -219.018179)
				(end 341.220552 -218.97848)
			)
			(xy 341.20582 -218.97848) (xy 341.1474 -218.887802) (xy 341.1474 -218.858084) (xy 341.130382 -218.832938)
			(xy 341.116158 -218.827096) (xy 341.094568 -218.81719) (xy 341.094314 -218.816936) (xy 341.049356 -218.79433)
			(xy 341.03945 -218.787726) (xy 340.999064 -218.753436) (xy 340.992714 -218.746832) (xy 340.975696 -218.726258)
			(arc
				(start 340.974172 -218.724226)
				(mid 340.894162 -218.685387)
				(end 340.814152 -218.724226)
			)
			(xy 340.812628 -218.726258) (xy 340.79561 -218.746832) (xy 340.78926 -218.753436) (xy 340.74862 -218.78798)
			(xy 340.738206 -218.794838) (xy 340.692486 -218.817444) (xy 340.692486 -218.817698) (xy 340.672166 -218.827096)
			(xy 340.657942 -218.832938) (xy 340.640924 -218.858084) (xy 340.640924 -218.887802) (xy 340.58225 -218.97848)
			(xy 340.405974 -218.97848) (xy 340.3473 -218.887802) (xy 340.3473 -218.858084) (xy 340.330536 -218.832938)
			(xy 340.316312 -218.827096) (xy 340.295738 -218.817698) (xy 340.295738 -218.817444) (xy 340.250018 -218.794838)
			(xy 340.239604 -218.78798) (xy 340.198964 -218.753436) (xy 340.192614 -218.746832) (xy 340.175596 -218.726258)
			(arc
				(start 340.173818 -218.723972)
				(mid 340.164782 -218.713942)
				(end 340.154514 -218.705176)
			)
			(xy 340.153244 -218.704414) (xy 340.137242 -218.693238) (xy 340.130638 -218.68765)
			(arc
				(start 340.113112 -218.670378)
				(mid 340.059951 -218.598684)
				(end 340.0298 -218.514676)
			)
			(xy 340.0298 -218.52636)
			(arc
				(start 339.938614 -218.617292)
				(mid 339.925969 -218.638021)
				(end 339.92439 -218.66225)
			)
			(arc
				(start 339.92439 -218.66225)
				(mid 339.927992 -218.68894)
				(end 339.929216 -218.715844)
			)
			(arc
				(start 339.929216 -218.926664)
				(mid 339.933097 -218.945885)
				(end 339.943948 -218.962224)
			)
			(xy 339.959696 -218.978226)
			(arc
				(start 339.96757 -218.982036)
				(mid 340.093308 -219.094649)
				(end 340.140036 -219.256864)
			)
			(arc
				(start 340.140036 -220.073474)
				(mid 340.110905 -220.203314)
				(end 340.029292 -220.308424)
			)
			(arc
				(start 340.029292 -220.308424)
				(mid 340.002012 -220.343527)
				(end 339.992208 -220.38691)
			)
			(arc
				(start 339.992208 -220.438218)
				(mid 339.991271 -220.448186)
				(end 339.988398 -220.457776)
			)
			(arc
				(start 339.983318 -220.469968)
				(mid 339.981009 -220.501534)
				(end 339.997796 -220.528388)
			)
		)
		(stroke
			(width 0)
			(type solid)
		)
		(fill yes)
		(layer "B.Cu")
		(net "GND")
	)
	(gr_poly
		(pts
			(xy 341.753698 -91.0844) (xy 341.763686 -91.083863) (xy 341.782118 -91.07615) (xy 341.789512 -91.069414)
			(xy 342.515444 -90.343482) (xy 342.522293 -90.336085) (xy 342.53003 -90.317486) (xy 342.53043 -90.307414)
			(xy 342.53043 -88.65235) (xy 342.529999 -88.642283) (xy 342.522275 -88.623689) (xy 342.515444 -88.616282)
			(xy 342.163654 -88.264492) (xy 342.156803 -88.257096) (xy 342.149063 -88.238497) (xy 342.148668 -88.228424)
			(xy 342.148668 -87.027004) (xy 342.148017 -87.015071) (xy 342.137281 -86.993754) (xy 342.128094 -86.98611)
			(xy 342.05291 -86.930484) (xy 342.029288 -86.926166) (xy 342.017858 -86.929722) (xy 341.990938 -86.937336)
			(xy 341.935594 -86.945497) (xy 341.907622 -86.945978) (xy 341.88037 -86.945516) (xy 341.826421 -86.937762)
			(xy 341.774125 -86.92241) (xy 341.724546 -86.89977) (xy 341.678694 -86.870305) (xy 341.637501 -86.834614)
			(xy 341.601808 -86.793424) (xy 341.572341 -86.747574) (xy 341.549698 -86.697996) (xy 341.534342 -86.6457)
			(xy 341.526585 -86.591752) (xy 341.526585 -86.537248) (xy 341.534342 -86.4833) (xy 341.549698 -86.431004)
			(xy 341.572341 -86.381426) (xy 341.601808 -86.335576) (xy 341.637501 -86.294386) (xy 341.678694 -86.258695)
			(xy 341.724546 -86.22923) (xy 341.774125 -86.206591) (xy 341.826421 -86.191238) (xy 341.88037 -86.183484)
			(xy 341.907622 -86.182962) (xy 341.935593 -86.183451) (xy 341.990938 -86.191606) (xy 342.017858 -86.199218)
			(xy 342.029288 -86.202774) (xy 342.05291 -86.198456) (xy 342.128094 -86.14283) (xy 342.137326 -86.135222)
			(xy 342.148069 -86.113883) (xy 342.148668 -86.101936) (xy 342.148668 -86.025736) (xy 342.148761 -86.020717)
			(xy 342.150683 -86.010866) (xy 342.152478 -86.006178) (xy 342.159844 -85.988906) (xy 342.161641 -85.984219)
			(xy 342.163559 -85.974367) (xy 342.163654 -85.969348) (xy 342.163654 -82.92338) (xy 342.164082 -82.913313)
			(xy 342.171808 -82.894719) (xy 342.17864 -82.887312) (xy 342.33104 -82.734912) (xy 342.337895 -82.727517)
			(xy 342.345643 -82.708918) (xy 342.346026 -82.698844) (xy 342.346026 -82.438494) (xy 342.345603 -82.428424)
			(xy 342.33789 -82.409818) (xy 342.33104 -82.402426) (xy 342.308434 -82.37982) (xy 342.295988 -82.372962)
			(xy 342.288876 -82.371438) (xy 342.260992 -82.364697) (xy 342.207041 -82.345191) (xy 342.155951 -82.319096)
			(xy 342.108522 -82.286822) (xy 342.065498 -82.248873) (xy 342.027553 -82.205846) (xy 341.995283 -82.158414)
			(xy 341.969193 -82.107322) (xy 341.949692 -82.053369) (xy 341.942928 -82.02549) (xy 341.941404 -82.018378)
			(xy 341.934546 -82.005932) (xy 341.763096 -81.834482) (xy 341.755701 -81.827627) (xy 341.737102 -81.819881)
			(xy 341.727028 -81.819496) (xy 338.97697 -81.819496) (xy 338.966522 -81.820057) (xy 338.947376 -81.828446)
			(xy 338.939886 -81.835752) (xy 338.88172 -81.897982) (xy 338.874862 -81.917794) (xy 338.875624 -81.928462)
			(xy 338.876894 -81.96199) (xy 338.876404 -81.991958) (xy 338.868581 -82.05138) (xy 338.853068 -82.109273)
			(xy 338.830132 -82.164646) (xy 338.800165 -82.216552) (xy 338.763678 -82.264102) (xy 338.721298 -82.306482)
			(xy 338.673748 -82.342969) (xy 338.621842 -82.372936) (xy 338.566469 -82.395872) (xy 338.508576 -82.411385)
			(xy 338.449154 -82.419208) (xy 338.389218 -82.419208) (xy 338.329796 -82.411385) (xy 338.271903 -82.395872)
			(xy 338.21653 -82.372936) (xy 338.164624 -82.342969) (xy 338.117074 -82.306482) (xy 338.074694 -82.264102)
			(xy 338.038207 -82.216552) (xy 338.00824 -82.164646) (xy 337.985304 -82.109273) (xy 337.969791 -82.05138)
			(xy 337.961968 -81.991958) (xy 337.961478 -81.96199) (xy 337.962748 -81.928462) (xy 337.96351 -81.917794)
			(xy 337.956652 -81.897982) (xy 337.898486 -81.835752) (xy 337.891012 -81.828423) (xy 337.871857 -81.820038)
			(xy 337.861402 -81.819496) (xy 335.334356 -81.819496) (xy 335.324289 -81.819927) (xy 335.305696 -81.827652)
			(xy 335.298288 -81.834482) (xy 334.665828 -82.466942) (xy 334.658429 -82.473784) (xy 334.63983 -82.481501)
			(xy 334.62976 -82.481928) (xy 334.622648 -82.481928) (xy 334.612685 -82.482412) (xy 334.59426 -82.489999)
			(xy 334.586834 -82.49666) (xy 334.561434 -82.521806) (xy 334.554085 -82.528606) (xy 334.535622 -82.536313)
			(xy 334.52562 -82.536792) (xy 332.913736 -82.536792) (xy 332.903746 -82.536261) (xy 332.885305 -82.528556)
			(xy 332.877922 -82.521806) (xy 332.866238 -82.510122) (xy 332.858804 -82.503406) (xy 332.840304 -82.49577)
			(xy 332.82029 -82.49577) (xy 332.80179 -82.503406) (xy 332.794356 -82.510122) (xy 332.756256 -82.548222)
			(xy 332.748912 -82.555034) (xy 332.730449 -82.562763) (xy 332.720442 -82.563208) (xy 331.77861 -82.563208)
			(xy 331.768642 -82.563681) (xy 331.750198 -82.57125) (xy 331.742796 -82.57794) (xy 331.72527 -82.595466)
			(xy 331.718584 -82.602875) (xy 331.710994 -82.621311) (xy 331.710538 -82.63128) (xy 331.710538 -82.815172)
			(xy 340.199708 -82.815172) (xy 340.199708 -82.755236) (xy 340.207531 -82.695814) (xy 340.223044 -82.637921)
			(xy 340.24598 -82.582548) (xy 340.275947 -82.530642) (xy 340.312434 -82.483092) (xy 340.354814 -82.440712)
			(xy 340.402364 -82.404225) (xy 340.45427 -82.374258) (xy 340.509643 -82.351322) (xy 340.567536 -82.335809)
			(xy 340.626958 -82.327986) (xy 340.686894 -82.327986) (xy 340.746316 -82.335809) (xy 340.804209 -82.351322)
			(xy 340.859582 -82.374258) (xy 340.911488 -82.404225) (xy 340.959038 -82.440712) (xy 341.001418 -82.483092)
			(xy 341.037905 -82.530642) (xy 341.067872 -82.582548) (xy 341.090808 -82.637921) (xy 341.106321 -82.695814)
			(xy 341.114144 -82.755236) (xy 341.114634 -82.785204) (xy 341.114144 -82.815172) (xy 341.106321 -82.874594)
			(xy 341.090808 -82.932487) (xy 341.067872 -82.98786) (xy 341.037905 -83.039766) (xy 341.001418 -83.087316)
			(xy 340.959038 -83.129696) (xy 340.911488 -83.166183) (xy 340.859582 -83.19615) (xy 340.804209 -83.219086)
			(xy 340.746316 -83.234599) (xy 340.686894 -83.242422) (xy 340.626958 -83.242422) (xy 340.567536 -83.234599)
			(xy 340.509643 -83.219086) (xy 340.45427 -83.19615) (xy 340.402364 -83.166183) (xy 340.354814 -83.129696)
			(xy 340.312434 -83.087316) (xy 340.275947 -83.039766) (xy 340.24598 -82.98786) (xy 340.223044 -82.932487)
			(xy 340.207531 -82.874594) (xy 340.199708 -82.815172) (xy 331.710538 -82.815172) (xy 331.710538 -84.164424)
			(xy 331.709995 -84.174408) (xy 331.702268 -84.192828) (xy 331.695552 -84.200238) (xy 331.670152 -84.225892)
			(xy 331.663472 -84.233303) (xy 331.655894 -84.251739) (xy 331.65542 -84.261706) (xy 331.65542 -84.286598)
			(xy 331.655843 -84.296668) (xy 331.663559 -84.315271) (xy 331.670406 -84.322666) (xy 331.78877 -84.44103)
			(xy 331.796169 -84.447873) (xy 331.814768 -84.455593) (xy 331.824838 -84.456016) (xy 333.613506 -84.456016)
			(xy 333.623575 -84.456441) (xy 333.642177 -84.464158) (xy 333.649574 -84.471002) (xy 333.684372 -84.5058)
			(xy 333.68962 -84.510762) (xy 333.702269 -84.517718) (xy 333.709264 -84.519516) (xy 333.721456 -84.520786)
			(xy 333.805022 -84.519008) (xy 333.823818 -84.510626) (xy 333.83093 -84.503006) (xy 333.849042 -84.484061)
			(xy 333.889561 -84.450816) (xy 333.934251 -84.423433) (xy 333.982271 -84.402429) (xy 334.032715 -84.3882)
			(xy 334.084632 -84.381014) (xy 334.110838 -84.380578) (xy 334.138088 -84.381066) (xy 334.192034 -84.388828)
			(xy 334.244326 -84.404187) (xy 334.2939 -84.426831) (xy 334.339748 -84.456299) (xy 334.380935 -84.491992)
			(xy 334.416624 -84.533183) (xy 334.446088 -84.579033) (xy 334.468727 -84.628609) (xy 334.48408 -84.680903)
			(xy 334.491836 -84.734849) (xy 334.491836 -84.789351) (xy 334.48408 -84.843297) (xy 334.468727 -84.895591)
			(xy 334.446088 -84.945167) (xy 334.416624 -84.991017) (xy 334.380935 -85.032208) (xy 334.339748 -85.067901)
			(xy 334.2939 -85.097369) (xy 334.244326 -85.120013) (xy 334.192034 -85.135372) (xy 334.138088 -85.143134)
			(xy 334.110838 -85.143594) (xy 334.085454 -85.143179) (xy 334.035134 -85.136452) (xy 333.98615 -85.123113)
			(xy 333.939367 -85.103396) (xy 333.895612 -85.077649) (xy 333.87538 -85.062314) (xy 333.868776 -85.057234)
			(xy 333.849472 -85.050376) (xy 333.841235 -85.047756) (xy 333.823963 -85.047619) (xy 333.81569 -85.050122)
			(xy 333.778352 -85.06333) (xy 333.760826 -85.08365) (xy 333.758032 -85.096858) (xy 333.749396 -85.13318)
			(xy 333.747618 -85.139784) (xy 333.747618 -85.82914) (xy 333.747954 -85.837752) (xy 333.753638 -85.854011)
			(xy 333.764358 -85.867492) (xy 333.771494 -85.87232) (xy 333.795917 -85.888191) (xy 333.840921 -85.925171)
			(xy 333.88087 -85.96756) (xy 333.915119 -86.014675) (xy 333.943114 -86.065754) (xy 333.964403 -86.119972)
			(xy 333.978642 -86.176453) (xy 333.982568 -86.205314) (xy 333.983584 -86.21395) (xy 333.99095 -86.228936)
			(xy 334.000856 -86.238842) (xy 334.008255 -86.245686) (xy 334.026854 -86.253409) (xy 334.036924 -86.253828)
			(xy 335.456276 -86.253828) (xy 335.466327 -86.253323) (xy 335.484889 -86.245603) (xy 335.492344 -86.238842)
			(xy 335.65084 -86.080346) (xy 335.657685 -86.072948) (xy 335.665409 -86.054349) (xy 335.665826 -86.044278)
			(xy 335.665826 -84.730336) (xy 335.666261 -84.720272) (xy 335.673995 -84.701686) (xy 335.680812 -84.694268)
			(xy 335.75117 -84.62391) (xy 335.751424 -84.623656) (xy 335.75498 -84.6201) (xy 335.87055 -84.50453)
			(xy 335.874106 -84.500974) (xy 335.87436 -84.50072) (xy 335.944718 -84.430362) (xy 335.952115 -84.423512)
			(xy 335.970713 -84.415774) (xy 335.980786 -84.415376) (xy 340.391496 -84.415376) (xy 340.401567 -84.415798)
			(xy 340.420175 -84.423508) (xy 340.427564 -84.430362) (xy 340.525862 -84.52866) (xy 340.532703 -84.53606)
			(xy 340.540422 -84.554659) (xy 340.540848 -84.564728) (xy 340.540848 -88.961214) (xy 340.540421 -88.971282)
			(xy 340.532697 -88.989878) (xy 340.525862 -88.997282) (xy 340.513924 -89.00922) (xy 340.506812 -89.023698)
			(xy 340.505542 -89.03208) (xy 340.501691 -89.056583) (xy 340.487101 -89.103986) (xy 340.465049 -89.148411)
			(xy 340.436114 -89.188694) (xy 340.418928 -89.206578) (xy 340.34476 -89.280492) (xy 340.337985 -89.287918)
			(xy 340.330395 -89.306514) (xy 340.330028 -89.31656) (xy 340.330028 -89.670636) (xy 340.329563 -89.694641)
			(xy 340.322015 -89.742054) (xy 340.307142 -89.787703) (xy 340.285311 -89.830462) (xy 340.257059 -89.86928)
			(xy 340.240366 -89.886536) (xy 340.240112 -89.886536) (xy 340.038944 -90.087704) (xy 340.038944 -90.087958)
			(xy 340.021673 -90.104634) (xy 339.982862 -90.132891) (xy 339.940106 -90.154723) (xy 339.894459 -90.169592)
			(xy 339.847048 -90.17713) (xy 339.823044 -90.17762) (xy 338.608416 -90.17762) (xy 338.584413 -90.177152)
			(xy 338.537003 -90.169597) (xy 338.49136 -90.154718) (xy 338.448606 -90.132882) (xy 338.409795 -90.104626)
			(xy 338.392516 -90.087958) (xy 338.341462 -90.036904) (xy 338.324781 -90.019635) (xy 338.296515 -89.980826)
			(xy 338.274673 -89.938071) (xy 338.259795 -89.892423) (xy 338.252246 -89.845009) (xy 338.2518 -89.821004)
			(xy 338.2518 -89.55278) (xy 338.251308 -89.542775) (xy 338.243645 -89.52429) (xy 338.229493 -89.510143)
			(xy 338.211005 -89.502488) (xy 338.201 -89.50198) (xy 337.725258 -89.50198) (xy 337.715273 -89.502524)
			(xy 337.69685 -89.510246) (xy 337.689444 -89.516966) (xy 337.65363 -89.55278) (xy 337.63636 -89.569449)
			(xy 337.597549 -89.597682) (xy 337.554788 -89.619477) (xy 337.509138 -89.634294) (xy 337.461728 -89.641766)
			(xy 337.43773 -89.642188) (xy 337.356196 -89.642188) (xy 337.346213 -89.642725) (xy 337.327788 -89.650431)
			(xy 337.313679 -89.664566) (xy 337.306007 -89.683005) (xy 337.305396 -89.692988) (xy 337.305396 -89.771728)
			(xy 337.305904 -89.775284) (xy 337.307582 -89.788236) (xy 337.309361 -89.814294) (xy 337.30946 -89.827354)
			(xy 337.30946 -90.228928) (xy 337.30989 -90.238995) (xy 337.317618 -90.257586) (xy 337.324446 -90.264996)
			(xy 337.76539 -90.705686) (xy 337.784658 -90.725645) (xy 337.817796 -90.770133) (xy 337.84413 -90.818959)
			(xy 337.863102 -90.871088) (xy 337.87431 -90.925419) (xy 337.876388 -90.953082) (xy 337.87715 -90.967306)
			(xy 337.892644 -90.989912) (xy 337.99907 -91.03995) (xy 338.026248 -91.03741) (xy 338.037678 -91.029028)
			(xy 338.061292 -91.012275) (xy 338.111943 -90.984222) (xy 338.165731 -90.962792) (xy 338.221795 -90.948329)
			(xy 338.279238 -90.941063) (xy 338.308188 -90.940636) (xy 338.337587 -90.941089) (xy 338.3959 -90.948619)
			(xy 338.452769 -90.963557) (xy 338.507255 -90.985657) (xy 338.558461 -91.014555) (xy 338.605544 -91.049774)
			(xy 338.626958 -91.069922) (xy 338.634285 -91.076471) (xy 338.652449 -91.083923) (xy 338.662264 -91.0844)
		)
		(stroke
			(width 0)
			(type solid)
		)
		(fill yes)
		(layer "B.Cu")
		(net "P3V3_VDD_9ZXL0851_8_15")
	)
	(gr_poly
		(pts
			(xy 68.965318 -297.7134) (xy 68.975387 -297.712973) (xy 68.993986 -297.705254) (xy 69.001386 -297.698414)
			(xy 69.047614 -297.652186) (xy 69.054468 -297.644791) (xy 69.06221 -297.626192) (xy 69.0626 -297.616118)
			(xy 69.0626 -294.254682) (xy 69.063027 -294.244613) (xy 69.070746 -294.226014) (xy 69.077586 -294.218614)
			(xy 69.314314 -293.981886) (xy 69.321168 -293.974491) (xy 69.32891 -293.955892) (xy 69.3293 -293.945818)
			(xy 69.3293 -293.642288) (xy 69.326252 -293.633906) (xy 69.317231 -293.607573) (xy 69.307519 -293.552769)
			(xy 69.306948 -293.52494) (xy 69.307582 -293.497117) (xy 69.317289 -293.442322) (xy 69.326252 -293.415974)
			(xy 69.3293 -293.407592) (xy 69.3293 -292.692074) (xy 69.326252 -292.683692) (xy 69.317232 -292.657359)
			(xy 69.307522 -292.602555) (xy 69.306948 -292.574726) (xy 69.307584 -292.546903) (xy 69.317292 -292.492109)
			(xy 69.326252 -292.46576) (xy 69.3293 -292.457378) (xy 69.3293 -291.742114) (xy 69.326252 -291.733732)
			(xy 69.317229 -291.7074) (xy 69.307512 -291.652595) (xy 69.306948 -291.624766) (xy 69.30758 -291.596942)
			(xy 69.317282 -291.542146) (xy 69.326252 -291.5158) (xy 69.3293 -291.507418) (xy 69.3293 -290.792154)
			(xy 69.326252 -290.783772) (xy 69.317234 -290.757439) (xy 69.307527 -290.702635) (xy 69.306948 -290.674806)
			(xy 69.307585 -290.646983) (xy 69.317297 -290.59219) (xy 69.326252 -290.56584) (xy 69.3293 -290.557458)
			(xy 69.3293 -290.279582) (xy 69.328873 -290.269513) (xy 69.321154 -290.250914) (xy 69.314314 -290.243514)
			(xy 69.255386 -290.184586) (xy 69.247991 -290.177732) (xy 69.229392 -290.16999) (xy 69.219318 -290.1696)
			(xy 68.244974 -290.1696) (xy 68.219574 -290.186872) (xy 68.21678 -290.193222) (xy 68.178426 -290.23183)
			(xy 68.163419 -290.246315) (xy 68.130174 -290.2715) (xy 68.093814 -290.291932) (xy 68.07454 -290.299902)
			(xy 68.064634 -290.303966) (xy 68.061586 -290.307014) (xy 68.054191 -290.313868) (xy 68.035592 -290.32161)
			(xy 68.025518 -290.322) (xy 50.287682 -290.322) (xy 50.277613 -290.322427) (xy 50.259014 -290.330146)
			(xy 50.251614 -290.336986) (xy 50.179986 -290.408614) (xy 50.17262 -290.415726) (xy 50.165 -290.434522)
			(xy 50.165 -290.699795) (xy 68.357224 -290.699795) (xy 68.357224 -290.649817) (xy 68.365043 -290.600454)
			(xy 68.380487 -290.552922) (xy 68.403177 -290.50839) (xy 68.432553 -290.467957) (xy 68.467893 -290.432617)
			(xy 68.508326 -290.403241) (xy 68.552858 -290.380551) (xy 68.60039 -290.365107) (xy 68.649753 -290.357288)
			(xy 68.699731 -290.357288) (xy 68.749094 -290.365107) (xy 68.796626 -290.380551) (xy 68.841158 -290.403241)
			(xy 68.881591 -290.432617) (xy 68.916931 -290.467957) (xy 68.946307 -290.50839) (xy 68.968997 -290.552922)
			(xy 68.984441 -290.600454) (xy 68.99226 -290.649817) (xy 68.99275 -290.674806) (xy 68.99226 -290.699795)
			(xy 68.984441 -290.749158) (xy 68.968997 -290.79669) (xy 68.946307 -290.841222) (xy 68.916931 -290.881655)
			(xy 68.881591 -290.916995) (xy 68.841158 -290.946371) (xy 68.796626 -290.969061) (xy 68.749094 -290.984505)
			(xy 68.699731 -290.992324) (xy 68.649753 -290.992324) (xy 68.60039 -290.984505) (xy 68.552858 -290.969061)
			(xy 68.508326 -290.946371) (xy 68.467893 -290.916995) (xy 68.432553 -290.881655) (xy 68.403177 -290.841222)
			(xy 68.380487 -290.79669) (xy 68.365043 -290.749158) (xy 68.357224 -290.699795) (xy 50.165 -290.699795)
			(xy 50.165 -291.624766) (xy 50.306986 -291.624766) (xy 50.307451 -291.599776) (xy 50.315274 -291.550413)
			(xy 50.330723 -291.50288) (xy 50.353416 -291.45835) (xy 50.382796 -291.417917) (xy 50.418138 -291.382577)
			(xy 50.458574 -291.353201) (xy 50.503106 -291.330512) (xy 50.55064 -291.315068) (xy 50.600004 -291.307249)
			(xy 50.624994 -291.306758) (xy 50.645283 -291.307034) (xy 50.685538 -291.312136) (xy 50.705258 -291.316918)
			(xy 50.718212 -291.320474) (xy 50.744374 -291.313362) (xy 50.93462 -291.123116) (xy 50.942046 -291.116456)
			(xy 50.960472 -291.10887) (xy 50.970434 -291.108384) (xy 67.733672 -291.108384) (xy 67.757671 -291.108787)
			(xy 67.805081 -291.116265) (xy 67.850731 -291.131087) (xy 67.893491 -291.152886) (xy 67.932303 -291.181122)
			(xy 67.949572 -291.197792) (xy 68.097146 -291.345366) (xy 68.113836 -291.362625) (xy 68.14209 -291.401441)
			(xy 68.163922 -291.4442) (xy 68.178795 -291.489848) (xy 68.186343 -291.537261) (xy 68.186808 -291.561266)
			(xy 68.186808 -291.649755) (xy 68.357224 -291.649755) (xy 68.357224 -291.599777) (xy 68.365043 -291.550414)
			(xy 68.380487 -291.502882) (xy 68.403177 -291.45835) (xy 68.432553 -291.417917) (xy 68.467893 -291.382577)
			(xy 68.508326 -291.353201) (xy 68.552858 -291.330511) (xy 68.60039 -291.315067) (xy 68.649753 -291.307248)
			(xy 68.699731 -291.307248) (xy 68.749094 -291.315067) (xy 68.796626 -291.330511) (xy 68.841158 -291.353201)
			(xy 68.881591 -291.382577) (xy 68.916931 -291.417917) (xy 68.946307 -291.45835) (xy 68.968997 -291.502882)
			(xy 68.984441 -291.550414) (xy 68.99226 -291.599777) (xy 68.99275 -291.624766) (xy 68.99226 -291.649755)
			(xy 68.984441 -291.699118) (xy 68.968997 -291.74665) (xy 68.946307 -291.791182) (xy 68.916931 -291.831615)
			(xy 68.881591 -291.866955) (xy 68.841158 -291.896331) (xy 68.796626 -291.919021) (xy 68.749094 -291.934465)
			(xy 68.699731 -291.942284) (xy 68.649753 -291.942284) (xy 68.60039 -291.934465) (xy 68.552858 -291.919021)
			(xy 68.508326 -291.896331) (xy 68.467893 -291.866955) (xy 68.432553 -291.831615) (xy 68.403177 -291.791182)
			(xy 68.380487 -291.74665) (xy 68.365043 -291.699118) (xy 68.357224 -291.649755) (xy 68.186808 -291.649755)
			(xy 68.186808 -291.82441) (xy 68.186363 -291.848415) (xy 68.178814 -291.895829) (xy 68.163935 -291.941477)
			(xy 68.142093 -291.984232) (xy 68.113827 -292.023041) (xy 68.097146 -292.04031) (xy 68.000372 -292.137084)
			(xy 67.983048 -292.153686) (xy 67.944225 -292.181876) (xy 67.901474 -292.203655) (xy 67.855846 -292.218488)
			(xy 67.808461 -292.22601) (xy 67.784472 -292.226492) (xy 50.89271 -292.226492) (xy 50.88274 -292.226039)
			(xy 50.864304 -292.218449) (xy 50.856896 -292.21176) (xy 50.720244 -292.075108) (xy 50.712878 -292.071552)
			(xy 50.694075 -292.061641) (xy 50.659622 -292.036751) (xy 50.644298 -292.022022) (xy 50.563526 -291.940996)
			(xy 50.551842 -291.934392) (xy 50.545238 -291.932614) (xy 50.520002 -291.925558) (xy 50.47212 -291.904278)
			(xy 50.428375 -291.875436) (xy 50.389949 -291.839813) (xy 50.357882 -291.798374) (xy 50.333042 -291.752238)
			(xy 50.316101 -291.702655) (xy 50.307517 -291.650965) (xy 50.306986 -291.624766) (xy 50.165 -291.624766)
			(xy 50.165 -292.599715) (xy 68.357224 -292.599715) (xy 68.357224 -292.549737) (xy 68.365043 -292.500374)
			(xy 68.380487 -292.452842) (xy 68.403177 -292.40831) (xy 68.432553 -292.367877) (xy 68.467893 -292.332537)
			(xy 68.508326 -292.303161) (xy 68.552858 -292.280471) (xy 68.60039 -292.265027) (xy 68.649753 -292.257208)
			(xy 68.699731 -292.257208) (xy 68.749094 -292.265027) (xy 68.796626 -292.280471) (xy 68.841158 -292.303161)
			(xy 68.881591 -292.332537) (xy 68.916931 -292.367877) (xy 68.946307 -292.40831) (xy 68.968997 -292.452842)
			(xy 68.984441 -292.500374) (xy 68.99226 -292.549737) (xy 68.99275 -292.574726) (xy 68.99226 -292.599715)
			(xy 68.984441 -292.649078) (xy 68.968997 -292.69661) (xy 68.946307 -292.741142) (xy 68.916931 -292.781575)
			(xy 68.881591 -292.816915) (xy 68.841158 -292.846291) (xy 68.796626 -292.868981) (xy 68.749094 -292.884425)
			(xy 68.699731 -292.892244) (xy 68.649753 -292.892244) (xy 68.60039 -292.884425) (xy 68.552858 -292.868981)
			(xy 68.508326 -292.846291) (xy 68.467893 -292.816915) (xy 68.432553 -292.781575) (xy 68.403177 -292.741142)
			(xy 68.380487 -292.69661) (xy 68.365043 -292.649078) (xy 68.357224 -292.599715) (xy 50.165 -292.599715)
			(xy 50.165 -292.739318) (xy 50.165427 -292.749387) (xy 50.173146 -292.767986) (xy 50.179986 -292.775386)
			(xy 50.429414 -293.024814) (xy 50.436809 -293.031668) (xy 50.455408 -293.03941) (xy 50.465482 -293.0398)
			(xy 66.298318 -293.0398) (xy 66.308387 -293.040227) (xy 66.326986 -293.047946) (xy 66.334386 -293.054786)
			(xy 66.482468 -293.202868) (xy 66.485903 -293.206485) (xy 66.491405 -293.214802) (xy 66.49339 -293.219378)
			(xy 66.496438 -293.226236) (xy 66.508884 -293.239952) (xy 66.564002 -293.266876) (xy 66.590672 -293.265352)
			(xy 66.601848 -293.257986) (xy 66.621265 -293.245902) (xy 66.662827 -293.22682) (xy 66.706691 -293.213877)
			(xy 66.751955 -293.20734) (xy 66.774822 -293.206932) (xy 66.799811 -293.207399) (xy 66.849173 -293.215221)
			(xy 66.896703 -293.230668) (xy 66.941232 -293.253362) (xy 66.981662 -293.282742) (xy 67.016999 -293.318085)
			(xy 67.046371 -293.358521) (xy 67.069055 -293.403054) (xy 67.084494 -293.450587) (xy 67.092306 -293.499951)
			(xy 67.09283 -293.52494) (xy 67.092539 -293.544314) (xy 67.091856 -293.549885) (xy 67.407322 -293.549885)
			(xy 67.407322 -293.499915) (xy 67.415139 -293.45056) (xy 67.43058 -293.403035) (xy 67.453265 -293.358511)
			(xy 67.482636 -293.318083) (xy 67.51797 -293.282748) (xy 67.558395 -293.253375) (xy 67.602918 -293.230687)
			(xy 67.650442 -293.215243) (xy 67.699797 -293.207424) (xy 67.724782 -293.206932) (xy 67.745731 -293.20726)
			(xy 67.787268 -293.212739) (xy 67.807586 -293.217854) (xy 67.813936 -293.219632) (xy 68.585588 -293.219632)
			(xy 68.591938 -293.217854) (xy 68.612253 -293.212725) (xy 68.653792 -293.207247) (xy 68.674742 -293.206932)
			(xy 68.699732 -293.207346) (xy 68.749096 -293.21517) (xy 68.796629 -293.23062) (xy 68.84116 -293.253315)
			(xy 68.881592 -293.282696) (xy 68.916932 -293.31804) (xy 68.946307 -293.358476) (xy 68.968996 -293.40301)
			(xy 68.98444 -293.450545) (xy 68.992258 -293.49991) (xy 68.992258 -293.54989) (xy 68.98444 -293.599255)
			(xy 68.968996 -293.64679) (xy 68.946307 -293.691324) (xy 68.916932 -293.73176) (xy 68.881592 -293.767104)
			(xy 68.84116 -293.796485) (xy 68.796629 -293.81918) (xy 68.749096 -293.83463) (xy 68.699732 -293.842454)
			(xy 68.674742 -293.842948) (xy 68.653793 -293.842616) (xy 68.612256 -293.837139) (xy 68.591938 -293.832026)
			(xy 68.585588 -293.830248) (xy 67.813936 -293.830248) (xy 67.807586 -293.832026) (xy 67.78727 -293.83715)
			(xy 67.745732 -293.842631) (xy 67.724782 -293.842948) (xy 67.699797 -293.842376) (xy 67.650442 -293.834557)
			(xy 67.602918 -293.819113) (xy 67.558395 -293.796425) (xy 67.51797 -293.767052) (xy 67.482636 -293.731717)
			(xy 67.453265 -293.691289) (xy 67.43058 -293.646765) (xy 67.415139 -293.59924) (xy 67.407322 -293.549885)
			(xy 67.091856 -293.549885) (xy 67.087822 -293.582775) (xy 67.083432 -293.601648) (xy 67.081908 -293.607744)
			(xy 67.081908 -293.88562) (xy 67.081415 -293.900668) (xy 67.073621 -293.929739) (xy 67.058569 -293.955802)
			(xy 67.037286 -293.977082) (xy 67.01122 -293.992128) (xy 66.982148 -293.999917) (xy 66.9671 -294.000428)
			(xy 66.5861 -294.000428) (xy 66.570606 -293.999158) (xy 66.570352 -293.999158) (xy 66.559684 -293.997126)
			(xy 66.516504 -294.031416) (xy 66.507792 -294.038993) (xy 66.49775 -294.05976) (xy 66.4972 -294.071294)
			(xy 66.4972 -295.994074) (xy 66.497565 -296.002575) (xy 66.503222 -296.018612) (xy 66.51382 -296.031911)
			(xy 66.520822 -296.036746) (xy 66.60388 -296.089832) (xy 66.629788 -296.09161) (xy 66.641472 -296.086022)
			(xy 66.662475 -296.076784) (xy 66.706471 -296.063762) (xy 66.751881 -296.057191) (xy 66.774822 -296.056812)
			(xy 66.795771 -296.057132) (xy 66.837309 -296.062616) (xy 66.857626 -296.067734) (xy 66.863976 -296.069512)
			(xy 67.00012 -296.069512) (xy 67.135502 -296.069512) (xy 67.150547 -296.069961) (xy 67.179609 -296.077759)
			(xy 67.205659 -296.092821) (xy 67.226915 -296.114118) (xy 67.241927 -296.140197) (xy 67.249668 -296.169274)
			(xy 67.250056 -296.18432) (xy 67.250056 -296.37482) (xy 67.25031 -296.37482) (xy 67.25031 -296.56532)
			(xy 67.249819 -296.580347) (xy 67.242047 -296.60938) (xy 67.227036 -296.635418) (xy 67.205806 -296.656692)
			(xy 67.179799 -296.671756) (xy 67.150782 -296.679588) (xy 67.135756 -296.680128) (xy 66.863976 -296.680128)
			(xy 66.857626 -296.681906) (xy 66.837309 -296.687022) (xy 66.795771 -296.692506) (xy 66.774822 -296.692828)
			(xy 66.75188 -296.692448) (xy 66.706467 -296.685892) (xy 66.66247 -296.672869) (xy 66.641472 -296.663618)
			(xy 66.629788 -296.65803) (xy 66.60388 -296.659808) (xy 66.520822 -296.712894) (xy 66.513809 -296.717714)
			(xy 66.503217 -296.731021) (xy 66.49757 -296.747064) (xy 66.4972 -296.755566) (xy 66.4972 -297.641518)
			(xy 66.497627 -297.651587) (xy 66.505346 -297.670186) (xy 66.512186 -297.677586) (xy 66.533014 -297.698414)
			(xy 66.540409 -297.705268) (xy 66.559008 -297.71301) (xy 66.569082 -297.7134)
		)
		(stroke
			(width 0)
			(type solid)
		)
		(fill yes)
		(layer "B.Cu")
		(net "P0V8_SERDES_VDDA_PEX0")
	)
	(gr_poly
		(pts
			(xy 301.16526 -297.7134) (xy 301.175325 -297.712966) (xy 301.193914 -297.705236) (xy 301.201328 -297.698414)
			(xy 301.247556 -297.652186) (xy 301.254405 -297.644789) (xy 301.262141 -297.62619) (xy 301.262542 -297.616118)
			(xy 301.262542 -294.254682) (xy 301.26297 -294.244614) (xy 301.270693 -294.226019) (xy 301.277528 -294.218614)
			(xy 301.514256 -293.981886) (xy 301.521105 -293.974489) (xy 301.528841 -293.95589) (xy 301.529242 -293.945818)
			(xy 301.529242 -293.642288) (xy 301.526194 -293.633906) (xy 301.517174 -293.607573) (xy 301.507464 -293.552769)
			(xy 301.50689 -293.52494) (xy 301.507525 -293.497117) (xy 301.517232 -293.442322) (xy 301.526194 -293.415974)
			(xy 301.529242 -293.407592) (xy 301.529242 -292.692074) (xy 301.526194 -292.683692) (xy 301.517175 -292.657359)
			(xy 301.507467 -292.602555) (xy 301.50689 -292.574726) (xy 301.507526 -292.546903) (xy 301.517236 -292.492109)
			(xy 301.526194 -292.46576) (xy 301.529242 -292.457378) (xy 301.529242 -291.742114) (xy 301.526194 -291.733732)
			(xy 301.517172 -291.707399) (xy 301.507457 -291.652595) (xy 301.50689 -291.624766) (xy 301.507522 -291.596942)
			(xy 301.517226 -291.542146) (xy 301.526194 -291.5158) (xy 301.529242 -291.507418) (xy 301.529242 -290.792154)
			(xy 301.526194 -290.783772) (xy 301.517177 -290.757439) (xy 301.507472 -290.702635) (xy 301.50689 -290.674806)
			(xy 301.507527 -290.646983) (xy 301.517241 -290.592191) (xy 301.526194 -290.56584) (xy 301.529242 -290.557458)
			(xy 301.529242 -290.279582) (xy 301.528814 -290.269515) (xy 301.521089 -290.25092) (xy 301.514256 -290.243514)
			(xy 301.455328 -290.184586) (xy 301.44793 -290.177742) (xy 301.42933 -290.17002) (xy 301.41926 -290.1696)
			(xy 300.444916 -290.1696) (xy 300.419516 -290.186872) (xy 300.416722 -290.193222) (xy 300.378368 -290.23183)
			(xy 300.36336 -290.246312) (xy 300.330112 -290.271492) (xy 300.293749 -290.291917) (xy 300.274482 -290.299902)
			(xy 300.264576 -290.303966) (xy 300.261528 -290.307014) (xy 300.25413 -290.313858) (xy 300.23553 -290.32158)
			(xy 300.22546 -290.322) (xy 282.487624 -290.322) (xy 282.47756 -290.322437) (xy 282.458976 -290.330171)
			(xy 282.451556 -290.336986) (xy 282.379928 -290.408614) (xy 282.372562 -290.415726) (xy 282.364942 -290.434522)
			(xy 282.364942 -290.699795) (xy 300.557166 -290.699795) (xy 300.557166 -290.649817) (xy 300.564985 -290.600454)
			(xy 300.580429 -290.552922) (xy 300.603119 -290.50839) (xy 300.632495 -290.467957) (xy 300.667835 -290.432617)
			(xy 300.708268 -290.403241) (xy 300.7528 -290.380551) (xy 300.800332 -290.365107) (xy 300.849695 -290.357288)
			(xy 300.899673 -290.357288) (xy 300.949036 -290.365107) (xy 300.996568 -290.380551) (xy 301.0411 -290.403241)
			(xy 301.081533 -290.432617) (xy 301.116873 -290.467957) (xy 301.146249 -290.50839) (xy 301.168939 -290.552922)
			(xy 301.184383 -290.600454) (xy 301.192202 -290.649817) (xy 301.192692 -290.674806) (xy 301.192202 -290.699795)
			(xy 301.184383 -290.749158) (xy 301.168939 -290.79669) (xy 301.146249 -290.841222) (xy 301.116873 -290.881655)
			(xy 301.081533 -290.916995) (xy 301.0411 -290.946371) (xy 300.996568 -290.969061) (xy 300.949036 -290.984505)
			(xy 300.899673 -290.992324) (xy 300.849695 -290.992324) (xy 300.800332 -290.984505) (xy 300.7528 -290.969061)
			(xy 300.708268 -290.946371) (xy 300.667835 -290.916995) (xy 300.632495 -290.881655) (xy 300.603119 -290.841222)
			(xy 300.580429 -290.79669) (xy 300.564985 -290.749158) (xy 300.557166 -290.699795) (xy 282.364942 -290.699795)
			(xy 282.364942 -291.624766) (xy 282.506928 -291.624766) (xy 282.507325 -291.599772) (xy 282.51515 -291.5504)
			(xy 282.530603 -291.502861) (xy 282.553302 -291.458323) (xy 282.582688 -291.417886) (xy 282.618039 -291.382543)
			(xy 282.658483 -291.353165) (xy 282.703025 -291.330476) (xy 282.750569 -291.315034) (xy 282.799942 -291.30722)
			(xy 282.824936 -291.306758) (xy 282.845225 -291.307045) (xy 282.88548 -291.312139) (xy 282.9052 -291.316918)
			(xy 282.918154 -291.320474) (xy 282.944316 -291.313362) (xy 283.134562 -291.123116) (xy 283.141973 -291.116437)
			(xy 283.16041 -291.108862) (xy 283.170376 -291.108384) (xy 299.933614 -291.108384) (xy 299.957611 -291.108824)
			(xy 300.00502 -291.116293) (xy 300.050669 -291.131106) (xy 300.09343 -291.152897) (xy 300.132243 -291.181126)
			(xy 300.149514 -291.197792) (xy 300.297088 -291.345366) (xy 300.313785 -291.362618) (xy 300.342036 -291.401437)
			(xy 300.363866 -291.444198) (xy 300.378738 -291.489847) (xy 300.386285 -291.537261) (xy 300.38675 -291.561266)
			(xy 300.38675 -291.649755) (xy 300.557166 -291.649755) (xy 300.557166 -291.599777) (xy 300.564985 -291.550414)
			(xy 300.580429 -291.502882) (xy 300.603119 -291.45835) (xy 300.632495 -291.417917) (xy 300.667835 -291.382577)
			(xy 300.708268 -291.353201) (xy 300.7528 -291.330511) (xy 300.800332 -291.315067) (xy 300.849695 -291.307248)
			(xy 300.899673 -291.307248) (xy 300.949036 -291.315067) (xy 300.996568 -291.330511) (xy 301.0411 -291.353201)
			(xy 301.081533 -291.382577) (xy 301.116873 -291.417917) (xy 301.146249 -291.45835) (xy 301.168939 -291.502882)
			(xy 301.184383 -291.550414) (xy 301.192202 -291.599777) (xy 301.192692 -291.624766) (xy 301.192202 -291.649755)
			(xy 301.184383 -291.699118) (xy 301.168939 -291.74665) (xy 301.146249 -291.791182) (xy 301.116873 -291.831615)
			(xy 301.081533 -291.866955) (xy 301.0411 -291.896331) (xy 300.996568 -291.919021) (xy 300.949036 -291.934465)
			(xy 300.899673 -291.942284) (xy 300.849695 -291.942284) (xy 300.800332 -291.934465) (xy 300.7528 -291.919021)
			(xy 300.708268 -291.896331) (xy 300.667835 -291.866955) (xy 300.632495 -291.831615) (xy 300.603119 -291.791182)
			(xy 300.580429 -291.74665) (xy 300.564985 -291.699118) (xy 300.557166 -291.649755) (xy 300.38675 -291.649755)
			(xy 300.38675 -291.82441) (xy 300.386322 -291.848416) (xy 300.378771 -291.895832) (xy 300.363889 -291.94148)
			(xy 300.342043 -291.984235) (xy 300.313772 -292.023042) (xy 300.297088 -292.04031) (xy 300.200314 -292.137084)
			(xy 300.183016 -292.153714) (xy 300.144186 -292.1819) (xy 300.101428 -292.203674) (xy 300.055795 -292.2185)
			(xy 300.008405 -292.226014) (xy 299.984414 -292.226492) (xy 283.092652 -292.226492) (xy 283.082671 -292.226085)
			(xy 283.064209 -292.218501) (xy 283.056838 -292.21176) (xy 282.920186 -292.075108) (xy 282.91282 -292.071552)
			(xy 282.894021 -292.061634) (xy 282.859566 -292.036749) (xy 282.84424 -292.022022) (xy 282.763468 -291.940996)
			(xy 282.751784 -291.934392) (xy 282.74518 -291.932614) (xy 282.719952 -291.925531) (xy 282.67207 -291.904257)
			(xy 282.628323 -291.87542) (xy 282.589895 -291.839802) (xy 282.557827 -291.798366) (xy 282.532986 -291.752233)
			(xy 282.516044 -291.702652) (xy 282.507459 -291.650964) (xy 282.506928 -291.624766) (xy 282.364942 -291.624766)
			(xy 282.364942 -292.599715) (xy 300.557166 -292.599715) (xy 300.557166 -292.549737) (xy 300.564985 -292.500374)
			(xy 300.580429 -292.452842) (xy 300.603119 -292.40831) (xy 300.632495 -292.367877) (xy 300.667835 -292.332537)
			(xy 300.708268 -292.303161) (xy 300.7528 -292.280471) (xy 300.800332 -292.265027) (xy 300.849695 -292.257208)
			(xy 300.899673 -292.257208) (xy 300.949036 -292.265027) (xy 300.996568 -292.280471) (xy 301.0411 -292.303161)
			(xy 301.081533 -292.332537) (xy 301.116873 -292.367877) (xy 301.146249 -292.40831) (xy 301.168939 -292.452842)
			(xy 301.184383 -292.500374) (xy 301.192202 -292.549737) (xy 301.192692 -292.574726) (xy 301.192202 -292.599715)
			(xy 301.184383 -292.649078) (xy 301.168939 -292.69661) (xy 301.146249 -292.741142) (xy 301.116873 -292.781575)
			(xy 301.081533 -292.816915) (xy 301.0411 -292.846291) (xy 300.996568 -292.868981) (xy 300.949036 -292.884425)
			(xy 300.899673 -292.892244) (xy 300.849695 -292.892244) (xy 300.800332 -292.884425) (xy 300.7528 -292.868981)
			(xy 300.708268 -292.846291) (xy 300.667835 -292.816915) (xy 300.632495 -292.781575) (xy 300.603119 -292.741142)
			(xy 300.580429 -292.69661) (xy 300.564985 -292.649078) (xy 300.557166 -292.599715) (xy 282.364942 -292.599715)
			(xy 282.364942 -292.739318) (xy 282.36537 -292.749386) (xy 282.373093 -292.767981) (xy 282.379928 -292.775386)
			(xy 282.629356 -293.024814) (xy 282.636753 -293.031661) (xy 282.655353 -293.039388) (xy 282.665424 -293.0398)
			(xy 298.49826 -293.0398) (xy 298.508325 -293.040234) (xy 298.526914 -293.047964) (xy 298.534328 -293.054786)
			(xy 298.68241 -293.202868) (xy 298.685842 -293.206486) (xy 298.69134 -293.214805) (xy 298.693332 -293.219378)
			(xy 298.69638 -293.226236) (xy 298.708826 -293.239952) (xy 298.763944 -293.266876) (xy 298.790614 -293.265352)
			(xy 298.80179 -293.257986) (xy 298.821206 -293.245899) (xy 298.862767 -293.226809) (xy 298.906631 -293.213858)
			(xy 298.951896 -293.207313) (xy 298.974764 -293.206932) (xy 298.999756 -293.207394) (xy 299.049125 -293.215209)
			(xy 299.096663 -293.230652) (xy 299.1412 -293.253342) (xy 299.181638 -293.282721) (xy 299.216982 -293.318065)
			(xy 299.24636 -293.358503) (xy 299.26905 -293.40304) (xy 299.284492 -293.450579) (xy 299.292306 -293.499948)
			(xy 299.292772 -293.52494) (xy 299.292481 -293.544314) (xy 299.291797 -293.549889) (xy 299.607197 -293.549889)
			(xy 299.607197 -293.499911) (xy 299.615016 -293.450548) (xy 299.630461 -293.403016) (xy 299.653151 -293.358485)
			(xy 299.682529 -293.318052) (xy 299.717871 -293.282714) (xy 299.758305 -293.253339) (xy 299.802838 -293.230651)
			(xy 299.850371 -293.21521) (xy 299.899735 -293.207395) (xy 299.924724 -293.206932) (xy 299.945673 -293.207252)
			(xy 299.987211 -293.212737) (xy 300.007528 -293.217854) (xy 300.013878 -293.219632) (xy 300.78553 -293.219632)
			(xy 300.79188 -293.217854) (xy 300.812197 -293.212736) (xy 300.853735 -293.207251) (xy 300.874684 -293.206932)
			(xy 300.899679 -293.207315) (xy 300.949054 -293.215133) (xy 300.996599 -293.230579) (xy 301.041141 -293.253273)
			(xy 301.081585 -293.282655) (xy 301.116934 -293.318003) (xy 301.146319 -293.358445) (xy 301.169015 -293.402987)
			(xy 301.184463 -293.45053) (xy 301.192283 -293.499905) (xy 301.192283 -293.549895) (xy 301.184463 -293.59927)
			(xy 301.169015 -293.646813) (xy 301.146319 -293.691355) (xy 301.116934 -293.731797) (xy 301.081585 -293.767145)
			(xy 301.041141 -293.796527) (xy 300.996599 -293.819221) (xy 300.949054 -293.834667) (xy 300.899679 -293.842485)
			(xy 300.874684 -293.842948) (xy 300.853735 -293.842627) (xy 300.812197 -293.837143) (xy 300.79188 -293.832026)
			(xy 300.78553 -293.830248) (xy 300.013878 -293.830248) (xy 300.007528 -293.832026) (xy 299.98721 -293.837142)
			(xy 299.945673 -293.842628) (xy 299.924724 -293.842948) (xy 299.899735 -293.842405) (xy 299.850371 -293.83459)
			(xy 299.802838 -293.819149) (xy 299.758305 -293.796461) (xy 299.717871 -293.767086) (xy 299.682529 -293.731748)
			(xy 299.653151 -293.691315) (xy 299.630461 -293.646784) (xy 299.615016 -293.599252) (xy 299.607197 -293.549889)
			(xy 299.291797 -293.549889) (xy 299.287763 -293.582775) (xy 299.283374 -293.601648) (xy 299.28185 -293.607744)
			(xy 299.28185 -293.88562) (xy 299.281357 -293.90067) (xy 299.273564 -293.929745) (xy 299.258513 -293.955813)
			(xy 299.237231 -293.9771) (xy 299.211165 -293.992155) (xy 299.182092 -293.999954) (xy 299.167042 -294.000428)
			(xy 298.786042 -294.000428) (xy 298.770548 -293.999158) (xy 298.770294 -293.999158) (xy 298.759626 -293.997126)
			(xy 298.716446 -294.031416) (xy 298.707742 -294.038998) (xy 298.697712 -294.059763) (xy 298.697142 -294.071294)
			(xy 298.697142 -295.994074) (xy 298.697506 -296.002576) (xy 298.703159 -296.018618) (xy 298.71375 -296.031927)
			(xy 298.720764 -296.036746) (xy 298.803822 -296.089832) (xy 298.82973 -296.09161) (xy 298.841414 -296.086022)
			(xy 298.862418 -296.076787) (xy 298.906414 -296.06377) (xy 298.951823 -296.057206) (xy 298.974764 -296.056812)
			(xy 298.995714 -296.057128) (xy 299.037253 -296.062605) (xy 299.057568 -296.067734) (xy 299.063918 -296.069512)
			(xy 299.200062 -296.069512) (xy 299.335444 -296.069512) (xy 299.350485 -296.069966) (xy 299.379539 -296.077771)
			(xy 299.405578 -296.092836) (xy 299.426826 -296.114132) (xy 299.441831 -296.140206) (xy 299.449568 -296.169278)
			(xy 299.449998 -296.18432) (xy 299.449998 -296.37482) (xy 299.450252 -296.37482) (xy 299.450252 -296.56532)
			(xy 299.449762 -296.580349) (xy 299.44199 -296.609386) (xy 299.42698 -296.635429) (xy 299.405751 -296.65671)
			(xy 299.379744 -296.671783) (xy 299.350726 -296.679625) (xy 299.335698 -296.680128) (xy 299.063918 -296.680128)
			(xy 299.057568 -296.681906) (xy 299.03725 -296.687018) (xy 298.995713 -296.692495) (xy 298.974764 -296.692828)
			(xy 298.951823 -296.692444) (xy 298.906413 -296.68588) (xy 298.862419 -296.67285) (xy 298.841414 -296.663618)
			(xy 298.82973 -296.65803) (xy 298.803822 -296.659808) (xy 298.720764 -296.712894) (xy 298.713747 -296.717712)
			(xy 298.703146 -296.731016) (xy 298.697493 -296.747062) (xy 298.697142 -296.755566) (xy 298.697142 -297.641518)
			(xy 298.69757 -297.651586) (xy 298.705293 -297.670181) (xy 298.712128 -297.677586) (xy 298.732956 -297.698414)
			(xy 298.740353 -297.705261) (xy 298.758953 -297.712988) (xy 298.769024 -297.7134)
		)
		(stroke
			(width 0)
			(type solid)
		)
		(fill yes)
		(layer "B.Cu")
		(net "P0V8_SERDES_VDDA_PEX2")
	)
	(gr_poly
		(pts
			(xy 417.265358 -297.7134) (xy 417.275423 -297.712966) (xy 417.294013 -297.705237) (xy 417.301426 -297.698414)
			(xy 417.347654 -297.652186) (xy 417.354503 -297.644789) (xy 417.36224 -297.62619) (xy 417.36264 -297.616118)
			(xy 417.36264 -294.254682) (xy 417.363068 -294.244614) (xy 417.370791 -294.226018) (xy 417.377626 -294.218614)
			(xy 417.614354 -293.981886) (xy 417.621203 -293.974489) (xy 417.62894 -293.95589) (xy 417.62934 -293.945818)
			(xy 417.62934 -293.642288) (xy 417.626292 -293.633906) (xy 417.617272 -293.607573) (xy 417.607562 -293.552769)
			(xy 417.606988 -293.52494) (xy 417.607622 -293.497117) (xy 417.61733 -293.442322) (xy 417.626292 -293.415974)
			(xy 417.62934 -293.407592) (xy 417.62934 -292.692074) (xy 417.626292 -292.683692) (xy 417.617273 -292.657359)
			(xy 417.607565 -292.602555) (xy 417.606988 -292.574726) (xy 417.607624 -292.546903) (xy 417.617334 -292.492109)
			(xy 417.626292 -292.46576) (xy 417.62934 -292.457378) (xy 417.62934 -291.742114) (xy 417.626292 -291.733732)
			(xy 417.61727 -291.707399) (xy 417.607555 -291.652595) (xy 417.606988 -291.624766) (xy 417.60762 -291.596942)
			(xy 417.617324 -291.542146) (xy 417.626292 -291.5158) (xy 417.62934 -291.507418) (xy 417.62934 -290.792154)
			(xy 417.626292 -290.783772) (xy 417.617275 -290.757439) (xy 417.60757 -290.702635) (xy 417.606988 -290.674806)
			(xy 417.607625 -290.646983) (xy 417.617339 -290.592191) (xy 417.626292 -290.56584) (xy 417.62934 -290.557458)
			(xy 417.62934 -290.279582) (xy 417.628912 -290.269515) (xy 417.621186 -290.250921) (xy 417.614354 -290.243514)
			(xy 417.555426 -290.184586) (xy 417.548028 -290.177742) (xy 417.529428 -290.170021) (xy 417.519358 -290.1696)
			(xy 416.545014 -290.1696) (xy 416.519614 -290.186872) (xy 416.51682 -290.193222) (xy 416.478466 -290.23183)
			(xy 416.463458 -290.246312) (xy 416.43021 -290.271492) (xy 416.393847 -290.291917) (xy 416.37458 -290.299902)
			(xy 416.364674 -290.303966) (xy 416.361626 -290.307014) (xy 416.354228 -290.313858) (xy 416.335628 -290.321579)
			(xy 416.325558 -290.322) (xy 398.587722 -290.322) (xy 398.577658 -290.322438) (xy 398.559074 -290.330172)
			(xy 398.551654 -290.336986) (xy 398.480026 -290.408614) (xy 398.47266 -290.415726) (xy 398.46504 -290.434522)
			(xy 398.46504 -290.699795) (xy 416.657264 -290.699795) (xy 416.657264 -290.649817) (xy 416.665083 -290.600454)
			(xy 416.680527 -290.552922) (xy 416.703217 -290.50839) (xy 416.732593 -290.467957) (xy 416.767933 -290.432617)
			(xy 416.808366 -290.403241) (xy 416.852898 -290.380551) (xy 416.90043 -290.365107) (xy 416.949793 -290.357288)
			(xy 416.999771 -290.357288) (xy 417.049134 -290.365107) (xy 417.096666 -290.380551) (xy 417.141198 -290.403241)
			(xy 417.181631 -290.432617) (xy 417.216971 -290.467957) (xy 417.246347 -290.50839) (xy 417.269037 -290.552922)
			(xy 417.284481 -290.600454) (xy 417.2923 -290.649817) (xy 417.29279 -290.674806) (xy 417.2923 -290.699795)
			(xy 417.284481 -290.749158) (xy 417.269037 -290.79669) (xy 417.246347 -290.841222) (xy 417.216971 -290.881655)
			(xy 417.181631 -290.916995) (xy 417.141198 -290.946371) (xy 417.096666 -290.969061) (xy 417.049134 -290.984505)
			(xy 416.999771 -290.992324) (xy 416.949793 -290.992324) (xy 416.90043 -290.984505) (xy 416.852898 -290.969061)
			(xy 416.808366 -290.946371) (xy 416.767933 -290.916995) (xy 416.732593 -290.881655) (xy 416.703217 -290.841222)
			(xy 416.680527 -290.79669) (xy 416.665083 -290.749158) (xy 416.657264 -290.699795) (xy 398.46504 -290.699795)
			(xy 398.46504 -291.624766) (xy 398.607026 -291.624766) (xy 398.607451 -291.599774) (xy 398.615276 -291.550407)
			(xy 398.630726 -291.502871) (xy 398.653423 -291.458338) (xy 398.682807 -291.417903) (xy 398.718155 -291.382563)
			(xy 398.758596 -291.353188) (xy 398.803134 -291.3305) (xy 398.850673 -291.31506) (xy 398.900042 -291.307246)
			(xy 398.925034 -291.306758) (xy 398.945323 -291.307045) (xy 398.985578 -291.31214) (xy 399.005298 -291.316918)
			(xy 399.018252 -291.320474) (xy 399.044414 -291.313362) (xy 399.23466 -291.123116) (xy 399.242072 -291.116438)
			(xy 399.260508 -291.108863) (xy 399.270474 -291.108384) (xy 416.033712 -291.108384) (xy 416.057709 -291.108825)
			(xy 416.105117 -291.116294) (xy 416.150767 -291.131106) (xy 416.193528 -291.152897) (xy 416.232341 -291.181126)
			(xy 416.249612 -291.197792) (xy 416.397186 -291.345366) (xy 416.413883 -291.362618) (xy 416.442134 -291.401437)
			(xy 416.463964 -291.444198) (xy 416.478836 -291.489847) (xy 416.486383 -291.537261) (xy 416.486848 -291.561266)
			(xy 416.486848 -291.649755) (xy 416.657264 -291.649755) (xy 416.657264 -291.599777) (xy 416.665083 -291.550414)
			(xy 416.680527 -291.502882) (xy 416.703217 -291.45835) (xy 416.732593 -291.417917) (xy 416.767933 -291.382577)
			(xy 416.808366 -291.353201) (xy 416.852898 -291.330511) (xy 416.90043 -291.315067) (xy 416.949793 -291.307248)
			(xy 416.999771 -291.307248) (xy 417.049134 -291.315067) (xy 417.096666 -291.330511) (xy 417.141198 -291.353201)
			(xy 417.181631 -291.382577) (xy 417.216971 -291.417917) (xy 417.246347 -291.45835) (xy 417.269037 -291.502882)
			(xy 417.284481 -291.550414) (xy 417.2923 -291.599777) (xy 417.29279 -291.624766) (xy 417.2923 -291.649755)
			(xy 417.284481 -291.699118) (xy 417.269037 -291.74665) (xy 417.246347 -291.791182) (xy 417.216971 -291.831615)
			(xy 417.181631 -291.866955) (xy 417.141198 -291.896331) (xy 417.096666 -291.919021) (xy 417.049134 -291.934465)
			(xy 416.999771 -291.942284) (xy 416.949793 -291.942284) (xy 416.90043 -291.934465) (xy 416.852898 -291.919021)
			(xy 416.808366 -291.896331) (xy 416.767933 -291.866955) (xy 416.732593 -291.831615) (xy 416.703217 -291.791182)
			(xy 416.680527 -291.74665) (xy 416.665083 -291.699118) (xy 416.657264 -291.649755) (xy 416.486848 -291.649755)
			(xy 416.486848 -291.82441) (xy 416.486421 -291.848416) (xy 416.47887 -291.895832) (xy 416.463988 -291.94148)
			(xy 416.442141 -291.984235) (xy 416.41387 -292.023042) (xy 416.397186 -292.04031) (xy 416.300412 -292.137084)
			(xy 416.283115 -292.153715) (xy 416.244284 -292.181901) (xy 416.201527 -292.203675) (xy 416.155893 -292.2185)
			(xy 416.108503 -292.226014) (xy 416.084512 -292.226492) (xy 399.19275 -292.226492) (xy 399.182769 -292.226086)
			(xy 399.164307 -292.218501) (xy 399.156936 -292.21176) (xy 399.020284 -292.075108) (xy 399.012918 -292.071552)
			(xy 398.994119 -292.061634) (xy 398.959664 -292.036749) (xy 398.944338 -292.022022) (xy 398.863566 -291.940996)
			(xy 398.851882 -291.934392) (xy 398.845278 -291.932614) (xy 398.82005 -291.925532) (xy 398.772167 -291.904258)
			(xy 398.728421 -291.875421) (xy 398.689993 -291.839803) (xy 398.657925 -291.798366) (xy 398.633084 -291.752233)
			(xy 398.616142 -291.702652) (xy 398.607557 -291.650964) (xy 398.607026 -291.624766) (xy 398.46504 -291.624766)
			(xy 398.46504 -292.599715) (xy 416.657264 -292.599715) (xy 416.657264 -292.549737) (xy 416.665083 -292.500374)
			(xy 416.680527 -292.452842) (xy 416.703217 -292.40831) (xy 416.732593 -292.367877) (xy 416.767933 -292.332537)
			(xy 416.808366 -292.303161) (xy 416.852898 -292.280471) (xy 416.90043 -292.265027) (xy 416.949793 -292.257208)
			(xy 416.999771 -292.257208) (xy 417.049134 -292.265027) (xy 417.096666 -292.280471) (xy 417.141198 -292.303161)
			(xy 417.181631 -292.332537) (xy 417.216971 -292.367877) (xy 417.246347 -292.40831) (xy 417.269037 -292.452842)
			(xy 417.284481 -292.500374) (xy 417.2923 -292.549737) (xy 417.29279 -292.574726) (xy 417.2923 -292.599715)
			(xy 417.284481 -292.649078) (xy 417.269037 -292.69661) (xy 417.246347 -292.741142) (xy 417.216971 -292.781575)
			(xy 417.181631 -292.816915) (xy 417.141198 -292.846291) (xy 417.096666 -292.868981) (xy 417.049134 -292.884425)
			(xy 416.999771 -292.892244) (xy 416.949793 -292.892244) (xy 416.90043 -292.884425) (xy 416.852898 -292.868981)
			(xy 416.808366 -292.846291) (xy 416.767933 -292.816915) (xy 416.732593 -292.781575) (xy 416.703217 -292.741142)
			(xy 416.680527 -292.69661) (xy 416.665083 -292.649078) (xy 416.657264 -292.599715) (xy 398.46504 -292.599715)
			(xy 398.46504 -292.739318) (xy 398.465468 -292.749386) (xy 398.473191 -292.767982) (xy 398.480026 -292.775386)
			(xy 398.729454 -293.024814) (xy 398.736851 -293.031661) (xy 398.755451 -293.039389) (xy 398.765522 -293.0398)
			(xy 414.598358 -293.0398) (xy 414.608423 -293.040234) (xy 414.627013 -293.047963) (xy 414.634426 -293.054786)
			(xy 414.782508 -293.202868) (xy 414.78594 -293.206486) (xy 414.791439 -293.214805) (xy 414.79343 -293.219378)
			(xy 414.796478 -293.226236) (xy 414.808924 -293.239952) (xy 414.864042 -293.266876) (xy 414.890712 -293.265352)
			(xy 414.901888 -293.257986) (xy 414.921304 -293.245899) (xy 414.962865 -293.226808) (xy 415.006729 -293.213857)
			(xy 415.051994 -293.207312) (xy 415.074862 -293.206932) (xy 415.099854 -293.207394) (xy 415.149223 -293.215209)
			(xy 415.196762 -293.230651) (xy 415.241299 -293.253341) (xy 415.281737 -293.28272) (xy 415.317081 -293.318064)
			(xy 415.34646 -293.358503) (xy 415.36915 -293.40304) (xy 415.384592 -293.450579) (xy 415.392406 -293.499948)
			(xy 415.39287 -293.52494) (xy 415.392579 -293.544314) (xy 415.391895 -293.549889) (xy 415.707297 -293.549889)
			(xy 415.707297 -293.499911) (xy 415.715116 -293.450548) (xy 415.73056 -293.403016) (xy 415.753251 -293.358485)
			(xy 415.782629 -293.318053) (xy 415.81797 -293.282714) (xy 415.858404 -293.253339) (xy 415.902936 -293.230652)
			(xy 415.950469 -293.21521) (xy 415.999833 -293.207395) (xy 416.024822 -293.206932) (xy 416.045771 -293.207252)
			(xy 416.087309 -293.212737) (xy 416.107626 -293.217854) (xy 416.113976 -293.219632) (xy 416.885628 -293.219632)
			(xy 416.891978 -293.217854) (xy 416.912295 -293.212736) (xy 416.953833 -293.207251) (xy 416.974782 -293.206932)
			(xy 416.999777 -293.207315) (xy 417.049153 -293.215133) (xy 417.096697 -293.230579) (xy 417.14124 -293.253272)
			(xy 417.181684 -293.282654) (xy 417.217034 -293.318002) (xy 417.246418 -293.358445) (xy 417.269114 -293.402986)
			(xy 417.284563 -293.45053) (xy 417.292383 -293.499905) (xy 417.292383 -293.549895) (xy 417.284563 -293.59927)
			(xy 417.269114 -293.646814) (xy 417.246418 -293.691355) (xy 417.217034 -293.731798) (xy 417.181684 -293.767146)
			(xy 417.14124 -293.796528) (xy 417.096697 -293.819221) (xy 417.049153 -293.834667) (xy 416.999777 -293.842485)
			(xy 416.974782 -293.842948) (xy 416.953833 -293.842628) (xy 416.912295 -293.837143) (xy 416.891978 -293.832026)
			(xy 416.885628 -293.830248) (xy 416.113976 -293.830248) (xy 416.107626 -293.832026) (xy 416.087308 -293.837143)
			(xy 416.045771 -293.842628) (xy 416.024822 -293.842948) (xy 415.999833 -293.842405) (xy 415.950469 -293.83459)
			(xy 415.902936 -293.819148) (xy 415.858404 -293.796461) (xy 415.81797 -293.767086) (xy 415.782629 -293.731747)
			(xy 415.753251 -293.691315) (xy 415.73056 -293.646784) (xy 415.715116 -293.599252) (xy 415.707297 -293.549889)
			(xy 415.391895 -293.549889) (xy 415.387861 -293.582775) (xy 415.383472 -293.601648) (xy 415.381948 -293.607744)
			(xy 415.381948 -293.88562) (xy 415.381455 -293.90067) (xy 415.373662 -293.929745) (xy 415.358611 -293.955813)
			(xy 415.337329 -293.977099) (xy 415.311263 -293.992154) (xy 415.28219 -293.999952) (xy 415.26714 -294.000428)
			(xy 414.88614 -294.000428) (xy 414.870646 -293.999158) (xy 414.870392 -293.999158) (xy 414.859724 -293.997126)
			(xy 414.816544 -294.031416) (xy 414.80784 -294.038998) (xy 414.79781 -294.059763) (xy 414.79724 -294.071294)
			(xy 414.79724 -295.994074) (xy 414.797604 -296.002577) (xy 414.803256 -296.018618) (xy 414.813848 -296.031927)
			(xy 414.820862 -296.036746) (xy 414.90392 -296.089832) (xy 414.929828 -296.09161) (xy 414.941512 -296.086022)
			(xy 414.962516 -296.076787) (xy 415.006512 -296.06377) (xy 415.051921 -296.057205) (xy 415.074862 -296.056812)
			(xy 415.095812 -296.057128) (xy 415.137351 -296.062605) (xy 415.157666 -296.067734) (xy 415.164016 -296.069512)
			(xy 415.30016 -296.069512) (xy 415.435542 -296.069512) (xy 415.450584 -296.069966) (xy 415.479637 -296.07777)
			(xy 415.505677 -296.092835) (xy 415.526925 -296.114132) (xy 415.54193 -296.140206) (xy 415.549668 -296.169277)
			(xy 415.550096 -296.18432) (xy 415.550096 -296.37482) (xy 415.55035 -296.37482) (xy 415.55035 -296.56532)
			(xy 415.54986 -296.580349) (xy 415.542088 -296.609386) (xy 415.527078 -296.635429) (xy 415.505849 -296.656709)
			(xy 415.479842 -296.671782) (xy 415.450824 -296.679623) (xy 415.435796 -296.680128) (xy 415.164016 -296.680128)
			(xy 415.157666 -296.681906) (xy 415.137348 -296.687018) (xy 415.095811 -296.692494) (xy 415.074862 -296.692828)
			(xy 415.051921 -296.692443) (xy 415.006511 -296.685879) (xy 414.962518 -296.67285) (xy 414.941512 -296.663618)
			(xy 414.929828 -296.65803) (xy 414.90392 -296.659808) (xy 414.820862 -296.712894) (xy 414.813845 -296.717712)
			(xy 414.803244 -296.731017) (xy 414.797592 -296.747062) (xy 414.79724 -296.755566) (xy 414.79724 -297.641518)
			(xy 414.797668 -297.651586) (xy 414.805391 -297.670182) (xy 414.812226 -297.677586) (xy 414.833054 -297.698414)
			(xy 414.840451 -297.705261) (xy 414.859051 -297.712989) (xy 414.869122 -297.7134)
		)
		(stroke
			(width 0)
			(type solid)
		)
		(fill yes)
		(layer "B.Cu")
		(net "P0V8_SERDES_VDDA_PEX3")
	)
	(gr_poly
		(pts
			(xy 185.094372 -297.70578) (xy 185.101484 -297.698414) (xy 185.147712 -297.652186) (xy 185.154566 -297.644791)
			(xy 185.162309 -297.626192) (xy 185.162698 -297.616118) (xy 185.162698 -294.254682) (xy 185.163125 -294.244613)
			(xy 185.170843 -294.226013) (xy 185.177684 -294.218614) (xy 185.414412 -293.981886) (xy 185.421266 -293.974491)
			(xy 185.429009 -293.955892) (xy 185.429398 -293.945818) (xy 185.429398 -293.642288) (xy 185.42635 -293.633906)
			(xy 185.417329 -293.607573) (xy 185.407617 -293.552769) (xy 185.407046 -293.52494) (xy 185.40768 -293.497117)
			(xy 185.417387 -293.442322) (xy 185.42635 -293.415974) (xy 185.429398 -293.407592) (xy 185.429398 -292.692074)
			(xy 185.42635 -292.683692) (xy 185.41733 -292.657359) (xy 185.40762 -292.602555) (xy 185.407046 -292.574726)
			(xy 185.407682 -292.546903) (xy 185.41739 -292.492109) (xy 185.42635 -292.46576) (xy 185.429398 -292.457378)
			(xy 185.429398 -291.742114) (xy 185.42635 -291.733732) (xy 185.417327 -291.7074) (xy 185.40761 -291.652595)
			(xy 185.407046 -291.624766) (xy 185.407678 -291.596942) (xy 185.41738 -291.542146) (xy 185.42635 -291.5158)
			(xy 185.429398 -291.507418) (xy 185.429398 -290.792154) (xy 185.42635 -290.783772) (xy 185.417332 -290.757439)
			(xy 185.407626 -290.702635) (xy 185.407046 -290.674806) (xy 185.407683 -290.646983) (xy 185.417395 -290.59219)
			(xy 185.42635 -290.56584) (xy 185.429398 -290.557458) (xy 185.429398 -290.279582) (xy 185.428971 -290.269513)
			(xy 185.421252 -290.250914) (xy 185.414412 -290.243514) (xy 185.355484 -290.184586) (xy 185.348372 -290.17722)
			(xy 185.329576 -290.1696) (xy 184.36082 -290.1696) (xy 184.353174 -290.169856) (xy 184.338565 -290.174373)
			(xy 184.332118 -290.17849) (xy 184.319418 -290.187126) (xy 184.316878 -290.193222) (xy 184.304178 -290.206176)
			(xy 184.303924 -290.206176) (xy 184.278524 -290.23183) (xy 184.26432 -290.245573) (xy 184.232977 -290.269649)
			(xy 184.21604 -290.279836) (xy 184.205913 -290.28561) (xy 184.184935 -290.295781) (xy 184.17413 -290.300156)
			(xy 184.170057 -290.301859) (xy 184.162524 -290.30646) (xy 184.159144 -290.3093) (xy 184.151988 -290.315078)
			(xy 184.134804 -290.321597) (xy 184.125616 -290.322) (xy 166.37762 -290.322) (xy 166.358824 -290.32962)
			(xy 166.351712 -290.336986) (xy 166.280084 -290.408614) (xy 166.273231 -290.416009) (xy 166.265488 -290.434608)
			(xy 166.265098 -290.444682) (xy 166.265098 -290.699795) (xy 184.457322 -290.699795) (xy 184.457322 -290.649817)
			(xy 184.465141 -290.600454) (xy 184.480585 -290.552922) (xy 184.503275 -290.50839) (xy 184.532651 -290.467957)
			(xy 184.567991 -290.432617) (xy 184.608424 -290.403241) (xy 184.652956 -290.380551) (xy 184.700488 -290.365107)
			(xy 184.749851 -290.357288) (xy 184.799829 -290.357288) (xy 184.849192 -290.365107) (xy 184.896724 -290.380551)
			(xy 184.941256 -290.403241) (xy 184.981689 -290.432617) (xy 185.017029 -290.467957) (xy 185.046405 -290.50839)
			(xy 185.069095 -290.552922) (xy 185.084539 -290.600454) (xy 185.092358 -290.649817) (xy 185.092848 -290.674806)
			(xy 185.092358 -290.699795) (xy 185.084539 -290.749158) (xy 185.069095 -290.79669) (xy 185.046405 -290.841222)
			(xy 185.017029 -290.881655) (xy 184.981689 -290.916995) (xy 184.941256 -290.946371) (xy 184.896724 -290.969061)
			(xy 184.849192 -290.984505) (xy 184.799829 -290.992324) (xy 184.749851 -290.992324) (xy 184.700488 -290.984505)
			(xy 184.652956 -290.969061) (xy 184.608424 -290.946371) (xy 184.567991 -290.916995) (xy 184.532651 -290.881655)
			(xy 184.503275 -290.841222) (xy 184.480585 -290.79669) (xy 184.465141 -290.749158) (xy 184.457322 -290.699795)
			(xy 166.265098 -290.699795) (xy 166.265098 -291.624766) (xy 166.407084 -291.624766) (xy 166.407497 -291.600219)
			(xy 166.415069 -291.551713) (xy 166.429998 -291.504943) (xy 166.451929 -291.46102) (xy 166.480342 -291.420984)
			(xy 166.514565 -291.385783) (xy 166.553785 -291.356254) (xy 166.597074 -291.333095) (xy 166.643404 -291.316856)
			(xy 166.691678 -291.307921) (xy 166.716202 -291.306758) (xy 166.725854 -291.306504) (xy 166.743634 -291.298884)
			(xy 166.844726 -291.197792) (xy 166.862003 -291.181139) (xy 166.900839 -291.152956) (xy 166.943602 -291.131188)
			(xy 166.98924 -291.116367) (xy 167.036634 -291.108859) (xy 167.060626 -291.108384) (xy 183.834024 -291.108384)
			(xy 183.86242 -291.109006) (xy 183.918237 -291.119477) (xy 183.971148 -291.140109) (xy 183.995568 -291.154612)
			(xy 184.240424 -291.399468) (xy 184.254926 -291.423888) (xy 184.275541 -291.476804) (xy 184.286028 -291.532617)
			(xy 184.286652 -291.561012) (xy 184.286652 -291.649755) (xy 184.457322 -291.649755) (xy 184.457322 -291.599777)
			(xy 184.465141 -291.550414) (xy 184.480585 -291.502882) (xy 184.503275 -291.45835) (xy 184.532651 -291.417917)
			(xy 184.567991 -291.382577) (xy 184.608424 -291.353201) (xy 184.652956 -291.330511) (xy 184.700488 -291.315067)
			(xy 184.749851 -291.307248) (xy 184.799829 -291.307248) (xy 184.849192 -291.315067) (xy 184.896724 -291.330511)
			(xy 184.941256 -291.353201) (xy 184.981689 -291.382577) (xy 185.017029 -291.417917) (xy 185.046405 -291.45835)
			(xy 185.069095 -291.502882) (xy 185.084539 -291.550414) (xy 185.092358 -291.599777) (xy 185.092848 -291.624766)
			(xy 185.092358 -291.649755) (xy 185.084539 -291.699118) (xy 185.069095 -291.74665) (xy 185.046405 -291.791182)
			(xy 185.017029 -291.831615) (xy 184.981689 -291.866955) (xy 184.941256 -291.896331) (xy 184.896724 -291.919021)
			(xy 184.849192 -291.934465) (xy 184.799829 -291.942284) (xy 184.749851 -291.942284) (xy 184.700488 -291.934465)
			(xy 184.652956 -291.919021) (xy 184.608424 -291.896331) (xy 184.567991 -291.866955) (xy 184.532651 -291.831615)
			(xy 184.503275 -291.791182) (xy 184.480585 -291.74665) (xy 184.465141 -291.699118) (xy 184.457322 -291.649755)
			(xy 184.286652 -291.649755) (xy 184.286652 -291.82441) (xy 184.286199 -291.848407) (xy 184.278732 -291.895814)
			(xy 184.263921 -291.941463) (xy 184.242134 -291.984224) (xy 184.213908 -292.023038) (xy 184.197244 -292.04031)
			(xy 184.10047 -292.137084) (xy 184.083147 -292.153687) (xy 184.044324 -292.181877) (xy 184.001573 -292.203656)
			(xy 183.955944 -292.218488) (xy 183.908559 -292.22601) (xy 183.88457 -292.226492) (xy 167.035226 -292.226492)
			(xy 167.011227 -292.226097) (xy 166.963816 -292.218618) (xy 166.918166 -292.203795) (xy 166.875406 -292.181994)
			(xy 166.836595 -292.153755) (xy 166.819326 -292.137084) (xy 166.78783 -292.105588) (xy 166.784385 -292.101907)
			(xy 166.778881 -292.093463) (xy 166.776908 -292.088824) (xy 166.723314 -291.958776) (xy 166.70147 -291.942266)
			(xy 166.687754 -291.940488) (xy 166.662309 -291.936947) (xy 166.612921 -291.922817) (xy 166.566449 -291.900928)
			(xy 166.524103 -291.87185) (xy 166.486984 -291.83634) (xy 166.456059 -291.795322) (xy 166.432134 -291.749865)
			(xy 166.415831 -291.701152) (xy 166.407575 -291.650451) (xy 166.407084 -291.624766) (xy 166.265098 -291.624766)
			(xy 166.265098 -292.599715) (xy 184.457322 -292.599715) (xy 184.457322 -292.549737) (xy 184.465141 -292.500374)
			(xy 184.480585 -292.452842) (xy 184.503275 -292.40831) (xy 184.532651 -292.367877) (xy 184.567991 -292.332537)
			(xy 184.608424 -292.303161) (xy 184.652956 -292.280471) (xy 184.700488 -292.265027) (xy 184.749851 -292.257208)
			(xy 184.799829 -292.257208) (xy 184.849192 -292.265027) (xy 184.896724 -292.280471) (xy 184.941256 -292.303161)
			(xy 184.981689 -292.332537) (xy 185.017029 -292.367877) (xy 185.046405 -292.40831) (xy 185.069095 -292.452842)
			(xy 185.084539 -292.500374) (xy 185.092358 -292.549737) (xy 185.092848 -292.574726) (xy 185.092358 -292.599715)
			(xy 185.084539 -292.649078) (xy 185.069095 -292.69661) (xy 185.046405 -292.741142) (xy 185.017029 -292.781575)
			(xy 184.981689 -292.816915) (xy 184.941256 -292.846291) (xy 184.896724 -292.868981) (xy 184.849192 -292.884425)
			(xy 184.799829 -292.892244) (xy 184.749851 -292.892244) (xy 184.700488 -292.884425) (xy 184.652956 -292.868981)
			(xy 184.608424 -292.846291) (xy 184.567991 -292.816915) (xy 184.532651 -292.781575) (xy 184.503275 -292.741142)
			(xy 184.480585 -292.69661) (xy 184.465141 -292.649078) (xy 184.457322 -292.599715) (xy 166.265098 -292.599715)
			(xy 166.265098 -292.749478) (xy 166.272718 -292.768274) (xy 166.280084 -292.775386) (xy 166.529512 -293.024814)
			(xy 166.536907 -293.031668) (xy 166.555506 -293.039412) (xy 166.56558 -293.0398) (xy 182.398416 -293.0398)
			(xy 182.408485 -293.040226) (xy 182.427085 -293.047945) (xy 182.434484 -293.054786) (xy 182.582566 -293.202868)
			(xy 182.585776 -293.206299) (xy 182.591021 -293.214092) (xy 182.59298 -293.218362) (xy 182.596536 -293.225982)
			(xy 182.602378 -293.23284) (xy 182.605756 -293.236315) (xy 182.613557 -293.242063) (xy 182.617872 -293.24427)
			(xy 182.6641 -293.266876) (xy 182.69077 -293.265352) (xy 182.701946 -293.257986) (xy 182.721363 -293.245902)
			(xy 182.762925 -293.226819) (xy 182.806789 -293.213876) (xy 182.852053 -293.207339) (xy 182.87492 -293.206932)
			(xy 182.881524 -293.206932) (xy 182.906174 -293.207903) (xy 182.954745 -293.216521) (xy 183.001402 -293.232537)
			(xy 183.045025 -293.255566) (xy 183.084569 -293.285058) (xy 183.119082 -293.320302) (xy 183.147738 -293.360455)
			(xy 183.169849 -293.404552) (xy 183.184883 -293.451534) (xy 183.192481 -293.500275) (xy 183.192928 -293.52494)
			(xy 183.192637 -293.544314) (xy 183.191954 -293.549885) (xy 183.507422 -293.549885) (xy 183.507422 -293.499915)
			(xy 183.515239 -293.45056) (xy 183.53068 -293.403035) (xy 183.553365 -293.358511) (xy 183.582736 -293.318084)
			(xy 183.618069 -293.282749) (xy 183.658494 -293.253375) (xy 183.703017 -293.230688) (xy 183.750541 -293.215244)
			(xy 183.799895 -293.207424) (xy 183.82488 -293.206932) (xy 183.845829 -293.20726) (xy 183.887366 -293.21274)
			(xy 183.907684 -293.217854) (xy 183.914034 -293.219632) (xy 184.685686 -293.219632) (xy 184.692036 -293.217854)
			(xy 184.712351 -293.212725) (xy 184.75389 -293.207248) (xy 184.77484 -293.206932) (xy 184.79983 -293.207345)
			(xy 184.849195 -293.21517) (xy 184.896728 -293.230619) (xy 184.941259 -293.253314) (xy 184.981692 -293.282695)
			(xy 185.017031 -293.318039) (xy 185.046407 -293.358476) (xy 185.069096 -293.403009) (xy 185.08454 -293.450544)
			(xy 185.092358 -293.49991) (xy 185.092358 -293.54989) (xy 185.08454 -293.599256) (xy 185.069096 -293.646791)
			(xy 185.046407 -293.691324) (xy 185.017031 -293.731761) (xy 184.981692 -293.767105) (xy 184.941259 -293.796486)
			(xy 184.896728 -293.819181) (xy 184.849195 -293.83463) (xy 184.79983 -293.842455) (xy 184.77484 -293.842948)
			(xy 184.753891 -293.842617) (xy 184.712354 -293.837139) (xy 184.692036 -293.832026) (xy 184.685686 -293.830248)
			(xy 183.914034 -293.830248) (xy 183.907684 -293.832026) (xy 183.887368 -293.837151) (xy 183.84583 -293.842631)
			(xy 183.82488 -293.842948) (xy 183.799895 -293.842376) (xy 183.750541 -293.834556) (xy 183.703017 -293.819112)
			(xy 183.658494 -293.796425) (xy 183.618069 -293.767051) (xy 183.582736 -293.731716) (xy 183.553365 -293.691289)
			(xy 183.53068 -293.646765) (xy 183.515239 -293.59924) (xy 183.507422 -293.549885) (xy 183.191954 -293.549885)
			(xy 183.18792 -293.582775) (xy 183.18353 -293.601648) (xy 183.182006 -293.607744) (xy 183.182006 -293.88562)
			(xy 183.181513 -293.900668) (xy 183.173719 -293.929738) (xy 183.158667 -293.955801) (xy 183.137384 -293.977081)
			(xy 183.111318 -293.992127) (xy 183.082246 -293.999916) (xy 183.067198 -294.000428) (xy 182.686198 -294.000428)
			(xy 182.68188 -294.000174) (xy 182.680864 -294.000174) (xy 182.677054 -294.000174) (xy 182.667402 -293.999412)
			(xy 182.649876 -294.005) (xy 182.616602 -294.031416) (xy 182.60789 -294.038994) (xy 182.597848 -294.05976)
			(xy 182.597298 -294.071294) (xy 182.597298 -295.99382) (xy 182.59758 -296.002346) (xy 182.603121 -296.018468)
			(xy 182.613675 -296.031856) (xy 182.620666 -296.036746) (xy 182.703978 -296.089832) (xy 182.729632 -296.09161)
			(xy 182.74157 -296.086022) (xy 182.762533 -296.076799) (xy 182.806445 -296.063788) (xy 182.851767 -296.057206)
			(xy 182.874666 -296.056812) (xy 182.87492 -296.056812) (xy 182.895806 -296.057141) (xy 182.937217 -296.06262)
			(xy 182.95747 -296.067734) (xy 182.964074 -296.069512) (xy 183.099964 -296.069512) (xy 183.2356 -296.069512)
			(xy 183.250655 -296.069959) (xy 183.279739 -296.077753) (xy 183.305814 -296.09281) (xy 183.327103 -296.114102)
			(xy 183.342154 -296.14018) (xy 183.349943 -296.169265) (xy 183.350408 -296.18432) (xy 183.350408 -296.37482)
			(xy 183.350408 -296.56532) (xy 183.349917 -296.580347) (xy 183.342145 -296.60938) (xy 183.327134 -296.635417)
			(xy 183.305904 -296.656691) (xy 183.279897 -296.671755) (xy 183.25088 -296.679587) (xy 183.235854 -296.680128)
			(xy 182.964328 -296.680128) (xy 182.957724 -296.681906) (xy 182.935962 -296.687356) (xy 182.891433 -296.692806)
			(xy 182.846579 -296.691962) (xy 182.824374 -296.688764) (xy 182.802989 -296.684997) (xy 182.761441 -296.672375)
			(xy 182.74157 -296.663618) (xy 182.729632 -296.65803) (xy 182.703978 -296.659808) (xy 182.620666 -296.712894)
			(xy 182.613672 -296.717776) (xy 182.603145 -296.731184) (xy 182.597579 -296.747297) (xy 182.597298 -296.75582)
			(xy 182.597298 -297.651678) (xy 182.604918 -297.670474) (xy 182.612284 -297.677586) (xy 182.633112 -297.698414)
			(xy 182.640507 -297.705268) (xy 182.659106 -297.713012) (xy 182.66918 -297.7134) (xy 185.075576 -297.7134)
		)
		(stroke
			(width 0)
			(type solid)
		)
		(fill yes)
		(layer "B.Cu")
		(net "P0V8_SERDES_VDDA_PEX1")
	)
	(gr_poly
		(pts
			(xy 110.08106 -232.535222) (xy 110.091126 -232.534789) (xy 110.109717 -232.527061) (xy 110.117128 -232.520236)
			(xy 110.260638 -232.376726) (xy 110.26748 -232.369327) (xy 110.275197 -232.350728) (xy 110.275624 -232.340658)
			(xy 110.275624 -223.823022) (xy 110.282482 -223.816164) (xy 110.282482 -213.274402) (xy 110.282059 -213.264332)
			(xy 110.274343 -213.245729) (xy 110.267496 -213.238334) (xy 110.121192 -213.09203) (xy 110.11408 -213.084664)
			(xy 110.095284 -213.077044) (xy 98.68916 -213.077044) (xy 98.679094 -213.077476) (xy 98.660504 -213.085205)
			(xy 98.653092 -213.09203) (xy 98.010218 -213.734904) (xy 98.002852 -213.742016) (xy 97.995232 -213.760812)
			(xy 97.995232 -219.08643) (xy 97.995838 -219.097759) (xy 98.005602 -219.118203) (xy 98.014028 -219.1258)
			(xy 98.083878 -219.182696) (xy 98.105722 -219.18803) (xy 98.117152 -219.185744) (xy 98.13606 -219.182147)
			(xy 98.17436 -219.178328) (xy 98.193606 -219.178124) (xy 98.220855 -219.178611) (xy 98.274797 -219.186367)
			(xy 98.327087 -219.201721) (xy 98.376659 -219.224361) (xy 98.422505 -219.253825) (xy 98.463691 -219.289513)
			(xy 98.499379 -219.3307) (xy 98.528842 -219.376546) (xy 98.551481 -219.426119) (xy 98.566834 -219.478409)
			(xy 98.57459 -219.532351) (xy 98.57459 -219.559886) (xy 100.279706 -219.559886) (xy 100.283777 -219.504264)
			(xy 100.295903 -219.449827) (xy 100.315826 -219.397736) (xy 100.343122 -219.349101) (xy 100.377208 -219.304958)
			(xy 100.417357 -219.266249) (xy 100.462715 -219.233798) (xy 100.512315 -219.208297) (xy 100.565099 -219.19029)
			(xy 100.619942 -219.18016) (xy 100.675676 -219.178123) (xy 100.731113 -219.184223) (xy 100.78507 -219.198329)
			(xy 100.836399 -219.220141) (xy 100.884005 -219.249195) (xy 100.926873 -219.28487) (xy 100.96409 -219.326407)
			(xy 100.994863 -219.37292) (xy 101.018535 -219.423417) (xy 101.034603 -219.476824) (xy 101.042723 -219.532)
			(xy 101.043232 -219.559886) (xy 101.042723 -219.587772) (xy 101.042491 -219.589346) (xy 102.277654 -219.589346)
			(xy 102.277654 -219.52941) (xy 102.285477 -219.469988) (xy 102.30099 -219.412095) (xy 102.323926 -219.356722)
			(xy 102.353893 -219.304816) (xy 102.39038 -219.257266) (xy 102.43276 -219.214886) (xy 102.48031 -219.178399)
			(xy 102.532216 -219.148432) (xy 102.587589 -219.125496) (xy 102.645482 -219.109983) (xy 102.704904 -219.10216)
			(xy 102.76484 -219.10216) (xy 102.824262 -219.109983) (xy 102.882155 -219.125496) (xy 102.937528 -219.148432)
			(xy 102.989434 -219.178399) (xy 103.036984 -219.214886) (xy 103.079364 -219.257266) (xy 103.115851 -219.304816)
			(xy 103.145818 -219.356722) (xy 103.168754 -219.412095) (xy 103.184267 -219.469988) (xy 103.19209 -219.52941)
			(xy 103.19258 -219.559378) (xy 103.19209 -219.589346) (xy 103.184267 -219.648768) (xy 103.168754 -219.706661)
			(xy 103.145818 -219.762034) (xy 103.115851 -219.81394) (xy 103.079364 -219.86149) (xy 103.036984 -219.90387)
			(xy 102.989434 -219.940357) (xy 102.937528 -219.970324) (xy 102.882155 -219.99326) (xy 102.824262 -220.008773)
			(xy 102.76484 -220.016596) (xy 102.704904 -220.016596) (xy 102.645482 -220.008773) (xy 102.587589 -219.99326)
			(xy 102.532216 -219.970324) (xy 102.48031 -219.940357) (xy 102.43276 -219.90387) (xy 102.39038 -219.86149)
			(xy 102.353893 -219.81394) (xy 102.323926 -219.762034) (xy 102.30099 -219.706661) (xy 102.285477 -219.648768)
			(xy 102.277654 -219.589346) (xy 101.042491 -219.589346) (xy 101.034603 -219.642948) (xy 101.018535 -219.696355)
			(xy 100.994863 -219.746852) (xy 100.96409 -219.793365) (xy 100.926873 -219.834902) (xy 100.884005 -219.870577)
			(xy 100.836399 -219.899631) (xy 100.78507 -219.921443) (xy 100.731113 -219.935549) (xy 100.675676 -219.941649)
			(xy 100.619942 -219.939612) (xy 100.565099 -219.929482) (xy 100.512315 -219.911475) (xy 100.462715 -219.885974)
			(xy 100.417357 -219.853523) (xy 100.377208 -219.814814) (xy 100.343122 -219.770671) (xy 100.315826 -219.722036)
			(xy 100.295903 -219.669945) (xy 100.283777 -219.615508) (xy 100.279706 -219.559886) (xy 98.57459 -219.559886)
			(xy 98.57459 -219.586849) (xy 98.566834 -219.640791) (xy 98.551481 -219.693081) (xy 98.528842 -219.742654)
			(xy 98.499379 -219.7885) (xy 98.463691 -219.829687) (xy 98.422505 -219.865375) (xy 98.376659 -219.894839)
			(xy 98.327087 -219.917479) (xy 98.274797 -219.932833) (xy 98.220855 -219.940589) (xy 98.193606 -219.94114)
			(xy 98.174361 -219.940923) (xy 98.136062 -219.937103) (xy 98.117152 -219.93352) (xy 98.105722 -219.931234)
			(xy 98.083878 -219.936568) (xy 98.014028 -219.993464) (xy 98.005138 -220.00083) (xy 97.995232 -220.021404)
			(xy 97.995232 -221.176084) (xy 100.490256 -221.176084) (xy 100.490256 -221.116148) (xy 100.498079 -221.056726)
			(xy 100.513592 -220.998833) (xy 100.536528 -220.94346) (xy 100.566495 -220.891554) (xy 100.602982 -220.844004)
			(xy 100.645362 -220.801624) (xy 100.692912 -220.765137) (xy 100.744818 -220.73517) (xy 100.800191 -220.712234)
			(xy 100.858084 -220.696721) (xy 100.917506 -220.688898) (xy 100.977442 -220.688898) (xy 101.036864 -220.696721)
			(xy 101.094757 -220.712234) (xy 101.15013 -220.73517) (xy 101.202036 -220.765137) (xy 101.249586 -220.801624)
			(xy 101.291966 -220.844004) (xy 101.328453 -220.891554) (xy 101.35842 -220.94346) (xy 101.361454 -220.950786)
			(xy 102.862362 -220.950786) (xy 102.862362 -220.89085) (xy 102.870185 -220.831428) (xy 102.885698 -220.773535)
			(xy 102.908634 -220.718162) (xy 102.938601 -220.666256) (xy 102.975088 -220.618706) (xy 103.017468 -220.576326)
			(xy 103.065018 -220.539839) (xy 103.116924 -220.509872) (xy 103.172297 -220.486936) (xy 103.23019 -220.471423)
			(xy 103.289612 -220.4636) (xy 103.349548 -220.4636) (xy 103.40897 -220.471423) (xy 103.466863 -220.486936)
			(xy 103.522236 -220.509872) (xy 103.574142 -220.539839) (xy 103.621692 -220.576326) (xy 103.664072 -220.618706)
			(xy 103.700559 -220.666256) (xy 103.730526 -220.718162) (xy 103.753462 -220.773535) (xy 103.768975 -220.831428)
			(xy 103.776798 -220.89085) (xy 103.777288 -220.920818) (xy 103.776798 -220.950786) (xy 103.768975 -221.010208)
			(xy 103.753462 -221.068101) (xy 103.730526 -221.123474) (xy 103.700559 -221.17538) (xy 103.664072 -221.22293)
			(xy 103.621692 -221.26531) (xy 103.574142 -221.301797) (xy 103.522236 -221.331764) (xy 103.466863 -221.3547)
			(xy 103.40897 -221.370213) (xy 103.349548 -221.378036) (xy 103.289612 -221.378036) (xy 103.23019 -221.370213)
			(xy 103.172297 -221.3547) (xy 103.116924 -221.331764) (xy 103.065018 -221.301797) (xy 103.017468 -221.26531)
			(xy 102.975088 -221.22293) (xy 102.938601 -221.17538) (xy 102.908634 -221.123474) (xy 102.885698 -221.068101)
			(xy 102.870185 -221.010208) (xy 102.862362 -220.950786) (xy 101.361454 -220.950786) (xy 101.381356 -220.998833)
			(xy 101.396869 -221.056726) (xy 101.404692 -221.116148) (xy 101.405182 -221.146116) (xy 101.404692 -221.176084)
			(xy 101.396869 -221.235506) (xy 101.381356 -221.293399) (xy 101.35842 -221.348772) (xy 101.328453 -221.400678)
			(xy 101.291966 -221.448228) (xy 101.249586 -221.490608) (xy 101.202036 -221.527095) (xy 101.15013 -221.557062)
			(xy 101.094757 -221.579998) (xy 101.036864 -221.595511) (xy 100.977442 -221.603334) (xy 100.917506 -221.603334)
			(xy 100.858084 -221.595511) (xy 100.800191 -221.579998) (xy 100.744818 -221.557062) (xy 100.692912 -221.527095)
			(xy 100.645362 -221.490608) (xy 100.602982 -221.448228) (xy 100.566495 -221.400678) (xy 100.536528 -221.348772)
			(xy 100.513592 -221.293399) (xy 100.498079 -221.235506) (xy 100.490256 -221.176084) (xy 97.995232 -221.176084)
			(xy 97.995232 -222.494598) (xy 99.259118 -222.494598) (xy 99.259118 -222.434662) (xy 99.266941 -222.37524)
			(xy 99.282454 -222.317347) (xy 99.30539 -222.261974) (xy 99.335357 -222.210068) (xy 99.371844 -222.162518)
			(xy 99.414224 -222.120138) (xy 99.461774 -222.083651) (xy 99.51368 -222.053684) (xy 99.569053 -222.030748)
			(xy 99.626946 -222.015235) (xy 99.686368 -222.007412) (xy 99.746304 -222.007412) (xy 99.805726 -222.015235)
			(xy 99.863619 -222.030748) (xy 99.918992 -222.053684) (xy 99.970898 -222.083651) (xy 100.018448 -222.120138)
			(xy 100.060828 -222.162518) (xy 100.097315 -222.210068) (xy 100.127282 -222.261974) (xy 100.150218 -222.317347)
			(xy 100.165731 -222.37524) (xy 100.173554 -222.434662) (xy 100.174044 -222.46463) (xy 100.173554 -222.494598)
			(xy 100.165731 -222.55402) (xy 100.150218 -222.611913) (xy 100.127282 -222.667286) (xy 100.097315 -222.719192)
			(xy 100.060828 -222.766742) (xy 100.018448 -222.809122) (xy 99.970898 -222.845609) (xy 99.918992 -222.875576)
			(xy 99.863619 -222.898512) (xy 99.805726 -222.914025) (xy 99.746304 -222.921848) (xy 99.686368 -222.921848)
			(xy 99.626946 -222.914025) (xy 99.569053 -222.898512) (xy 99.51368 -222.875576) (xy 99.461774 -222.845609)
			(xy 99.414224 -222.809122) (xy 99.371844 -222.766742) (xy 99.335357 -222.719192) (xy 99.30539 -222.667286)
			(xy 99.282454 -222.611913) (xy 99.266941 -222.55402) (xy 99.259118 -222.494598) (xy 97.995232 -222.494598)
			(xy 97.995232 -223.170316) (xy 101.287067 -223.170316) (xy 101.287067 -223.10108) (xy 101.295105 -223.032313)
			(xy 101.311072 -222.964943) (xy 101.334752 -222.899883) (xy 101.365825 -222.838012) (xy 101.40387 -222.780166)
			(xy 101.448374 -222.727129) (xy 101.498734 -222.679617) (xy 101.55427 -222.638272) (xy 101.61423 -222.603654)
			(xy 101.677803 -222.576231) (xy 101.74413 -222.556374) (xy 101.812314 -222.544352) (xy 101.881432 -222.540326)
			(xy 101.95055 -222.544352) (xy 102.018734 -222.556374) (xy 102.085061 -222.576231) (xy 102.148634 -222.603654)
			(xy 102.208594 -222.638272) (xy 102.26413 -222.679617) (xy 102.31449 -222.727129) (xy 102.358994 -222.780166)
			(xy 102.397039 -222.838012) (xy 102.428112 -222.899883) (xy 102.451792 -222.964943) (xy 102.467759 -223.032313)
			(xy 102.475797 -223.10108) (xy 102.4763 -223.135698) (xy 102.475797 -223.170316) (xy 102.467759 -223.239083)
			(xy 102.451792 -223.306453) (xy 102.428112 -223.371513) (xy 102.397039 -223.433384) (xy 102.358994 -223.49123)
			(xy 102.31449 -223.544267) (xy 102.26413 -223.591779) (xy 102.208594 -223.633124) (xy 102.148634 -223.667742)
			(xy 102.085061 -223.695165) (xy 102.018734 -223.715022) (xy 101.95055 -223.727044) (xy 101.881432 -223.73107)
			(xy 101.812314 -223.727044) (xy 101.74413 -223.715022) (xy 101.677803 -223.695165) (xy 101.61423 -223.667742)
			(xy 101.55427 -223.633124) (xy 101.498734 -223.591779) (xy 101.448374 -223.544267) (xy 101.40387 -223.49123)
			(xy 101.365825 -223.433384) (xy 101.334752 -223.371513) (xy 101.311072 -223.306453) (xy 101.295105 -223.239083)
			(xy 101.287067 -223.170316) (xy 97.995232 -223.170316) (xy 97.995232 -223.879914) (xy 102.531146 -223.879914)
			(xy 102.531146 -223.819978) (xy 102.538969 -223.760556) (xy 102.554482 -223.702663) (xy 102.577418 -223.64729)
			(xy 102.607385 -223.595384) (xy 102.643872 -223.547834) (xy 102.686252 -223.505454) (xy 102.733802 -223.468967)
			(xy 102.785708 -223.439) (xy 102.841081 -223.416064) (xy 102.898974 -223.400551) (xy 102.958396 -223.392728)
			(xy 103.018332 -223.392728) (xy 103.077754 -223.400551) (xy 103.135647 -223.416064) (xy 103.19102 -223.439)
			(xy 103.242926 -223.468967) (xy 103.290476 -223.505454) (xy 103.332856 -223.547834) (xy 103.369343 -223.595384)
			(xy 103.39931 -223.64729) (xy 103.422246 -223.702663) (xy 103.437759 -223.760556) (xy 103.445582 -223.819978)
			(xy 103.446072 -223.849946) (xy 103.445582 -223.879914) (xy 103.437759 -223.939336) (xy 103.422246 -223.997229)
			(xy 103.39931 -224.052602) (xy 103.369343 -224.104508) (xy 103.332856 -224.152058) (xy 103.290476 -224.194438)
			(xy 103.242926 -224.230925) (xy 103.19102 -224.260892) (xy 103.135647 -224.283828) (xy 103.077754 -224.299341)
			(xy 103.018332 -224.307164) (xy 102.958396 -224.307164) (xy 102.898974 -224.299341) (xy 102.841081 -224.283828)
			(xy 102.785708 -224.260892) (xy 102.733802 -224.230925) (xy 102.686252 -224.194438) (xy 102.643872 -224.152058)
			(xy 102.607385 -224.104508) (xy 102.577418 -224.052602) (xy 102.554482 -223.997229) (xy 102.538969 -223.939336)
			(xy 102.531146 -223.879914) (xy 97.995232 -223.879914) (xy 97.995232 -224.561142) (xy 107.50853 -224.561142)
			(xy 107.50853 -224.501206) (xy 107.516353 -224.441784) (xy 107.531866 -224.383891) (xy 107.554802 -224.328518)
			(xy 107.584769 -224.276612) (xy 107.621256 -224.229062) (xy 107.663636 -224.186682) (xy 107.711186 -224.150195)
			(xy 107.763092 -224.120228) (xy 107.818465 -224.097292) (xy 107.876358 -224.081779) (xy 107.93578 -224.073956)
			(xy 107.995716 -224.073956) (xy 108.055138 -224.081779) (xy 108.113031 -224.097292) (xy 108.168404 -224.120228)
			(xy 108.22031 -224.150195) (xy 108.26786 -224.186682) (xy 108.31024 -224.229062) (xy 108.346727 -224.276612)
			(xy 108.376694 -224.328518) (xy 108.39963 -224.383891) (xy 108.415143 -224.441784) (xy 108.422966 -224.501206)
			(xy 108.423456 -224.531174) (xy 108.422966 -224.561142) (xy 108.415143 -224.620564) (xy 108.39963 -224.678457)
			(xy 108.376694 -224.73383) (xy 108.346727 -224.785736) (xy 108.31024 -224.833286) (xy 108.26786 -224.875666)
			(xy 108.22031 -224.912153) (xy 108.168404 -224.94212) (xy 108.113031 -224.965056) (xy 108.055138 -224.980569)
			(xy 107.995716 -224.988392) (xy 107.93578 -224.988392) (xy 107.876358 -224.980569) (xy 107.818465 -224.965056)
			(xy 107.763092 -224.94212) (xy 107.711186 -224.912153) (xy 107.663636 -224.875666) (xy 107.621256 -224.833286)
			(xy 107.584769 -224.785736) (xy 107.554802 -224.73383) (xy 107.531866 -224.678457) (xy 107.516353 -224.620564)
			(xy 107.50853 -224.561142) (xy 97.995232 -224.561142) (xy 97.995232 -232.241852) (xy 97.995665 -232.251917)
			(xy 98.003397 -232.270505) (xy 98.010218 -232.27792) (xy 98.252534 -232.520236) (xy 98.259931 -232.527084)
			(xy 98.27853 -232.534816) (xy 98.288602 -232.535222)
		)
		(stroke
			(width 0)
			(type solid)
		)
		(fill yes)
		(layer "B.Cu")
		(net "GND")
	)
	(gr_poly
		(pts
			(xy 343.06256 -224.932748) (xy 343.081628 -224.916011) (xy 343.123767 -224.887756) (xy 343.169607 -224.866012)
			(xy 343.218148 -224.851253) (xy 343.268332 -224.843799) (xy 343.2937 -224.84334) (xy 343.322646 -224.843939)
			(xy 343.37972 -224.853645) (xy 343.407238 -224.862644) (xy 343.420954 -224.86747) (xy 343.449656 -224.860866)
			(xy 343.767664 -224.542858) (xy 343.774268 -224.514156) (xy 343.769442 -224.50044) (xy 343.760439 -224.472922)
			(xy 343.750728 -224.415849) (xy 343.750138 -224.386902) (xy 343.75064 -224.359916) (xy 343.759083 -224.306608)
			(xy 343.775763 -224.255278) (xy 343.800267 -224.207189) (xy 343.831994 -224.163527) (xy 343.87016 -224.125365)
			(xy 343.913827 -224.093644) (xy 343.961919 -224.069146) (xy 344.013251 -224.052473) (xy 344.06656 -224.044036)
			(xy 344.093546 -224.043494) (xy 344.122493 -224.044088) (xy 344.179569 -224.053787) (xy 344.207084 -224.062798)
			(xy 344.2208 -224.067624) (xy 344.249502 -224.06102) (xy 344.53576 -223.774762) (xy 344.542605 -223.767363)
			(xy 344.550332 -223.748765) (xy 344.550746 -223.738694) (xy 344.550746 -223.604328) (xy 344.550238 -223.586802)
			(xy 344.550746 -223.569276) (xy 344.550746 -223.458024) (xy 344.564208 -223.434656) (xy 344.568526 -223.432116)
			(xy 344.57767 -223.422464) (xy 344.581226 -223.416114) (xy 344.597683 -223.387527) (xy 344.639351 -223.336401)
			(xy 344.66403 -223.314514) (xy 344.682064 -223.275652) (xy 344.682064 -223.125792) (xy 344.68249 -223.115724)
			(xy 344.690214 -223.097128) (xy 344.69705 -223.089724) (xy 344.746326 -223.040448) (xy 344.753724 -223.033601)
			(xy 344.772322 -223.025868) (xy 344.782394 -223.025462) (xy 344.959432 -223.025462) (xy 344.969588 -223.025014)
			(xy 344.988317 -223.017153) (xy 344.995754 -223.010222) (xy 344.99931 -223.006666) (xy 345.006676 -222.996506)
			(xy 345.01201 -222.990156) (xy 345.066366 -222.9358) (xy 345.073216 -222.928403) (xy 345.080956 -222.909805)
			(xy 345.081352 -222.899732) (xy 345.081352 -222.786956) (xy 345.080919 -222.77689) (xy 345.073188 -222.758302)
			(xy 345.066366 -222.750888) (xy 344.82278 -222.507302) (xy 344.815925 -222.499907) (xy 344.808177 -222.481309)
			(xy 344.807794 -222.471234) (xy 344.807794 -222.418148) (xy 344.807361 -222.408082) (xy 344.799633 -222.389492)
			(xy 344.792808 -222.38208) (xy 344.68943 -222.278702) (xy 344.686128 -222.276416) (xy 344.666106 -222.261484)
			(xy 344.630036 -222.226935) (xy 344.614246 -222.207582) (xy 344.61069 -222.203264) (xy 344.602308 -222.196152)
			(xy 344.577924 -222.18396) (xy 344.572497 -222.181378) (xy 344.560817 -222.178559) (xy 344.55481 -222.178372)
			(xy 344.432382 -222.178372) (xy 344.426513 -222.178519) (xy 344.415089 -222.181209) (xy 344.409776 -222.183706)
			(xy 344.385138 -222.195898) (xy 344.376756 -222.20301) (xy 344.3732 -222.207328) (xy 344.356216 -222.228087)
			(xy 344.31707 -222.264749) (xy 344.272869 -222.295127) (xy 344.224611 -222.318533) (xy 344.17339 -222.334437)
			(xy 344.120363 -222.34248) (xy 344.066729 -222.34248) (xy 344.013702 -222.334437) (xy 343.962481 -222.318533)
			(xy 343.914223 -222.295127) (xy 343.870022 -222.264749) (xy 343.830876 -222.228087) (xy 343.813892 -222.207328)
			(xy 343.810336 -222.20301) (xy 343.801954 -222.195898) (xy 343.777316 -222.183706) (xy 343.771989 -222.181249)
			(xy 343.760573 -222.178566) (xy 343.75471 -222.178372) (xy 343.632536 -222.178372) (xy 343.626669 -222.178525)
			(xy 343.615249 -222.181224) (xy 343.60993 -222.183706) (xy 343.585292 -222.195898) (xy 343.57691 -222.20301)
			(xy 343.573354 -222.207328) (xy 343.55637 -222.228087) (xy 343.517224 -222.264749) (xy 343.473023 -222.295127)
			(xy 343.424765 -222.318533) (xy 343.373544 -222.334437) (xy 343.320517 -222.34248) (xy 343.266883 -222.34248)
			(xy 343.213856 -222.334437) (xy 343.162635 -222.318533) (xy 343.114377 -222.295127) (xy 343.070176 -222.264749)
			(xy 343.03103 -222.228087) (xy 343.014046 -222.207328) (xy 343.01049 -222.20301) (xy 343.002108 -222.195898)
			(xy 342.977724 -222.183706) (xy 342.973218 -222.181582) (xy 342.963628 -222.178888) (xy 342.958674 -222.178372)
			(xy 342.805004 -222.178372) (xy 342.791288 -222.156782) (xy 342.790018 -222.155004) (xy 342.785954 -222.148654)
			(xy 342.228424 -222.148654) (xy 342.215867 -222.149292) (xy 342.193731 -222.161148) (xy 342.18626 -222.17126)
			(xy 342.181688 -222.177864) (xy 342.181434 -222.178372) (xy 342.032844 -222.178372) (xy 342.026976 -222.178524)
			(xy 342.015556 -222.181222) (xy 342.010238 -222.183706) (xy 341.9856 -222.195898) (xy 341.977218 -222.20301)
			(xy 341.973662 -222.207328) (xy 341.956678 -222.228087) (xy 341.917532 -222.264749) (xy 341.873331 -222.295127)
			(xy 341.825073 -222.318533) (xy 341.773852 -222.334437) (xy 341.720825 -222.34248) (xy 341.667191 -222.34248)
			(xy 341.614164 -222.334437) (xy 341.562943 -222.318533) (xy 341.514685 -222.295127) (xy 341.470484 -222.264749)
			(xy 341.431338 -222.228087) (xy 341.414354 -222.207328) (xy 341.410798 -222.20301) (xy 341.402416 -222.195898)
			(xy 341.377778 -222.183706) (xy 341.372453 -222.181243) (xy 341.361037 -222.178545) (xy 341.355172 -222.178372)
			(xy 341.232998 -222.178372) (xy 341.227129 -222.178518) (xy 341.215703 -222.181204) (xy 341.210392 -222.183706)
			(xy 341.185754 -222.195898) (xy 341.177372 -222.20301) (xy 341.173816 -222.207328) (xy 341.156832 -222.228087)
			(xy 341.117686 -222.264749) (xy 341.073485 -222.295127) (xy 341.025227 -222.318533) (xy 340.974006 -222.334437)
			(xy 340.920979 -222.34248) (xy 340.867345 -222.34248) (xy 340.814318 -222.334437) (xy 340.763097 -222.318533)
			(xy 340.714839 -222.295127) (xy 340.670638 -222.264749) (xy 340.631492 -222.228087) (xy 340.614508 -222.207328)
			(xy 340.610952 -222.20301) (xy 340.60257 -222.195898) (xy 340.577932 -222.183706) (xy 340.572606 -222.181248)
			(xy 340.56119 -222.17856) (xy 340.555326 -222.178372) (xy 340.432898 -222.178372) (xy 340.42689 -222.178545)
			(xy 340.415212 -222.181378) (xy 340.409784 -222.18396) (xy 340.3854 -222.196152) (xy 340.377018 -222.203264)
			(xy 340.373462 -222.207582) (xy 340.357137 -222.227505) (xy 340.319721 -222.262903) (xy 340.277608 -222.292559)
			(xy 340.254844 -222.30461) (xy 340.247478 -222.30842) (xy 339.934296 -222.621602) (xy 339.930486 -222.630238)
			(xy 339.919056 -222.655892) (xy 339.918294 -222.657924) (xy 339.91804 -222.658432) (xy 339.912773 -222.673025)
			(xy 339.899667 -222.701148) (xy 339.891878 -222.714566) (xy 339.888576 -222.720154) (xy 339.882734 -222.739966)
			(xy 339.881784 -222.743445) (xy 339.880763 -222.750584) (xy 339.880702 -222.75419) (xy 339.880702 -222.877888)
			(xy 339.881192 -222.887848) (xy 339.888786 -222.906267) (xy 339.895434 -222.913702) (xy 339.992208 -223.01073)
			(xy 339.999604 -223.017583) (xy 340.018202 -223.025325) (xy 340.028276 -223.025716) (xy 340.209632 -223.025716)
			(xy 340.219699 -223.026145) (xy 340.238294 -223.03387) (xy 340.2457 -223.040702) (xy 340.277196 -223.072198)
			(xy 340.284816 -223.09074) (xy 340.284816 -223.259396) (xy 340.285534 -223.271353) (xy 340.296401 -223.292668)
			(xy 340.305644 -223.30029) (xy 340.326116 -223.316013) (xy 340.362737 -223.352391) (xy 340.393719 -223.393677)
			(xy 340.406482 -223.416114) (xy 340.406482 -223.416368) (xy 340.411183 -223.42411) (xy 340.424908 -223.435911)
			(xy 340.441882 -223.442199) (xy 340.450932 -223.44253) (xy 340.500462 -223.44253) (xy 340.510486 -223.442944)
			(xy 340.529011 -223.450608) (xy 340.543188 -223.464782) (xy 340.550855 -223.483306) (xy 340.551262 -223.49333)
			(xy 340.551262 -223.586802) (xy 341.350095 -223.586802) (xy 341.354125 -223.534304) (xy 341.366122 -223.483036)
			(xy 341.385805 -223.434201) (xy 341.412711 -223.388942) (xy 341.446211 -223.348321) (xy 341.485519 -223.31329)
			(xy 341.529714 -223.28467) (xy 341.577759 -223.263131) (xy 341.62853 -223.249179) (xy 341.680835 -223.243141)
			(xy 341.733449 -223.245158) (xy 341.785139 -223.255182) (xy 341.834692 -223.27298) (xy 341.880948 -223.298133)
			(xy 341.922822 -223.330052) (xy 341.959334 -223.36799) (xy 341.989626 -223.411056) (xy 342.012989 -223.458241)
			(xy 342.028875 -223.50844) (xy 342.036912 -223.560476) (xy 342.037416 -223.586802) (xy 342.949787 -223.586802)
			(xy 342.953817 -223.534304) (xy 342.965814 -223.483036) (xy 342.985497 -223.434201) (xy 343.012403 -223.388942)
			(xy 343.045903 -223.348321) (xy 343.085211 -223.31329) (xy 343.129406 -223.28467) (xy 343.177451 -223.263131)
			(xy 343.228222 -223.249179) (xy 343.280527 -223.243141) (xy 343.333141 -223.245158) (xy 343.384831 -223.255182)
			(xy 343.434384 -223.27298) (xy 343.48064 -223.298133) (xy 343.522514 -223.330052) (xy 343.559026 -223.36799)
			(xy 343.589318 -223.411056) (xy 343.612681 -223.458241) (xy 343.628567 -223.50844) (xy 343.636604 -223.560476)
			(xy 343.637108 -223.586802) (xy 343.636604 -223.613128) (xy 343.628567 -223.665164) (xy 343.612681 -223.715363)
			(xy 343.589318 -223.762548) (xy 343.559026 -223.805614) (xy 343.522514 -223.843552) (xy 343.48064 -223.875471)
			(xy 343.434384 -223.900624) (xy 343.384831 -223.918422) (xy 343.333141 -223.928446) (xy 343.280527 -223.930463)
			(xy 343.228222 -223.924425) (xy 343.177451 -223.910473) (xy 343.129406 -223.888934) (xy 343.085211 -223.860314)
			(xy 343.045903 -223.825283) (xy 343.012403 -223.784662) (xy 342.985497 -223.739403) (xy 342.965814 -223.690568)
			(xy 342.953817 -223.6393) (xy 342.949787 -223.586802) (xy 342.037416 -223.586802) (xy 342.036912 -223.613128)
			(xy 342.028875 -223.665164) (xy 342.012989 -223.715363) (xy 341.989626 -223.762548) (xy 341.959334 -223.805614)
			(xy 341.922822 -223.843552) (xy 341.880948 -223.875471) (xy 341.834692 -223.900624) (xy 341.785139 -223.918422)
			(xy 341.733449 -223.928446) (xy 341.680835 -223.930463) (xy 341.62853 -223.924425) (xy 341.577759 -223.910473)
			(xy 341.529714 -223.888934) (xy 341.485519 -223.860314) (xy 341.446211 -223.825283) (xy 341.412711 -223.784662)
			(xy 341.385805 -223.739403) (xy 341.366122 -223.690568) (xy 341.354125 -223.6393) (xy 341.350095 -223.586802)
			(xy 340.551262 -223.586802) (xy 340.551262 -223.73971) (xy 340.551689 -223.749778) (xy 340.559412 -223.768374)
			(xy 340.566248 -223.775778) (xy 340.828884 -224.038414) (xy 340.85022 -224.046034) (xy 340.86165 -224.045018)
			(xy 340.893654 -224.043494) (xy 340.894162 -224.043494) (xy 340.921151 -224.043993) (xy 340.974466 -224.052432)
			(xy 341.025804 -224.069108) (xy 341.0739 -224.093609) (xy 341.117572 -224.125334) (xy 341.155742 -224.163501)
			(xy 341.187472 -224.207169) (xy 341.211979 -224.255263) (xy 341.22866 -224.306599) (xy 341.237104 -224.359913)
			(xy 341.23757 -224.386902) (xy 341.23757 -224.38741) (xy 341.236046 -224.419414) (xy 341.23503 -224.430844)
			(xy 341.24265 -224.45218) (xy 341.267542 -224.477072) (xy 341.274908 -224.483912) (xy 341.293441 -224.491654)
			(xy 341.313525 -224.491654) (xy 341.332058 -224.483912) (xy 341.339424 -224.477072) (xy 341.34806 -224.46869)
			(xy 341.355426 -224.446338) (xy 341.353902 -224.434146) (xy 341.352363 -224.422395) (xy 341.350709 -224.398752)
			(xy 341.3506 -224.386902) (xy 341.351087 -224.360788) (xy 341.358996 -224.309163) (xy 341.37463 -224.259331)
			(xy 341.397631 -224.21244) (xy 341.427466 -224.169574) (xy 341.463449 -224.13172) (xy 341.504749 -224.09975)
			(xy 341.550413 -224.074404) (xy 341.599389 -224.056265) (xy 341.650548 -224.045751) (xy 341.702708 -224.043105)
			(xy 341.754668 -224.048388) (xy 341.805228 -224.061478) (xy 341.853223 -224.082074) (xy 341.897546 -224.1097)
			(xy 341.937174 -224.143719) (xy 341.971194 -224.183346) (xy 341.998822 -224.227668) (xy 342.019419 -224.275663)
			(xy 342.03251 -224.326223) (xy 342.037795 -224.378182) (xy 342.037353 -224.386902) (xy 342.949787 -224.386902)
			(xy 342.953817 -224.334404) (xy 342.965814 -224.283136) (xy 342.985497 -224.234301) (xy 343.012403 -224.189042)
			(xy 343.045903 -224.148421) (xy 343.085211 -224.11339) (xy 343.129406 -224.08477) (xy 343.177451 -224.063231)
			(xy 343.228222 -224.049279) (xy 343.280527 -224.043241) (xy 343.333141 -224.045258) (xy 343.384831 -224.055282)
			(xy 343.434384 -224.07308) (xy 343.48064 -224.098233) (xy 343.522514 -224.130152) (xy 343.559026 -224.16809)
			(xy 343.589318 -224.211156) (xy 343.612681 -224.258341) (xy 343.628567 -224.30854) (xy 343.636604 -224.360576)
			(xy 343.637108 -224.386902) (xy 343.636604 -224.413228) (xy 343.628567 -224.465264) (xy 343.612681 -224.515463)
			(xy 343.589318 -224.562648) (xy 343.559026 -224.605714) (xy 343.522514 -224.643652) (xy 343.48064 -224.675571)
			(xy 343.434384 -224.700724) (xy 343.384831 -224.718522) (xy 343.333141 -224.728546) (xy 343.280527 -224.730563)
			(xy 343.228222 -224.724525) (xy 343.177451 -224.710573) (xy 343.129406 -224.689034) (xy 343.085211 -224.660414)
			(xy 343.045903 -224.625383) (xy 343.012403 -224.584762) (xy 342.985497 -224.539503) (xy 342.965814 -224.490668)
			(xy 342.953817 -224.4394) (xy 342.949787 -224.386902) (xy 342.037353 -224.386902) (xy 342.035151 -224.430342)
			(xy 342.024638 -224.481501) (xy 342.0065 -224.530478) (xy 341.981155 -224.576143) (xy 341.949187 -224.617444)
			(xy 341.911334 -224.653428) (xy 341.868468 -224.683264) (xy 341.821579 -224.706266) (xy 341.771747 -224.721902)
			(xy 341.720122 -224.729812) (xy 341.694008 -224.73031) (xy 341.682158 -224.7302) (xy 341.658515 -224.728544)
			(xy 341.646764 -224.727008) (xy 341.634572 -224.725484) (xy 341.61222 -224.73285) (xy 341.603838 -224.741486)
			(xy 341.596998 -224.748849) (xy 341.589258 -224.767378) (xy 341.589266 -224.787459) (xy 341.597019 -224.805983)
			(xy 341.603838 -224.813368) (xy 341.62873 -224.83826) (xy 341.650066 -224.84588) (xy 341.661496 -224.844864)
			(xy 341.6935 -224.84334) (xy 341.694008 -224.84334) (xy 341.719376 -224.843796) (xy 341.769559 -224.851258)
			(xy 341.818099 -224.86602) (xy 341.86394 -224.88776) (xy 341.906086 -224.916005) (xy 341.925148 -224.932748)
			(xy 341.959184 -224.945956) (xy 343.028524 -224.945956)
		)
		(stroke
			(width 0)
			(type solid)
		)
		(fill yes)
		(layer "B.Cu")
		(net "P3V3_FPGA_VCCIO0")
	)
	(gr_poly
		(pts
			(xy 236.44225 -153.908252) (xy 236.449362 -153.900886) (xy 236.70006 -153.650188) (xy 236.706909 -153.642791)
			(xy 236.714645 -153.624192) (xy 236.715046 -153.61412) (xy 236.715046 -152.735534) (xy 236.714552 -152.725721)
			(xy 236.707117 -152.707551) (xy 236.700568 -152.700228) (xy 236.643926 -152.642316) (xy 236.625892 -152.634442)
			(xy 236.615732 -152.634188) (xy 236.588909 -152.633092) (xy 236.53595 -152.624303) (xy 236.484748 -152.608174)
			(xy 236.436312 -152.585025) (xy 236.391602 -152.555312) (xy 236.3515 -152.519624) (xy 236.316798 -152.478664)
			(xy 236.288183 -152.433244) (xy 236.26622 -152.384259) (xy 236.251343 -152.332679) (xy 236.243846 -152.279522)
			(xy 236.243368 -152.25268) (xy 236.243833 -152.22574) (xy 236.251416 -152.172397) (xy 236.266428 -152.120651)
			(xy 236.288571 -152.071532) (xy 236.317405 -152.026016) (xy 236.352355 -151.98501) (xy 236.392726 -151.949329)
			(xy 236.437716 -151.919682) (xy 236.486429 -151.89666) (xy 236.537897 -151.88072) (xy 236.564424 -151.875998)
			(xy 236.575041 -151.873832) (xy 236.593153 -151.861976) (xy 236.60477 -151.84371) (xy 236.606842 -151.833072)
			(xy 236.612016 -151.800264) (xy 236.62902 -151.736059) (xy 236.653375 -151.674266) (xy 236.684751 -151.615724)
			(xy 236.703362 -151.588216) (xy 236.70768 -151.581866) (xy 236.712252 -151.567134) (xy 236.712252 -151.397462)
			(xy 236.70768 -151.38273) (xy 236.703362 -151.37638) (xy 236.683217 -151.346539) (xy 236.649798 -151.282765)
			(xy 236.624687 -151.215286) (xy 236.608287 -151.145179) (xy 236.604048 -151.109426) (xy 236.602425 -151.098734)
			(xy 236.591524 -151.080082) (xy 236.573907 -151.067575) (xy 236.563408 -151.064976) (xy 236.534964 -151.058718)
			(xy 236.480261 -151.038734) (xy 236.429232 -151.010665) (xy 236.383064 -150.975165) (xy 236.34283 -150.933059)
			(xy 236.309464 -150.885325) (xy 236.283744 -150.833074) (xy 236.266266 -150.777519) (xy 236.257437 -150.719954)
			(xy 236.25683 -150.690834) (xy 236.257322 -150.663088) (xy 236.265357 -150.608181) (xy 236.281278 -150.555022)
			(xy 236.304746 -150.504736) (xy 236.335265 -150.45839) (xy 236.35335 -150.437342) (xy 236.3597 -150.429976)
			(xy 236.366304 -150.411942) (xy 236.364018 -150.323042) (xy 236.356398 -150.305262) (xy 236.34954 -150.29815)
			(xy 236.329017 -150.276585) (xy 236.294239 -150.228272) (xy 236.267384 -150.175146) (xy 236.249104 -150.118493)
			(xy 236.239842 -150.05969) (xy 236.239304 -150.029926) (xy 236.239766 -150.002985) (xy 236.247344 -149.949639)
			(xy 236.262353 -149.897889) (xy 236.284494 -149.848767) (xy 236.313327 -149.803248) (xy 236.348277 -149.762239)
			(xy 236.38865 -149.726556) (xy 236.433642 -149.696909) (xy 236.482359 -149.673887) (xy 236.533829 -149.65795)
			(xy 236.56036 -149.653244) (xy 236.57099 -149.651091) (xy 236.589134 -149.639246) (xy 236.600784 -149.620977)
			(xy 236.602778 -149.610318) (xy 236.607954 -149.577511) (xy 236.624962 -149.513307) (xy 236.64932 -149.451517)
			(xy 236.680696 -149.392977) (xy 236.699298 -149.365462) (xy 236.703616 -149.359112) (xy 236.708188 -149.34438)
			(xy 236.708188 -149.174708) (xy 236.703616 -149.159976) (xy 236.699298 -149.153626) (xy 236.681783 -149.127807)
			(xy 236.651874 -149.073051) (xy 236.62814 -149.015348) (xy 236.610867 -148.955394) (xy 236.600263 -148.893909)
			(xy 236.597952 -148.862796) (xy 236.596719 -148.851693) (xy 236.586083 -148.832078) (xy 236.568137 -148.81882)
			(xy 236.557312 -148.81606) (xy 236.528822 -148.809844) (xy 236.47402 -148.789926) (xy 236.422884 -148.761904)
			(xy 236.376607 -148.72643) (xy 236.336263 -148.68433) (xy 236.302794 -148.636583) (xy 236.276976 -148.5843)
			(xy 236.259412 -148.528699) (xy 236.250509 -148.471073) (xy 236.249972 -148.441918) (xy 236.25043 -148.41505)
			(xy 236.257972 -148.361846) (xy 236.272908 -148.310227) (xy 236.294943 -148.261216) (xy 236.32364 -148.215785)
			(xy 236.358432 -148.174832) (xy 236.378242 -148.156676) (xy 236.386624 -148.14931) (xy 236.39526 -148.129752)
			(xy 236.395514 -148.031708) (xy 236.386878 -148.012404) (xy 236.37875 -148.005038) (xy 236.359135 -147.986868)
			(xy 236.324676 -147.945987) (xy 236.296265 -147.900693) (xy 236.274457 -147.851875) (xy 236.259681 -147.80049)
			(xy 236.252226 -147.747546) (xy 236.25175 -147.720812) (xy 236.252236 -147.693561) (xy 236.259992 -147.639613)
			(xy 236.275347 -147.587318) (xy 236.297989 -147.537741) (xy 236.327455 -147.491891) (xy 236.363146 -147.4507)
			(xy 236.404337 -147.415009) (xy 236.450187 -147.385543) (xy 236.499764 -147.362901) (xy 236.552059 -147.347546)
			(xy 236.606007 -147.33979) (xy 236.660509 -147.33979) (xy 236.714457 -147.347546) (xy 236.766752 -147.362901)
			(xy 236.816329 -147.385543) (xy 236.862179 -147.415009) (xy 236.90337 -147.4507) (xy 236.939061 -147.491891)
			(xy 236.968527 -147.537741) (xy 236.991169 -147.587318) (xy 237.006524 -147.639613) (xy 237.01428 -147.693561)
			(xy 237.014766 -147.720812) (xy 237.014306 -147.74768) (xy 237.006761 -147.800882) (xy 236.991823 -147.852499)
			(xy 236.969787 -147.901508) (xy 236.94109 -147.946939) (xy 236.906299 -147.987891) (xy 236.886496 -148.006054)
			(xy 236.878114 -148.01342) (xy 236.869478 -148.032978) (xy 236.869224 -148.131022) (xy 236.87786 -148.150326)
			(xy 236.885988 -148.157692) (xy 236.908614 -148.178755) (xy 236.947416 -148.226873) (xy 236.963204 -148.25345)
			(xy 236.969207 -148.262889) (xy 236.987436 -148.275808) (xy 237.009432 -148.27973) (xy 237.020354 -148.277326)
			(xy 237.040847 -148.272114) (xy 237.082418 -148.26436) (xy 237.103412 -148.261832) (xy 237.12297 -148.259546)
			(xy 237.148624 -148.230844) (xy 237.148624 -145.07972) (xy 237.148118 -145.069669) (xy 237.140397 -145.051109)
			(xy 237.133638 -145.043652) (xy 237.039658 -144.949672) (xy 237.032546 -144.94256) (xy 237.014258 -144.934686)
			(xy 236.923072 -144.933924) (xy 236.904784 -144.94129) (xy 236.897418 -144.948148) (xy 236.875963 -144.967947)
			(xy 236.82816 -145.001457) (xy 236.775814 -145.027301) (xy 236.720144 -145.044875) (xy 236.662447 -145.05377)
			(xy 236.633258 -145.05432) (xy 236.605747 -145.053836) (xy 236.551295 -145.045925) (xy 236.498545 -145.030275)
			(xy 236.44859 -145.007209) (xy 236.402466 -144.977206) (xy 236.361131 -144.940889) (xy 236.325442 -144.89901)
			(xy 236.296139 -144.852439) (xy 236.284516 -144.827498) (xy 236.280706 -144.818862) (xy 236.222032 -144.760188)
			(xy 236.214634 -144.753343) (xy 236.196035 -144.745619) (xy 236.185964 -144.745202) (xy 235.328968 -144.745202)
			(xy 235.310172 -144.752822) (xy 235.30306 -144.760188) (xy 234.952032 -145.111216) (xy 234.945185 -145.118614)
			(xy 234.937451 -145.137212) (xy 234.937046 -145.147284) (xy 234.937046 -145.688812) (xy 236.25124 -145.688812)
			(xy 236.255311 -145.63319) (xy 236.267437 -145.578753) (xy 236.28736 -145.526662) (xy 236.314656 -145.478027)
			(xy 236.348742 -145.433884) (xy 236.388891 -145.395175) (xy 236.434249 -145.362724) (xy 236.483849 -145.337223)
			(xy 236.536633 -145.319216) (xy 236.591476 -145.309086) (xy 236.64721 -145.307049) (xy 236.702647 -145.313149)
			(xy 236.756604 -145.327255) (xy 236.807933 -145.349067) (xy 236.855539 -145.378121) (xy 236.898407 -145.413796)
			(xy 236.935624 -145.455333) (xy 236.966397 -145.501846) (xy 236.990069 -145.552343) (xy 237.006137 -145.60575)
			(xy 237.014257 -145.660926) (xy 237.014766 -145.688812) (xy 237.014257 -145.716698) (xy 237.006137 -145.771874)
			(xy 236.990069 -145.825281) (xy 236.966397 -145.875778) (xy 236.935624 -145.922291) (xy 236.898407 -145.963828)
			(xy 236.855539 -145.999503) (xy 236.807933 -146.028557) (xy 236.756604 -146.050369) (xy 236.702647 -146.064475)
			(xy 236.64721 -146.070575) (xy 236.591476 -146.068538) (xy 236.536633 -146.058408) (xy 236.483849 -146.040401)
			(xy 236.434249 -146.0149) (xy 236.388891 -145.982449) (xy 236.348742 -145.94374) (xy 236.314656 -145.899597)
			(xy 236.28736 -145.850962) (xy 236.267437 -145.798871) (xy 236.255311 -145.744434) (xy 236.25124 -145.688812)
			(xy 234.937046 -145.688812) (xy 234.937046 -146.704812) (xy 236.25124 -146.704812) (xy 236.255311 -146.64919)
			(xy 236.267437 -146.594753) (xy 236.28736 -146.542662) (xy 236.314656 -146.494027) (xy 236.348742 -146.449884)
			(xy 236.388891 -146.411175) (xy 236.434249 -146.378724) (xy 236.483849 -146.353223) (xy 236.536633 -146.335216)
			(xy 236.591476 -146.325086) (xy 236.64721 -146.323049) (xy 236.702647 -146.329149) (xy 236.756604 -146.343255)
			(xy 236.807933 -146.365067) (xy 236.855539 -146.394121) (xy 236.898407 -146.429796) (xy 236.935624 -146.471333)
			(xy 236.966397 -146.517846) (xy 236.990069 -146.568343) (xy 237.006137 -146.62175) (xy 237.014257 -146.676926)
			(xy 237.014766 -146.704812) (xy 237.014257 -146.732698) (xy 237.006137 -146.787874) (xy 236.990069 -146.841281)
			(xy 236.966397 -146.891778) (xy 236.935624 -146.938291) (xy 236.898407 -146.979828) (xy 236.855539 -147.015503)
			(xy 236.807933 -147.044557) (xy 236.756604 -147.066369) (xy 236.702647 -147.080475) (xy 236.64721 -147.086575)
			(xy 236.591476 -147.084538) (xy 236.536633 -147.074408) (xy 236.483849 -147.056401) (xy 236.434249 -147.0309)
			(xy 236.388891 -146.998449) (xy 236.348742 -146.95974) (xy 236.314656 -146.915597) (xy 236.28736 -146.866962)
			(xy 236.267437 -146.814871) (xy 236.255311 -146.760434) (xy 236.25124 -146.704812) (xy 234.937046 -146.704812)
			(xy 234.937046 -147.26412) (xy 234.936618 -147.274187) (xy 234.928892 -147.292781) (xy 234.92206 -147.300188)
			(xy 234.907328 -147.31492) (xy 234.900672 -147.32214) (xy 234.892947 -147.340174) (xy 234.892588 -147.35979)
			(xy 234.899648 -147.378095) (xy 234.906058 -147.385532) (xy 234.908344 -147.387818) (xy 234.909614 -147.389088)
			(xy 234.931662 -147.410782) (xy 234.970312 -147.459074) (xy 235.002111 -147.512128) (xy 235.02648 -147.56898)
			(xy 235.042977 -147.628593) (xy 235.0513 -147.689885) (xy 235.051854 -147.720812) (xy 235.051854 -147.730464)
			(xy 235.050772 -147.76002) (xy 235.041928 -147.8185) (xy 235.025625 -147.875354) (xy 235.002133 -147.929633)
			(xy 234.971844 -147.980433) (xy 234.935263 -148.026908) (xy 234.892999 -148.068284) (xy 234.845758 -148.10387)
			(xy 234.794326 -148.133073) (xy 234.73956 -148.155407) (xy 234.682373 -148.1705) (xy 234.623719 -148.178099)
			(xy 234.594146 -148.17852) (xy 234.564175 -148.178054) (xy 234.504744 -148.170235) (xy 234.446843 -148.154726)
			(xy 234.391462 -148.131792) (xy 234.339548 -148.101824) (xy 234.29199 -148.065337) (xy 234.249601 -148.022954)
			(xy 234.213108 -147.975401) (xy 234.183134 -147.923491) (xy 234.160192 -147.868112) (xy 234.144676 -147.810213)
			(xy 234.13685 -147.750783) (xy 234.136438 -147.720812) (xy 234.136438 -147.717002) (xy 234.135951 -147.706991)
			(xy 234.128293 -147.688492) (xy 234.114141 -147.674329) (xy 234.095648 -147.666657) (xy 234.085638 -147.666202)
			(xy 232.153968 -147.666202) (xy 232.135172 -147.673822) (xy 232.12806 -147.681188) (xy 232.050844 -147.758404)
			(xy 232.044166 -147.765816) (xy 232.036594 -147.784252) (xy 232.036112 -147.794218) (xy 232.036112 -149.660864)
			(xy 233.6071 -149.660864) (xy 233.611171 -149.605242) (xy 233.623297 -149.550805) (xy 233.64322 -149.498714)
			(xy 233.670516 -149.450079) (xy 233.704602 -149.405936) (xy 233.744751 -149.367227) (xy 233.790109 -149.334776)
			(xy 233.839709 -149.309275) (xy 233.892493 -149.291268) (xy 233.947336 -149.281138) (xy 234.00307 -149.279101)
			(xy 234.058507 -149.285201) (xy 234.112464 -149.299307) (xy 234.163793 -149.321119) (xy 234.211399 -149.350173)
			(xy 234.254267 -149.385848) (xy 234.291484 -149.427385) (xy 234.322257 -149.473898) (xy 234.345929 -149.524395)
			(xy 234.361997 -149.577802) (xy 234.370117 -149.632978) (xy 234.370626 -149.660864) (xy 234.370117 -149.68875)
			(xy 234.361997 -149.743926) (xy 234.345929 -149.797333) (xy 234.322257 -149.84783) (xy 234.291484 -149.894343)
			(xy 234.254267 -149.93588) (xy 234.211399 -149.971555) (xy 234.163793 -150.000609) (xy 234.112464 -150.022421)
			(xy 234.058507 -150.036527) (xy 234.00307 -150.042627) (xy 233.947336 -150.04059) (xy 233.892493 -150.03046)
			(xy 233.839709 -150.012453) (xy 233.790109 -149.986952) (xy 233.744751 -149.954501) (xy 233.704602 -149.915792)
			(xy 233.670516 -149.871649) (xy 233.64322 -149.823014) (xy 233.623297 -149.770923) (xy 233.611171 -149.716486)
			(xy 233.6071 -149.660864) (xy 232.036112 -149.660864) (xy 232.036112 -149.960838) (xy 232.035568 -149.970823)
			(xy 232.027846 -149.989246) (xy 232.021126 -149.996652) (xy 231.950768 -150.06701) (xy 231.949498 -150.06828)
			(xy 231.948736 -150.069042) (xy 231.94645 -150.071582) (xy 231.453436 -150.564596) (xy 231.448356 -150.564596)
			(xy 231.428798 -150.572724) (xy 231.42417 -150.574498) (xy 231.414449 -150.576418) (xy 231.409494 -150.576534)
			(xy 230.0605 -150.576534) (xy 230.041704 -150.584154) (xy 230.034592 -150.59152) (xy 229.982268 -150.643844)
			(xy 229.975421 -150.651242) (xy 229.967692 -150.669841) (xy 229.967282 -150.679912) (xy 229.967282 -151.664162)
			(xy 231.773474 -151.664162) (xy 231.777545 -151.60854) (xy 231.789671 -151.554103) (xy 231.809594 -151.502012)
			(xy 231.83689 -151.453377) (xy 231.870976 -151.409234) (xy 231.911125 -151.370525) (xy 231.956483 -151.338074)
			(xy 232.006083 -151.312573) (xy 232.058867 -151.294566) (xy 232.11371 -151.284436) (xy 232.169444 -151.282399)
			(xy 232.224881 -151.288499) (xy 232.278838 -151.302605) (xy 232.330167 -151.324417) (xy 232.377773 -151.353471)
			(xy 232.420641 -151.389146) (xy 232.457858 -151.430683) (xy 232.488631 -151.477196) (xy 232.512303 -151.527693)
			(xy 232.528371 -151.5811) (xy 232.536491 -151.636276) (xy 232.537 -151.664162) (xy 232.536491 -151.692048)
			(xy 232.528371 -151.747224) (xy 232.512303 -151.800631) (xy 232.488631 -151.851128) (xy 232.457858 -151.897641)
			(xy 232.420641 -151.939178) (xy 232.377773 -151.974853) (xy 232.330167 -152.003907) (xy 232.278838 -152.025719)
			(xy 232.224881 -152.039825) (xy 232.169444 -152.045925) (xy 232.11371 -152.043888) (xy 232.058867 -152.033758)
			(xy 232.006083 -152.015751) (xy 231.956483 -151.99025) (xy 231.911125 -151.957799) (xy 231.870976 -151.91909)
			(xy 231.83689 -151.874947) (xy 231.809594 -151.826312) (xy 231.789671 -151.774221) (xy 231.777545 -151.719784)
			(xy 231.773474 -151.664162) (xy 229.967282 -151.664162) (xy 229.967282 -153.641044) (xy 229.974902 -153.65984)
			(xy 229.982268 -153.666952) (xy 230.216456 -153.900886) (xy 230.223857 -153.907725) (xy 230.242455 -153.915442)
			(xy 230.252524 -153.915872) (xy 236.423454 -153.915872)
		)
		(stroke
			(width 0)
			(type solid)
		)
		(fill yes)
		(layer "B.Cu")
		(net "P3V3_CLK_GEN_VDD_CK440_PEX")
	)
	(gr_poly
		(pts
			(xy 340.57082 -216.976706) (xy 340.576401 -216.976556) (xy 340.587292 -216.974112) (xy 340.59241 -216.97188)
			(xy 340.620858 -216.958672) (xy 340.627716 -216.950798) (xy 340.644686 -216.932342) (xy 340.682914 -216.899901)
			(xy 340.725311 -216.873139) (xy 340.771041 -216.852583) (xy 340.819201 -216.838641) (xy 340.86884 -216.831586)
			(xy 340.893908 -216.831164) (xy 340.894416 -216.831164) (xy 340.919487 -216.831587) (xy 340.969134 -216.838614)
			(xy 341.017303 -216.852542) (xy 341.06304 -216.873094) (xy 341.105439 -216.899863) (xy 341.14366 -216.932319)
			(xy 341.160608 -216.950798) (xy 341.167466 -216.958672) (xy 341.195914 -216.97188) (xy 341.201028 -216.974123)
			(xy 341.211922 -216.976564) (xy 341.217504 -216.976706) (xy 341.370666 -216.976706) (xy 341.376248 -216.976562)
			(xy 341.387145 -216.974129) (xy 341.392256 -216.97188) (xy 341.420704 -216.958672) (xy 341.427562 -216.950798)
			(xy 341.444533 -216.932344) (xy 341.482762 -216.899908) (xy 341.52516 -216.873151) (xy 341.57089 -216.852602)
			(xy 341.619049 -216.838665) (xy 341.668687 -216.831617) (xy 341.693754 -216.831164) (xy 341.694262 -216.831164)
			(xy 341.719332 -216.83159) (xy 341.768976 -216.838623) (xy 341.817141 -216.852555) (xy 341.862873 -216.873111)
			(xy 341.905267 -216.899883) (xy 341.943482 -216.932341) (xy 341.960454 -216.950798) (xy 341.967312 -216.958672)
			(xy 341.99576 -216.97188) (xy 342.000875 -216.974118) (xy 342.011769 -216.97655) (xy 342.01735 -216.976706)
			(xy 342.970358 -216.976706) (xy 342.975941 -216.976563) (xy 342.986838 -216.974131) (xy 342.991948 -216.97188)
			(xy 343.020396 -216.958672) (xy 343.027254 -216.950798) (xy 343.044225 -216.932344) (xy 343.082454 -216.899907)
			(xy 343.124852 -216.873149) (xy 343.170582 -216.852599) (xy 343.218741 -216.838661) (xy 343.268378 -216.831612)
			(xy 343.293446 -216.831164) (xy 343.293954 -216.831164) (xy 343.319024 -216.831589) (xy 343.368668 -216.838622)
			(xy 343.416834 -216.852553) (xy 343.462567 -216.873108) (xy 343.504962 -216.89988) (xy 343.543178 -216.932337)
			(xy 343.560146 -216.950798) (xy 343.567004 -216.958672) (xy 343.595452 -216.97188) (xy 343.600567 -216.974119)
			(xy 343.611461 -216.976552) (xy 343.617042 -216.976706) (xy 343.770204 -216.976706) (xy 343.775785 -216.976558)
			(xy 343.786678 -216.974117) (xy 343.791794 -216.97188) (xy 343.820242 -216.958672) (xy 343.8271 -216.950798)
			(xy 343.84407 -216.932341) (xy 343.882297 -216.899898) (xy 343.924694 -216.873134) (xy 343.970424 -216.852577)
			(xy 344.018584 -216.838632) (xy 344.068223 -216.831575) (xy 344.093292 -216.831164) (xy 344.0938 -216.831164)
			(xy 344.118872 -216.831586) (xy 344.16852 -216.838611) (xy 344.21669 -216.852537) (xy 344.262429 -216.873088)
			(xy 344.304829 -216.899856) (xy 344.343052 -216.932311) (xy 344.359992 -216.950798) (xy 344.36685 -216.958672)
			(xy 344.395298 -216.97188) (xy 344.400412 -216.974124) (xy 344.411306 -216.976569) (xy 344.416888 -216.976706)
			(xy 344.570558 -216.976706) (xy 344.576141 -216.976563) (xy 344.587038 -216.974131) (xy 344.592148 -216.97188)
			(xy 344.620596 -216.958672) (xy 344.627454 -216.950798) (xy 344.646163 -216.930455) (xy 344.688752 -216.895234)
			(xy 344.736271 -216.867015) (xy 344.787578 -216.846474) (xy 344.814398 -216.8398) (xy 344.83167 -216.835736)
			(xy 344.853768 -216.80805) (xy 344.853768 -216.570052) (xy 344.854396 -216.55821) (xy 344.864999 -216.537031)
			(xy 344.874088 -216.529412) (xy 344.955114 -216.468452) (xy 344.963474 -216.461815) (xy 344.977445 -216.445681)
			(xy 344.9828 -216.436448) (xy 344.994738 -216.414858) (xy 344.999878 -216.404383) (xy 345.001053 -216.381105)
			(xy 344.997024 -216.370154) (xy 344.987372 -216.348056) (xy 344.987118 -216.347548) (xy 344.9801 -216.332247)
			(xy 344.957779 -216.307075) (xy 344.94343 -216.298272) (xy 344.943176 -216.298272) (xy 344.9202 -216.284822)
			(xy 344.878873 -216.251268) (xy 344.843976 -216.211069) (xy 344.81656 -216.165438) (xy 344.797453 -216.115752)
			(xy 344.791792 -216.089738) (xy 344.791792 -215.935306) (xy 344.775028 -215.909906) (xy 344.76055 -215.904064)
			(xy 344.737501 -215.893882) (xy 344.694414 -215.867761) (xy 344.655602 -215.835629) (xy 344.621897 -215.798174)
			(xy 344.594023 -215.756199) (xy 344.572576 -215.710604) (xy 344.558016 -215.662366) (xy 344.550655 -215.61252)
			(xy 344.550238 -215.587326) (xy 344.550712 -215.561354) (xy 344.55853 -215.510003) (xy 344.573991 -215.460414)
			(xy 344.596743 -215.413719) (xy 344.626267 -215.370982) (xy 344.66189 -215.333179) (xy 344.682064 -215.316816)
			(xy 344.6907 -215.309958) (xy 344.70086 -215.290654) (xy 344.706194 -215.203786) (xy 344.706356 -215.193014)
			(xy 344.698715 -215.172892) (xy 344.691462 -215.164924) (xy 344.515948 -214.98941) (xy 344.507926 -214.982244)
			(xy 344.487841 -214.974618) (xy 344.477086 -214.974678) (xy 344.390218 -214.980012) (xy 344.370914 -214.990172)
			(xy 344.364056 -214.998808) (xy 344.347681 -215.018972) (xy 344.309884 -215.054602) (xy 344.267151 -215.084132)
			(xy 344.220458 -215.106888) (xy 344.170869 -215.12235) (xy 344.119518 -215.130166) (xy 344.093546 -215.130634)
			(xy 344.06661 -215.130105) (xy 344.013399 -215.121687) (xy 343.962155 -215.105067) (xy 343.914133 -215.080651)
			(xy 343.870511 -215.049039) (xy 343.832358 -215.011005) (xy 343.80061 -214.967482) (xy 343.776045 -214.919537)
			(xy 343.759265 -214.868345) (xy 343.754456 -214.841836) (xy 343.751408 -214.823294) (xy 343.723214 -214.799164)
			(xy 343.664032 -214.799164) (xy 343.635838 -214.823294) (xy 343.63279 -214.841836) (xy 343.627988 -214.868349)
			(xy 343.61122 -214.919553) (xy 343.586662 -214.96751) (xy 343.554917 -215.011045) (xy 343.516764 -215.049088)
			(xy 343.473138 -215.080707) (xy 343.42511 -215.105126) (xy 343.373858 -215.121747) (xy 343.32064 -215.13016)
			(xy 343.26676 -215.13016) (xy 343.213542 -215.121747) (xy 343.16229 -215.105126) (xy 343.114262 -215.080707)
			(xy 343.070636 -215.049088) (xy 343.032483 -215.011045) (xy 343.000738 -214.96751) (xy 342.97618 -214.919553)
			(xy 342.959412 -214.868349) (xy 342.95461 -214.841836) (xy 342.951562 -214.823294) (xy 342.923368 -214.799164)
			(xy 342.06434 -214.799164) (xy 342.036146 -214.823294) (xy 342.033098 -214.841836) (xy 342.028296 -214.868349)
			(xy 342.011528 -214.919553) (xy 341.98697 -214.96751) (xy 341.955225 -215.011045) (xy 341.917072 -215.049088)
			(xy 341.873446 -215.080707) (xy 341.825418 -215.105126) (xy 341.774166 -215.121747) (xy 341.720948 -215.13016)
			(xy 341.667068 -215.13016) (xy 341.61385 -215.121747) (xy 341.562598 -215.105126) (xy 341.51457 -215.080707)
			(xy 341.470944 -215.049088) (xy 341.432791 -215.011045) (xy 341.401046 -214.96751) (xy 341.376488 -214.919553)
			(xy 341.35972 -214.868349) (xy 341.354918 -214.841836) (xy 341.35187 -214.823294) (xy 341.323676 -214.799164)
			(xy 341.264494 -214.799164) (xy 341.2363 -214.823294) (xy 341.233252 -214.841836) (xy 341.22845 -214.868349)
			(xy 341.211682 -214.919553) (xy 341.187124 -214.96751) (xy 341.155379 -215.011045) (xy 341.117226 -215.049088)
			(xy 341.0736 -215.080707) (xy 341.025572 -215.105126) (xy 340.97432 -215.121747) (xy 340.921102 -215.13016)
			(xy 340.867222 -215.13016) (xy 340.814004 -215.121747) (xy 340.762752 -215.105126) (xy 340.714724 -215.080707)
			(xy 340.671098 -215.049088) (xy 340.632945 -215.011045) (xy 340.6012 -214.96751) (xy 340.576642 -214.919553)
			(xy 340.559874 -214.868349) (xy 340.555072 -214.841836) (xy 340.552024 -214.823294) (xy 340.52383 -214.799164)
			(xy 340.464394 -214.799164) (xy 340.4362 -214.823294) (xy 340.433152 -214.841836) (xy 340.428354 -214.868349)
			(xy 340.411591 -214.919552) (xy 340.387035 -214.967508) (xy 340.35529 -215.01104) (xy 340.317135 -215.049078)
			(xy 340.273506 -215.080689) (xy 340.225474 -215.105096) (xy 340.17422 -215.121701) (xy 340.121001 -215.130096)
			(xy 340.094062 -215.130634) (xy 340.072757 -215.130348) (xy 340.030467 -215.125132) (xy 340.009734 -215.12022)
			(xy 339.996526 -215.116918) (xy 339.971126 -215.123776) (xy 339.90788 -215.187022) (xy 339.901198 -215.194431)
			(xy 339.893606 -215.21286) (xy 339.893616 -215.232791) (xy 339.901226 -215.251212) (xy 339.90788 -215.25865)
			(xy 339.919056 -215.269826) (xy 339.948774 -215.275668) (xy 339.963252 -215.269826) (xy 339.984076 -215.261633)
			(xy 340.027315 -215.250102) (xy 340.071687 -215.244291) (xy 340.094062 -215.243918) (xy 340.119763 -215.244371)
			(xy 340.17059 -215.252027) (xy 340.219709 -215.267174) (xy 340.266022 -215.289472) (xy 340.308493 -215.318424)
			(xy 340.346175 -215.353384) (xy 340.378225 -215.393569) (xy 340.403927 -215.438083) (xy 340.422707 -215.48593)
			(xy 340.434146 -215.536043) (xy 340.437988 -215.5873) (xy 340.437986 -215.587326) (xy 340.550249 -215.587326)
			(xy 340.554279 -215.534828) (xy 340.566276 -215.48356) (xy 340.585959 -215.434725) (xy 340.612865 -215.389466)
			(xy 340.646365 -215.348845) (xy 340.685673 -215.313814) (xy 340.729868 -215.285194) (xy 340.777913 -215.263655)
			(xy 340.828684 -215.249703) (xy 340.880989 -215.243665) (xy 340.933603 -215.245682) (xy 340.985293 -215.255706)
			(xy 341.034846 -215.273504) (xy 341.081102 -215.298657) (xy 341.122976 -215.330576) (xy 341.159488 -215.368514)
			(xy 341.18978 -215.41158) (xy 341.213143 -215.458765) (xy 341.229029 -215.508964) (xy 341.237066 -215.561)
			(xy 341.23757 -215.587326) (xy 341.350095 -215.587326) (xy 341.354125 -215.534828) (xy 341.366122 -215.48356)
			(xy 341.385805 -215.434725) (xy 341.412711 -215.389466) (xy 341.446211 -215.348845) (xy 341.485519 -215.313814)
			(xy 341.529714 -215.285194) (xy 341.577759 -215.263655) (xy 341.62853 -215.249703) (xy 341.680835 -215.243665)
			(xy 341.733449 -215.245682) (xy 341.785139 -215.255706) (xy 341.834692 -215.273504) (xy 341.880948 -215.298657)
			(xy 341.922822 -215.330576) (xy 341.959334 -215.368514) (xy 341.989626 -215.41158) (xy 342.012989 -215.458765)
			(xy 342.028875 -215.508964) (xy 342.036912 -215.561) (xy 342.037416 -215.587326) (xy 342.949787 -215.587326)
			(xy 342.953817 -215.534828) (xy 342.965814 -215.48356) (xy 342.985497 -215.434725) (xy 343.012403 -215.389466)
			(xy 343.045903 -215.348845) (xy 343.085211 -215.313814) (xy 343.129406 -215.285194) (xy 343.177451 -215.263655)
			(xy 343.228222 -215.249703) (xy 343.280527 -215.243665) (xy 343.333141 -215.245682) (xy 343.384831 -215.255706)
			(xy 343.434384 -215.273504) (xy 343.48064 -215.298657) (xy 343.522514 -215.330576) (xy 343.559026 -215.368514)
			(xy 343.589318 -215.41158) (xy 343.612681 -215.458765) (xy 343.628567 -215.508964) (xy 343.636604 -215.561)
			(xy 343.637108 -215.587326) (xy 343.749633 -215.587326) (xy 343.753663 -215.534828) (xy 343.76566 -215.48356)
			(xy 343.785343 -215.434725) (xy 343.812249 -215.389466) (xy 343.845749 -215.348845) (xy 343.885057 -215.313814)
			(xy 343.929252 -215.285194) (xy 343.977297 -215.263655) (xy 344.028068 -215.249703) (xy 344.080373 -215.243665)
			(xy 344.132987 -215.245682) (xy 344.184677 -215.255706) (xy 344.23423 -215.273504) (xy 344.280486 -215.298657)
			(xy 344.32236 -215.330576) (xy 344.358872 -215.368514) (xy 344.389164 -215.41158) (xy 344.412527 -215.458765)
			(xy 344.428413 -215.508964) (xy 344.43645 -215.561) (xy 344.436954 -215.587326) (xy 344.43645 -215.613652)
			(xy 344.428413 -215.665688) (xy 344.412527 -215.715887) (xy 344.389164 -215.763072) (xy 344.358872 -215.806138)
			(xy 344.32236 -215.844076) (xy 344.280486 -215.875995) (xy 344.23423 -215.901148) (xy 344.184677 -215.918946)
			(xy 344.132987 -215.92897) (xy 344.080373 -215.930987) (xy 344.028068 -215.924949) (xy 343.977297 -215.910997)
			(xy 343.929252 -215.889458) (xy 343.885057 -215.860838) (xy 343.845749 -215.825807) (xy 343.812249 -215.785186)
			(xy 343.785343 -215.739927) (xy 343.76566 -215.691092) (xy 343.753663 -215.639824) (xy 343.749633 -215.587326)
			(xy 343.637108 -215.587326) (xy 343.636604 -215.613652) (xy 343.628567 -215.665688) (xy 343.612681 -215.715887)
			(xy 343.589318 -215.763072) (xy 343.559026 -215.806138) (xy 343.522514 -215.844076) (xy 343.48064 -215.875995)
			(xy 343.434384 -215.901148) (xy 343.384831 -215.918946) (xy 343.333141 -215.92897) (xy 343.280527 -215.930987)
			(xy 343.228222 -215.924949) (xy 343.177451 -215.910997) (xy 343.129406 -215.889458) (xy 343.085211 -215.860838)
			(xy 343.045903 -215.825807) (xy 343.012403 -215.785186) (xy 342.985497 -215.739927) (xy 342.965814 -215.691092)
			(xy 342.953817 -215.639824) (xy 342.949787 -215.587326) (xy 342.037416 -215.587326) (xy 342.036912 -215.613652)
			(xy 342.028875 -215.665688) (xy 342.012989 -215.715887) (xy 341.989626 -215.763072) (xy 341.959334 -215.806138)
			(xy 341.922822 -215.844076) (xy 341.880948 -215.875995) (xy 341.834692 -215.901148) (xy 341.785139 -215.918946)
			(xy 341.733449 -215.92897) (xy 341.680835 -215.930987) (xy 341.62853 -215.924949) (xy 341.577759 -215.910997)
			(xy 341.529714 -215.889458) (xy 341.485519 -215.860838) (xy 341.446211 -215.825807) (xy 341.412711 -215.785186)
			(xy 341.385805 -215.739927) (xy 341.366122 -215.691092) (xy 341.354125 -215.639824) (xy 341.350095 -215.587326)
			(xy 341.23757 -215.587326) (xy 341.237066 -215.613652) (xy 341.229029 -215.665688) (xy 341.213143 -215.715887)
			(xy 341.18978 -215.763072) (xy 341.159488 -215.806138) (xy 341.122976 -215.844076) (xy 341.081102 -215.875995)
			(xy 341.034846 -215.901148) (xy 340.985293 -215.918946) (xy 340.933603 -215.92897) (xy 340.880989 -215.930987)
			(xy 340.828684 -215.924949) (xy 340.777913 -215.910997) (xy 340.729868 -215.889458) (xy 340.685673 -215.860838)
			(xy 340.646365 -215.825807) (xy 340.612865 -215.785186) (xy 340.585959 -215.739927) (xy 340.566276 -215.691092)
			(xy 340.554279 -215.639824) (xy 340.550249 -215.587326) (xy 340.437986 -215.587326) (xy 340.434146 -215.638557)
			(xy 340.422707 -215.68867) (xy 340.403927 -215.736517) (xy 340.378225 -215.781031) (xy 340.346175 -215.821216)
			(xy 340.308493 -215.856176) (xy 340.266022 -215.885128) (xy 340.219709 -215.907426) (xy 340.17059 -215.922573)
			(xy 340.119763 -215.930229) (xy 340.094062 -215.930734) (xy 340.072143 -215.930389) (xy 340.028663 -215.924802)
			(xy 339.986252 -215.913712) (xy 339.965792 -215.905842) (xy 339.953854 -215.901016) (xy 339.928962 -215.90381)
			(xy 339.848444 -215.957912) (xy 339.838424 -215.965441) (xy 339.826698 -215.987557) (xy 339.826092 -216.000076)
			(xy 339.826092 -216.278714) (xy 339.826579 -216.289087) (xy 339.834759 -216.308154) (xy 339.84979 -216.322454)
			(xy 339.859366 -216.326466) (xy 339.85962 -216.326466) (xy 339.882528 -216.335258) (xy 339.925418 -216.359086)
			(xy 339.963947 -216.389465) (xy 339.997122 -216.425613) (xy 340.011004 -216.445846) (xy 340.01329 -216.449148)
			(xy 340.017961 -216.454882) (xy 340.028675 -216.465076) (xy 340.034626 -216.469468) (xy 340.041484 -216.474294)
			(xy 340.05266 -216.483692) (xy 340.072721 -216.501276) (xy 340.107019 -216.542128) (xy 340.133706 -216.588314)
			(xy 340.151971 -216.63843) (xy 340.161259 -216.690956) (xy 340.16188 -216.717626) (xy 340.16188 -216.779602)
			(xy 340.162303 -216.789673) (xy 340.170015 -216.808278) (xy 340.176866 -216.81567) (xy 340.212172 -216.850976)
			(xy 340.222078 -216.854786) (xy 340.248312 -216.865492) (xy 340.297271 -216.894008) (xy 340.341082 -216.929935)
			(xy 340.360254 -216.950798) (xy 340.367112 -216.958672) (xy 340.39556 -216.97188) (xy 340.400675 -216.974118)
			(xy 340.411569 -216.97655) (xy 340.41715 -216.976706)
		)
		(stroke
			(width 0)
			(type solid)
		)
		(fill yes)
		(layer "B.Cu")
		(net "P3V3_FPGA_VCCIO2")
	)
	(gr_poly
		(pts
			(xy 364.770162 -399.739104) (xy 364.780227 -399.738669) (xy 364.798816 -399.73094) (xy 364.80623 -399.724118)
			(xy 365.563404 -398.966944) (xy 365.570241 -398.959542) (xy 365.577955 -398.940944) (xy 365.57839 -398.930876)
			(xy 365.57839 -397.362172) (xy 365.577771 -397.350748) (xy 365.567889 -397.330149) (xy 365.55934 -397.322548)
			(xy 365.537585 -397.304329) (xy 365.499185 -397.262552) (xy 365.467396 -397.215549) (xy 365.442919 -397.164356)
			(xy 365.426294 -397.110103) (xy 365.417888 -397.053986) (xy 365.417886 -396.997242) (xy 365.426288 -396.941124)
			(xy 365.442909 -396.886869) (xy 365.467382 -396.835675) (xy 365.499168 -396.788669) (xy 365.537564 -396.74689)
			(xy 365.55934 -396.728696) (xy 365.567854 -396.721065) (xy 365.577746 -396.700487) (xy 365.57839 -396.689072)
			(xy 365.57839 -390.90981) (xy 365.577968 -390.899739) (xy 365.570255 -390.881133) (xy 365.563404 -390.873742)
			(xy 363.040422 -388.35076) (xy 363.028484 -388.343902) (xy 363.021626 -388.342124) (xy 362.994549 -388.334763)
			(xy 362.942754 -388.313185) (xy 362.894677 -388.284255) (xy 362.851355 -388.248595) (xy 362.813723 -388.206976)
			(xy 362.782591 -388.160295) (xy 362.758631 -388.109557) (xy 362.74236 -388.055858) (xy 362.734128 -388.000355)
			(xy 362.73359 -387.9723) (xy 362.733915 -387.950317) (xy 362.739012 -387.906647) (xy 362.74375 -387.885178)
			(xy 362.74502 -387.879336) (xy 362.74502 -386.60832) (xy 362.744487 -386.59833) (xy 362.736781 -386.579891)
			(xy 362.730034 -386.572506) (xy 360.389932 -384.232404) (xy 360.382583 -384.225603) (xy 360.364121 -384.217895)
			(xy 360.354118 -384.217418) (xy 356.972616 -384.217418) (xy 356.962553 -384.217857) (xy 356.943972 -384.225595)
			(xy 356.936548 -384.232404) (xy 355.990652 -385.1783) (xy 355.9838 -385.185696) (xy 355.976057 -385.204295)
			(xy 355.975666 -385.214368) (xy 355.975666 -387.160008) (xy 361.264706 -387.160008) (xy 361.268777 -387.104386)
			(xy 361.280903 -387.049949) (xy 361.300826 -386.997858) (xy 361.328122 -386.949223) (xy 361.362208 -386.90508)
			(xy 361.402357 -386.866371) (xy 361.447715 -386.83392) (xy 361.497315 -386.808419) (xy 361.550099 -386.790412)
			(xy 361.604942 -386.780282) (xy 361.660676 -386.778245) (xy 361.716113 -386.784345) (xy 361.77007 -386.798451)
			(xy 361.821399 -386.820263) (xy 361.869005 -386.849317) (xy 361.911873 -386.884992) (xy 361.94909 -386.926529)
			(xy 361.979863 -386.973042) (xy 362.003535 -387.023539) (xy 362.019603 -387.076946) (xy 362.027723 -387.132122)
			(xy 362.028232 -387.160008) (xy 362.027723 -387.187894) (xy 362.019603 -387.24307) (xy 362.003535 -387.296477)
			(xy 361.979863 -387.346974) (xy 361.94909 -387.393487) (xy 361.911873 -387.435024) (xy 361.869005 -387.470699)
			(xy 361.821399 -387.499753) (xy 361.77007 -387.521565) (xy 361.716113 -387.535671) (xy 361.660676 -387.541771)
			(xy 361.604942 -387.539734) (xy 361.550099 -387.529604) (xy 361.497315 -387.511597) (xy 361.447715 -387.486096)
			(xy 361.402357 -387.453645) (xy 361.362208 -387.414936) (xy 361.328122 -387.370793) (xy 361.300826 -387.322158)
			(xy 361.280903 -387.270067) (xy 361.268777 -387.21563) (xy 361.264706 -387.160008) (xy 355.975666 -387.160008)
			(xy 355.975666 -390.507728) (xy 361.709714 -390.507728) (xy 361.713785 -390.452106) (xy 361.725911 -390.397669)
			(xy 361.745834 -390.345578) (xy 361.77313 -390.296943) (xy 361.807216 -390.2528) (xy 361.847365 -390.214091)
			(xy 361.892723 -390.18164) (xy 361.942323 -390.156139) (xy 361.995107 -390.138132) (xy 362.04995 -390.128002)
			(xy 362.105684 -390.125965) (xy 362.161121 -390.132065) (xy 362.215078 -390.146171) (xy 362.266407 -390.167983)
			(xy 362.314013 -390.197037) (xy 362.356881 -390.232712) (xy 362.394098 -390.274249) (xy 362.424871 -390.320762)
			(xy 362.448543 -390.371259) (xy 362.464611 -390.424666) (xy 362.472731 -390.479842) (xy 362.47324 -390.507728)
			(xy 362.472731 -390.535614) (xy 362.464611 -390.59079) (xy 362.448543 -390.644197) (xy 362.424871 -390.694694)
			(xy 362.394098 -390.741207) (xy 362.356881 -390.782744) (xy 362.314013 -390.818419) (xy 362.266407 -390.847473)
			(xy 362.215078 -390.869285) (xy 362.161121 -390.883391) (xy 362.105684 -390.889491) (xy 362.04995 -390.887454)
			(xy 361.995107 -390.877324) (xy 361.942323 -390.859317) (xy 361.892723 -390.833816) (xy 361.847365 -390.801365)
			(xy 361.807216 -390.762656) (xy 361.77313 -390.718513) (xy 361.745834 -390.669878) (xy 361.725911 -390.617787)
			(xy 361.713785 -390.56335) (xy 361.709714 -390.507728) (xy 355.975666 -390.507728) (xy 355.975666 -392.007852)
			(xy 361.376212 -392.007852) (xy 361.380283 -391.95223) (xy 361.392409 -391.897793) (xy 361.412332 -391.845702)
			(xy 361.439628 -391.797067) (xy 361.473714 -391.752924) (xy 361.513863 -391.714215) (xy 361.559221 -391.681764)
			(xy 361.608821 -391.656263) (xy 361.661605 -391.638256) (xy 361.716448 -391.628126) (xy 361.772182 -391.626089)
			(xy 361.827619 -391.632189) (xy 361.881576 -391.646295) (xy 361.932905 -391.668107) (xy 361.980511 -391.697161)
			(xy 362.023379 -391.732836) (xy 362.060596 -391.774373) (xy 362.091369 -391.820886) (xy 362.115041 -391.871383)
			(xy 362.131109 -391.92479) (xy 362.139229 -391.979966) (xy 362.139738 -392.007852) (xy 362.139229 -392.035738)
			(xy 362.131109 -392.090914) (xy 362.115041 -392.144321) (xy 362.091369 -392.194818) (xy 362.060596 -392.241331)
			(xy 362.023379 -392.282868) (xy 361.980511 -392.318543) (xy 361.932905 -392.347597) (xy 361.881576 -392.369409)
			(xy 361.827619 -392.383515) (xy 361.772182 -392.389615) (xy 361.716448 -392.387578) (xy 361.661605 -392.377448)
			(xy 361.608821 -392.359441) (xy 361.559221 -392.33394) (xy 361.513863 -392.301489) (xy 361.473714 -392.26278)
			(xy 361.439628 -392.218637) (xy 361.412332 -392.170002) (xy 361.392409 -392.117911) (xy 361.380283 -392.063474)
			(xy 361.376212 -392.007852) (xy 355.975666 -392.007852) (xy 355.975666 -392.71575) (xy 364.690404 -392.71575)
			(xy 364.694475 -392.660128) (xy 364.706601 -392.605691) (xy 364.726524 -392.5536) (xy 364.75382 -392.504965)
			(xy 364.787906 -392.460822) (xy 364.828055 -392.422113) (xy 364.873413 -392.389662) (xy 364.923013 -392.364161)
			(xy 364.975797 -392.346154) (xy 365.03064 -392.336024) (xy 365.086374 -392.333987) (xy 365.141811 -392.340087)
			(xy 365.195768 -392.354193) (xy 365.247097 -392.376005) (xy 365.294703 -392.405059) (xy 365.337571 -392.440734)
			(xy 365.374788 -392.482271) (xy 365.405561 -392.528784) (xy 365.429233 -392.579281) (xy 365.445301 -392.632688)
			(xy 365.453421 -392.687864) (xy 365.45393 -392.71575) (xy 365.453421 -392.743636) (xy 365.445301 -392.798812)
			(xy 365.429233 -392.852219) (xy 365.405561 -392.902716) (xy 365.374788 -392.949229) (xy 365.337571 -392.990766)
			(xy 365.294703 -393.026441) (xy 365.247097 -393.055495) (xy 365.195768 -393.077307) (xy 365.141811 -393.091413)
			(xy 365.086374 -393.097513) (xy 365.03064 -393.095476) (xy 364.975797 -393.085346) (xy 364.923013 -393.067339)
			(xy 364.873413 -393.041838) (xy 364.828055 -393.009387) (xy 364.787906 -392.970678) (xy 364.75382 -392.926535)
			(xy 364.726524 -392.8779) (xy 364.706601 -392.825809) (xy 364.694475 -392.771372) (xy 364.690404 -392.71575)
			(xy 355.975666 -392.71575) (xy 355.975666 -393.12977) (xy 356.294688 -393.12977) (xy 356.298759 -393.074148)
			(xy 356.310885 -393.019711) (xy 356.330808 -392.96762) (xy 356.358104 -392.918985) (xy 356.39219 -392.874842)
			(xy 356.432339 -392.836133) (xy 356.477697 -392.803682) (xy 356.527297 -392.778181) (xy 356.580081 -392.760174)
			(xy 356.634924 -392.750044) (xy 356.690658 -392.748007) (xy 356.746095 -392.754107) (xy 356.800052 -392.768213)
			(xy 356.851381 -392.790025) (xy 356.898987 -392.819079) (xy 356.941855 -392.854754) (xy 356.979072 -392.896291)
			(xy 357.009845 -392.942804) (xy 357.033517 -392.993301) (xy 357.049585 -393.046708) (xy 357.057705 -393.101884)
			(xy 357.058214 -393.12977) (xy 357.057705 -393.157656) (xy 357.049585 -393.212832) (xy 357.033517 -393.266239)
			(xy 357.009845 -393.316736) (xy 356.979072 -393.363249) (xy 356.941855 -393.404786) (xy 356.898987 -393.440461)
			(xy 356.851381 -393.469515) (xy 356.800052 -393.491327) (xy 356.746095 -393.505433) (xy 356.690658 -393.511533)
			(xy 356.634924 -393.509496) (xy 356.580081 -393.499366) (xy 356.527297 -393.481359) (xy 356.477697 -393.455858)
			(xy 356.432339 -393.423407) (xy 356.39219 -393.384698) (xy 356.358104 -393.340555) (xy 356.330808 -393.29192)
			(xy 356.310885 -393.239829) (xy 356.298759 -393.185392) (xy 356.294688 -393.12977) (xy 355.975666 -393.12977)
			(xy 355.975666 -395.062964) (xy 363.741714 -395.062964) (xy 363.745785 -395.007342) (xy 363.757911 -394.952905)
			(xy 363.777834 -394.900814) (xy 363.80513 -394.852179) (xy 363.839216 -394.808036) (xy 363.879365 -394.769327)
			(xy 363.924723 -394.736876) (xy 363.974323 -394.711375) (xy 364.027107 -394.693368) (xy 364.08195 -394.683238)
			(xy 364.137684 -394.681201) (xy 364.193121 -394.687301) (xy 364.247078 -394.701407) (xy 364.298407 -394.723219)
			(xy 364.346013 -394.752273) (xy 364.388881 -394.787948) (xy 364.426098 -394.829485) (xy 364.456871 -394.875998)
			(xy 364.480543 -394.926495) (xy 364.496611 -394.979902) (xy 364.504731 -395.035078) (xy 364.50524 -395.062964)
			(xy 364.504731 -395.09085) (xy 364.496611 -395.146026) (xy 364.480543 -395.199433) (xy 364.456871 -395.24993)
			(xy 364.426098 -395.296443) (xy 364.388881 -395.33798) (xy 364.346013 -395.373655) (xy 364.298407 -395.402709)
			(xy 364.247078 -395.424521) (xy 364.193121 -395.438627) (xy 364.137684 -395.444727) (xy 364.08195 -395.44269)
			(xy 364.027107 -395.43256) (xy 363.974323 -395.414553) (xy 363.924723 -395.389052) (xy 363.879365 -395.356601)
			(xy 363.839216 -395.317892) (xy 363.80513 -395.273749) (xy 363.777834 -395.225114) (xy 363.757911 -395.173023)
			(xy 363.745785 -395.118586) (xy 363.741714 -395.062964) (xy 355.975666 -395.062964) (xy 355.975666 -395.750288)
			(xy 361.634022 -395.750288) (xy 361.638093 -395.694666) (xy 361.650219 -395.640229) (xy 361.670142 -395.588138)
			(xy 361.697438 -395.539503) (xy 361.731524 -395.49536) (xy 361.771673 -395.456651) (xy 361.817031 -395.4242)
			(xy 361.866631 -395.398699) (xy 361.919415 -395.380692) (xy 361.974258 -395.370562) (xy 362.029992 -395.368525)
			(xy 362.085429 -395.374625) (xy 362.139386 -395.388731) (xy 362.190715 -395.410543) (xy 362.238321 -395.439597)
			(xy 362.281189 -395.475272) (xy 362.318406 -395.516809) (xy 362.349179 -395.563322) (xy 362.372851 -395.613819)
			(xy 362.388919 -395.667226) (xy 362.397039 -395.722402) (xy 362.397548 -395.750288) (xy 362.397039 -395.778174)
			(xy 362.388919 -395.83335) (xy 362.372851 -395.886757) (xy 362.349179 -395.937254) (xy 362.318406 -395.983767)
			(xy 362.281189 -396.025304) (xy 362.238321 -396.060979) (xy 362.190715 -396.090033) (xy 362.139386 -396.111845)
			(xy 362.085429 -396.125951) (xy 362.029992 -396.132051) (xy 361.974258 -396.130014) (xy 361.919415 -396.119884)
			(xy 361.866631 -396.101877) (xy 361.817031 -396.076376) (xy 361.771673 -396.043925) (xy 361.731524 -396.005216)
			(xy 361.697438 -395.961073) (xy 361.670142 -395.912438) (xy 361.650219 -395.860347) (xy 361.638093 -395.80591)
			(xy 361.634022 -395.750288) (xy 355.975666 -395.750288) (xy 355.975666 -397.250412) (xy 361.238036 -397.250412)
			(xy 361.242107 -397.19479) (xy 361.254233 -397.140353) (xy 361.274156 -397.088262) (xy 361.301452 -397.039627)
			(xy 361.335538 -396.995484) (xy 361.375687 -396.956775) (xy 361.421045 -396.924324) (xy 361.470645 -396.898823)
			(xy 361.523429 -396.880816) (xy 361.578272 -396.870686) (xy 361.634006 -396.868649) (xy 361.689443 -396.874749)
			(xy 361.7434 -396.888855) (xy 361.794729 -396.910667) (xy 361.842335 -396.939721) (xy 361.885203 -396.975396)
			(xy 361.92242 -397.016933) (xy 361.953193 -397.063446) (xy 361.976865 -397.113943) (xy 361.992933 -397.16735)
			(xy 362.001053 -397.222526) (xy 362.001562 -397.250412) (xy 362.001053 -397.278298) (xy 361.992933 -397.333474)
			(xy 361.976865 -397.386881) (xy 361.953193 -397.437378) (xy 361.92242 -397.483891) (xy 361.885203 -397.525428)
			(xy 361.842335 -397.561103) (xy 361.794729 -397.590157) (xy 361.7434 -397.611969) (xy 361.689443 -397.626075)
			(xy 361.634006 -397.632175) (xy 361.578272 -397.630138) (xy 361.523429 -397.620008) (xy 361.470645 -397.602001)
			(xy 361.421045 -397.5765) (xy 361.375687 -397.544049) (xy 361.335538 -397.50534) (xy 361.301452 -397.461197)
			(xy 361.274156 -397.412562) (xy 361.254233 -397.360471) (xy 361.242107 -397.306034) (xy 361.238036 -397.250412)
			(xy 355.975666 -397.250412) (xy 355.975666 -398.475962) (xy 364.565436 -398.475962) (xy 364.569507 -398.42034)
			(xy 364.581633 -398.365903) (xy 364.601556 -398.313812) (xy 364.628852 -398.265177) (xy 364.662938 -398.221034)
			(xy 364.703087 -398.182325) (xy 364.748445 -398.149874) (xy 364.798045 -398.124373) (xy 364.850829 -398.106366)
			(xy 364.905672 -398.096236) (xy 364.961406 -398.094199) (xy 365.016843 -398.100299) (xy 365.0708 -398.114405)
			(xy 365.122129 -398.136217) (xy 365.169735 -398.165271) (xy 365.212603 -398.200946) (xy 365.24982 -398.242483)
			(xy 365.280593 -398.288996) (xy 365.304265 -398.339493) (xy 365.320333 -398.3929) (xy 365.328453 -398.448076)
			(xy 365.328962 -398.475962) (xy 365.328453 -398.503848) (xy 365.320333 -398.559024) (xy 365.304265 -398.612431)
			(xy 365.280593 -398.662928) (xy 365.24982 -398.709441) (xy 365.212603 -398.750978) (xy 365.169735 -398.786653)
			(xy 365.122129 -398.815707) (xy 365.0708 -398.837519) (xy 365.016843 -398.851625) (xy 364.961406 -398.857725)
			(xy 364.905672 -398.855688) (xy 364.850829 -398.845558) (xy 364.798045 -398.827551) (xy 364.748445 -398.80205)
			(xy 364.703087 -398.769599) (xy 364.662938 -398.73089) (xy 364.628852 -398.686747) (xy 364.601556 -398.638112)
			(xy 364.581633 -398.586021) (xy 364.569507 -398.531584) (xy 364.565436 -398.475962) (xy 355.975666 -398.475962)
			(xy 355.975666 -398.836388) (xy 355.976089 -398.846458) (xy 355.983807 -398.865059) (xy 355.990652 -398.872456)
			(xy 356.003098 -398.884902) (xy 356.009987 -398.891118) (xy 356.026954 -398.898595) (xy 356.045468 -398.899579)
			(xy 356.054406 -398.897094) (xy 356.154228 -398.86509) (xy 356.17277 -398.843246) (xy 356.175056 -398.829276)
			(xy 356.179794 -398.80276) (xy 356.195749 -398.751313) (xy 356.218782 -398.702622) (xy 356.248435 -398.657655)
			(xy 356.284118 -398.617306) (xy 356.325122 -398.582377) (xy 356.370632 -398.553564) (xy 356.419742 -398.531438)
			(xy 356.471476 -398.516441) (xy 356.524806 -398.508869) (xy 356.551738 -398.508474) (xy 356.578988 -398.508962)
			(xy 356.632933 -398.516723) (xy 356.685224 -398.532081) (xy 356.734797 -398.554724) (xy 356.780644 -398.584191)
			(xy 356.821831 -398.619883) (xy 356.857521 -398.661072) (xy 356.886985 -398.70692) (xy 356.909626 -398.756495)
			(xy 356.924981 -398.808787) (xy 356.932739 -398.862732) (xy 356.933246 -398.889982) (xy 356.932784 -398.916911)
			(xy 356.925213 -398.970235) (xy 356.910218 -399.021964) (xy 356.888098 -399.07107) (xy 356.859291 -399.116577)
			(xy 356.824372 -399.157581) (xy 356.784033 -399.193267) (xy 356.739076 -399.222926) (xy 356.690396 -399.245968)
			(xy 356.638958 -399.261935) (xy 356.612444 -399.266664) (xy 356.598474 -399.26895) (xy 356.57663 -399.287492)
			(xy 356.544626 -399.387314) (xy 356.542135 -399.396257) (xy 356.54307 -399.414781) (xy 356.55059 -399.431735)
			(xy 356.556818 -399.438622) (xy 356.842314 -399.724118) (xy 356.849709 -399.730971) (xy 356.868308 -399.738713)
			(xy 356.878382 -399.739104)
		)
		(stroke
			(width 0)
			(type solid)
		)
		(fill yes)
		(layer "B.Cu")
		(net "P3V3_AUX")
	)
	(gr_poly
		(pts
			(xy 324.747636 -295.632632) (xy 324.760051 -295.632008) (xy 324.782012 -295.620422) (xy 324.789546 -295.610534)
			(xy 324.843902 -295.530778) (xy 324.84695 -295.505886) (xy 324.842378 -295.494202) (xy 324.834088 -295.472032)
			(xy 324.822437 -295.426154) (xy 324.816565 -295.379185) (xy 324.816216 -295.355518) (xy 324.816702 -295.328267)
			(xy 324.824458 -295.274319) (xy 324.839813 -295.222024) (xy 324.862455 -295.172447) (xy 324.891921 -295.126597)
			(xy 324.927612 -295.085406) (xy 324.968803 -295.049715) (xy 325.014653 -295.020249) (xy 325.06423 -294.997607)
			(xy 325.116525 -294.982252) (xy 325.170473 -294.974496) (xy 325.224975 -294.974496) (xy 325.278923 -294.982252)
			(xy 325.331218 -294.997607) (xy 325.380795 -295.020249) (xy 325.426645 -295.049715) (xy 325.467836 -295.085406)
			(xy 325.503527 -295.126597) (xy 325.532993 -295.172447) (xy 325.555635 -295.222024) (xy 325.57099 -295.274319)
			(xy 325.578746 -295.328267) (xy 325.579232 -295.355518) (xy 325.578858 -295.379184) (xy 325.57298 -295.426149)
			(xy 325.561352 -295.47203) (xy 325.55307 -295.494202) (xy 325.548498 -295.505886) (xy 325.551546 -295.530778)
			(xy 325.605902 -295.610534) (xy 325.613431 -295.620423) (xy 325.635398 -295.631991) (xy 325.647812 -295.632632)
			(xy 325.827136 -295.632632) (xy 325.837204 -295.632203) (xy 325.855802 -295.624483) (xy 325.863204 -295.617646)
			(xy 326.218042 -295.262808) (xy 326.224896 -295.255413) (xy 326.232643 -295.236814) (xy 326.233028 -295.22674)
			(xy 326.233028 -291.7063) (xy 326.23265 -291.696872) (xy 326.225827 -291.679293) (xy 326.213107 -291.665374)
			(xy 326.204834 -291.660834) (xy 326.110346 -291.614098) (xy 326.08139 -291.616892) (xy 326.06996 -291.625528)
			(xy 326.044882 -291.643857) (xy 325.990023 -291.672982) (xy 325.931169 -291.692833) (xy 325.869876 -291.702884)
			(xy 325.83882 -291.703506) (xy 325.811566 -291.703044) (xy 325.757614 -291.695289) (xy 325.705314 -291.679935)
			(xy 325.655731 -291.657294) (xy 325.609876 -291.627827) (xy 325.568681 -291.592133) (xy 325.532985 -291.55094)
			(xy 325.503516 -291.505086) (xy 325.480872 -291.455505) (xy 325.465515 -291.403206) (xy 325.457757 -291.349254)
			(xy 325.457757 -291.294746) (xy 325.465515 -291.240794) (xy 325.480872 -291.188495) (xy 325.503516 -291.138914)
			(xy 325.532985 -291.09306) (xy 325.568681 -291.051867) (xy 325.609876 -291.016173) (xy 325.655731 -290.986706)
			(xy 325.705314 -290.964065) (xy 325.757614 -290.948711) (xy 325.811566 -290.940956) (xy 325.83882 -290.94049)
			(xy 325.869876 -290.941101) (xy 325.931167 -290.951163) (xy 325.99002 -290.971018) (xy 326.04488 -291.000142)
			(xy 326.06996 -291.018468) (xy 326.08139 -291.027104) (xy 326.110346 -291.029898) (xy 326.204834 -290.983162)
			(xy 326.213079 -290.978584) (xy 326.225791 -290.964675) (xy 326.232625 -290.947116) (xy 326.233028 -290.937696)
			(xy 326.233028 -285.01594) (xy 326.232595 -285.005874) (xy 326.224868 -284.987283) (xy 326.218042 -284.979872)
			(xy 326.040496 -284.802326) (xy 326.033098 -284.795477) (xy 326.0145 -284.78774) (xy 326.004428 -284.78734)
			(xy 323.922898 -284.78734) (xy 323.912829 -284.787765) (xy 323.894229 -284.795484) (xy 323.88683 -284.802326)
			(xy 323.798438 -284.890718) (xy 323.79159 -284.898116) (xy 323.783856 -284.916714) (xy 323.783452 -284.926786)
			(xy 323.783452 -286.603186) (xy 323.783892 -286.613248) (xy 323.791634 -286.631825) (xy 323.798438 -286.639254)
			(xy 324.539102 -287.379918) (xy 324.545945 -287.387318) (xy 324.553673 -287.405916) (xy 324.554088 -287.415986)
			(xy 324.554088 -287.929828) (xy 324.554253 -287.935982) (xy 324.557201 -287.947932) (xy 324.55993 -287.95345)
			(xy 324.575724 -287.984495) (xy 324.600523 -288.049585) (xy 324.617266 -288.117198) (xy 324.625708 -288.186339)
			(xy 324.626224 -288.221166) (xy 324.625757 -288.253401) (xy 324.618511 -288.317464) (xy 324.60414 -288.380312)
			(xy 324.582825 -288.441157) (xy 324.554833 -288.499234) (xy 324.520516 -288.553813) (xy 324.480305 -288.604208)
			(xy 324.457822 -288.627312) (xy 323.781166 -289.303968) (xy 323.75529 -289.32905) (xy 323.69836 -289.373237)
			(xy 323.636352 -289.409959) (xy 323.57024 -289.43864) (xy 323.535802 -289.449256) (xy 323.529452 -289.451034)
			(xy 323.51853 -289.457638) (xy 323.502274 -289.473894) (xy 323.494874 -289.480737) (xy 323.476276 -289.488463)
			(xy 323.466206 -289.48888) (xy 321.414394 -289.48888) (xy 321.404325 -289.488455) (xy 321.385724 -289.480737)
			(xy 321.378326 -289.473894) (xy 320.479674 -288.575242) (xy 320.472828 -288.567844) (xy 320.465103 -288.549245)
			(xy 320.464688 -288.539174) (xy 320.464688 -288.281618) (xy 320.464434 -288.279078) (xy 320.463092 -288.264638)
			(xy 320.461695 -288.235668) (xy 320.46164 -288.221166) (xy 320.46164 -287.90646) (xy 320.461094 -287.896477)
			(xy 320.453363 -287.878061) (xy 320.446654 -287.870646) (xy 320.321686 -287.745678) (xy 320.31429 -287.738825)
			(xy 320.295692 -287.731084) (xy 320.285618 -287.730692) (xy 319.53708 -287.730692) (xy 319.527074 -287.731184)
			(xy 319.508588 -287.738846) (xy 319.49444 -287.752998) (xy 319.486781 -287.771486) (xy 319.48628 -287.781492)
			(xy 319.48628 -289.30981) (xy 319.485828 -289.342038) (xy 319.478614 -289.406088) (xy 319.464276 -289.468929)
			(xy 319.442996 -289.52977) (xy 319.415041 -289.587847) (xy 319.380762 -289.642431) (xy 319.340589 -289.692836)
			(xy 319.318132 -289.715956) (xy 319.167764 -289.866324) (xy 319.160994 -289.873752) (xy 319.153415 -289.892348)
			(xy 319.153032 -289.902392) (xy 319.153032 -290.267132) (xy 321.289154 -290.267132) (xy 321.289154 -290.207196)
			(xy 321.296977 -290.147774) (xy 321.31249 -290.089881) (xy 321.335426 -290.034508) (xy 321.365393 -289.982602)
			(xy 321.40188 -289.935052) (xy 321.44426 -289.892672) (xy 321.49181 -289.856185) (xy 321.543716 -289.826218)
			(xy 321.599089 -289.803282) (xy 321.656982 -289.787769) (xy 321.716404 -289.779946) (xy 321.77634 -289.779946)
			(xy 321.835762 -289.787769) (xy 321.893655 -289.803282) (xy 321.949028 -289.826218) (xy 322.000934 -289.856185)
			(xy 322.048484 -289.892672) (xy 322.090864 -289.935052) (xy 322.127351 -289.982602) (xy 322.157318 -290.034508)
			(xy 322.180254 -290.089881) (xy 322.195767 -290.147774) (xy 322.20359 -290.207196) (xy 322.20408 -290.237164)
			(xy 322.20359 -290.267132) (xy 322.195767 -290.326554) (xy 322.180254 -290.384447) (xy 322.157318 -290.43982)
			(xy 322.127351 -290.491726) (xy 322.090864 -290.539276) (xy 322.048484 -290.581656) (xy 322.000934 -290.618143)
			(xy 321.949028 -290.64811) (xy 321.893655 -290.671046) (xy 321.835762 -290.686559) (xy 321.77634 -290.694382)
			(xy 321.716404 -290.694382) (xy 321.656982 -290.686559) (xy 321.599089 -290.671046) (xy 321.543716 -290.64811)
			(xy 321.49181 -290.618143) (xy 321.44426 -290.581656) (xy 321.40188 -290.539276) (xy 321.365393 -290.491726)
			(xy 321.335426 -290.43982) (xy 321.31249 -290.384447) (xy 321.296977 -290.326554) (xy 321.289154 -290.267132)
			(xy 319.153032 -290.267132) (xy 319.153032 -291.224716) (xy 319.152473 -291.259417) (xy 319.144046 -291.328306)
			(xy 319.127388 -291.39568) (xy 319.102742 -291.460559) (xy 319.070466 -291.522) (xy 319.051178 -291.550852)
			(xy 319.047038 -291.557361) (xy 319.042504 -291.572098) (xy 319.042288 -291.579808) (xy 319.042288 -291.592)
			(xy 320.641724 -291.592) (xy 320.645795 -291.536378) (xy 320.657921 -291.481941) (xy 320.677844 -291.42985)
			(xy 320.70514 -291.381215) (xy 320.739226 -291.337072) (xy 320.779375 -291.298363) (xy 320.824733 -291.265912)
			(xy 320.874333 -291.240411) (xy 320.927117 -291.222404) (xy 320.98196 -291.212274) (xy 321.037694 -291.210237)
			(xy 321.093131 -291.216337) (xy 321.147088 -291.230443) (xy 321.198417 -291.252255) (xy 321.246023 -291.281309)
			(xy 321.288891 -291.316984) (xy 321.326108 -291.358521) (xy 321.356881 -291.405034) (xy 321.380553 -291.455531)
			(xy 321.396621 -291.508938) (xy 321.404741 -291.564114) (xy 321.40525 -291.592) (xy 321.404741 -291.619886)
			(xy 321.396621 -291.675062) (xy 321.380553 -291.728469) (xy 321.356881 -291.778966) (xy 321.326108 -291.825479)
			(xy 321.288891 -291.867016) (xy 321.246023 -291.902691) (xy 321.198417 -291.931745) (xy 321.147088 -291.953557)
			(xy 321.093131 -291.967663) (xy 321.037694 -291.973763) (xy 320.98196 -291.971726) (xy 320.927117 -291.961596)
			(xy 320.874333 -291.943589) (xy 320.824733 -291.918088) (xy 320.779375 -291.885637) (xy 320.739226 -291.846928)
			(xy 320.70514 -291.802785) (xy 320.677844 -291.75415) (xy 320.657921 -291.702059) (xy 320.645795 -291.647622)
			(xy 320.641724 -291.592) (xy 319.042288 -291.592) (xy 319.042288 -292.885368) (xy 319.041852 -292.895432)
			(xy 319.034119 -292.914018) (xy 319.027302 -292.921436) (xy 318.80048 -293.148258) (xy 318.793082 -293.155106)
			(xy 318.774484 -293.16284) (xy 318.764412 -293.163244) (xy 318.371982 -293.163244) (xy 318.361914 -293.162816)
			(xy 318.34332 -293.155091) (xy 318.335914 -293.148258) (xy 318.04991 -292.862254) (xy 318.04307 -292.854853)
			(xy 318.03535 -292.836255) (xy 318.034924 -292.826186) (xy 318.034924 -291.45357) (xy 318.031368 -291.44468)
			(xy 318.01898 -291.411369) (xy 318.001573 -291.342462) (xy 317.992784 -291.271936) (xy 317.992252 -291.2364)
			(xy 317.992627 -291.208594) (xy 317.998095 -291.153251) (xy 318.003174 -291.12591) (xy 318.003936 -291.121084)
			(xy 318.003936 -290.731702) (xy 318.003211 -290.719454) (xy 317.991932 -290.697706) (xy 317.982346 -290.690046)
			(xy 317.903606 -290.635182) (xy 317.879222 -290.632134) (xy 317.867284 -290.636452) (xy 317.835495 -290.647378)
			(xy 317.769319 -290.659133) (xy 317.735712 -290.65982) (xy 317.708458 -290.659358) (xy 317.654504 -290.651602)
			(xy 317.602203 -290.636247) (xy 317.552619 -290.613604) (xy 317.506763 -290.584135) (xy 317.465568 -290.548441)
			(xy 317.429872 -290.507246) (xy 317.400402 -290.461391) (xy 317.377758 -290.411809) (xy 317.3624 -290.359508)
			(xy 317.354643 -290.305554) (xy 317.354643 -290.251046) (xy 317.3624 -290.197092) (xy 317.377758 -290.144791)
			(xy 317.400402 -290.095209) (xy 317.429872 -290.049354) (xy 317.465568 -290.008159) (xy 317.506763 -289.972465)
			(xy 317.552619 -289.942996) (xy 317.602203 -289.920353) (xy 317.654504 -289.904998) (xy 317.708458 -289.897242)
			(xy 317.735712 -289.896804) (xy 317.764846 -289.897353) (xy 317.822435 -289.906226) (xy 317.877997 -289.923778)
			(xy 317.904368 -289.936174) (xy 317.915898 -289.941096) (xy 317.940928 -289.940298) (xy 317.95212 -289.93465)
			(xy 317.978536 -289.91941) (xy 317.986031 -289.914631) (xy 317.997453 -289.901028) (xy 318.003558 -289.884348)
			(xy 318.003936 -289.875468) (xy 318.003936 -289.872928) (xy 317.615316 -289.484054) (xy 317.607915 -289.477215)
			(xy 317.589317 -289.469503) (xy 317.579248 -289.469068) (xy 316.890654 -289.469068) (xy 316.880587 -289.469499)
			(xy 316.861991 -289.477221) (xy 316.854586 -289.484054) (xy 316.548516 -289.790124) (xy 316.541672 -289.797523)
			(xy 316.533943 -289.816121) (xy 316.53353 -289.826192) (xy 316.53353 -294.682672) (xy 321.362578 -294.682672)
			(xy 321.363131 -294.654635) (xy 321.371356 -294.599168) (xy 321.38761 -294.545501) (xy 321.411544 -294.494792)
			(xy 321.442641 -294.448131) (xy 321.480233 -294.406524) (xy 321.523509 -294.370866) (xy 321.571538 -294.341926)
			(xy 321.623285 -294.320327) (xy 321.677636 -294.306534) (xy 321.705478 -294.303196) (xy 321.717162 -294.301926)
			(xy 321.736974 -294.289734) (xy 321.792092 -294.202612) (xy 321.794886 -294.179244) (xy 321.790822 -294.168322)
			(xy 321.782603 -294.143808) (xy 321.771062 -294.093407) (xy 321.765261 -294.042029) (xy 321.764914 -294.016176)
			(xy 321.765408 -293.986211) (xy 321.773233 -293.926793) (xy 321.788747 -293.868905) (xy 321.811684 -293.813537)
			(xy 321.841652 -293.761636) (xy 321.878137 -293.714091) (xy 321.920516 -293.671715) (xy 321.968064 -293.635233)
			(xy 322.019966 -293.60527) (xy 322.075336 -293.582336) (xy 322.133225 -293.566827) (xy 322.192643 -293.559005)
			(xy 322.252574 -293.559007) (xy 322.311992 -293.56683) (xy 322.369881 -293.582342) (xy 322.425249 -293.605277)
			(xy 322.477151 -293.635243) (xy 322.524697 -293.671727) (xy 322.567074 -293.714105) (xy 322.603558 -293.761651)
			(xy 322.633524 -293.813552) (xy 322.656459 -293.868921) (xy 322.67197 -293.92681) (xy 322.679794 -293.986228)
			(xy 322.679794 -294.046159) (xy 322.671973 -294.105577) (xy 322.656463 -294.163466) (xy 322.63353 -294.218836)
			(xy 322.603565 -294.270738) (xy 322.567083 -294.318285) (xy 322.524707 -294.360664) (xy 322.477162 -294.39715)
			(xy 322.425261 -294.427117) (xy 322.369893 -294.450054) (xy 322.312005 -294.465567) (xy 322.252587 -294.473393)
			(xy 322.222622 -294.473884) (xy 322.216526 -294.473884) (xy 322.204842 -294.47363) (xy 322.18376 -294.483536)
			(xy 322.161332 -294.51122) (xy 322.709089 -294.51122) (xy 322.711688 -294.454543) (xy 322.722091 -294.398768)
			(xy 322.740099 -294.344965) (xy 322.765367 -294.294166) (xy 322.79741 -294.247344) (xy 322.835614 -294.205398)
			(xy 322.879246 -294.169132) (xy 322.92747 -294.13924) (xy 322.979361 -294.116297) (xy 323.033924 -294.100743)
			(xy 323.090112 -294.092875) (xy 323.11848 -294.092376) (xy 323.144012 -294.092742) (xy 323.194683 -294.099044)
			(xy 323.244174 -294.111616) (xy 323.268086 -294.12057) (xy 323.281992 -294.125525) (xy 323.311389 -294.12807)
			(xy 323.340285 -294.122098) (xy 323.366264 -294.108107) (xy 323.387155 -294.087269) (xy 323.40121 -294.061325)
			(xy 323.407254 -294.032443) (xy 323.406516 -294.0177) (xy 323.404992 -293.980616) (xy 323.405444 -293.950646)
			(xy 323.413266 -293.891218) (xy 323.428778 -293.833319) (xy 323.451714 -293.77794) (xy 323.481683 -293.726029)
			(xy 323.518171 -293.678474) (xy 323.560554 -293.636089) (xy 323.608107 -293.599598) (xy 323.660016 -293.569626)
			(xy 323.715394 -293.546686) (xy 323.773291 -293.531171) (xy 323.832719 -293.523346) (xy 323.89266 -293.523344)
			(xy 323.952088 -293.531167) (xy 324.009986 -293.546679) (xy 324.065364 -293.569617) (xy 324.117275 -293.599586)
			(xy 324.16483 -293.636075) (xy 324.207215 -293.678458) (xy 324.243705 -293.726012) (xy 324.273676 -293.777921)
			(xy 324.296615 -293.833299) (xy 324.31213 -293.891197) (xy 324.319955 -293.950624) (xy 324.319955 -294.010565)
			(xy 324.312132 -294.069993) (xy 324.296619 -294.127891) (xy 324.273681 -294.183269) (xy 324.243711 -294.23518)
			(xy 324.207222 -294.282734) (xy 324.164838 -294.325118) (xy 324.117284 -294.361608) (xy 324.065374 -294.391579)
			(xy 324.009996 -294.414517) (xy 323.952098 -294.430031) (xy 323.89267 -294.437855) (xy 323.8627 -294.438324)
			(xy 323.82984 -294.437739) (xy 323.764803 -294.428281) (xy 323.701783 -294.409631) (xy 323.671692 -294.396414)
			(xy 323.658102 -294.390676) (xy 323.628899 -294.38657) (xy 323.599737 -294.390962) (xy 323.573039 -294.403488)
			(xy 323.551022 -294.423108) (xy 323.535514 -294.448192) (xy 323.527804 -294.476657) (xy 323.527674 -294.49141)
			(xy 323.527928 -294.50157) (xy 323.527442 -294.529938) (xy 323.519609 -294.586131) (xy 323.504088 -294.640704)
			(xy 323.481176 -294.692608) (xy 323.451315 -294.740851) (xy 323.415075 -294.784505) (xy 323.373152 -294.822735)
			(xy 323.32635 -294.854807) (xy 323.275566 -294.880106) (xy 323.221774 -294.898146) (xy 323.166006 -294.908583)
			(xy 323.109331 -294.911216) (xy 323.052835 -294.905995) (xy 322.997602 -294.893019) (xy 322.944691 -294.872537)
			(xy 322.895117 -294.844943) (xy 322.849831 -294.810765) (xy 322.8097 -294.770658) (xy 322.775494 -294.725392)
			(xy 322.747869 -294.675835) (xy 322.727355 -294.622937) (xy 322.714345 -294.567712) (xy 322.709089 -294.51122)
			(xy 322.161332 -294.51122) (xy 322.118736 -294.5638) (xy 322.113402 -294.58666) (xy 322.116196 -294.59809)
			(xy 322.120626 -294.618953) (xy 322.125338 -294.661345) (xy 322.125594 -294.682672) (xy 322.125108 -294.709923)
			(xy 322.117352 -294.763871) (xy 322.101997 -294.816166) (xy 322.079355 -294.865743) (xy 322.049889 -294.911593)
			(xy 322.014198 -294.952784) (xy 321.973007 -294.988475) (xy 321.927157 -295.017941) (xy 321.87758 -295.040583)
			(xy 321.825285 -295.055938) (xy 321.771337 -295.063694) (xy 321.716835 -295.063694) (xy 321.662887 -295.055938)
			(xy 321.610592 -295.040583) (xy 321.561015 -295.017941) (xy 321.515165 -294.988475) (xy 321.473974 -294.952784)
			(xy 321.438283 -294.911593) (xy 321.408817 -294.865743) (xy 321.386175 -294.816166) (xy 321.37082 -294.763871)
			(xy 321.363064 -294.709923) (xy 321.362578 -294.682672) (xy 316.53353 -294.682672) (xy 316.53353 -295.197022)
			(xy 316.533958 -295.20709) (xy 316.541681 -295.225686) (xy 316.548516 -295.23309) (xy 316.933072 -295.617646)
			(xy 316.940472 -295.624487) (xy 316.959071 -295.632204) (xy 316.96914 -295.632632)
		)
		(stroke
			(width 0)
			(type solid)
		)
		(fill yes)
		(layer "B.Cu")
		(net "P3V3_AUX")
	)
	(gr_poly
		(pts
			(arc
				(start 200.481692 -418.081968)
				(mid 201.086106 -417.953924)
				(end 201.586846 -417.592002)
			)
			(arc
				(start 201.586846 -417.592002)
				(mid 202.42889 -416.98332)
				(end 203.445364 -416.768026)
			)
			(arc
				(start 271.794732 -416.768026)
				(mid 272.811071 -416.983322)
				(end 273.652996 -417.592002)
			)
			(arc
				(start 273.652996 -417.592002)
				(mid 274.153727 -417.953921)
				(end 274.75815 -418.081968)
			)
			(arc
				(start 465.600034 -418.081968)
				(mid 466.655034 -417.644972)
				(end 467.09203 -416.589972)
			)
			(arc
				(start 467.09203 -246.488204)
				(mid 466.978493 -245.917325)
				(end 466.65515 -245.433342)
			)
			(arc
				(start 464.026504 -242.80495)
				(mid 463.482885 -241.991412)
				(end 463.291936 -241.031776)
			)
			(arc
				(start 463.291936 -87.588344)
				(mid 463.482826 -86.628673)
				(end 464.026504 -85.81517)
			)
			(arc
				(start 466.65515 -83.186524)
				(mid 466.978483 -82.702667)
				(end 467.09203 -82.131916)
			)
			(arc
				(start 467.09203 -1.999996)
				(mid 466.655034 -0.944996)
				(end 465.600034 -0.508)
			)
			(arc
				(start 446.265046 -0.508)
				(mid 445.210046 -0.944996)
				(end 444.77305 -1.999996)
			)
			(arc
				(start 444.77305 -11.850116)
				(mid 444.676277 -12.381671)
				(end 444.3984 -12.845034)
			)
			(xy 444.3984 -12.869164) (xy 444.399924 -12.870688)
			(arc
				(start 445.002666 -12.870688)
				(mid 445.20965 -12.378943)
				(end 445.280288 -11.850116)
			)
			(arc
				(start 445.280288 -1.999996)
				(mid 445.568553 -1.303936)
				(end 446.264538 -1.015492)
			)
			(arc
				(start 465.600034 -1.015492)
				(mid 466.296273 -1.303831)
				(end 466.584792 -1.999996)
			)
			(arc
				(start 466.584792 -82.131916)
				(mid 466.509885 -82.508586)
				(end 466.296502 -82.827876)
			)
			(arc
				(start 463.667856 -85.456522)
				(mid 463.014235 -86.434595)
				(end 462.784698 -87.588344)
			)
			(xy 462.784444 -87.588344) (xy 462.784444 -241.031776)
			(arc
				(start 462.784698 -241.031776)
				(mid 463.014268 -242.185519)
				(end 463.667856 -243.163598)
			)
			(arc
				(start 466.296502 -245.79199)
				(mid 466.509882 -246.11143)
				(end 466.584792 -246.488204)
			)
			(arc
				(start 466.584792 -416.589972)
				(mid 466.296527 -417.286032)
				(end 465.600542 -417.574476)
			)
			(xy 414.915604 -417.574476) (xy 414.915604 -417.797742) (xy 400.95424 -417.797742) (xy 400.95424 -417.574476)
			(xy 326.621648 -417.574476) (xy 326.621648 -417.747958) (xy 313.065922 -417.747958) (xy 313.065922 -417.574476)
			(arc
				(start 274.757896 -417.574476)
				(mid 274.359217 -417.490052)
				(end 274.028916 -417.251388)
			)
			(arc
				(start 274.028916 -417.251388)
				(mid 273.01669 -416.519565)
				(end 271.794732 -416.260788)
			)
			(arc
				(start 203.445364 -416.260788)
				(mid 202.223266 -416.519531)
				(end 201.210926 -417.251388)
			)
			(arc
				(start 201.210926 -417.251388)
				(mid 200.880626 -417.490098)
				(end 200.481946 -417.574476)
			)
			(xy 154.673554 -417.574476) (xy 154.673554 -417.693856) (xy 141.027912 -417.693856) (xy 141.027912 -417.574476)
			(xy 66.745104 -417.574476) (xy 66.745104 -417.671758) (xy 53.039772 -417.671758) (xy 53.039772 -417.574476)
			(arc
				(start 1.999996 -417.574476)
				(mid 1.303847 -417.286121)
				(end 1.015492 -416.589972)
			)
			(arc
				(start 1.015492 -246.48795)
				(mid 1.090466 -246.111319)
				(end 1.303782 -245.79199)
			)
			(arc
				(start 3.93192 -243.163852)
				(mid 4.58575 -242.18556)
				(end 4.815332 -241.031522)
			)
			(arc
				(start 4.815332 -87.588344)
				(mid 4.585694 -86.434435)
				(end 3.93192 -85.456268)
			)
			(arc
				(start 1.303528 -82.827876)
				(mid 1.090411 -82.508641)
				(end 1.015492 -82.13217)
			)
			(arc
				(start 1.015492 -1.999996)
				(mid 1.303847 -1.303847)
				(end 1.999996 -1.015492)
			)
			(arc
				(start 5.964936 -1.015492)
				(mid 6.661085 -1.303847)
				(end 6.94944 -1.999996)
			)
			(arc
				(start 6.94944 -11.850116)
				(mid 7.539853 -13.275118)
				(end 8.96493 -13.865352)
			)
			(xy 16.2814 -13.865352) (xy 16.371316 -13.775436) (xy 16.371316 -13.44803) (xy 16.2814 -13.358114)
			(arc
				(start 8.96493 -13.358114)
				(mid 7.898614 -12.916432)
				(end 7.456932 -11.850116)
			)
			(arc
				(start 7.456932 -1.999996)
				(mid 7.019936 -0.944996)
				(end 5.964936 -0.508)
			)
			(arc
				(start 1.999996 -0.508)
				(mid 0.944996 -0.944996)
				(end 0.508 -1.999996)
			)
			(arc
				(start 0.508 -82.131916)
				(mid 0.621601 -82.702644)
				(end 0.94488 -83.186524)
			)
			(arc
				(start 3.573272 -85.81517)
				(mid 4.117081 -86.628665)
				(end 4.308094 -87.588344)
			)
			(arc
				(start 4.308094 -241.031522)
				(mid 4.117082 -241.991334)
				(end 3.573272 -242.80495)
			)
			(arc
				(start 0.94488 -245.433342)
				(mid 0.621552 -245.917331)
				(end 0.508 -246.488204)
			)
			(arc
				(start 0.508 -416.589972)
				(mid 0.944996 -417.644972)
				(end 1.999996 -418.081968)
			)
		)
		(stroke
			(width 0)
			(type solid)
		)
		(fill yes)
		(layer "B.Cu")
		(net "GND")
	)
	(gr_poly
		(pts
			(xy 144.520158 -387.296406) (xy 144.525746 -387.293612) (xy 144.548497 -387.282428) (xy 144.596653 -387.266593)
			(xy 144.646704 -387.258547) (xy 144.67205 -387.258052) (xy 148.025866 -387.258052) (xy 148.035827 -387.257565)
			(xy 148.054247 -387.249972) (xy 148.06168 -387.24332) (xy 149.133814 -386.171186) (xy 149.141209 -386.164332)
			(xy 149.159808 -386.15659) (xy 149.169882 -386.1562) (xy 156.123386 -386.1562) (xy 156.133449 -386.155761)
			(xy 156.152031 -386.148025) (xy 156.159454 -386.141214) (xy 157.170882 -385.129786) (xy 157.177728 -385.122387)
			(xy 157.18546 -385.103789) (xy 157.185868 -385.093718) (xy 157.185868 -365.35995) (xy 157.185435 -365.349885)
			(xy 157.177704 -365.331296) (xy 157.170882 -365.323882) (xy 156.644086 -364.797086) (xy 156.636691 -364.790232)
			(xy 156.618092 -364.78249) (xy 156.608018 -364.7821) (xy 140.952982 -364.7821) (xy 140.942913 -364.782527)
			(xy 140.924314 -364.790246) (xy 140.916914 -364.797086) (xy 140.427456 -365.286544) (xy 140.42061 -365.293942)
			(xy 140.412883 -365.312541) (xy 140.41247 -365.322612) (xy 140.41247 -378.717298) (xy 149.112968 -378.717298)
			(xy 149.112968 -378.657362) (xy 149.120791 -378.59794) (xy 149.136304 -378.540047) (xy 149.15924 -378.484674)
			(xy 149.189207 -378.432768) (xy 149.225694 -378.385218) (xy 149.268074 -378.342838) (xy 149.315624 -378.306351)
			(xy 149.36753 -378.276384) (xy 149.422903 -378.253448) (xy 149.480796 -378.237935) (xy 149.540218 -378.230112)
			(xy 149.600154 -378.230112) (xy 149.659576 -378.237935) (xy 149.717469 -378.253448) (xy 149.772842 -378.276384)
			(xy 149.824748 -378.306351) (xy 149.872298 -378.342838) (xy 149.914678 -378.385218) (xy 149.951165 -378.432768)
			(xy 149.981132 -378.484674) (xy 150.004068 -378.540047) (xy 150.019581 -378.59794) (xy 150.027404 -378.657362)
			(xy 150.027894 -378.68733) (xy 150.027404 -378.717298) (xy 150.019581 -378.77672) (xy 150.004068 -378.834613)
			(xy 149.981132 -378.889986) (xy 149.951165 -378.941892) (xy 149.914678 -378.989442) (xy 149.872298 -379.031822)
			(xy 149.824748 -379.068309) (xy 149.772842 -379.098276) (xy 149.717469 -379.121212) (xy 149.659576 -379.136725)
			(xy 149.600154 -379.144548) (xy 149.540218 -379.144548) (xy 149.480796 -379.136725) (xy 149.422903 -379.121212)
			(xy 149.36753 -379.098276) (xy 149.315624 -379.068309) (xy 149.268074 -379.031822) (xy 149.225694 -378.989442)
			(xy 149.189207 -378.941892) (xy 149.15924 -378.889986) (xy 149.136304 -378.834613) (xy 149.120791 -378.77672)
			(xy 149.112968 -378.717298) (xy 140.41247 -378.717298) (xy 140.41247 -379.426466) (xy 147.320744 -379.426466)
			(xy 147.320744 -379.36653) (xy 147.328567 -379.307108) (xy 147.34408 -379.249215) (xy 147.367016 -379.193842)
			(xy 147.396983 -379.141936) (xy 147.43347 -379.094386) (xy 147.47585 -379.052006) (xy 147.5234 -379.015519)
			(xy 147.575306 -378.985552) (xy 147.630679 -378.962616) (xy 147.688572 -378.947103) (xy 147.747994 -378.93928)
			(xy 147.80793 -378.93928) (xy 147.867352 -378.947103) (xy 147.925245 -378.962616) (xy 147.980618 -378.985552)
			(xy 148.032524 -379.015519) (xy 148.080074 -379.052006) (xy 148.122454 -379.094386) (xy 148.158941 -379.141936)
			(xy 148.188908 -379.193842) (xy 148.211844 -379.249215) (xy 148.227357 -379.307108) (xy 148.23518 -379.36653)
			(xy 148.23567 -379.396498) (xy 148.23518 -379.426466) (xy 148.227357 -379.485888) (xy 148.211844 -379.543781)
			(xy 148.188908 -379.599154) (xy 148.158941 -379.65106) (xy 148.122454 -379.69861) (xy 148.080074 -379.74099)
			(xy 148.032524 -379.777477) (xy 147.980618 -379.807444) (xy 147.925245 -379.83038) (xy 147.867352 -379.845893)
			(xy 147.80793 -379.853716) (xy 147.747994 -379.853716) (xy 147.688572 -379.845893) (xy 147.630679 -379.83038)
			(xy 147.575306 -379.807444) (xy 147.5234 -379.777477) (xy 147.47585 -379.74099) (xy 147.43347 -379.69861)
			(xy 147.396983 -379.65106) (xy 147.367016 -379.599154) (xy 147.34408 -379.543781) (xy 147.328567 -379.485888)
			(xy 147.320744 -379.426466) (xy 140.41247 -379.426466) (xy 140.41247 -379.93472) (xy 149.612586 -379.93472)
			(xy 149.612586 -379.874784) (xy 149.620409 -379.815362) (xy 149.635922 -379.757469) (xy 149.658858 -379.702096)
			(xy 149.688825 -379.65019) (xy 149.725312 -379.60264) (xy 149.767692 -379.56026) (xy 149.815242 -379.523773)
			(xy 149.867148 -379.493806) (xy 149.922521 -379.47087) (xy 149.980414 -379.455357) (xy 150.039836 -379.447534)
			(xy 150.099772 -379.447534) (xy 150.159194 -379.455357) (xy 150.217087 -379.47087) (xy 150.27246 -379.493806)
			(xy 150.324366 -379.523773) (xy 150.371916 -379.56026) (xy 150.414296 -379.60264) (xy 150.450783 -379.65019)
			(xy 150.48075 -379.702096) (xy 150.503686 -379.757469) (xy 150.519199 -379.815362) (xy 150.527022 -379.874784)
			(xy 150.527512 -379.904752) (xy 150.527022 -379.93472) (xy 150.519199 -379.994142) (xy 150.503686 -380.052035)
			(xy 150.48075 -380.107408) (xy 150.450783 -380.159314) (xy 150.414296 -380.206864) (xy 150.371916 -380.249244)
			(xy 150.324366 -380.285731) (xy 150.27246 -380.315698) (xy 150.217087 -380.338634) (xy 150.159194 -380.354147)
			(xy 150.099772 -380.36197) (xy 150.039836 -380.36197) (xy 149.980414 -380.354147) (xy 149.922521 -380.338634)
			(xy 149.867148 -380.315698) (xy 149.815242 -380.285731) (xy 149.767692 -380.249244) (xy 149.725312 -380.206864)
			(xy 149.688825 -380.159314) (xy 149.658858 -380.107408) (xy 149.635922 -380.052035) (xy 149.620409 -379.994142)
			(xy 149.612586 -379.93472) (xy 140.41247 -379.93472) (xy 140.41247 -380.4605) (xy 146.572968 -380.4605)
			(xy 146.572968 -380.400564) (xy 146.580791 -380.341142) (xy 146.596304 -380.283249) (xy 146.61924 -380.227876)
			(xy 146.649207 -380.17597) (xy 146.685694 -380.12842) (xy 146.728074 -380.08604) (xy 146.775624 -380.049553)
			(xy 146.82753 -380.019586) (xy 146.882903 -379.99665) (xy 146.940796 -379.981137) (xy 147.000218 -379.973314)
			(xy 147.060154 -379.973314) (xy 147.119576 -379.981137) (xy 147.177469 -379.99665) (xy 147.232842 -380.019586)
			(xy 147.284748 -380.049553) (xy 147.332298 -380.08604) (xy 147.374678 -380.12842) (xy 147.411165 -380.17597)
			(xy 147.441132 -380.227876) (xy 147.464068 -380.283249) (xy 147.479581 -380.341142) (xy 147.487404 -380.400564)
			(xy 147.487894 -380.430532) (xy 147.487404 -380.4605) (xy 147.479581 -380.519922) (xy 147.464068 -380.577815)
			(xy 147.441132 -380.633188) (xy 147.411165 -380.685094) (xy 147.374678 -380.732644) (xy 147.332298 -380.775024)
			(xy 147.284748 -380.811511) (xy 147.232842 -380.841478) (xy 147.177469 -380.864414) (xy 147.119576 -380.879927)
			(xy 147.060154 -380.88775) (xy 147.000218 -380.88775) (xy 146.940796 -380.879927) (xy 146.882903 -380.864414)
			(xy 146.82753 -380.841478) (xy 146.775624 -380.811511) (xy 146.728074 -380.775024) (xy 146.685694 -380.732644)
			(xy 146.649207 -380.685094) (xy 146.61924 -380.633188) (xy 146.596304 -380.577815) (xy 146.580791 -380.519922)
			(xy 146.572968 -380.4605) (xy 140.41247 -380.4605) (xy 140.41247 -381.741168) (xy 147.37764 -381.741168)
			(xy 147.37764 -381.681232) (xy 147.385463 -381.62181) (xy 147.400976 -381.563917) (xy 147.423912 -381.508544)
			(xy 147.453879 -381.456638) (xy 147.490366 -381.409088) (xy 147.532746 -381.366708) (xy 147.580296 -381.330221)
			(xy 147.632202 -381.300254) (xy 147.687575 -381.277318) (xy 147.745468 -381.261805) (xy 147.80489 -381.253982)
			(xy 147.864826 -381.253982) (xy 147.924248 -381.261805) (xy 147.982141 -381.277318) (xy 148.037514 -381.300254)
			(xy 148.08942 -381.330221) (xy 148.13697 -381.366708) (xy 148.17935 -381.409088) (xy 148.215837 -381.456638)
			(xy 148.216892 -381.458466) (xy 149.78048 -381.458466) (xy 149.78048 -381.39853) (xy 149.788303 -381.339108)
			(xy 149.803816 -381.281215) (xy 149.826752 -381.225842) (xy 149.856719 -381.173936) (xy 149.893206 -381.126386)
			(xy 149.935586 -381.084006) (xy 149.983136 -381.047519) (xy 150.035042 -381.017552) (xy 150.090415 -380.994616)
			(xy 150.148308 -380.979103) (xy 150.20773 -380.97128) (xy 150.267666 -380.97128) (xy 150.327088 -380.979103)
			(xy 150.384981 -380.994616) (xy 150.440354 -381.017552) (xy 150.49226 -381.047519) (xy 150.53981 -381.084006)
			(xy 150.58219 -381.126386) (xy 150.618677 -381.173936) (xy 150.648644 -381.225842) (xy 150.67158 -381.281215)
			(xy 150.687093 -381.339108) (xy 150.694916 -381.39853) (xy 150.695406 -381.428498) (xy 150.694916 -381.458466)
			(xy 150.687093 -381.517888) (xy 150.67158 -381.575781) (xy 150.648644 -381.631154) (xy 150.618677 -381.68306)
			(xy 150.58219 -381.73061) (xy 150.53981 -381.77299) (xy 150.49226 -381.809477) (xy 150.440354 -381.839444)
			(xy 150.384981 -381.86238) (xy 150.327088 -381.877893) (xy 150.267666 -381.885716) (xy 150.20773 -381.885716)
			(xy 150.148308 -381.877893) (xy 150.090415 -381.86238) (xy 150.035042 -381.839444) (xy 149.983136 -381.809477)
			(xy 149.935586 -381.77299) (xy 149.893206 -381.73061) (xy 149.856719 -381.68306) (xy 149.826752 -381.631154)
			(xy 149.803816 -381.575781) (xy 149.788303 -381.517888) (xy 149.78048 -381.458466) (xy 148.216892 -381.458466)
			(xy 148.245804 -381.508544) (xy 148.26874 -381.563917) (xy 148.284253 -381.62181) (xy 148.292076 -381.681232)
			(xy 148.292566 -381.7112) (xy 148.292076 -381.741168) (xy 148.284253 -381.80059) (xy 148.26874 -381.858483)
			(xy 148.245804 -381.913856) (xy 148.215837 -381.965762) (xy 148.17935 -382.013312) (xy 148.13697 -382.055692)
			(xy 148.08942 -382.092179) (xy 148.037514 -382.122146) (xy 147.982141 -382.145082) (xy 147.924248 -382.160595)
			(xy 147.864826 -382.168418) (xy 147.80489 -382.168418) (xy 147.745468 -382.160595) (xy 147.687575 -382.145082)
			(xy 147.632202 -382.122146) (xy 147.580296 -382.092179) (xy 147.532746 -382.055692) (xy 147.490366 -382.013312)
			(xy 147.453879 -381.965762) (xy 147.423912 -381.913856) (xy 147.400976 -381.858483) (xy 147.385463 -381.80059)
			(xy 147.37764 -381.741168) (xy 140.41247 -381.741168) (xy 140.41247 -382.474466) (xy 146.337256 -382.474466)
			(xy 146.337256 -382.41453) (xy 146.345079 -382.355108) (xy 146.360592 -382.297215) (xy 146.383528 -382.241842)
			(xy 146.413495 -382.189936) (xy 146.449982 -382.142386) (xy 146.492362 -382.100006) (xy 146.539912 -382.063519)
			(xy 146.591818 -382.033552) (xy 146.647191 -382.010616) (xy 146.705084 -381.995103) (xy 146.764506 -381.98728)
			(xy 146.824442 -381.98728) (xy 146.883864 -381.995103) (xy 146.941757 -382.010616) (xy 146.99713 -382.033552)
			(xy 147.049036 -382.063519) (xy 147.096586 -382.100006) (xy 147.138966 -382.142386) (xy 147.175453 -382.189936)
			(xy 147.20542 -382.241842) (xy 147.228356 -382.297215) (xy 147.243869 -382.355108) (xy 147.251692 -382.41453)
			(xy 147.252182 -382.444498) (xy 147.251692 -382.474466) (xy 147.243869 -382.533888) (xy 147.228356 -382.591781)
			(xy 147.20542 -382.647154) (xy 147.175453 -382.69906) (xy 147.138966 -382.74661) (xy 147.096586 -382.78899)
			(xy 147.049036 -382.825477) (xy 146.99713 -382.855444) (xy 146.941757 -382.87838) (xy 146.883864 -382.893893)
			(xy 146.824442 -382.901716) (xy 146.764506 -382.901716) (xy 146.705084 -382.893893) (xy 146.647191 -382.87838)
			(xy 146.591818 -382.855444) (xy 146.539912 -382.825477) (xy 146.492362 -382.78899) (xy 146.449982 -382.74661)
			(xy 146.413495 -382.69906) (xy 146.383528 -382.647154) (xy 146.360592 -382.591781) (xy 146.345079 -382.533888)
			(xy 146.337256 -382.474466) (xy 140.41247 -382.474466) (xy 140.41247 -383.490466) (xy 147.320744 -383.490466)
			(xy 147.320744 -383.43053) (xy 147.328567 -383.371108) (xy 147.34408 -383.313215) (xy 147.367016 -383.257842)
			(xy 147.396983 -383.205936) (xy 147.43347 -383.158386) (xy 147.47585 -383.116006) (xy 147.5234 -383.079519)
			(xy 147.575306 -383.049552) (xy 147.630679 -383.026616) (xy 147.688572 -383.011103) (xy 147.747994 -383.00328)
			(xy 147.80793 -383.00328) (xy 147.867352 -383.011103) (xy 147.925245 -383.026616) (xy 147.980618 -383.049552)
			(xy 148.032524 -383.079519) (xy 148.080074 -383.116006) (xy 148.122454 -383.158386) (xy 148.158941 -383.205936)
			(xy 148.188908 -383.257842) (xy 148.211844 -383.313215) (xy 148.227357 -383.371108) (xy 148.230564 -383.39547)
			(xy 149.778956 -383.39547) (xy 149.778956 -383.335534) (xy 149.786779 -383.276112) (xy 149.802292 -383.218219)
			(xy 149.825228 -383.162846) (xy 149.855195 -383.11094) (xy 149.891682 -383.06339) (xy 149.934062 -383.02101)
			(xy 149.981612 -382.984523) (xy 150.033518 -382.954556) (xy 150.088891 -382.93162) (xy 150.146784 -382.916107)
			(xy 150.206206 -382.908284) (xy 150.266142 -382.908284) (xy 150.325564 -382.916107) (xy 150.383457 -382.93162)
			(xy 150.43883 -382.954556) (xy 150.490736 -382.984523) (xy 150.538286 -383.02101) (xy 150.580666 -383.06339)
			(xy 150.617153 -383.11094) (xy 150.64712 -383.162846) (xy 150.670056 -383.218219) (xy 150.685569 -383.276112)
			(xy 150.693392 -383.335534) (xy 150.693882 -383.365502) (xy 150.693392 -383.39547) (xy 150.685569 -383.454892)
			(xy 150.670056 -383.512785) (xy 150.64712 -383.568158) (xy 150.617153 -383.620064) (xy 150.580666 -383.667614)
			(xy 150.538286 -383.709994) (xy 150.490736 -383.746481) (xy 150.43883 -383.776448) (xy 150.383457 -383.799384)
			(xy 150.325564 -383.814897) (xy 150.266142 -383.82272) (xy 150.206206 -383.82272) (xy 150.146784 -383.814897)
			(xy 150.088891 -383.799384) (xy 150.033518 -383.776448) (xy 149.981612 -383.746481) (xy 149.934062 -383.709994)
			(xy 149.891682 -383.667614) (xy 149.855195 -383.620064) (xy 149.825228 -383.568158) (xy 149.802292 -383.512785)
			(xy 149.786779 -383.454892) (xy 149.778956 -383.39547) (xy 148.230564 -383.39547) (xy 148.23518 -383.43053)
			(xy 148.23567 -383.460498) (xy 148.23518 -383.490466) (xy 148.227357 -383.549888) (xy 148.211844 -383.607781)
			(xy 148.188908 -383.663154) (xy 148.158941 -383.71506) (xy 148.122454 -383.76261) (xy 148.080074 -383.80499)
			(xy 148.032524 -383.841477) (xy 147.980618 -383.871444) (xy 147.925245 -383.89438) (xy 147.867352 -383.909893)
			(xy 147.80793 -383.917716) (xy 147.747994 -383.917716) (xy 147.688572 -383.909893) (xy 147.630679 -383.89438)
			(xy 147.575306 -383.871444) (xy 147.5234 -383.841477) (xy 147.47585 -383.80499) (xy 147.43347 -383.76261)
			(xy 147.396983 -383.71506) (xy 147.367016 -383.663154) (xy 147.34408 -383.607781) (xy 147.328567 -383.549888)
			(xy 147.320744 -383.490466) (xy 140.41247 -383.490466) (xy 140.41247 -384.621782) (xy 149.02356 -384.621782)
			(xy 149.02356 -384.561846) (xy 149.031383 -384.502424) (xy 149.046896 -384.444531) (xy 149.069832 -384.389158)
			(xy 149.099799 -384.337252) (xy 149.136286 -384.289702) (xy 149.178666 -384.247322) (xy 149.226216 -384.210835)
			(xy 149.278122 -384.180868) (xy 149.333495 -384.157932) (xy 149.391388 -384.142419) (xy 149.45081 -384.134596)
			(xy 149.510746 -384.134596) (xy 149.570168 -384.142419) (xy 149.628061 -384.157932) (xy 149.683434 -384.180868)
			(xy 149.73534 -384.210835) (xy 149.78289 -384.247322) (xy 149.82527 -384.289702) (xy 149.861757 -384.337252)
			(xy 149.891724 -384.389158) (xy 149.91466 -384.444531) (xy 149.930173 -384.502424) (xy 149.937996 -384.561846)
			(xy 149.938486 -384.591814) (xy 149.937996 -384.621782) (xy 149.930173 -384.681204) (xy 149.91466 -384.739097)
			(xy 149.891724 -384.79447) (xy 149.861757 -384.846376) (xy 149.82527 -384.893926) (xy 149.78289 -384.936306)
			(xy 149.73534 -384.972793) (xy 149.683434 -385.00276) (xy 149.628061 -385.025696) (xy 149.570168 -385.041209)
			(xy 149.510746 -385.049032) (xy 149.45081 -385.049032) (xy 149.391388 -385.041209) (xy 149.333495 -385.025696)
			(xy 149.278122 -385.00276) (xy 149.226216 -384.972793) (xy 149.178666 -384.936306) (xy 149.136286 -384.893926)
			(xy 149.099799 -384.846376) (xy 149.069832 -384.79447) (xy 149.046896 -384.739097) (xy 149.031383 -384.681204)
			(xy 149.02356 -384.621782) (xy 140.41247 -384.621782) (xy 140.41247 -386.451348) (xy 145.01622 -386.451348)
			(xy 145.016665 -386.424798) (xy 145.024028 -386.372211) (xy 145.038619 -386.321156) (xy 145.060154 -386.272619)
			(xy 145.088218 -386.227541) (xy 145.122267 -386.186795) (xy 145.161641 -386.151168) (xy 145.183352 -386.13588)
			(xy 145.192242 -386.129784) (xy 145.203418 -386.112004) (xy 145.217642 -386.017008) (xy 145.212308 -385.996688)
			(xy 145.20545 -385.988306) (xy 145.189739 -385.967951) (xy 145.16336 -385.923815) (xy 145.143146 -385.876536)
			(xy 145.129463 -385.826971) (xy 145.122558 -385.776017) (xy 145.122138 -385.750308) (xy 145.122624 -385.723057)
			(xy 145.13038 -385.669109) (xy 145.145735 -385.616814) (xy 145.168377 -385.567237) (xy 145.197843 -385.521387)
			(xy 145.233534 -385.480196) (xy 145.274725 -385.444505) (xy 145.320575 -385.415039) (xy 145.370152 -385.392397)
			(xy 145.422447 -385.377042) (xy 145.476395 -385.369286) (xy 145.530897 -385.369286) (xy 145.584845 -385.377042)
			(xy 145.63714 -385.392397) (xy 145.686717 -385.415039) (xy 145.732567 -385.444505) (xy 145.773758 -385.480196)
			(xy 145.809449 -385.521387) (xy 145.838915 -385.567237) (xy 145.849326 -385.590034) (xy 149.95347 -385.590034)
			(xy 149.957541 -385.534412) (xy 149.969667 -385.479975) (xy 149.98959 -385.427884) (xy 150.016886 -385.379249)
			(xy 150.050972 -385.335106) (xy 150.091121 -385.296397) (xy 150.136479 -385.263946) (xy 150.186079 -385.238445)
			(xy 150.238863 -385.220438) (xy 150.293706 -385.210308) (xy 150.34944 -385.208271) (xy 150.404877 -385.214371)
			(xy 150.458834 -385.228477) (xy 150.510163 -385.250289) (xy 150.557769 -385.279343) (xy 150.600637 -385.315018)
			(xy 150.637854 -385.356555) (xy 150.668627 -385.403068) (xy 150.692299 -385.453565) (xy 150.708367 -385.506972)
			(xy 150.716487 -385.562148) (xy 150.716996 -385.590034) (xy 150.716487 -385.61792) (xy 150.708367 -385.673096)
			(xy 150.692299 -385.726503) (xy 150.668627 -385.777) (xy 150.637854 -385.823513) (xy 150.600637 -385.86505)
			(xy 150.557769 -385.900725) (xy 150.510163 -385.929779) (xy 150.458834 -385.951591) (xy 150.404877 -385.965697)
			(xy 150.34944 -385.971797) (xy 150.293706 -385.96976) (xy 150.238863 -385.95963) (xy 150.186079 -385.941623)
			(xy 150.136479 -385.916122) (xy 150.091121 -385.883671) (xy 150.050972 -385.844962) (xy 150.016886 -385.800819)
			(xy 149.98959 -385.752184) (xy 149.969667 -385.700093) (xy 149.957541 -385.645656) (xy 149.95347 -385.590034)
			(xy 145.849326 -385.590034) (xy 145.861557 -385.616814) (xy 145.876912 -385.669109) (xy 145.884668 -385.723057)
			(xy 145.885154 -385.750308) (xy 145.884687 -385.776857) (xy 145.877329 -385.829443) (xy 145.862743 -385.880499)
			(xy 145.841212 -385.929036) (xy 145.813151 -385.974114) (xy 145.779105 -386.014861) (xy 145.739732 -386.050488)
			(xy 145.718022 -386.065776) (xy 145.709132 -386.071872) (xy 145.697956 -386.089652) (xy 145.683732 -386.184648)
			(xy 145.689066 -386.204968) (xy 145.695924 -386.21335) (xy 145.711625 -386.233711) (xy 145.738003 -386.277847)
			(xy 145.758218 -386.325125) (xy 145.771904 -386.374688) (xy 145.778813 -386.425639) (xy 145.779236 -386.451348)
			(xy 145.77875 -386.478599) (xy 145.770994 -386.532547) (xy 145.755639 -386.584842) (xy 145.732997 -386.634419)
			(xy 145.703531 -386.680269) (xy 145.66784 -386.72146) (xy 145.626649 -386.757151) (xy 145.580799 -386.786617)
			(xy 145.531222 -386.809259) (xy 145.478927 -386.824614) (xy 145.424979 -386.83237) (xy 145.370477 -386.83237)
			(xy 145.316529 -386.824614) (xy 145.264234 -386.809259) (xy 145.214657 -386.786617) (xy 145.168807 -386.757151)
			(xy 145.127616 -386.72146) (xy 145.091925 -386.680269) (xy 145.062459 -386.634419) (xy 145.039817 -386.584842)
			(xy 145.024462 -386.532547) (xy 145.016706 -386.478599) (xy 145.01622 -386.451348) (xy 140.41247 -386.451348)
			(xy 140.41247 -386.771388) (xy 140.41289 -386.78146) (xy 140.420598 -386.80007) (xy 140.427456 -386.807456)
			(xy 140.904214 -387.284214) (xy 140.911609 -387.291068) (xy 140.930208 -387.29881) (xy 140.940282 -387.2992)
			(xy 144.508728 -387.2992)
		)
		(stroke
			(width 0)
			(type solid)
		)
		(fill yes)
		(layer "B.Cu")
		(net "GND")
	)
	(gr_poly
		(pts
			(xy 112.215422 -184.152032) (xy 112.22254 -184.151764) (xy 112.236209 -184.147775) (xy 112.242346 -184.144158)
			(xy 112.269919 -184.127444) (xy 112.328065 -184.099573) (xy 112.388959 -184.07837) (xy 112.45184 -184.0641)
			(xy 112.515922 -184.05694) (xy 112.548162 -184.056528) (xy 120.145302 -184.056528) (xy 120.15529 -184.055991)
			(xy 120.173724 -184.04828) (xy 120.181116 -184.041542) (xy 120.720358 -183.5023) (xy 120.727209 -183.494903)
			(xy 120.73495 -183.476305) (xy 120.735344 -183.466232) (xy 120.735344 -163.218368) (xy 120.734913 -163.208302)
			(xy 120.727185 -163.189711) (xy 120.720358 -163.1823) (xy 119.586248 -162.04819) (xy 119.579398 -162.040793)
			(xy 119.571659 -162.022195) (xy 119.571262 -162.012122) (xy 119.571262 -154.827224) (xy 119.571357 -154.822205)
			(xy 119.57328 -154.812355) (xy 119.575072 -154.807666) (xy 119.582438 -154.790394) (xy 119.584235 -154.785707)
			(xy 119.58615 -154.775855) (xy 119.586248 -154.770836) (xy 119.586248 -147.606258) (xy 119.585816 -147.596192)
			(xy 119.578085 -147.577604) (xy 119.571262 -147.57019) (xy 119.118634 -147.117562) (xy 119.111235 -147.110719)
			(xy 119.092636 -147.102999) (xy 119.082566 -147.102576) (xy 104.36098 -147.102576) (xy 104.342438 -147.110196)
			(xy 104.336596 -147.116038) (xy 101.94163 -147.116038) (xy 101.931566 -147.116475) (xy 101.912984 -147.124211)
			(xy 101.905562 -147.131024) (xy 100.70592 -148.330666) (xy 100.699082 -148.338067) (xy 100.691368 -148.356666)
			(xy 100.690934 -148.366734) (xy 100.690934 -158.947612) (xy 107.178348 -158.947612) (xy 107.178854 -158.914331)
			(xy 107.187531 -158.848338) (xy 107.204751 -158.784043) (xy 107.23022 -158.722548) (xy 107.263501 -158.664904)
			(xy 107.304025 -158.612101) (xy 107.327192 -158.588202) (xy 108.949744 -156.96565) (xy 108.973606 -156.942433)
			(xy 109.026407 -156.901874) (xy 109.084051 -156.868557) (xy 109.145552 -156.843052) (xy 109.209857 -156.825795)
			(xy 109.275864 -156.817083) (xy 109.309154 -156.816552) (xy 113.70564 -156.816552) (xy 113.738925 -156.817108)
			(xy 113.80492 -156.825848) (xy 113.869211 -156.843121) (xy 113.9307 -156.868632) (xy 113.988337 -156.901945)
			(xy 114.041136 -156.942491) (xy 114.06505 -156.96565) (xy 118.412514 -161.313114) (xy 118.43571 -161.336996)
			(xy 118.476272 -161.389792) (xy 118.509593 -161.447432) (xy 118.535102 -161.508929) (xy 118.552362 -161.57323)
			(xy 118.561079 -161.639235) (xy 118.561612 -161.672524) (xy 118.561612 -163.598098) (xy 118.561206 -163.628826)
			(xy 118.553796 -163.689834) (xy 118.539084 -163.749503) (xy 118.517283 -163.806963) (xy 118.488714 -163.861375)
			(xy 118.453791 -163.911944) (xy 118.413026 -163.957934) (xy 118.367013 -163.998673) (xy 118.316423 -164.033566)
			(xy 118.261994 -164.062104) (xy 118.204522 -164.083871) (xy 118.144844 -164.098549) (xy 118.083832 -164.105924)
			(xy 118.053104 -164.106352) (xy 118.027077 -164.106075) (xy 117.975286 -164.100857) (xy 117.949726 -164.095938)
			(xy 117.938296 -164.093398) (xy 117.916452 -164.098732) (xy 117.846094 -164.155882) (xy 117.837736 -164.163512)
			(xy 117.828097 -164.18395) (xy 117.827552 -164.195252) (xy 117.827552 -164.802058) (xy 117.827051 -164.836776)
			(xy 117.818683 -164.905707) (xy 117.802064 -164.973126) (xy 117.777438 -165.038049) (xy 117.745162 -165.099529)
			(xy 117.705709 -165.156668) (xy 117.659653 -165.208633) (xy 117.607668 -165.254666) (xy 117.550511 -165.294094)
			(xy 117.489017 -165.326342) (xy 117.424083 -165.35094) (xy 117.356657 -165.367529) (xy 117.287723 -165.375866)
			(xy 117.253004 -165.376352) (xy 115.490498 -165.376352) (xy 115.458269 -165.375939) (xy 115.394215 -165.368723)
			(xy 115.331372 -165.354383) (xy 115.270529 -165.333099) (xy 115.212451 -165.305137) (xy 115.157867 -165.270851)
			(xy 115.107465 -165.23067) (xy 115.084352 -165.208204) (xy 113.878868 -164.00272) (xy 113.871393 -163.996019)
			(xy 113.852829 -163.988434) (xy 113.8428 -163.987988) (xy 113.534698 -163.987988) (xy 113.501265 -163.987422)
			(xy 113.434851 -163.979659) (xy 113.369788 -163.964239) (xy 113.306955 -163.941369) (xy 113.247201 -163.91136)
			(xy 113.191336 -163.874616) (xy 113.140114 -163.831635) (xy 113.094228 -163.782999) (xy 113.054298 -163.729364)
			(xy 113.020865 -163.671457) (xy 112.994381 -163.610059) (xy 112.975204 -163.546003) (xy 112.963593 -163.480153)
			(xy 112.959705 -163.4134) (xy 112.963593 -163.346647) (xy 112.975204 -163.280797) (xy 112.994381 -163.216741)
			(xy 113.020865 -163.155343) (xy 113.054298 -163.097436) (xy 113.094228 -163.043801) (xy 113.140114 -162.995165)
			(xy 113.191336 -162.952184) (xy 113.247201 -162.91544) (xy 113.306955 -162.885431) (xy 113.369788 -162.862561)
			(xy 113.434851 -162.847141) (xy 113.501265 -162.839378) (xy 113.534698 -162.838892) (xy 114.10188 -162.838892)
			(xy 114.134115 -162.839386) (xy 114.198177 -162.846624) (xy 114.261025 -162.860989) (xy 114.321871 -162.882299)
			(xy 114.379948 -162.910288) (xy 114.434526 -162.944604) (xy 114.484919 -162.984814) (xy 114.508026 -163.007294)
			(xy 115.71351 -164.212778) (xy 115.720915 -164.219612) (xy 115.73951 -164.227336) (xy 115.749578 -164.227764)
			(xy 116.627656 -164.227764) (xy 116.637679 -164.227344) (xy 116.656202 -164.219681) (xy 116.670377 -164.205508)
			(xy 116.678042 -164.186987) (xy 116.678456 -164.176964) (xy 116.678456 -163.598098) (xy 116.679008 -163.563382)
			(xy 116.687379 -163.494457) (xy 116.703999 -163.427044) (xy 116.728625 -163.362126) (xy 116.760899 -163.300651)
			(xy 116.800348 -163.243515) (xy 116.846399 -163.191553) (xy 116.898378 -163.145521) (xy 116.955528 -163.106092)
			(xy 117.017014 -163.073841) (xy 117.081941 -163.049238) (xy 117.14936 -163.032642) (xy 117.218288 -163.024295)
			(xy 117.253004 -163.023804) (xy 117.293957 -163.024521) (xy 117.375038 -163.036117) (xy 117.414548 -163.046918)
			(xy 117.426232 -163.05022) (xy 117.4496 -163.046156) (xy 117.524276 -162.990022) (xy 117.533389 -162.982426)
			(xy 117.54398 -162.96123) (xy 117.544596 -162.949382) (xy 117.544596 -161.904172) (xy 117.544243 -161.894124)
			(xy 117.536645 -161.875527) (xy 117.529864 -161.868104) (xy 113.51006 -157.8483) (xy 113.50259 -157.841593)
			(xy 113.484022 -157.834012) (xy 113.473992 -157.833568) (xy 109.540802 -157.833568) (xy 109.530757 -157.833946)
			(xy 109.51216 -157.841527) (xy 109.504734 -157.8483) (xy 108.046012 -159.307022) (xy 108.022119 -159.330207)
			(xy 107.969326 -159.37077) (xy 107.911688 -159.404092) (xy 107.850193 -159.429603) (xy 107.785894 -159.446866)
			(xy 107.71989 -159.455585) (xy 107.686602 -159.45612) (xy 107.655874 -159.455706) (xy 107.594867 -159.448296)
			(xy 107.535198 -159.433584) (xy 107.477739 -159.411784) (xy 107.423328 -159.383215) (xy 107.372758 -159.348293)
			(xy 107.326769 -159.307529) (xy 107.28603 -159.261516) (xy 107.251137 -159.210927) (xy 107.222598 -159.1565)
			(xy 107.200831 -159.099028) (xy 107.186152 -159.039351) (xy 107.178776 -158.97834) (xy 107.178348 -158.947612)
			(xy 100.690934 -158.947612) (xy 100.690934 -159.711386) (xy 112.101358 -159.711386) (xy 112.101358 -159.65145)
			(xy 112.109181 -159.592028) (xy 112.124694 -159.534135) (xy 112.14763 -159.478762) (xy 112.177597 -159.426856)
			(xy 112.214084 -159.379306) (xy 112.256464 -159.336926) (xy 112.304014 -159.300439) (xy 112.35592 -159.270472)
			(xy 112.411293 -159.247536) (xy 112.469186 -159.232023) (xy 112.528608 -159.2242) (xy 112.588544 -159.2242)
			(xy 112.647966 -159.232023) (xy 112.705859 -159.247536) (xy 112.761232 -159.270472) (xy 112.813138 -159.300439)
			(xy 112.860688 -159.336926) (xy 112.903068 -159.379306) (xy 112.939555 -159.426856) (xy 112.969522 -159.478762)
			(xy 112.992458 -159.534135) (xy 113.007971 -159.592028) (xy 113.015794 -159.65145) (xy 113.016284 -159.681418)
			(xy 113.015794 -159.711386) (xy 113.007971 -159.770808) (xy 112.992458 -159.828701) (xy 112.969522 -159.884074)
			(xy 112.939555 -159.93598) (xy 112.903068 -159.98353) (xy 112.860688 -160.02591) (xy 112.813138 -160.062397)
			(xy 112.761232 -160.092364) (xy 112.705859 -160.1153) (xy 112.647966 -160.130813) (xy 112.588544 -160.138636)
			(xy 112.528608 -160.138636) (xy 112.469186 -160.130813) (xy 112.411293 -160.1153) (xy 112.35592 -160.092364)
			(xy 112.304014 -160.062397) (xy 112.256464 -160.02591) (xy 112.214084 -159.98353) (xy 112.177597 -159.93598)
			(xy 112.14763 -159.884074) (xy 112.124694 -159.828701) (xy 112.109181 -159.770808) (xy 112.101358 -159.711386)
			(xy 100.690934 -159.711386) (xy 100.690934 -160.250374) (xy 113.314716 -160.250374) (xy 113.314716 -160.190438)
			(xy 113.322539 -160.131016) (xy 113.338052 -160.073123) (xy 113.360988 -160.01775) (xy 113.390955 -159.965844)
			(xy 113.427442 -159.918294) (xy 113.469822 -159.875914) (xy 113.517372 -159.839427) (xy 113.569278 -159.80946)
			(xy 113.624651 -159.786524) (xy 113.682544 -159.771011) (xy 113.741966 -159.763188) (xy 113.801902 -159.763188)
			(xy 113.861324 -159.771011) (xy 113.919217 -159.786524) (xy 113.97459 -159.80946) (xy 114.026496 -159.839427)
			(xy 114.074046 -159.875914) (xy 114.116426 -159.918294) (xy 114.152913 -159.965844) (xy 114.18288 -160.01775)
			(xy 114.205816 -160.073123) (xy 114.221329 -160.131016) (xy 114.229152 -160.190438) (xy 114.229642 -160.220406)
			(xy 114.229152 -160.250374) (xy 114.221329 -160.309796) (xy 114.205816 -160.367689) (xy 114.18288 -160.423062)
			(xy 114.152913 -160.474968) (xy 114.132298 -160.501834) (xy 114.74499 -160.501834) (xy 114.74499 -160.441898)
			(xy 114.752813 -160.382476) (xy 114.768326 -160.324583) (xy 114.791262 -160.26921) (xy 114.821229 -160.217304)
			(xy 114.857716 -160.169754) (xy 114.900096 -160.127374) (xy 114.947646 -160.090887) (xy 114.999552 -160.06092)
			(xy 115.054925 -160.037984) (xy 115.112818 -160.022471) (xy 115.17224 -160.014648) (xy 115.232176 -160.014648)
			(xy 115.291598 -160.022471) (xy 115.349491 -160.037984) (xy 115.404864 -160.06092) (xy 115.45677 -160.090887)
			(xy 115.50432 -160.127374) (xy 115.5467 -160.169754) (xy 115.583187 -160.217304) (xy 115.613154 -160.26921)
			(xy 115.63609 -160.324583) (xy 115.651603 -160.382476) (xy 115.659426 -160.441898) (xy 115.659916 -160.471866)
			(xy 115.659426 -160.501834) (xy 115.651603 -160.561256) (xy 115.63609 -160.619149) (xy 115.613154 -160.674522)
			(xy 115.583187 -160.726428) (xy 115.5467 -160.773978) (xy 115.50432 -160.816358) (xy 115.45677 -160.852845)
			(xy 115.404864 -160.882812) (xy 115.349491 -160.905748) (xy 115.291598 -160.921261) (xy 115.232176 -160.929084)
			(xy 115.17224 -160.929084) (xy 115.112818 -160.921261) (xy 115.054925 -160.905748) (xy 114.999552 -160.882812)
			(xy 114.947646 -160.852845) (xy 114.900096 -160.816358) (xy 114.857716 -160.773978) (xy 114.821229 -160.726428)
			(xy 114.791262 -160.674522) (xy 114.768326 -160.619149) (xy 114.752813 -160.561256) (xy 114.74499 -160.501834)
			(xy 114.132298 -160.501834) (xy 114.116426 -160.522518) (xy 114.074046 -160.564898) (xy 114.026496 -160.601385)
			(xy 113.97459 -160.631352) (xy 113.919217 -160.654288) (xy 113.861324 -160.669801) (xy 113.801902 -160.677624)
			(xy 113.741966 -160.677624) (xy 113.682544 -160.669801) (xy 113.624651 -160.654288) (xy 113.569278 -160.631352)
			(xy 113.517372 -160.601385) (xy 113.469822 -160.564898) (xy 113.427442 -160.522518) (xy 113.390955 -160.474968)
			(xy 113.360988 -160.423062) (xy 113.338052 -160.367689) (xy 113.322539 -160.309796) (xy 113.314716 -160.250374)
			(xy 100.690934 -160.250374) (xy 100.690934 -162.16147) (xy 111.59793 -162.16147) (xy 111.59793 -162.101534)
			(xy 111.605753 -162.042112) (xy 111.621266 -161.984219) (xy 111.644202 -161.928846) (xy 111.674169 -161.87694)
			(xy 111.710656 -161.82939) (xy 111.753036 -161.78701) (xy 111.800586 -161.750523) (xy 111.852492 -161.720556)
			(xy 111.907865 -161.69762) (xy 111.965758 -161.682107) (xy 112.02518 -161.674284) (xy 112.085116 -161.674284)
			(xy 112.144538 -161.682107) (xy 112.202431 -161.69762) (xy 112.257804 -161.720556) (xy 112.30971 -161.750523)
			(xy 112.35726 -161.78701) (xy 112.39964 -161.82939) (xy 112.404591 -161.835842) (xy 113.151648 -161.835842)
			(xy 113.151648 -161.775906) (xy 113.159471 -161.716484) (xy 113.174984 -161.658591) (xy 113.19792 -161.603218)
			(xy 113.227887 -161.551312) (xy 113.264374 -161.503762) (xy 113.306754 -161.461382) (xy 113.354304 -161.424895)
			(xy 113.40621 -161.394928) (xy 113.461583 -161.371992) (xy 113.519476 -161.356479) (xy 113.578898 -161.348656)
			(xy 113.638834 -161.348656) (xy 113.698256 -161.356479) (xy 113.756149 -161.371992) (xy 113.811522 -161.394928)
			(xy 113.863428 -161.424895) (xy 113.910978 -161.461382) (xy 113.953358 -161.503762) (xy 113.989845 -161.551312)
			(xy 114.019812 -161.603218) (xy 114.042748 -161.658591) (xy 114.058261 -161.716484) (xy 114.066084 -161.775906)
			(xy 114.066574 -161.805874) (xy 114.066084 -161.835842) (xy 114.058261 -161.895264) (xy 114.042748 -161.953157)
			(xy 114.019812 -162.00853) (xy 113.989845 -162.060436) (xy 113.953358 -162.107986) (xy 113.932636 -162.128708)
			(xy 115.561108 -162.128708) (xy 115.565179 -162.073086) (xy 115.577305 -162.018649) (xy 115.597228 -161.966558)
			(xy 115.624524 -161.917923) (xy 115.65861 -161.87378) (xy 115.698759 -161.835071) (xy 115.744117 -161.80262)
			(xy 115.793717 -161.777119) (xy 115.846501 -161.759112) (xy 115.901344 -161.748982) (xy 115.957078 -161.746945)
			(xy 116.012515 -161.753045) (xy 116.066472 -161.767151) (xy 116.117801 -161.788963) (xy 116.165407 -161.818017)
			(xy 116.208275 -161.853692) (xy 116.245492 -161.895229) (xy 116.276265 -161.941742) (xy 116.299937 -161.992239)
			(xy 116.316005 -162.045646) (xy 116.324125 -162.100822) (xy 116.324634 -162.128708) (xy 116.324125 -162.156594)
			(xy 116.316005 -162.21177) (xy 116.299937 -162.265177) (xy 116.276265 -162.315674) (xy 116.245492 -162.362187)
			(xy 116.208275 -162.403724) (xy 116.165407 -162.439399) (xy 116.117801 -162.468453) (xy 116.066472 -162.490265)
			(xy 116.012515 -162.504371) (xy 115.957078 -162.510471) (xy 115.901344 -162.508434) (xy 115.846501 -162.498304)
			(xy 115.793717 -162.480297) (xy 115.744117 -162.454796) (xy 115.698759 -162.422345) (xy 115.65861 -162.383636)
			(xy 115.624524 -162.339493) (xy 115.597228 -162.290858) (xy 115.577305 -162.238767) (xy 115.565179 -162.18433)
			(xy 115.561108 -162.128708) (xy 113.932636 -162.128708) (xy 113.910978 -162.150366) (xy 113.863428 -162.186853)
			(xy 113.811522 -162.21682) (xy 113.756149 -162.239756) (xy 113.698256 -162.255269) (xy 113.638834 -162.263092)
			(xy 113.578898 -162.263092) (xy 113.519476 -162.255269) (xy 113.461583 -162.239756) (xy 113.40621 -162.21682)
			(xy 113.354304 -162.186853) (xy 113.306754 -162.150366) (xy 113.264374 -162.107986) (xy 113.227887 -162.060436)
			(xy 113.19792 -162.00853) (xy 113.174984 -161.953157) (xy 113.159471 -161.895264) (xy 113.151648 -161.835842)
			(xy 112.404591 -161.835842) (xy 112.436127 -161.87694) (xy 112.466094 -161.928846) (xy 112.48903 -161.984219)
			(xy 112.504543 -162.042112) (xy 112.512366 -162.101534) (xy 112.512856 -162.131502) (xy 112.512366 -162.16147)
			(xy 112.504543 -162.220892) (xy 112.48903 -162.278785) (xy 112.466094 -162.334158) (xy 112.436127 -162.386064)
			(xy 112.39964 -162.433614) (xy 112.35726 -162.475994) (xy 112.30971 -162.512481) (xy 112.257804 -162.542448)
			(xy 112.202431 -162.565384) (xy 112.144538 -162.580897) (xy 112.085116 -162.58872) (xy 112.02518 -162.58872)
			(xy 111.965758 -162.580897) (xy 111.907865 -162.565384) (xy 111.852492 -162.542448) (xy 111.800586 -162.512481)
			(xy 111.753036 -162.475994) (xy 111.710656 -162.433614) (xy 111.674169 -162.386064) (xy 111.644202 -162.334158)
			(xy 111.621266 -162.278785) (xy 111.605753 -162.220892) (xy 111.59793 -162.16147) (xy 100.690934 -162.16147)
			(xy 100.690934 -180.494686) (xy 100.691374 -180.504749) (xy 100.699114 -180.523327) (xy 100.70592 -180.530754)
			(xy 101.114606 -180.93944) (xy 107.97667 -180.93944) (xy 107.977165 -180.9107) (xy 107.985796 -180.853872)
			(xy 108.002853 -180.798981) (xy 108.027951 -180.74727) (xy 108.060521 -180.699908) (xy 108.079794 -180.678582)
			(xy 108.086398 -180.67147) (xy 108.09351 -180.653944) (xy 108.09351 -180.564536) (xy 108.086398 -180.54701)
			(xy 108.079794 -180.539898) (xy 108.060552 -180.518546) (xy 108.02798 -180.471192) (xy 108.002881 -180.419487)
			(xy 107.985824 -180.364601) (xy 107.977195 -180.307777) (xy 107.97667 -180.27904) (xy 107.977192 -180.251789)
			(xy 107.984943 -180.197841) (xy 108.000293 -180.145546) (xy 108.022929 -180.095968) (xy 108.052391 -180.050115)
			(xy 108.088079 -180.008923) (xy 108.129266 -179.973228) (xy 108.175113 -179.943759) (xy 108.224688 -179.921115)
			(xy 108.276981 -179.905757) (xy 108.330927 -179.897997) (xy 108.358178 -179.897532) (xy 108.383547 -179.897949)
			(xy 108.433837 -179.904672) (xy 108.482791 -179.918002) (xy 108.529547 -179.937705) (xy 108.573278 -179.963431)
			(xy 108.613213 -179.994728) (xy 108.631228 -180.012594) (xy 108.63834 -180.01996) (xy 108.656628 -180.027834)
			(xy 108.74883 -180.029104) (xy 108.767118 -180.021738) (xy 108.774484 -180.014626) (xy 108.795961 -179.994638)
			(xy 108.843891 -179.960808) (xy 108.896434 -179.934711) (xy 108.952352 -179.916962) (xy 109.010327 -179.907978)
			(xy 109.03966 -179.907438) (xy 109.06703 -179.907918) (xy 109.121209 -179.915731) (xy 109.173712 -179.931216)
			(xy 109.223459 -179.954055) (xy 109.269426 -179.983778) (xy 109.290358 -180.001418) (xy 109.29747 -180.007514)
			(xy 109.314488 -180.013864) (xy 109.399832 -180.013864) (xy 109.41685 -180.007514) (xy 109.423962 -180.001418)
			(xy 109.444895 -179.983777) (xy 109.490863 -179.954053) (xy 109.540609 -179.931207) (xy 109.593111 -179.915711)
			(xy 109.647289 -179.907882) (xy 109.702031 -179.907882) (xy 109.756209 -179.915711) (xy 109.808711 -179.931207)
			(xy 109.858457 -179.954053) (xy 109.904425 -179.983777) (xy 109.925358 -180.001418) (xy 109.93247 -180.007514)
			(xy 109.949488 -180.013864) (xy 110.034832 -180.013864) (xy 110.05185 -180.007514) (xy 110.058962 -180.001418)
			(xy 110.079895 -179.983777) (xy 110.125863 -179.954053) (xy 110.175609 -179.931207) (xy 110.228111 -179.915711)
			(xy 110.282289 -179.907882) (xy 110.337031 -179.907882) (xy 110.391209 -179.915711) (xy 110.443711 -179.931207)
			(xy 110.493457 -179.954053) (xy 110.539425 -179.983777) (xy 110.560358 -180.001418) (xy 110.56747 -180.007514)
			(xy 110.584488 -180.013864) (xy 110.669832 -180.013864) (xy 110.68685 -180.007514) (xy 110.693962 -180.001418)
			(xy 110.714895 -179.983777) (xy 110.760863 -179.954053) (xy 110.810609 -179.931207) (xy 110.863111 -179.915711)
			(xy 110.917289 -179.907882) (xy 110.972031 -179.907882) (xy 111.026209 -179.915711) (xy 111.078711 -179.931207)
			(xy 111.128457 -179.954053) (xy 111.174425 -179.983777) (xy 111.195358 -180.001418) (xy 111.20247 -180.007514)
			(xy 111.219488 -180.013864) (xy 111.304832 -180.013864) (xy 111.32185 -180.007514) (xy 111.328962 -180.001418)
			(xy 111.3499 -179.983786) (xy 111.395871 -179.954073) (xy 111.445617 -179.931235) (xy 111.498116 -179.915742)
			(xy 111.552291 -179.907913) (xy 111.57966 -179.907438) (xy 111.606914 -179.907893) (xy 111.660868 -179.915645)
			(xy 111.713168 -179.930999) (xy 111.762751 -179.95364) (xy 111.808607 -179.983108) (xy 111.849801 -180.018803)
			(xy 111.885496 -180.059998) (xy 111.914963 -180.105854) (xy 111.937603 -180.155437) (xy 111.952956 -180.207738)
			(xy 111.960708 -180.261692) (xy 111.961168 -180.288946) (xy 111.960654 -180.317685) (xy 111.952026 -180.374512)
			(xy 111.934973 -180.429402) (xy 111.90988 -180.481114) (xy 111.877314 -180.528477) (xy 111.858044 -180.549804)
			(xy 111.85144 -180.556916) (xy 111.844328 -180.574442) (xy 111.844328 -180.66385) (xy 111.85144 -180.681376)
			(xy 111.858044 -180.688488) (xy 111.877334 -180.709799) (xy 111.909898 -180.757165) (xy 111.934987 -180.808881)
			(xy 111.952033 -180.863775) (xy 111.96065 -180.920606) (xy 111.961168 -180.949346) (xy 111.960765 -180.9766)
			(xy 111.953001 -181.030553) (xy 111.937638 -181.082852) (xy 111.914989 -181.132432) (xy 111.885514 -181.178284)
			(xy 111.849814 -181.219475) (xy 111.808615 -181.255165) (xy 111.762756 -181.28463) (xy 111.713171 -181.307268)
			(xy 111.660869 -181.322619) (xy 111.606914 -181.330371) (xy 111.57966 -181.330854) (xy 111.552291 -181.330364)
			(xy 111.498112 -181.322554) (xy 111.445609 -181.307071) (xy 111.395861 -181.284234) (xy 111.349894 -181.254514)
			(xy 111.328962 -181.236874) (xy 111.32185 -181.230778) (xy 111.304832 -181.224428) (xy 111.219488 -181.224428)
			(xy 111.20247 -181.230778) (xy 111.195358 -181.236874) (xy 111.174425 -181.254515) (xy 111.128457 -181.284239)
			(xy 111.078711 -181.307085) (xy 111.026209 -181.322581) (xy 110.972031 -181.33041) (xy 110.917289 -181.33041)
			(xy 110.863111 -181.322581) (xy 110.810609 -181.307085) (xy 110.760863 -181.284239) (xy 110.714895 -181.254515)
			(xy 110.693962 -181.236874) (xy 110.68685 -181.230778) (xy 110.669832 -181.224428) (xy 110.584488 -181.224428)
			(xy 110.56747 -181.230778) (xy 110.560358 -181.236874) (xy 110.539425 -181.254515) (xy 110.493457 -181.284239)
			(xy 110.443711 -181.307085) (xy 110.391209 -181.322581) (xy 110.337031 -181.33041) (xy 110.282289 -181.33041)
			(xy 110.228111 -181.322581) (xy 110.175609 -181.307085) (xy 110.125863 -181.284239) (xy 110.079895 -181.254515)
			(xy 110.058962 -181.236874) (xy 110.05185 -181.230778) (xy 110.034832 -181.224428) (xy 109.949488 -181.224428)
			(xy 109.93247 -181.230778) (xy 109.925358 -181.236874) (xy 109.904425 -181.254515) (xy 109.858457 -181.284239)
			(xy 109.808711 -181.307085) (xy 109.756209 -181.322581) (xy 109.702031 -181.33041) (xy 109.647289 -181.33041)
			(xy 109.593111 -181.322581) (xy 109.540609 -181.307085) (xy 109.490863 -181.284239) (xy 109.444895 -181.254515)
			(xy 109.423962 -181.236874) (xy 109.41685 -181.230778) (xy 109.399832 -181.224428) (xy 109.314488 -181.224428)
			(xy 109.29747 -181.230778) (xy 109.290358 -181.236874) (xy 109.269412 -181.254495) (xy 109.223443 -181.284211)
			(xy 109.173699 -181.30705) (xy 109.121202 -181.322546) (xy 109.067028 -181.330378) (xy 109.03966 -181.330854)
			(xy 109.01429 -181.330482) (xy 108.963998 -181.32375) (xy 108.915042 -181.310411) (xy 108.868286 -181.290701)
			(xy 108.824556 -181.264966) (xy 108.784624 -181.233662) (xy 108.76661 -181.215792) (xy 108.759498 -181.208426)
			(xy 108.74121 -181.200552) (xy 108.649008 -181.199282) (xy 108.63072 -181.206648) (xy 108.623354 -181.21376)
			(xy 108.601875 -181.233744) (xy 108.553943 -181.267571) (xy 108.501401 -181.293668) (xy 108.445485 -181.311418)
			(xy 108.387511 -181.320405) (xy 108.358178 -181.320948) (xy 108.330928 -181.320443) (xy 108.276983 -181.312684)
			(xy 108.224691 -181.297328) (xy 108.175117 -181.274688) (xy 108.129268 -181.245223) (xy 108.088079 -181.209534)
			(xy 108.052388 -181.168346) (xy 108.022921 -181.122499) (xy 108.000278 -181.072926) (xy 107.98492 -181.020635)
			(xy 107.977158 -180.96669) (xy 107.97667 -180.93944) (xy 101.114606 -180.93944) (xy 104.312212 -184.137046)
			(xy 104.319608 -184.143897) (xy 104.338207 -184.151635) (xy 104.34828 -184.152032)
		)
		(stroke
			(width 0)
			(type solid)
		)
		(fill yes)
		(layer "B.Cu")
		(net "GND")
	)
	(gr_poly
		(pts
			(xy 237.620048 -96.799654) (xy 237.630113 -96.799221) (xy 237.648701 -96.791489) (xy 237.656116 -96.784668)
			(xy 238.173006 -96.267778) (xy 238.179848 -96.260378) (xy 238.187574 -96.24178) (xy 238.187992 -96.23171)
			(xy 238.187992 -94.927928) (xy 238.188086 -94.922909) (xy 238.19001 -94.913059) (xy 238.191802 -94.90837)
			(xy 238.199168 -94.891098) (xy 238.200967 -94.886411) (xy 238.202886 -94.876559) (xy 238.202978 -94.87154)
			(xy 238.202978 -94.554548) (xy 238.202545 -94.544482) (xy 238.194815 -94.525894) (xy 238.187992 -94.51848)
			(xy 237.943644 -94.273878) (xy 237.89513 -94.225618) (xy 237.892336 -94.222824) (xy 237.892336 -94.22257)
			(xy 237.820454 -94.150688) (xy 237.813639 -94.143345) (xy 237.805903 -94.124882) (xy 237.805468 -94.114874)
			(xy 237.805468 -93.192092) (xy 237.805022 -93.182546) (xy 237.797979 -93.164796) (xy 237.791752 -93.157548)
			(xy 237.777782 -93.142562) (xy 237.774588 -93.13936) (xy 237.767309 -93.133995) (xy 237.763304 -93.131894)
			(xy 237.739936 -93.12021) (xy 237.7313 -93.119194) (xy 237.7015 -93.114967) (xy 237.643281 -93.099698)
			(xy 237.587565 -93.076931) (xy 237.535313 -93.047059) (xy 237.487426 -93.010596) (xy 237.444731 -92.968173)
			(xy 237.407964 -92.92052) (xy 237.377759 -92.868459) (xy 237.354636 -92.812889) (xy 237.338996 -92.754769)
			(xy 237.331108 -92.695099) (xy 237.331107 -92.634911) (xy 237.338994 -92.575242) (xy 237.354633 -92.517121)
			(xy 237.377754 -92.46155) (xy 237.407958 -92.409489) (xy 237.444724 -92.361835) (xy 237.487418 -92.319411)
			(xy 237.535304 -92.282947) (xy 237.587555 -92.253073) (xy 237.643271 -92.230305) (xy 237.70149 -92.215035)
			(xy 237.7313 -92.21089) (xy 237.739936 -92.209874) (xy 237.763304 -92.19819) (xy 237.76733 -92.196123)
			(xy 237.774616 -92.190756) (xy 237.777782 -92.187522) (xy 237.791752 -92.172536) (xy 237.798008 -92.165302)
			(xy 237.805075 -92.147546) (xy 237.805468 -92.137992) (xy 237.805468 -90.563446) (xy 237.804963 -90.553014)
			(xy 237.796631 -90.533886) (xy 237.78134 -90.519691) (xy 237.771686 -90.515694) (xy 237.681516 -90.48369)
			(xy 237.67142 -90.480714) (xy 237.650452 -90.482277) (xy 237.631838 -90.492056) (xy 237.624874 -90.499946)
			(xy 237.606202 -90.522381) (xy 237.564091 -90.562801) (xy 237.517181 -90.597537) (xy 237.466235 -90.626026)
			(xy 237.41208 -90.647804) (xy 237.355595 -90.662519) (xy 237.297697 -90.669931) (xy 237.268512 -90.67038)
			(xy 237.238544 -90.669912) (xy 237.179121 -90.66209) (xy 237.121228 -90.646579) (xy 237.065854 -90.623644)
			(xy 237.013948 -90.593677) (xy 236.966398 -90.557191) (xy 236.924017 -90.514811) (xy 236.88753 -90.467262)
			(xy 236.857562 -90.415356) (xy 236.834625 -90.359983) (xy 236.819112 -90.30209) (xy 236.811289 -90.242668)
			(xy 236.811289 -90.182732) (xy 236.819112 -90.12331) (xy 236.834625 -90.065417) (xy 236.857562 -90.010044)
			(xy 236.88753 -89.958138) (xy 236.924017 -89.910589) (xy 236.966398 -89.868209) (xy 237.013948 -89.831723)
			(xy 237.065854 -89.801756) (xy 237.121228 -89.778821) (xy 237.179121 -89.76331) (xy 237.238544 -89.755488)
			(xy 237.268512 -89.754964) (xy 237.298541 -89.755432) (xy 237.358085 -89.763278) (xy 237.41609 -89.778847)
			(xy 237.47156 -89.801872) (xy 237.52354 -89.831956) (xy 237.571137 -89.868583) (xy 237.613533 -89.911122)
			(xy 237.649999 -89.958842) (xy 237.679909 -90.010923) (xy 237.702746 -90.06647) (xy 237.718121 -90.124527)
			(xy 237.72241 -90.154252) (xy 237.723426 -90.161364) (xy 237.729014 -90.174318) (xy 237.733586 -90.179906)
			(xy 237.738246 -90.18519) (xy 237.749852 -90.19317) (xy 237.756446 -90.195654) (xy 237.842552 -90.225372)
			(xy 237.851684 -90.228093) (xy 237.870708 -90.227305) (xy 237.888148 -90.219662) (xy 237.89513 -90.21318)
			(xy 237.993174 -90.115136) (xy 238.187992 -89.920064) (xy 238.194798 -89.912717) (xy 238.202518 -89.894255)
			(xy 238.202978 -89.88425) (xy 238.202978 -88.525858) (xy 238.202547 -88.515792) (xy 238.194819 -88.4972)
			(xy 238.187992 -88.48979) (xy 237.788704 -88.090502) (xy 237.760647 -88.084716) (xy 237.706554 -88.065858)
			(xy 237.655887 -88.03913) (xy 237.609782 -88.00513) (xy 237.569274 -87.964624) (xy 237.535274 -87.918519)
			(xy 237.508545 -87.867852) (xy 237.489686 -87.81376) (xy 237.483904 -87.785702) (xy 237.449614 -87.751412)
			(xy 237.442502 -87.744046) (xy 237.423706 -87.736426) (xy 235.997242 -87.736426) (xy 235.97239 -87.756633)
			(xy 235.918107 -87.790631) (xy 235.859614 -87.816728) (xy 235.798053 -87.834415) (xy 235.734628 -87.843345)
			(xy 235.702602 -87.843868) (xy 234.839002 -87.843868) (xy 234.806977 -87.843332) (xy 234.743552 -87.834404)
			(xy 234.68199 -87.816722) (xy 234.623495 -87.79063) (xy 234.569208 -87.756639) (xy 234.544362 -87.736426)
			(xy 234.405424 -87.736426) (xy 234.427328 -87.755474) (xy 234.465929 -87.798825) (xy 234.497835 -87.847317)
			(xy 234.52237 -87.899922) (xy 234.539017 -87.95553) (xy 234.547423 -88.012965) (xy 234.547918 -88.041988)
			(xy 234.54741 -88.070473) (xy 234.539302 -88.126863) (xy 234.523252 -88.181525) (xy 234.499586 -88.233347)
			(xy 234.468786 -88.281273) (xy 234.431478 -88.324328) (xy 234.388423 -88.361636) (xy 234.340497 -88.392436)
			(xy 234.288675 -88.416102) (xy 234.234013 -88.432152) (xy 234.177623 -88.44026) (xy 234.120653 -88.44026)
			(xy 234.064263 -88.432152) (xy 234.009601 -88.416102) (xy 233.957779 -88.392436) (xy 233.909853 -88.361636)
			(xy 233.866798 -88.324328) (xy 233.82949 -88.281273) (xy 233.79869 -88.233347) (xy 233.775024 -88.181525)
			(xy 233.758974 -88.126863) (xy 233.750866 -88.070473) (xy 233.750358 -88.041988) (xy 233.750881 -88.012967)
			(xy 233.759294 -87.955537) (xy 233.77594 -87.899932) (xy 233.800469 -87.847327) (xy 233.832362 -87.798831)
			(xy 233.870946 -87.755469) (xy 233.892852 -87.736426) (xy 233.840274 -87.736426) (xy 233.818735 -87.757438)
			(xy 233.771103 -87.794206) (xy 233.719061 -87.824411) (xy 233.663507 -87.847533) (xy 233.605402 -87.863171)
			(xy 233.545748 -87.871055) (xy 233.515662 -87.871554) (xy 232.652062 -87.871554) (xy 232.621976 -87.871074)
			(xy 232.562324 -87.86318) (xy 232.504222 -87.847534) (xy 232.448672 -87.824405) (xy 232.396635 -87.794193)
			(xy 232.349008 -87.757419) (xy 232.32745 -87.736426) (xy 231.256332 -87.736426) (xy 231.246268 -87.736862)
			(xy 231.227684 -87.744597) (xy 231.220264 -87.751412) (xy 229.974902 -88.996774) (xy 229.968067 -89.004177)
			(xy 229.960359 -89.022775) (xy 229.959916 -89.032842) (xy 229.959916 -89.707974) (xy 229.960393 -89.717699)
			(xy 229.967695 -89.73573) (xy 229.97414 -89.743026) (xy 229.995222 -89.76487) (xy 230.027734 -89.78011)
			(xy 230.057358 -89.782861) (xy 230.115588 -89.795062) (xy 230.171747 -89.814705) (xy 230.190899 -89.824347)
			(xy 230.769206 -89.824347) (xy 230.769206 -89.769853) (xy 230.776961 -89.715912) (xy 230.792313 -89.663625)
			(xy 230.814949 -89.614054) (xy 230.84441 -89.568209) (xy 230.880094 -89.527023) (xy 230.921277 -89.491334)
			(xy 230.967119 -89.461869) (xy 231.016687 -89.439227) (xy 231.068973 -89.423869) (xy 231.122913 -89.416109)
			(xy 231.15016 -89.41562) (xy 231.81691 -89.41562) (xy 231.849779 -89.416357) (xy 231.91453 -89.427731)
			(xy 231.945688 -89.438226) (xy 231.95407 -89.44102) (xy 231.966516 -89.44102) (xy 231.988829 -89.441376)
			(xy 232.032641 -89.449829) (xy 232.073949 -89.4667) (xy 232.111151 -89.491336) (xy 232.142807 -89.522783)
			(xy 232.16769 -89.55982) (xy 232.184836 -89.601015) (xy 232.19358 -89.64477) (xy 232.1941 -89.66708)
			(xy 232.1941 -89.741502) (xy 232.194608 -89.745058) (xy 232.196276 -89.758011) (xy 232.198052 -89.784069)
			(xy 232.198164 -89.797128) (xy 232.198063 -89.810188) (xy 232.196285 -89.836246) (xy 232.194608 -89.849198)
			(xy 232.1941 -89.852754) (xy 232.1941 -89.934796) (xy 232.191052 -89.934796) (xy 232.166668 -89.950036)
			(xy 232.160064 -89.963244) (xy 232.141776 -89.996772) (xy 232.138266 -90.002877) (xy 232.134386 -90.016405)
			(xy 232.134156 -90.023442) (xy 232.134156 -90.148918) (xy 232.133676 -90.158876) (xy 232.12605 -90.177273)
			(xy 232.111967 -90.191355) (xy 232.093568 -90.198977) (xy 232.08361 -90.199464) (xy 231.520492 -90.199464)
			(xy 231.510524 -90.199001) (xy 231.492088 -90.191416) (xy 231.484678 -90.184732) (xy 231.478328 -90.178636)
			(xy 231.15016 -90.178636) (xy 231.122913 -90.178091) (xy 231.068973 -90.170331) (xy 231.016687 -90.154973)
			(xy 230.967119 -90.132331) (xy 230.921277 -90.102866) (xy 230.880094 -90.067177) (xy 230.84441 -90.025991)
			(xy 230.814949 -89.980146) (xy 230.792313 -89.930575) (xy 230.776961 -89.878288) (xy 230.769206 -89.824347)
			(xy 230.190899 -89.824347) (xy 230.224888 -89.841458) (xy 230.274114 -89.874871) (xy 230.318596 -89.914381)
			(xy 230.357584 -89.95932) (xy 230.390421 -90.008933) (xy 230.416553 -90.062381) (xy 230.43554 -90.118765)
			(xy 230.447062 -90.177134) (xy 230.450924 -90.236504) (xy 230.447061 -90.295873) (xy 230.435538 -90.354242)
			(xy 230.416551 -90.410625) (xy 230.390418 -90.464074) (xy 230.35758 -90.513685) (xy 230.318591 -90.558624)
			(xy 230.274108 -90.598133) (xy 230.224881 -90.631545) (xy 230.17174 -90.658298) (xy 230.115581 -90.67794)
			(xy 230.057351 -90.69014) (xy 230.027734 -90.692986) (xy 229.995222 -90.708226) (xy 229.97414 -90.73007)
			(xy 229.967699 -90.73737) (xy 229.960396 -90.755397) (xy 229.959916 -90.765122) (xy 229.959916 -91.516708)
			(xy 229.980236 -91.543632) (xy 229.996746 -91.548204) (xy 230.024994 -91.556843) (xy 230.079168 -91.580396)
			(xy 230.129863 -91.610722) (xy 230.176236 -91.647315) (xy 230.217518 -91.689568) (xy 230.253024 -91.73678)
			(xy 230.282162 -91.788165) (xy 230.30445 -91.842872) (xy 230.319517 -91.899991) (xy 230.327114 -91.958573)
			(xy 230.327112 -92.017645) (xy 230.319514 -92.076227) (xy 230.304445 -92.133345) (xy 230.282155 -92.188051)
			(xy 230.253014 -92.239435) (xy 230.217507 -92.286646) (xy 230.176223 -92.328897) (xy 230.129848 -92.365488)
			(xy 230.079152 -92.395812) (xy 230.024978 -92.419363) (xy 229.996746 -92.42806) (xy 229.980236 -92.432632)
			(xy 229.959916 -92.459556) (xy 229.959916 -92.717112) (xy 229.96054 -92.728244) (xy 229.970025 -92.748396)
			(xy 229.978204 -92.755974) (xy 230.047292 -92.813124) (xy 230.069136 -92.818712) (xy 230.080312 -92.81668)
			(xy 230.101262 -92.81299) (xy 230.143622 -92.809051) (xy 230.164894 -92.808806) (xy 230.194862 -92.809275)
			(xy 230.254286 -92.817097) (xy 230.312181 -92.832609) (xy 230.367556 -92.855546) (xy 230.419462 -92.885514)
			(xy 230.467014 -92.922) (xy 230.509396 -92.964382) (xy 230.545883 -93.011933) (xy 230.575852 -93.063839)
			(xy 230.598789 -93.119213) (xy 230.614302 -93.177108) (xy 230.622125 -93.236532) (xy 230.622125 -93.296468)
			(xy 230.614302 -93.355892) (xy 230.598789 -93.413787) (xy 230.575852 -93.469161) (xy 230.545883 -93.521067)
			(xy 230.509396 -93.568618) (xy 230.467014 -93.611) (xy 230.419462 -93.647486) (xy 230.367556 -93.677454)
			(xy 230.331912 -93.692218) (xy 231.990392 -93.692218) (xy 231.990392 -90.74023) (xy 231.990794 -90.716231)
			(xy 231.998272 -90.668821) (xy 232.013094 -90.623171) (xy 232.034893 -90.580411) (xy 232.06313 -90.541599)
			(xy 232.0798 -90.52433) (xy 232.080054 -90.52433) (xy 232.341166 -90.263218) (xy 232.341166 -90.262964)
			(xy 232.358481 -90.246352) (xy 232.397306 -90.218161) (xy 232.440058 -90.196384) (xy 232.485689 -90.181553)
			(xy 232.533076 -90.174035) (xy 232.557066 -90.173556) (xy 232.740454 -90.173556) (xy 232.764452 -90.173979)
			(xy 232.811861 -90.181453) (xy 232.85751 -90.196271) (xy 232.900271 -90.218065) (xy 232.939083 -90.246297)
			(xy 232.956354 -90.262964) (xy 232.956354 -90.263218) (xy 233.056938 -90.363802) (xy 233.064331 -90.370651)
			(xy 233.082936 -90.378366) (xy 233.093006 -90.378788) (xy 233.601768 -90.378788) (xy 233.611836 -90.378349)
			(xy 233.630434 -90.370638) (xy 233.637836 -90.363802) (xy 233.66222 -90.339418) (xy 233.679489 -90.322884)
			(xy 233.718191 -90.294818) (xy 233.76079 -90.27312) (xy 233.806248 -90.258319) (xy 233.853456 -90.250776)
			(xy 233.877358 -90.250264) (xy 234.135422 -90.250264) (xy 234.160717 -90.250801) (xy 234.210607 -90.259201)
			(xy 234.258433 -90.275702) (xy 234.302888 -90.299853) (xy 234.323128 -90.315034) (xy 234.329946 -90.320044)
			(xy 234.345915 -90.32561) (xy 234.35437 -90.325956) (xy 235.608368 -90.325956) (xy 235.632366 -90.32637)
			(xy 235.679775 -90.333846) (xy 235.725425 -90.348666) (xy 235.768185 -90.370462) (xy 235.806998 -90.398696)
			(xy 235.824268 -90.415364) (xy 235.824268 -90.415618) (xy 236.05871 -90.65006) (xy 236.058964 -90.65006)
			(xy 236.075578 -90.667373) (xy 236.103767 -90.706199) (xy 236.125544 -90.748952) (xy 236.140374 -90.794583)
			(xy 236.147892 -90.84197) (xy 236.148372 -90.86596) (xy 236.148372 -93.817694) (xy 236.14794 -93.840424)
			(xy 236.141187 -93.885381) (xy 236.127843 -93.928839) (xy 236.1184 -93.94952) (xy 236.114082 -93.958664)
			(xy 236.112812 -93.977968) (xy 236.141514 -94.064074) (xy 236.154214 -94.078806) (xy 236.163104 -94.083632)
			(xy 236.188652 -94.097518) (xy 236.235593 -94.131828) (xy 236.256576 -94.151958) (xy 236.47527 -94.370652)
			(xy 236.49603 -94.392271) (xy 236.531217 -94.440791) (xy 236.558384 -94.494215) (xy 236.576865 -94.551229)
			(xy 236.586205 -94.610432) (xy 236.586776 -94.6404) (xy 236.586323 -94.667641) (xy 236.578572 -94.721569)
			(xy 236.563228 -94.773846) (xy 236.540603 -94.823409) (xy 236.511158 -94.869249) (xy 236.47549 -94.910433)
			(xy 236.434327 -94.946124) (xy 236.388504 -94.975597) (xy 236.338955 -94.998251) (xy 236.286687 -95.013625)
			(xy 236.232763 -95.021407) (xy 236.205522 -95.021908) (xy 236.175545 -95.021314) (xy 236.116329 -95.011925)
			(xy 236.059311 -94.993392) (xy 236.005892 -94.96617) (xy 235.957388 -94.930929) (xy 235.935774 -94.910148)
			(xy 235.843826 -94.817946) (xy 235.836406 -94.811131) (xy 235.817822 -94.803395) (xy 235.807758 -94.80296)
			(xy 235.29417 -94.80296) (xy 235.28111 -94.80286) (xy 235.255052 -94.801081) (xy 235.2421 -94.799404)
			(xy 235.238544 -94.798896) (xy 235.156756 -94.798896) (xy 235.156756 -94.795848) (xy 235.141262 -94.771464)
			(xy 235.128054 -94.76486) (xy 235.094526 -94.746572) (xy 235.088422 -94.743061) (xy 235.074893 -94.739181)
			(xy 235.067856 -94.738952) (xy 234.94238 -94.738952) (xy 234.932351 -94.738595) (xy 234.913825 -94.73091)
			(xy 234.899652 -94.716718) (xy 234.891991 -94.698181) (xy 234.89158 -94.688152) (xy 234.89158 -94.276164)
			(xy 234.891141 -94.266152) (xy 234.883466 -94.247655) (xy 234.869298 -94.233503) (xy 234.850793 -94.225848)
			(xy 234.84078 -94.225364) (xy 232.523538 -94.225364) (xy 232.49954 -94.22494) (xy 232.452132 -94.217466)
			(xy 232.406482 -94.202648) (xy 232.363722 -94.180854) (xy 232.324909 -94.152623) (xy 232.307638 -94.135956)
			(xy 232.307638 -94.135702) (xy 232.080054 -93.908118) (xy 232.0798 -93.908118) (xy 232.063169 -93.890821)
			(xy 232.034984 -93.85199) (xy 232.01321 -93.809233) (xy 231.998385 -93.763599) (xy 231.99087 -93.716209)
			(xy 231.990392 -93.692218) (xy 230.331912 -93.692218) (xy 230.312181 -93.700391) (xy 230.254286 -93.715903)
			(xy 230.194862 -93.723725) (xy 230.164894 -93.724222) (xy 230.143622 -93.723981) (xy 230.101262 -93.720041)
			(xy 230.080312 -93.716348) (xy 230.069136 -93.714316) (xy 230.047292 -93.719904) (xy 229.978204 -93.777054)
			(xy 229.969981 -93.784604) (xy 229.960467 -93.804769) (xy 229.959916 -93.815916) (xy 229.959916 -94.082362)
			(xy 229.960514 -94.094117) (xy 229.970977 -94.115169) (xy 229.979982 -94.122748) (xy 230.053896 -94.178882)
			(xy 230.077264 -94.183454) (xy 230.088694 -94.180152) (xy 230.11876 -94.17233) (xy 230.180314 -94.163925)
			(xy 230.211376 -94.163388) (xy 230.241346 -94.163856) (xy 230.300774 -94.171677) (xy 230.358673 -94.187188)
			(xy 230.414052 -94.210124) (xy 230.465963 -94.240092) (xy 230.513518 -94.27658) (xy 230.555904 -94.318964)
			(xy 230.592394 -94.366517) (xy 230.622366 -94.418426) (xy 230.645305 -94.473804) (xy 230.660819 -94.531702)
			(xy 230.668643 -94.59113) (xy 230.668643 -94.65107) (xy 230.660819 -94.710498) (xy 230.645305 -94.768396)
			(xy 230.622366 -94.823774) (xy 230.592394 -94.875683) (xy 230.555904 -94.923236) (xy 230.513518 -94.96562)
			(xy 230.465963 -95.002108) (xy 230.414052 -95.032076) (xy 230.358673 -95.055012) (xy 230.300774 -95.070523)
			(xy 230.241346 -95.078344) (xy 230.211376 -95.078804) (xy 230.180312 -95.078287) (xy 230.118757 -95.069879)
			(xy 230.088694 -95.06204) (xy 230.077264 -95.058738) (xy 230.053896 -95.06331) (xy 229.979982 -95.119444)
			(xy 229.970994 -95.127036) (xy 229.960531 -95.148081) (xy 229.959916 -95.15983) (xy 229.959916 -95.555304)
			(xy 230.846866 -95.555304) (xy 230.846866 -95.495368) (xy 230.854689 -95.435946) (xy 230.870202 -95.378053)
			(xy 230.893138 -95.32268) (xy 230.923105 -95.270774) (xy 230.959592 -95.223224) (xy 231.001972 -95.180844)
			(xy 231.049522 -95.144357) (xy 231.101428 -95.11439) (xy 231.156801 -95.091454) (xy 231.214694 -95.075941)
			(xy 231.274116 -95.068118) (xy 231.334052 -95.068118) (xy 231.393474 -95.075941) (xy 231.451367 -95.091454)
			(xy 231.50674 -95.11439) (xy 231.558646 -95.144357) (xy 231.606196 -95.180844) (xy 231.648576 -95.223224)
			(xy 231.685063 -95.270774) (xy 231.71503 -95.32268) (xy 231.737966 -95.378053) (xy 231.753479 -95.435946)
			(xy 231.761302 -95.495368) (xy 231.761792 -95.525336) (xy 231.761302 -95.555304) (xy 231.753479 -95.614726)
			(xy 231.737966 -95.672619) (xy 231.71503 -95.727992) (xy 231.685063 -95.779898) (xy 231.648576 -95.827448)
			(xy 231.606196 -95.869828) (xy 231.558646 -95.906315) (xy 231.50674 -95.936282) (xy 231.451367 -95.959218)
			(xy 231.393474 -95.974731) (xy 231.368947 -95.97796) (xy 232.290602 -95.97796) (xy 232.290602 -95.918024)
			(xy 232.298425 -95.858602) (xy 232.313938 -95.800709) (xy 232.336874 -95.745336) (xy 232.366841 -95.69343)
			(xy 232.403328 -95.64588) (xy 232.445708 -95.6035) (xy 232.493258 -95.567013) (xy 232.545164 -95.537046)
			(xy 232.600537 -95.51411) (xy 232.65843 -95.498597) (xy 232.717852 -95.490774) (xy 232.777788 -95.490774)
			(xy 232.83721 -95.498597) (xy 232.895103 -95.51411) (xy 232.950476 -95.537046) (xy 233.002382 -95.567013)
			(xy 233.049932 -95.6035) (xy 233.092312 -95.64588) (xy 233.128799 -95.69343) (xy 233.158766 -95.745336)
			(xy 233.164641 -95.75952) (xy 233.563904 -95.75952) (xy 233.563904 -95.699584) (xy 233.571727 -95.640162)
			(xy 233.58724 -95.582269) (xy 233.610176 -95.526896) (xy 233.640143 -95.47499) (xy 233.67663 -95.42744)
			(xy 233.71901 -95.38506) (xy 233.76656 -95.348573) (xy 233.818466 -95.318606) (xy 233.873839 -95.29567)
			(xy 233.931732 -95.280157) (xy 233.991154 -95.272334) (xy 234.05109 -95.272334) (xy 234.110512 -95.280157)
			(xy 234.168405 -95.29567) (xy 234.223778 -95.318606) (xy 234.275684 -95.348573) (xy 234.323234 -95.38506)
			(xy 234.365614 -95.42744) (xy 234.402101 -95.47499) (xy 234.432068 -95.526896) (xy 234.455004 -95.582269)
			(xy 234.470517 -95.640162) (xy 234.47834 -95.699584) (xy 234.47883 -95.729552) (xy 234.478618 -95.742502)
			(xy 235.74932 -95.742502) (xy 235.74932 -95.682566) (xy 235.757143 -95.623144) (xy 235.772656 -95.565251)
			(xy 235.795592 -95.509878) (xy 235.825559 -95.457972) (xy 235.862046 -95.410422) (xy 235.904426 -95.368042)
			(xy 235.951976 -95.331555) (xy 236.003882 -95.301588) (xy 236.059255 -95.278652) (xy 236.117148 -95.263139)
			(xy 236.17657 -95.255316) (xy 236.236506 -95.255316) (xy 236.295928 -95.263139) (xy 236.353821 -95.278652)
			(xy 236.409194 -95.301588) (xy 236.4611 -95.331555) (xy 236.50865 -95.368042) (xy 236.55103 -95.410422)
			(xy 236.587517 -95.457972) (xy 236.617484 -95.509878) (xy 236.64042 -95.565251) (xy 236.655933 -95.623144)
			(xy 236.663756 -95.682566) (xy 236.664246 -95.712534) (xy 236.663756 -95.742502) (xy 236.655933 -95.801924)
			(xy 236.64042 -95.859817) (xy 236.617484 -95.91519) (xy 236.587517 -95.967096) (xy 236.55103 -96.014646)
			(xy 236.50865 -96.057026) (xy 236.4611 -96.093513) (xy 236.409194 -96.12348) (xy 236.353821 -96.146416)
			(xy 236.295928 -96.161929) (xy 236.236506 -96.169752) (xy 236.17657 -96.169752) (xy 236.117148 -96.161929)
			(xy 236.059255 -96.146416) (xy 236.003882 -96.12348) (xy 235.951976 -96.093513) (xy 235.904426 -96.057026)
			(xy 235.862046 -96.014646) (xy 235.825559 -95.967096) (xy 235.795592 -95.91519) (xy 235.772656 -95.859817)
			(xy 235.757143 -95.801924) (xy 235.74932 -95.742502) (xy 234.478618 -95.742502) (xy 234.47834 -95.75952)
			(xy 234.470517 -95.818942) (xy 234.455004 -95.876835) (xy 234.432068 -95.932208) (xy 234.402101 -95.984114)
			(xy 234.365614 -96.031664) (xy 234.323234 -96.074044) (xy 234.275684 -96.110531) (xy 234.223778 -96.140498)
			(xy 234.168405 -96.163434) (xy 234.110512 -96.178947) (xy 234.05109 -96.18677) (xy 233.991154 -96.18677)
			(xy 233.931732 -96.178947) (xy 233.873839 -96.163434) (xy 233.818466 -96.140498) (xy 233.76656 -96.110531)
			(xy 233.71901 -96.074044) (xy 233.67663 -96.031664) (xy 233.640143 -95.984114) (xy 233.610176 -95.932208)
			(xy 233.58724 -95.876835) (xy 233.571727 -95.818942) (xy 233.563904 -95.75952) (xy 233.164641 -95.75952)
			(xy 233.181702 -95.800709) (xy 233.197215 -95.858602) (xy 233.205038 -95.918024) (xy 233.205528 -95.947992)
			(xy 233.205038 -95.97796) (xy 233.197215 -96.037382) (xy 233.181702 -96.095275) (xy 233.158766 -96.150648)
			(xy 233.128799 -96.202554) (xy 233.092312 -96.250104) (xy 233.049932 -96.292484) (xy 233.002382 -96.328971)
			(xy 232.950476 -96.358938) (xy 232.895103 -96.381874) (xy 232.83721 -96.397387) (xy 232.777788 -96.40521)
			(xy 232.717852 -96.40521) (xy 232.65843 -96.397387) (xy 232.600537 -96.381874) (xy 232.545164 -96.358938)
			(xy 232.493258 -96.328971) (xy 232.445708 -96.292484) (xy 232.403328 -96.250104) (xy 232.366841 -96.202554)
			(xy 232.336874 -96.150648) (xy 232.313938 -96.095275) (xy 232.298425 -96.037382) (xy 232.290602 -95.97796)
			(xy 231.368947 -95.97796) (xy 231.334052 -95.982554) (xy 231.274116 -95.982554) (xy 231.214694 -95.974731)
			(xy 231.156801 -95.959218) (xy 231.101428 -95.936282) (xy 231.049522 -95.906315) (xy 231.001972 -95.869828)
			(xy 230.959592 -95.827448) (xy 230.923105 -95.779898) (xy 230.893138 -95.727992) (xy 230.870202 -95.672619)
			(xy 230.854689 -95.614726) (xy 230.846866 -95.555304) (xy 229.959916 -95.555304) (xy 229.959916 -96.242378)
			(xy 229.960354 -96.252442) (xy 229.96809 -96.271024) (xy 229.974902 -96.278446) (xy 230.481124 -96.784668)
			(xy 230.488522 -96.791514) (xy 230.507121 -96.799245) (xy 230.517192 -96.799654)
		)
		(stroke
			(width 0)
			(type solid)
		)
		(fill yes)
		(layer "B.Cu")
		(net "P3V3_PEX_USB_HUB")
	)
	(gr_poly
		(pts
			(xy 339.864954 -117.509544) (xy 339.877109 -117.50884) (xy 339.89871 -117.497686) (xy 339.906356 -117.488208)
			(xy 339.961474 -117.41023) (xy 339.96503 -117.3861) (xy 339.960966 -117.374416) (xy 339.95092 -117.343826)
			(xy 339.940061 -117.280368) (xy 339.939376 -117.248178) (xy 339.939862 -117.220927) (xy 339.947618 -117.166979)
			(xy 339.962973 -117.114684) (xy 339.985615 -117.065107) (xy 340.015081 -117.019257) (xy 340.050772 -116.978066)
			(xy 340.091963 -116.942375) (xy 340.137813 -116.912909) (xy 340.18739 -116.890267) (xy 340.239685 -116.874912)
			(xy 340.293633 -116.867156) (xy 340.348135 -116.867156) (xy 340.402083 -116.874912) (xy 340.454378 -116.890267)
			(xy 340.503955 -116.912909) (xy 340.549805 -116.942375) (xy 340.590996 -116.978066) (xy 340.626687 -117.019257)
			(xy 340.656153 -117.065107) (xy 340.678795 -117.114684) (xy 340.69415 -117.166979) (xy 340.701906 -117.220927)
			(xy 340.702392 -117.248178) (xy 340.701707 -117.280369) (xy 340.690862 -117.34383) (xy 340.680802 -117.374416)
			(xy 340.676738 -117.3861) (xy 340.680294 -117.41023) (xy 340.735412 -117.488208) (xy 340.743027 -117.497721)
			(xy 340.764648 -117.508878) (xy 340.776814 -117.509544) (xy 340.880954 -117.509544) (xy 340.893109 -117.50884)
			(xy 340.91471 -117.497686) (xy 340.922356 -117.488208) (xy 340.977474 -117.41023) (xy 340.98103 -117.3861)
			(xy 340.976966 -117.374416) (xy 340.96692 -117.343826) (xy 340.956061 -117.280368) (xy 340.955376 -117.248178)
			(xy 340.955862 -117.220927) (xy 340.963618 -117.166979) (xy 340.978973 -117.114684) (xy 341.001615 -117.065107)
			(xy 341.031081 -117.019257) (xy 341.066772 -116.978066) (xy 341.107963 -116.942375) (xy 341.153813 -116.912909)
			(xy 341.20339 -116.890267) (xy 341.255685 -116.874912) (xy 341.309633 -116.867156) (xy 341.364135 -116.867156)
			(xy 341.418083 -116.874912) (xy 341.470378 -116.890267) (xy 341.519955 -116.912909) (xy 341.565805 -116.942375)
			(xy 341.606996 -116.978066) (xy 341.642687 -117.019257) (xy 341.672153 -117.065107) (xy 341.694795 -117.114684)
			(xy 341.71015 -117.166979) (xy 341.717906 -117.220927) (xy 341.718392 -117.248178) (xy 341.717707 -117.280369)
			(xy 341.706862 -117.34383) (xy 341.696802 -117.374416) (xy 341.692738 -117.3861) (xy 341.696294 -117.41023)
			(xy 341.751412 -117.488208) (xy 341.759027 -117.497721) (xy 341.780648 -117.508878) (xy 341.792814 -117.509544)
			(xy 341.896954 -117.509544) (xy 341.909109 -117.50884) (xy 341.93071 -117.497686) (xy 341.938356 -117.488208)
			(xy 341.993474 -117.41023) (xy 341.99703 -117.3861) (xy 341.992966 -117.374416) (xy 341.98292 -117.343826)
			(xy 341.972061 -117.280368) (xy 341.971376 -117.248178) (xy 341.971863 -117.220927) (xy 341.979622 -117.166981)
			(xy 341.994979 -117.114688) (xy 342.017621 -117.065113) (xy 342.047088 -117.019264) (xy 342.082779 -116.978075)
			(xy 342.123969 -116.942384) (xy 342.169818 -116.912918) (xy 342.219394 -116.890277) (xy 342.271687 -116.874921)
			(xy 342.325633 -116.867163) (xy 342.352884 -116.86667) (xy 342.378826 -116.867105) (xy 342.430231 -116.874134)
			(xy 342.480209 -116.888064) (xy 342.527839 -116.908638) (xy 342.572241 -116.935478) (xy 342.612596 -116.968086)
			(xy 342.64816 -117.005863) (xy 342.678277 -117.048111) (xy 342.690704 -117.070886) (xy 342.696292 -117.081554)
			(xy 342.71585 -117.095524) (xy 342.808814 -117.109748) (xy 342.820783 -117.110891) (xy 342.843571 -117.103323)
			(xy 342.852502 -117.09527) (xy 343.387426 -116.560346) (xy 343.394272 -116.552948) (xy 343.401999 -116.534349)
			(xy 343.402412 -116.524278) (xy 343.402412 -115.43665) (xy 343.381076 -115.409218) (xy 343.363804 -115.4049)
			(xy 343.334416 -115.39711) (xy 343.277855 -115.37481) (xy 343.224745 -115.345217) (xy 343.176021 -115.308851)
			(xy 343.132542 -115.266355) (xy 343.095073 -115.218474) (xy 343.064274 -115.166054) (xy 343.040688 -115.110018)
			(xy 343.02473 -115.051351) (xy 343.016681 -114.991088) (xy 343.016682 -114.93029) (xy 343.024734 -114.870027)
			(xy 343.040695 -114.811361) (xy 343.064284 -114.755326) (xy 343.095086 -114.702907) (xy 343.132557 -114.655029)
			(xy 343.176038 -114.612534) (xy 343.224763 -114.576171) (xy 343.277875 -114.546581) (xy 343.334437 -114.524283)
			(xy 343.363804 -114.516408) (xy 343.381076 -114.51209) (xy 343.402412 -114.484658) (xy 343.402412 -114.045238)
			(xy 343.380568 -114.017552) (xy 343.36355 -114.013488) (xy 343.334034 -114.005786) (xy 343.277204 -113.983617)
			(xy 343.223823 -113.954097) (xy 343.174834 -113.917749) (xy 343.131108 -113.875217) (xy 343.093417 -113.827254)
			(xy 343.06243 -113.77471) (xy 343.038696 -113.718516) (xy 343.022636 -113.659668) (xy 343.014533 -113.599208)
			(xy 343.014532 -113.538208) (xy 343.022632 -113.477748) (xy 343.038691 -113.418899) (xy 343.062423 -113.362704)
			(xy 343.093408 -113.310159) (xy 343.131097 -113.262195) (xy 343.174822 -113.219661) (xy 343.223809 -113.183311)
			(xy 343.27719 -113.153789) (xy 343.334019 -113.131619) (xy 343.36355 -113.12398) (xy 343.380568 -113.119916)
			(xy 343.402412 -113.09223) (xy 343.402412 -112.77219) (xy 343.38133 -112.745012) (xy 343.364058 -112.740694)
			(xy 343.334853 -112.73275) (xy 343.278683 -112.710211) (xy 343.225971 -112.680467) (xy 343.177638 -112.644038)
			(xy 343.134526 -112.601558) (xy 343.097386 -112.553769) (xy 343.066867 -112.501503) (xy 343.0435 -112.445671)
			(xy 343.027692 -112.387248) (xy 343.019719 -112.327251) (xy 343.019721 -112.266727) (xy 343.027696 -112.206731)
			(xy 343.043507 -112.148308) (xy 343.066877 -112.092478) (xy 343.097399 -112.040213) (xy 343.134541 -111.992426)
			(xy 343.177655 -111.949948) (xy 343.225989 -111.913521) (xy 343.278702 -111.88378) (xy 343.334874 -111.861243)
			(xy 343.364058 -111.853218) (xy 343.38133 -111.8489) (xy 343.402412 -111.821722) (xy 343.402412 -111.001556)
			(xy 343.376758 -110.9726) (xy 343.357454 -110.970314) (xy 343.327417 -110.966348) (xy 343.268674 -110.951511)
			(xy 343.212403 -110.929051) (xy 343.159588 -110.899364) (xy 343.111152 -110.862966) (xy 343.067942 -110.820495)
			(xy 343.030714 -110.772694) (xy 343.000119 -110.720399) (xy 342.976693 -110.664524) (xy 342.960844 -110.606046)
			(xy 342.95285 -110.545988) (xy 342.95285 -110.485401) (xy 342.960846 -110.425343) (xy 342.976696 -110.366866)
			(xy 343.000124 -110.310991) (xy 343.03072 -110.258697) (xy 343.067949 -110.210897) (xy 343.11116 -110.168427)
			(xy 343.159597 -110.132031) (xy 343.212413 -110.102344) (xy 343.268684 -110.079886) (xy 343.327427 -110.06505)
			(xy 343.357454 -110.060994) (xy 343.376758 -110.058708) (xy 343.402412 -110.029752) (xy 343.402412 -97.00133)
			(xy 343.401977 -96.991265) (xy 343.394246 -96.972678) (xy 343.387426 -96.965262) (xy 342.236044 -95.81388)
			(xy 342.228636 -95.807191) (xy 342.2102 -95.799596) (xy 342.20023 -95.799148) (xy 338.159598 -95.799148)
			(xy 338.134416 -95.798632) (xy 338.084677 -95.790716) (xy 338.036787 -95.775125) (xy 337.99192 -95.752243)
			(xy 337.95118 -95.722632) (xy 337.93303 -95.705168) (xy 337.778344 -95.550482) (xy 337.771 -95.543672)
			(xy 337.752536 -95.535947) (xy 337.74253 -95.535496) (xy 332.102968 -95.535496) (xy 332.093771 -95.535902)
			(xy 332.076559 -95.542394) (xy 332.062714 -95.554506) (xy 332.05801 -95.56242) (xy 332.009242 -95.654114)
			(xy 332.010512 -95.6818) (xy 332.018386 -95.693738) (xy 332.032132 -95.71505) (xy 332.054485 -95.760571)
			(xy 332.070619 -95.80865) (xy 332.080248 -95.858441) (xy 332.08214 -95.88373) (xy 332.082648 -95.895414)
			(xy 332.093824 -95.91548) (xy 332.17739 -95.97517) (xy 332.199996 -95.97898) (xy 332.211172 -95.975678)
			(xy 332.241778 -95.967588) (xy 332.304487 -95.95892) (xy 332.33614 -95.958406) (xy 332.366106 -95.958899)
			(xy 332.425525 -95.966726) (xy 332.483413 -95.982242) (xy 332.538781 -96.005182) (xy 332.590682 -96.035152)
			(xy 332.638226 -96.071639) (xy 332.680602 -96.11402) (xy 332.717083 -96.16157) (xy 332.747046 -96.213474)
			(xy 332.769977 -96.268846) (xy 332.785486 -96.326736) (xy 332.793305 -96.386156) (xy 332.793303 -96.446088)
			(xy 332.785477 -96.505507) (xy 332.769963 -96.563396) (xy 332.747026 -96.618765) (xy 332.717058 -96.670667)
			(xy 332.680573 -96.718213) (xy 332.638193 -96.76059) (xy 332.590645 -96.797073) (xy 332.538742 -96.827038)
			(xy 332.483371 -96.849972) (xy 332.425481 -96.865482) (xy 332.366062 -96.873304) (xy 332.30613 -96.873304)
			(xy 332.246711 -96.865481) (xy 332.188821 -96.849969) (xy 332.133451 -96.827034) (xy 332.081548 -96.797068)
			(xy 332.034001 -96.760585) (xy 331.991622 -96.718207) (xy 331.955137 -96.67066) (xy 331.92517 -96.618758)
			(xy 331.902234 -96.563388) (xy 331.886721 -96.505499) (xy 331.878897 -96.44608) (xy 331.878432 -96.416114)
			(xy 331.879194 -96.388682) (xy 331.879956 -96.376998) (xy 331.87132 -96.355662) (xy 331.79512 -96.286828)
			(xy 331.773276 -96.280478) (xy 331.761592 -96.282256) (xy 331.746581 -96.284513) (xy 331.716319 -96.286931)
			(xy 331.70114 -96.287082) (xy 331.673886 -96.286621) (xy 331.619932 -96.278869) (xy 331.567631 -96.263516)
			(xy 331.518047 -96.240875) (xy 331.472191 -96.211408) (xy 331.430996 -96.175714) (xy 331.3953 -96.13452)
			(xy 331.365831 -96.088665) (xy 331.343189 -96.039082) (xy 331.327834 -95.986782) (xy 331.32008 -95.932828)
			(xy 331.319632 -95.905574) (xy 331.320134 -95.877485) (xy 331.328381 -95.821917) (xy 331.344693 -95.76816)
			(xy 331.368717 -95.717379) (xy 331.383894 -95.693738) (xy 331.391768 -95.6818) (xy 331.393038 -95.654114)
			(xy 331.34427 -95.56242) (xy 331.339614 -95.554461) (xy 331.325782 -95.542293) (xy 331.308526 -95.535839)
			(xy 331.299312 -95.535496) (xy 330.284328 -95.535496) (xy 330.274303 -95.535911) (xy 330.255775 -95.543575)
			(xy 330.241593 -95.557749) (xy 330.233917 -95.576271) (xy 330.233528 -95.586296) (xy 330.233528 -96.212152)
			(xy 330.234036 -96.215454) (xy 330.235719 -96.229809) (xy 330.237498 -96.258659) (xy 330.237592 -96.273112)
			(xy 330.237503 -96.287565) (xy 330.235722 -96.316415) (xy 330.234036 -96.33077) (xy 330.233528 -96.334072)
			(xy 330.233528 -99.095052) (xy 330.233961 -99.105117) (xy 330.241692 -99.123706) (xy 330.248514 -99.13112)
			(xy 331.084682 -99.967288) (xy 331.092084 -99.974123) (xy 331.110683 -99.981829) (xy 331.12075 -99.982274)
			(xy 331.415136 -99.982274) (xy 331.42512 -99.981729) (xy 331.44354 -99.974004) (xy 331.45095 -99.967288)
			(xy 331.581252 -99.836986) (xy 331.588649 -99.830139) (xy 331.607248 -99.82241) (xy 331.61732 -99.822)
			(xy 338.857082 -99.822) (xy 338.867146 -99.822438) (xy 338.885728 -99.830174) (xy 338.89315 -99.836986)
			(xy 339.370924 -100.31476) (xy 339.377705 -100.322184) (xy 339.38531 -100.34078) (xy 339.385656 -100.350828)
			(xy 339.385656 -103.194612) (xy 339.385206 -103.204639) (xy 339.377612 -103.223194) (xy 339.370924 -103.23068)
			(xy 338.516722 -104.084628) (xy 338.509878 -104.092027) (xy 338.50215 -104.110625) (xy 338.501736 -104.120696)
			(xy 338.501736 -108.53674) (xy 338.502282 -108.546723) (xy 338.510009 -108.565141) (xy 338.516722 -108.572554)
			(xy 339.125814 -109.181646) (xy 339.142832 -109.19841) (xy 339.149684 -109.205806) (xy 339.157426 -109.224405)
			(xy 339.157818 -109.234478) (xy 339.157818 -109.502448) (xy 341.538814 -109.502448) (xy 341.539304 -109.47248)
			(xy 341.547127 -109.413058) (xy 341.56264 -109.355165) (xy 341.585576 -109.299792) (xy 341.615543 -109.247886)
			(xy 341.65203 -109.200336) (xy 341.69441 -109.157956) (xy 341.74196 -109.121469) (xy 341.793866 -109.091502)
			(xy 341.849239 -109.068566) (xy 341.907132 -109.053053) (xy 341.966554 -109.04523) (xy 342.02649 -109.04523)
			(xy 342.085912 -109.053053) (xy 342.143805 -109.068566) (xy 342.199178 -109.091502) (xy 342.251084 -109.121469)
			(xy 342.298634 -109.157956) (xy 342.341014 -109.200336) (xy 342.377501 -109.247886) (xy 342.407468 -109.299792)
			(xy 342.430404 -109.355165) (xy 342.445917 -109.413058) (xy 342.45374 -109.47248) (xy 342.45423 -109.502448)
			(xy 342.453818 -109.530203) (xy 342.447074 -109.585303) (xy 342.433729 -109.639185) (xy 342.413976 -109.691063)
			(xy 342.401398 -109.715808) (xy 342.396064 -109.726222) (xy 342.395048 -109.749082) (xy 342.436196 -109.843316)
			(xy 342.453722 -109.858302) (xy 342.464898 -109.86135) (xy 342.491558 -109.869006) (xy 342.542474 -109.891008)
			(xy 342.589666 -109.920153) (xy 342.63214 -109.955826) (xy 342.668999 -109.997275) (xy 342.699466 -110.043625)
			(xy 342.722899 -110.093898) (xy 342.738804 -110.147036) (xy 342.746844 -110.201917) (xy 342.747346 -110.22965)
			(xy 342.746775 -110.25781) (xy 342.738501 -110.313519) (xy 342.722127 -110.367406) (xy 342.698008 -110.4183)
			(xy 342.666667 -110.465095) (xy 342.628787 -110.506773) (xy 342.585191 -110.542429) (xy 342.536827 -110.571287)
			(xy 342.484744 -110.592721) (xy 342.457532 -110.599982) (xy 342.448134 -110.602268) (xy 342.432386 -110.613698)
			(xy 342.383872 -110.688374) (xy 342.380316 -110.707424) (xy 342.38184 -110.716822) (xy 342.384791 -110.733878)
			(xy 342.387971 -110.768348) (xy 342.38819 -110.785656) (xy 342.387704 -110.812907) (xy 342.379948 -110.866855)
			(xy 342.364593 -110.91915) (xy 342.341951 -110.968727) (xy 342.312485 -111.014577) (xy 342.276794 -111.055768)
			(xy 342.235603 -111.091459) (xy 342.189753 -111.120925) (xy 342.140176 -111.143567) (xy 342.087881 -111.158922)
			(xy 342.033933 -111.166678) (xy 341.979431 -111.166678) (xy 341.925483 -111.158922) (xy 341.873188 -111.143567)
			(xy 341.823611 -111.120925) (xy 341.777761 -111.091459) (xy 341.73657 -111.055768) (xy 341.700879 -111.014577)
			(xy 341.671413 -110.968727) (xy 341.648771 -110.91915) (xy 341.633416 -110.866855) (xy 341.62566 -110.812907)
			(xy 341.625174 -110.785656) (xy 341.625735 -110.757495) (xy 341.634009 -110.701785) (xy 341.650383 -110.647897)
			(xy 341.674503 -110.597002) (xy 341.705845 -110.550207) (xy 341.743726 -110.508529) (xy 341.787324 -110.472873)
			(xy 341.835691 -110.444016) (xy 341.887775 -110.422584) (xy 341.914988 -110.415324) (xy 341.924386 -110.413038)
			(xy 341.940134 -110.401608) (xy 341.988648 -110.326932) (xy 341.992204 -110.307882) (xy 341.99068 -110.298484)
			(xy 341.98773 -110.281428) (xy 341.984549 -110.246958) (xy 341.98433 -110.22965) (xy 341.984708 -110.206213)
			(xy 341.990475 -110.159695) (xy 342.001879 -110.11423) (xy 342.009984 -110.092236) (xy 342.014048 -110.081314)
			(xy 342.01227 -110.058708) (xy 341.960454 -109.969808) (xy 341.941404 -109.957108) (xy 341.929974 -109.95533)
			(xy 341.900705 -109.950532) (xy 341.843632 -109.934394) (xy 341.78912 -109.91102) (xy 341.738084 -109.880801)
			(xy 341.691379 -109.844245) (xy 341.649785 -109.801962) (xy 341.614001 -109.754662) (xy 341.584626 -109.703136)
			(xy 341.562151 -109.648248) (xy 341.546953 -109.590917) (xy 341.539287 -109.532104) (xy 341.538814 -109.502448)
			(xy 339.157818 -109.502448) (xy 339.157818 -111.815622) (xy 341.582484 -111.815622) (xy 341.582484 -111.755686)
			(xy 341.590307 -111.696264) (xy 341.60582 -111.638371) (xy 341.628756 -111.582998) (xy 341.658723 -111.531092)
			(xy 341.69521 -111.483542) (xy 341.73759 -111.441162) (xy 341.78514 -111.404675) (xy 341.837046 -111.374708)
			(xy 341.892419 -111.351772) (xy 341.950312 -111.336259) (xy 342.009734 -111.328436) (xy 342.06967 -111.328436)
			(xy 342.129092 -111.336259) (xy 342.186985 -111.351772) (xy 342.242358 -111.374708) (xy 342.294264 -111.404675)
			(xy 342.341814 -111.441162) (xy 342.384194 -111.483542) (xy 342.420681 -111.531092) (xy 342.450648 -111.582998)
			(xy 342.473584 -111.638371) (xy 342.489097 -111.696264) (xy 342.49692 -111.755686) (xy 342.49741 -111.785654)
			(xy 342.49692 -111.815622) (xy 342.489097 -111.875044) (xy 342.473584 -111.932937) (xy 342.450648 -111.98831)
			(xy 342.420681 -112.040216) (xy 342.384194 -112.087766) (xy 342.341814 -112.130146) (xy 342.294264 -112.166633)
			(xy 342.242358 -112.1966) (xy 342.186985 -112.219536) (xy 342.129092 -112.235049) (xy 342.06967 -112.242872)
			(xy 342.009734 -112.242872) (xy 341.950312 -112.235049) (xy 341.892419 -112.219536) (xy 341.837046 -112.1966)
			(xy 341.78514 -112.166633) (xy 341.73759 -112.130146) (xy 341.69521 -112.087766) (xy 341.658723 -112.040216)
			(xy 341.628756 -111.98831) (xy 341.60582 -111.932937) (xy 341.590307 -111.875044) (xy 341.582484 -111.815622)
			(xy 339.157818 -111.815622) (xy 339.157818 -113.483136) (xy 339.158248 -113.493203) (xy 339.165974 -113.511796)
			(xy 339.172804 -113.519204) (xy 339.179408 -113.525808) (xy 339.179408 -114.19967) (xy 339.178973 -114.209735)
			(xy 339.171241 -114.228322) (xy 339.164422 -114.235738) (xy 339.048344 -114.351816) (xy 339.040946 -114.358663)
			(xy 339.022347 -114.36639) (xy 339.012276 -114.366802) (xy 337.914488 -114.366802) (xy 337.905565 -114.367189)
			(xy 337.888792 -114.373285) (xy 337.881722 -114.37874) (xy 337.859152 -114.397131) (xy 337.810205 -114.428657)
			(xy 337.757655 -114.453722) (xy 337.702351 -114.471919) (xy 337.645186 -114.482957) (xy 337.587082 -114.486656)
			(xy 337.528978 -114.482957) (xy 337.471813 -114.471919) (xy 337.416509 -114.453722) (xy 337.363959 -114.428657)
			(xy 337.315012 -114.397131) (xy 337.292442 -114.37874) (xy 337.285392 -114.373245) (xy 337.268608 -114.36713)
			(xy 337.259676 -114.366802) (xy 336.854546 -114.366802) (xy 336.84448 -114.367235) (xy 336.82589 -114.374964)
			(xy 336.818478 -114.381788) (xy 336.6389 -114.561366) (xy 336.632064 -114.568768) (xy 336.624353 -114.587366)
			(xy 336.623914 -114.597434) (xy 336.623914 -115.040914) (xy 338.744542 -115.040914) (xy 338.744542 -114.980978)
			(xy 338.752365 -114.921556) (xy 338.767878 -114.863663) (xy 338.790814 -114.80829) (xy 338.820781 -114.756384)
			(xy 338.857268 -114.708834) (xy 338.899648 -114.666454) (xy 338.947198 -114.629967) (xy 338.999104 -114.6)
			(xy 339.054477 -114.577064) (xy 339.11237 -114.561551) (xy 339.171792 -114.553728) (xy 339.231728 -114.553728)
			(xy 339.29115 -114.561551) (xy 339.349043 -114.577064) (xy 339.404416 -114.6) (xy 339.456322 -114.629967)
			(xy 339.503872 -114.666454) (xy 339.546252 -114.708834) (xy 339.582739 -114.756384) (xy 339.612706 -114.80829)
			(xy 339.635642 -114.863663) (xy 339.651155 -114.921556) (xy 339.658978 -114.980978) (xy 339.659468 -115.010946)
			(xy 339.658978 -115.040914) (xy 339.652691 -115.088666) (xy 340.111062 -115.088666) (xy 340.111062 -115.02873)
			(xy 340.118885 -114.969308) (xy 340.134398 -114.911415) (xy 340.157334 -114.856042) (xy 340.187301 -114.804136)
			(xy 340.223788 -114.756586) (xy 340.266168 -114.714206) (xy 340.313718 -114.677719) (xy 340.365624 -114.647752)
			(xy 340.420997 -114.624816) (xy 340.47889 -114.609303) (xy 340.538312 -114.60148) (xy 340.598248 -114.60148)
			(xy 340.65767 -114.609303) (xy 340.715563 -114.624816) (xy 340.770936 -114.647752) (xy 340.822842 -114.677719)
			(xy 340.870392 -114.714206) (xy 340.912772 -114.756586) (xy 340.949259 -114.804136) (xy 340.979226 -114.856042)
			(xy 341.002162 -114.911415) (xy 341.017675 -114.969308) (xy 341.024393 -115.02034) (xy 341.489774 -115.02034)
			(xy 341.489774 -114.960404) (xy 341.497597 -114.900982) (xy 341.51311 -114.843089) (xy 341.536046 -114.787716)
			(xy 341.566013 -114.73581) (xy 341.6025 -114.68826) (xy 341.64488 -114.64588) (xy 341.69243 -114.609393)
			(xy 341.744336 -114.579426) (xy 341.799709 -114.55649) (xy 341.857602 -114.540977) (xy 341.917024 -114.533154)
			(xy 341.97696 -114.533154) (xy 342.036382 -114.540977) (xy 342.094275 -114.55649) (xy 342.149648 -114.579426)
			(xy 342.201554 -114.609393) (xy 342.249104 -114.64588) (xy 342.291484 -114.68826) (xy 342.327971 -114.73581)
			(xy 342.357938 -114.787716) (xy 342.380874 -114.843089) (xy 342.396387 -114.900982) (xy 342.40421 -114.960404)
			(xy 342.4047 -114.990372) (xy 342.40421 -115.02034) (xy 342.396387 -115.079762) (xy 342.380874 -115.137655)
			(xy 342.357938 -115.193028) (xy 342.327971 -115.244934) (xy 342.291484 -115.292484) (xy 342.249104 -115.334864)
			(xy 342.201554 -115.371351) (xy 342.149648 -115.401318) (xy 342.094275 -115.424254) (xy 342.036382 -115.439767)
			(xy 341.97696 -115.44759) (xy 341.917024 -115.44759) (xy 341.857602 -115.439767) (xy 341.799709 -115.424254)
			(xy 341.744336 -115.401318) (xy 341.69243 -115.371351) (xy 341.64488 -115.334864) (xy 341.6025 -115.292484)
			(xy 341.566013 -115.244934) (xy 341.536046 -115.193028) (xy 341.51311 -115.137655) (xy 341.497597 -115.079762)
			(xy 341.489774 -115.02034) (xy 341.024393 -115.02034) (xy 341.025498 -115.02873) (xy 341.025988 -115.058698)
			(xy 341.025498 -115.088666) (xy 341.017675 -115.148088) (xy 341.002162 -115.205981) (xy 340.979226 -115.261354)
			(xy 340.949259 -115.31326) (xy 340.912772 -115.36081) (xy 340.870392 -115.40319) (xy 340.822842 -115.439677)
			(xy 340.770936 -115.469644) (xy 340.715563 -115.49258) (xy 340.65767 -115.508093) (xy 340.598248 -115.515916)
			(xy 340.538312 -115.515916) (xy 340.47889 -115.508093) (xy 340.420997 -115.49258) (xy 340.365624 -115.469644)
			(xy 340.313718 -115.439677) (xy 340.266168 -115.40319) (xy 340.223788 -115.36081) (xy 340.187301 -115.31326)
			(xy 340.157334 -115.261354) (xy 340.134398 -115.205981) (xy 340.118885 -115.148088) (xy 340.111062 -115.088666)
			(xy 339.652691 -115.088666) (xy 339.651155 -115.100336) (xy 339.635642 -115.158229) (xy 339.612706 -115.213602)
			(xy 339.582739 -115.265508) (xy 339.546252 -115.313058) (xy 339.503872 -115.355438) (xy 339.456322 -115.391925)
			(xy 339.404416 -115.421892) (xy 339.349043 -115.444828) (xy 339.29115 -115.460341) (xy 339.231728 -115.468164)
			(xy 339.171792 -115.468164) (xy 339.11237 -115.460341) (xy 339.054477 -115.444828) (xy 338.999104 -115.421892)
			(xy 338.947198 -115.391925) (xy 338.899648 -115.355438) (xy 338.857268 -115.313058) (xy 338.820781 -115.265508)
			(xy 338.790814 -115.213602) (xy 338.767878 -115.158229) (xy 338.752365 -115.100336) (xy 338.744542 -115.040914)
			(xy 336.623914 -115.040914) (xy 336.623914 -115.579906) (xy 337.342986 -115.579906) (xy 337.347057 -115.524284)
			(xy 337.359183 -115.469847) (xy 337.379106 -115.417756) (xy 337.406402 -115.369121) (xy 337.440488 -115.324978)
			(xy 337.480637 -115.286269) (xy 337.525995 -115.253818) (xy 337.575595 -115.228317) (xy 337.628379 -115.21031)
			(xy 337.683222 -115.20018) (xy 337.738956 -115.198143) (xy 337.794393 -115.204243) (xy 337.84835 -115.218349)
			(xy 337.899679 -115.240161) (xy 337.947285 -115.269215) (xy 337.990153 -115.30489) (xy 338.02737 -115.346427)
			(xy 338.058143 -115.39294) (xy 338.081815 -115.443437) (xy 338.097883 -115.496844) (xy 338.106003 -115.55202)
			(xy 338.106512 -115.579906) (xy 338.106003 -115.607792) (xy 338.097883 -115.662968) (xy 338.081815 -115.716375)
			(xy 338.058143 -115.766872) (xy 338.02737 -115.813385) (xy 337.990153 -115.854922) (xy 337.947285 -115.890597)
			(xy 337.899679 -115.919651) (xy 337.84835 -115.941463) (xy 337.794393 -115.955569) (xy 337.738956 -115.961669)
			(xy 337.683222 -115.959632) (xy 337.628379 -115.949502) (xy 337.575595 -115.931495) (xy 337.525995 -115.905994)
			(xy 337.480637 -115.873543) (xy 337.440488 -115.834834) (xy 337.406402 -115.790691) (xy 337.379106 -115.742056)
			(xy 337.359183 -115.689965) (xy 337.347057 -115.635528) (xy 337.342986 -115.579906) (xy 336.623914 -115.579906)
			(xy 336.623914 -116.964714) (xy 336.62434 -116.974783) (xy 336.63206 -116.993382) (xy 336.6389 -117.000782)
			(xy 337.132676 -117.494558) (xy 337.140077 -117.501397) (xy 337.158675 -117.509111) (xy 337.168744 -117.509544)
		)
		(stroke
			(width 0)
			(type solid)
		)
		(fill yes)
		(layer "B.Cu")
		(net "P12V_AUX")
	)
	(gr_poly
		(pts
			(xy 374.131586 -181.79796) (xy 374.136158 -181.78145) (xy 374.143976 -181.754979) (xy 374.166185 -181.704449)
			(xy 374.195443 -181.657646) (xy 374.231139 -181.615548) (xy 374.272528 -181.579032) (xy 374.318747 -181.54886)
			(xy 374.36883 -181.525662) (xy 374.421733 -181.509923) (xy 374.476352 -181.50197) (xy 374.531548 -181.50197)
			(xy 374.586167 -181.509923) (xy 374.63907 -181.525662) (xy 374.689153 -181.54886) (xy 374.735372 -181.579032)
			(xy 374.776761 -181.615548) (xy 374.812457 -181.657646) (xy 374.841715 -181.704449) (xy 374.863924 -181.754979)
			(xy 374.871742 -181.78145) (xy 374.876314 -181.79796) (xy 374.903492 -181.818788) (xy 403.397466 -181.818788)
			(xy 403.407339 -181.818319) (xy 403.425624 -181.810862) (xy 403.433026 -181.80431) (xy 403.43328 -181.804056)
			(xy 403.741128 -181.496208) (xy 403.741636 -181.4957) (xy 403.748213 -181.488317) (xy 403.755649 -181.470018)
			(xy 403.756114 -181.46014) (xy 403.756114 -168.228772) (xy 403.755686 -168.218704) (xy 403.747966 -168.200105)
			(xy 403.741128 -168.192704) (xy 403.677374 -168.12895) (xy 403.67003 -168.122138) (xy 403.651567 -168.114407)
			(xy 403.64156 -168.113964) (xy 400.739102 -168.113964) (xy 400.726548 -168.114608) (xy 400.704422 -168.12647)
			(xy 400.696938 -168.13657) (xy 400.642582 -168.217088) (xy 400.640042 -168.24198) (xy 400.644868 -168.253918)
			(xy 400.653719 -168.276752) (xy 400.66616 -168.324118) (xy 400.672433 -168.372688) (xy 400.672808 -168.397174)
			(xy 400.672322 -168.424425) (xy 400.664566 -168.478373) (xy 400.649211 -168.530668) (xy 400.626569 -168.580245)
			(xy 400.597103 -168.626095) (xy 400.561412 -168.667286) (xy 400.520221 -168.702977) (xy 400.474371 -168.732443)
			(xy 400.424794 -168.755085) (xy 400.372499 -168.77044) (xy 400.318551 -168.778196) (xy 400.264049 -168.778196)
			(xy 400.210101 -168.77044) (xy 400.157806 -168.755085) (xy 400.108229 -168.732443) (xy 400.062379 -168.702977)
			(xy 400.021188 -168.667286) (xy 399.985497 -168.626095) (xy 399.956031 -168.580245) (xy 399.933389 -168.530668)
			(xy 399.918034 -168.478373) (xy 399.910278 -168.424425) (xy 399.909792 -168.397174) (xy 399.910171 -168.372688)
			(xy 399.916446 -168.32412) (xy 399.928889 -168.276755) (xy 399.937732 -168.253918) (xy 399.942558 -168.24198)
			(xy 399.940018 -168.217088) (xy 399.885662 -168.13657) (xy 399.878144 -168.126512) (xy 399.856036 -168.114669)
			(xy 399.843498 -168.113964) (xy 398.717262 -168.113964) (xy 398.707257 -168.114458) (xy 398.688772 -168.122123)
			(xy 398.674622 -168.136273) (xy 398.666958 -168.154759) (xy 398.666462 -168.164764) (xy 398.666462 -169.413682)
			(xy 398.66695 -169.423644) (xy 398.674538 -169.442068) (xy 398.681194 -169.449496) (xy 398.738344 -169.507408)
			(xy 398.756378 -169.515282) (xy 398.766538 -169.515282) (xy 398.794828 -169.516192) (xy 398.850684 -169.525336)
			(xy 398.904577 -169.54263) (xy 398.955323 -169.567696) (xy 399.00181 -169.599984) (xy 399.043017 -169.638784)
			(xy 399.07804 -169.683246) (xy 399.106111 -169.732395) (xy 399.126614 -169.78515) (xy 399.139098 -169.840356)
			(xy 399.14329 -169.8968) (xy 399.139098 -169.953244) (xy 399.126614 -170.00845) (xy 399.106112 -170.061205)
			(xy 399.078041 -170.110353) (xy 399.043017 -170.154816) (xy 399.00181 -170.193616) (xy 398.955323 -170.225904)
			(xy 398.904577 -170.25097) (xy 398.850684 -170.268264) (xy 398.794828 -170.277408) (xy 398.766538 -170.278298)
			(xy 398.756378 -170.278298) (xy 398.738344 -170.286172) (xy 398.681194 -170.344084) (xy 398.674508 -170.351493)
			(xy 398.666921 -170.369929) (xy 398.666462 -170.379898) (xy 398.666462 -171.580048) (xy 398.689576 -171.607988)
			(xy 398.707864 -171.611544) (xy 398.73503 -171.617249) (xy 398.787462 -171.635469) (xy 398.8367 -171.661097)
			(xy 398.881703 -171.69359) (xy 398.921521 -171.732263) (xy 398.955314 -171.776299) (xy 398.982367 -171.824768)
			(xy 399.00211 -171.876646) (xy 399.014125 -171.930838) (xy 399.018158 -171.986199) (xy 399.014125 -172.04156)
			(xy 399.002111 -172.095752) (xy 398.982368 -172.14763) (xy 398.955315 -172.196099) (xy 398.921523 -172.240135)
			(xy 398.881705 -172.278808) (xy 398.836702 -172.311302) (xy 398.787464 -172.33693) (xy 398.735032 -172.35515)
			(xy 398.707864 -172.360844) (xy 398.689576 -172.3644) (xy 398.666462 -172.39234) (xy 398.666462 -172.409104)
			(xy 400.429982 -172.409104) (xy 400.434053 -172.353482) (xy 400.446179 -172.299045) (xy 400.466102 -172.246954)
			(xy 400.493398 -172.198319) (xy 400.527484 -172.154176) (xy 400.567633 -172.115467) (xy 400.612991 -172.083016)
			(xy 400.662591 -172.057515) (xy 400.715375 -172.039508) (xy 400.770218 -172.029378) (xy 400.825952 -172.027341)
			(xy 400.881389 -172.033441) (xy 400.935346 -172.047547) (xy 400.986675 -172.069359) (xy 401.034281 -172.098413)
			(xy 401.077149 -172.134088) (xy 401.114366 -172.175625) (xy 401.145139 -172.222138) (xy 401.168811 -172.272635)
			(xy 401.184879 -172.326042) (xy 401.192999 -172.381218) (xy 401.193508 -172.409104) (xy 401.192999 -172.43699)
			(xy 401.184879 -172.492166) (xy 401.168811 -172.545573) (xy 401.145139 -172.59607) (xy 401.114366 -172.642583)
			(xy 401.077149 -172.68412) (xy 401.034281 -172.719795) (xy 400.986675 -172.748849) (xy 400.935346 -172.770661)
			(xy 400.881389 -172.784767) (xy 400.825952 -172.790867) (xy 400.770218 -172.78883) (xy 400.715375 -172.7787)
			(xy 400.662591 -172.760693) (xy 400.612991 -172.735192) (xy 400.567633 -172.702741) (xy 400.527484 -172.664032)
			(xy 400.493398 -172.619889) (xy 400.466102 -172.571254) (xy 400.446179 -172.519163) (xy 400.434053 -172.464726)
			(xy 400.429982 -172.409104) (xy 398.666462 -172.409104) (xy 398.666462 -172.591984) (xy 398.666023 -172.602047)
			(xy 398.658283 -172.620625) (xy 398.651476 -172.628052) (xy 398.389602 -172.889926) (xy 398.382207 -172.896781)
			(xy 398.363608 -172.904528) (xy 398.353534 -172.904912) (xy 394.707618 -172.904912) (xy 394.697555 -172.90535)
			(xy 394.678973 -172.913087) (xy 394.67155 -172.919898) (xy 394.666978 -172.92447) (xy 394.648436 -172.93209)
			(xy 375.225056 -172.93209) (xy 375.215361 -172.932522) (xy 375.197356 -172.939721) (xy 375.183298 -172.953077)
			(xy 375.175187 -172.97069) (xy 375.174256 -172.98035) (xy 375.172115 -173.011921) (xy 375.160224 -173.074071)
			(xy 375.139885 -173.13399) (xy 375.111485 -173.190536) (xy 375.075565 -173.24263) (xy 375.032811 -173.289278)
			(xy 374.984038 -173.329592) (xy 374.930176 -173.362802) (xy 374.872252 -173.388275) (xy 374.811371 -173.405524)
			(xy 374.748695 -173.414222) (xy 374.717056 -173.41469) (xy 374.706388 -173.41469) (xy 374.674892 -173.412658)
			(xy 374.662446 -173.411642) (xy 374.651778 -173.415452) (xy 374.646548 -173.417507) (xy 374.637067 -173.423532)
			(xy 374.632982 -173.42739) (xy 374.559576 -173.500796) (xy 374.553988 -173.5074) (xy 374.553988 -173.507654)
			(xy 374.547521 -173.517933) (xy 374.544088 -173.541938) (xy 374.547384 -173.553628) (xy 374.57761 -173.639988)
			(xy 374.581234 -173.648756) (xy 374.593664 -173.663066) (xy 374.610418 -173.671932) (xy 374.619774 -173.673516)
			(xy 374.647387 -173.677128) (xy 374.701234 -173.691327) (xy 374.752444 -173.713206) (xy 374.799926 -173.742301)
			(xy 374.842673 -173.777992) (xy 374.879774 -173.81952) (xy 374.910441 -173.866003) (xy 374.934021 -173.916452)
			(xy 374.950014 -173.969793) (xy 374.958079 -174.024894) (xy 374.95861 -174.052738) (xy 374.958122 -174.079988)
			(xy 374.950361 -174.133931) (xy 374.945635 -174.15002) (xy 375.210322 -174.15002) (xy 375.214393 -174.094398)
			(xy 375.226519 -174.039961) (xy 375.246442 -173.98787) (xy 375.273738 -173.939235) (xy 375.307824 -173.895092)
			(xy 375.347973 -173.856383) (xy 375.393331 -173.823932) (xy 375.442931 -173.798431) (xy 375.495715 -173.780424)
			(xy 375.550558 -173.770294) (xy 375.606292 -173.768257) (xy 375.661729 -173.774357) (xy 375.715686 -173.788463)
			(xy 375.767015 -173.810275) (xy 375.814621 -173.839329) (xy 375.857489 -173.875004) (xy 375.894706 -173.916541)
			(xy 375.925479 -173.963054) (xy 375.949151 -174.013551) (xy 375.965219 -174.066958) (xy 375.973339 -174.122134)
			(xy 375.973848 -174.15002) (xy 375.973339 -174.177906) (xy 375.965219 -174.233082) (xy 375.949151 -174.286489)
			(xy 375.925479 -174.336986) (xy 375.894706 -174.383499) (xy 375.857489 -174.425036) (xy 375.814621 -174.460711)
			(xy 375.767015 -174.489765) (xy 375.76497 -174.490634) (xy 398.11147 -174.490634) (xy 398.115541 -174.435012)
			(xy 398.127667 -174.380575) (xy 398.14759 -174.328484) (xy 398.174886 -174.279849) (xy 398.208972 -174.235706)
			(xy 398.249121 -174.196997) (xy 398.294479 -174.164546) (xy 398.344079 -174.139045) (xy 398.396863 -174.121038)
			(xy 398.451706 -174.110908) (xy 398.50744 -174.108871) (xy 398.562877 -174.114971) (xy 398.616834 -174.129077)
			(xy 398.668163 -174.150889) (xy 398.715769 -174.179943) (xy 398.758637 -174.215618) (xy 398.795854 -174.257155)
			(xy 398.826627 -174.303668) (xy 398.850299 -174.354165) (xy 398.866367 -174.407572) (xy 398.874487 -174.462748)
			(xy 398.874996 -174.490634) (xy 398.874487 -174.51852) (xy 398.866367 -174.573696) (xy 398.850299 -174.627103)
			(xy 398.826627 -174.6776) (xy 398.795854 -174.724113) (xy 398.758637 -174.76565) (xy 398.715769 -174.801325)
			(xy 398.668163 -174.830379) (xy 398.616834 -174.852191) (xy 398.562877 -174.866297) (xy 398.50744 -174.872397)
			(xy 398.451706 -174.87036) (xy 398.396863 -174.86023) (xy 398.344079 -174.842223) (xy 398.294479 -174.816722)
			(xy 398.249121 -174.784271) (xy 398.208972 -174.745562) (xy 398.174886 -174.701419) (xy 398.14759 -174.652784)
			(xy 398.127667 -174.600693) (xy 398.115541 -174.546256) (xy 398.11147 -174.490634) (xy 375.76497 -174.490634)
			(xy 375.715686 -174.511577) (xy 375.661729 -174.525683) (xy 375.606292 -174.531783) (xy 375.550558 -174.529746)
			(xy 375.495715 -174.519616) (xy 375.442931 -174.501609) (xy 375.393331 -174.476108) (xy 375.347973 -174.443657)
			(xy 375.307824 -174.404948) (xy 375.273738 -174.360805) (xy 375.246442 -174.31217) (xy 375.226519 -174.260079)
			(xy 375.214393 -174.205642) (xy 375.210322 -174.15002) (xy 374.945635 -174.15002) (xy 374.935002 -174.186222)
			(xy 374.912359 -174.235794) (xy 374.882892 -174.28164) (xy 374.8472 -174.322826) (xy 374.806011 -174.358513)
			(xy 374.760162 -174.387976) (xy 374.710588 -174.410615) (xy 374.658296 -174.425968) (xy 374.604352 -174.433724)
			(xy 374.577102 -174.434246) (xy 374.549262 -174.433734) (xy 374.494175 -174.425631) (xy 374.44085 -174.409612)
			(xy 374.390418 -174.386015) (xy 374.343948 -174.355343) (xy 374.302428 -174.318245) (xy 374.266737 -174.275508)
			(xy 374.237633 -174.22804) (xy 374.215734 -174.176848) (xy 374.201504 -174.123017) (xy 374.19788 -174.09541)
			(xy 374.196461 -174.085997) (xy 374.187619 -174.069154) (xy 374.173207 -174.056738) (xy 374.164352 -174.053246)
			(xy 374.077992 -174.02302) (xy 374.066306 -174.019741) (xy 374.042318 -174.023201) (xy 374.032018 -174.029624)
			(xy 374.028208 -174.032164) (xy 373.68099 -174.379382) (xy 373.673624 -174.386494) (xy 373.666004 -174.40529)
			(xy 373.666004 -175.654747) (xy 374.724716 -175.654747) (xy 374.724716 -175.600253) (xy 374.732471 -175.546312)
			(xy 374.747824 -175.494025) (xy 374.770461 -175.444454) (xy 374.799922 -175.39861) (xy 374.835607 -175.357424)
			(xy 374.87679 -175.321736) (xy 374.922633 -175.292272) (xy 374.972202 -175.269632) (xy 375.024489 -175.254276)
			(xy 375.078429 -175.246518) (xy 375.105676 -175.24603) (xy 375.131268 -175.246459) (xy 375.181986 -175.253344)
			(xy 375.206768 -175.259746) (xy 375.219714 -175.262885) (xy 375.246344 -175.263036) (xy 375.272108 -175.256296)
			(xy 375.295254 -175.243126) (xy 375.314208 -175.224419) (xy 375.327682 -175.201449) (xy 375.334759 -175.175776)
			(xy 375.335292 -175.162464) (xy 375.336036 -175.13265) (xy 375.344239 -175.073578) (xy 375.360045 -175.016073)
			(xy 375.383187 -174.961107) (xy 375.413272 -174.909613) (xy 375.44979 -174.862463) (xy 375.492123 -174.820455)
			(xy 375.539554 -174.784302) (xy 375.591279 -174.754616) (xy 375.646422 -174.7319) (xy 375.704048 -174.716539)
			(xy 375.763181 -174.708792) (xy 375.793 -174.708312) (xy 375.822969 -174.708762) (xy 375.882394 -174.716586)
			(xy 375.94029 -174.732099) (xy 375.995665 -174.755036) (xy 376.047573 -174.785005) (xy 376.095125 -174.821493)
			(xy 376.137507 -174.863875) (xy 376.173995 -174.911427) (xy 376.203964 -174.963335) (xy 376.226901 -175.01871)
			(xy 376.242414 -175.076606) (xy 376.250238 -175.136031) (xy 376.250238 -175.195969) (xy 376.242414 -175.255394)
			(xy 376.226901 -175.31329) (xy 376.203964 -175.368665) (xy 376.173995 -175.420573) (xy 376.137507 -175.468125)
			(xy 376.095125 -175.510507) (xy 376.047573 -175.546995) (xy 375.995665 -175.576964) (xy 375.94029 -175.599901)
			(xy 375.882394 -175.615414) (xy 375.822969 -175.623238) (xy 375.793 -175.623728) (xy 375.763971 -175.623278)
			(xy 375.706381 -175.61593) (xy 375.650188 -175.60134) (xy 375.623074 -175.590962) (xy 375.610539 -175.586406)
			(xy 375.58407 -175.583214) (xy 375.557679 -175.586991) (xy 375.533168 -175.597479) (xy 375.512212 -175.61396)
			(xy 375.496244 -175.635309) (xy 375.486353 -175.660067) (xy 375.48439 -175.673258) (xy 375.480599 -175.700685)
			(xy 375.472599 -175.730154) (xy 398.482056 -175.730154) (xy 398.486127 -175.674532) (xy 398.498253 -175.620095)
			(xy 398.518176 -175.568004) (xy 398.545472 -175.519369) (xy 398.579558 -175.475226) (xy 398.619707 -175.436517)
			(xy 398.665065 -175.404066) (xy 398.714665 -175.378565) (xy 398.767449 -175.360558) (xy 398.822292 -175.350428)
			(xy 398.878026 -175.348391) (xy 398.933463 -175.354491) (xy 398.98742 -175.368597) (xy 399.038749 -175.390409)
			(xy 399.086355 -175.419463) (xy 399.129223 -175.455138) (xy 399.16644 -175.496675) (xy 399.197213 -175.543188)
			(xy 399.220885 -175.593685) (xy 399.236953 -175.647092) (xy 399.245073 -175.702268) (xy 399.245582 -175.730154)
			(xy 399.245073 -175.75804) (xy 399.236953 -175.813216) (xy 399.220885 -175.866623) (xy 399.197213 -175.91712)
			(xy 399.16644 -175.963633) (xy 399.129223 -176.00517) (xy 399.086355 -176.040845) (xy 399.038749 -176.069899)
			(xy 398.98742 -176.091711) (xy 398.933463 -176.105817) (xy 398.878026 -176.111917) (xy 398.822292 -176.10988)
			(xy 398.767449 -176.09975) (xy 398.714665 -176.081743) (xy 398.665065 -176.056242) (xy 398.619707 -176.023791)
			(xy 398.579558 -175.985082) (xy 398.545472 -175.940939) (xy 398.518176 -175.892304) (xy 398.498253 -175.840213)
			(xy 398.486127 -175.785776) (xy 398.482056 -175.730154) (xy 375.472599 -175.730154) (xy 375.466093 -175.75412)
			(xy 375.444014 -175.804896) (xy 375.414827 -175.851946) (xy 375.379143 -175.894282) (xy 375.337714 -175.931014)
			(xy 375.291409 -175.96137) (xy 375.241202 -175.984713) (xy 375.188147 -176.000552) (xy 375.13336 -176.008553)
			(xy 375.105676 -176.009046) (xy 375.078429 -176.008482) (xy 375.024489 -176.000724) (xy 374.972202 -175.985368)
			(xy 374.922633 -175.962728) (xy 374.87679 -175.933264) (xy 374.835607 -175.897576) (xy 374.799922 -175.85639)
			(xy 374.770461 -175.810546) (xy 374.747824 -175.760975) (xy 374.732471 -175.708688) (xy 374.724716 -175.654747)
			(xy 373.666004 -175.654747) (xy 373.666004 -177.227988) (xy 375.335782 -177.227988) (xy 375.335782 -177.168052)
			(xy 375.343605 -177.10863) (xy 375.359118 -177.050737) (xy 375.382054 -176.995364) (xy 375.412021 -176.943458)
			(xy 375.448508 -176.895908) (xy 375.490888 -176.853528) (xy 375.538438 -176.817041) (xy 375.590344 -176.787074)
			(xy 375.645717 -176.764138) (xy 375.70361 -176.748625) (xy 375.763032 -176.740802) (xy 375.822968 -176.740802)
			(xy 375.88239 -176.748625) (xy 375.940283 -176.764138) (xy 375.995656 -176.787074) (xy 376.047562 -176.817041)
			(xy 376.095112 -176.853528) (xy 376.137492 -176.895908) (xy 376.173979 -176.943458) (xy 376.203946 -176.995364)
			(xy 376.226882 -177.050737) (xy 376.242395 -177.10863) (xy 376.250218 -177.168052) (xy 376.250708 -177.19802)
			(xy 376.250218 -177.227988) (xy 376.242395 -177.28741) (xy 376.226882 -177.345303) (xy 376.203946 -177.400676)
			(xy 376.173979 -177.452582) (xy 376.137492 -177.500132) (xy 376.095112 -177.542512) (xy 376.047562 -177.578999)
			(xy 375.995656 -177.608966) (xy 375.940283 -177.631902) (xy 375.88239 -177.647415) (xy 375.822968 -177.655238)
			(xy 375.763032 -177.655238) (xy 375.70361 -177.647415) (xy 375.645717 -177.631902) (xy 375.590344 -177.608966)
			(xy 375.538438 -177.578999) (xy 375.490888 -177.542512) (xy 375.448508 -177.500132) (xy 375.412021 -177.452582)
			(xy 375.382054 -177.400676) (xy 375.359118 -177.345303) (xy 375.343605 -177.28741) (xy 375.335782 -177.227988)
			(xy 373.666004 -177.227988) (xy 373.666004 -178.947043) (xy 374.628717 -178.947043) (xy 374.628719 -178.887114)
			(xy 374.636544 -178.827698) (xy 374.652058 -178.769811) (xy 374.674994 -178.714444) (xy 374.70496 -178.662545)
			(xy 374.741444 -178.615001) (xy 374.783822 -178.572626) (xy 374.831368 -178.536145) (xy 374.88327 -178.506181)
			(xy 374.938638 -178.483249) (xy 374.996525 -178.467739) (xy 375.055942 -178.459917) (xy 375.115871 -178.459918)
			(xy 375.175288 -178.467741) (xy 375.233175 -178.483253) (xy 375.288542 -178.506187) (xy 375.340443 -178.536152)
			(xy 375.387988 -178.572635) (xy 375.430364 -178.615011) (xy 375.466847 -178.662556) (xy 375.496812 -178.714456)
			(xy 375.519747 -178.769824) (xy 375.535258 -178.827711) (xy 375.543082 -178.887127) (xy 375.543572 -178.917092)
			(xy 375.543421 -178.932637) (xy 375.541257 -178.963652) (xy 375.539254 -178.979068) (xy 375.537476 -178.992022)
			(xy 375.547128 -179.01666) (xy 375.633996 -179.088542) (xy 375.65965 -179.093368) (xy 375.672096 -179.08905)
			(xy 375.701484 -179.079917) (xy 375.762231 -179.070092) (xy 375.793 -179.069492) (xy 375.820251 -179.069978)
			(xy 375.874199 -179.077734) (xy 375.885056 -179.080922) (xy 399.90725 -179.080922) (xy 399.911321 -179.0253)
			(xy 399.923447 -178.970863) (xy 399.94337 -178.918772) (xy 399.970666 -178.870137) (xy 400.004752 -178.825994)
			(xy 400.044901 -178.787285) (xy 400.090259 -178.754834) (xy 400.139859 -178.729333) (xy 400.192643 -178.711326)
			(xy 400.247486 -178.701196) (xy 400.30322 -178.699159) (xy 400.358657 -178.705259) (xy 400.412614 -178.719365)
			(xy 400.463943 -178.741177) (xy 400.511549 -178.770231) (xy 400.554417 -178.805906) (xy 400.591634 -178.847443)
			(xy 400.622407 -178.893956) (xy 400.646079 -178.944453) (xy 400.662147 -178.99786) (xy 400.670267 -179.053036)
			(xy 400.670776 -179.080922) (xy 400.670267 -179.108808) (xy 400.662147 -179.163984) (xy 400.646079 -179.217391)
			(xy 400.622407 -179.267888) (xy 400.591634 -179.314401) (xy 400.554417 -179.355938) (xy 400.511549 -179.391613)
			(xy 400.463943 -179.420667) (xy 400.412614 -179.442479) (xy 400.358657 -179.456585) (xy 400.30322 -179.462685)
			(xy 400.247486 -179.460648) (xy 400.192643 -179.450518) (xy 400.139859 -179.432511) (xy 400.090259 -179.40701)
			(xy 400.044901 -179.374559) (xy 400.004752 -179.33585) (xy 399.970666 -179.291707) (xy 399.94337 -179.243072)
			(xy 399.923447 -179.190981) (xy 399.911321 -179.136544) (xy 399.90725 -179.080922) (xy 375.885056 -179.080922)
			(xy 375.926494 -179.093089) (xy 375.976071 -179.115731) (xy 376.021921 -179.145197) (xy 376.063112 -179.180888)
			(xy 376.098803 -179.222079) (xy 376.128269 -179.267929) (xy 376.150911 -179.317506) (xy 376.166266 -179.369801)
			(xy 376.174022 -179.423749) (xy 376.174508 -179.451) (xy 376.173952 -179.480007) (xy 376.165175 -179.537353)
			(xy 376.147824 -179.592711) (xy 376.122296 -179.644807) (xy 376.106182 -179.668932) (xy 376.100086 -179.677568)
			(xy 376.096022 -179.696618) (xy 376.112024 -179.78755) (xy 376.122692 -179.804314) (xy 376.131074 -179.810156)
			(xy 376.156406 -179.828593) (xy 376.202245 -179.871305) (xy 376.24183 -179.919868) (xy 376.274424 -179.973377)
			(xy 376.299415 -180.030831) (xy 376.316337 -180.091156) (xy 376.324875 -180.153225) (xy 376.325384 -180.184552)
			(xy 376.324894 -180.21452) (xy 376.317071 -180.273942) (xy 376.301558 -180.331835) (xy 376.278622 -180.387208)
			(xy 376.248655 -180.439114) (xy 376.212168 -180.486664) (xy 376.169788 -180.529044) (xy 376.122238 -180.565531)
			(xy 376.070332 -180.595498) (xy 376.014959 -180.618434) (xy 375.957066 -180.633947) (xy 375.897644 -180.64177)
			(xy 375.837708 -180.64177) (xy 375.778286 -180.633947) (xy 375.720393 -180.618434) (xy 375.66502 -180.595498)
			(xy 375.613114 -180.565531) (xy 375.565564 -180.529044) (xy 375.523184 -180.486664) (xy 375.486697 -180.439114)
			(xy 375.45673 -180.387208) (xy 375.433794 -180.331835) (xy 375.418281 -180.273942) (xy 375.410458 -180.21452)
			(xy 375.409968 -180.184552) (xy 375.41038 -180.155737) (xy 375.417613 -180.098562) (xy 375.431972 -180.04275)
			(xy 375.453229 -179.989183) (xy 375.481047 -179.938711) (xy 375.514985 -179.892134) (xy 375.534428 -179.870862)
			(xy 375.541286 -179.863496) (xy 375.548398 -179.844954) (xy 375.545858 -179.752752) (xy 375.53773 -179.734718)
			(xy 375.530364 -179.727606) (xy 375.511929 -179.709548) (xy 375.479625 -179.669306) (xy 375.453044 -179.625074)
			(xy 375.432672 -179.577662) (xy 375.418879 -179.527935) (xy 375.411919 -179.476802) (xy 375.411492 -179.451)
			(xy 375.412 -179.433982) (xy 375.412508 -179.420774) (xy 375.400824 -179.397152) (xy 375.30786 -179.333398)
			(xy 375.281698 -179.331112) (xy 375.269506 -179.336192) (xy 375.240442 -179.348385) (xy 375.179803 -179.365572)
			(xy 375.117377 -179.374259) (xy 375.085864 -179.3748) (xy 375.055899 -179.37428) (xy 374.996483 -179.366453)
			(xy 374.938597 -179.350938) (xy 374.883231 -179.328) (xy 374.831333 -179.298032) (xy 374.78379 -179.261546)
			(xy 374.741416 -179.219167) (xy 374.704936 -179.171619) (xy 374.674975 -179.119717) (xy 374.652044 -179.064349)
			(xy 374.636536 -179.00646) (xy 374.628717 -178.947043) (xy 373.666004 -178.947043) (xy 373.666004 -179.195984)
			(xy 373.666512 -179.206405) (xy 373.67478 -179.22554) (xy 373.682006 -179.233068) (xy 373.704423 -179.254793)
			(xy 373.743758 -179.303266) (xy 373.77614 -179.356635) (xy 373.800968 -179.41391) (xy 373.817781 -179.474027)
			(xy 373.826267 -179.535873) (xy 373.826269 -179.598297) (xy 373.817787 -179.660143) (xy 373.800978 -179.720262)
			(xy 373.776154 -179.777539) (xy 373.743775 -179.83091) (xy 373.704443 -179.879385) (xy 373.682006 -179.901088)
			(xy 373.674733 -179.908585) (xy 373.666456 -179.927738) (xy 373.666004 -179.938172) (xy 373.666004 -180.353208)
			(xy 373.848376 -180.353208) (xy 373.848863 -180.324438) (xy 373.856597 -180.267421) (xy 373.871911 -180.211958)
			(xy 373.894531 -180.159051) (xy 373.924045 -180.109658) (xy 373.95992 -180.064672) (xy 374.001508 -180.024908)
			(xy 374.048056 -179.991083) (xy 374.073166 -179.977034) (xy 374.083326 -179.971446) (xy 374.096788 -179.953412)
			(xy 374.116092 -179.853082) (xy 374.110504 -179.831492) (xy 374.103138 -179.822348) (xy 374.086477 -179.801692)
			(xy 374.058457 -179.756623) (xy 374.036945 -179.70811) (xy 374.022355 -179.657086) (xy 374.014968 -179.604534)
			(xy 374.014492 -179.578) (xy 374.014978 -179.550749) (xy 374.022734 -179.496801) (xy 374.038089 -179.444506)
			(xy 374.060731 -179.394929) (xy 374.090197 -179.349079) (xy 374.125888 -179.307888) (xy 374.167079 -179.272197)
			(xy 374.212929 -179.242731) (xy 374.262506 -179.220089) (xy 374.314801 -179.204734) (xy 374.368749 -179.196978)
			(xy 374.423251 -179.196978) (xy 374.477199 -179.204734) (xy 374.529494 -179.220089) (xy 374.579071 -179.242731)
			(xy 374.624921 -179.272197) (xy 374.666112 -179.307888) (xy 374.701803 -179.349079) (xy 374.731269 -179.394929)
			(xy 374.753911 -179.444506) (xy 374.769266 -179.496801) (xy 374.777022 -179.550749) (xy 374.777508 -179.578)
			(xy 374.777006 -179.605376) (xy 374.769186 -179.659567) (xy 374.753693 -179.712081) (xy 374.730846 -179.761838)
			(xy 374.701115 -179.807814) (xy 374.665111 -179.849063) (xy 374.623576 -179.884737) (xy 374.600724 -179.899818)
			(xy 374.590818 -179.906168) (xy 374.57888 -179.925218) (xy 374.566942 -180.026564) (xy 374.574308 -180.0479)
			(xy 374.582436 -180.056282) (xy 374.601112 -180.076284) (xy 374.633794 -180.120176) (xy 374.660601 -180.167883)
			(xy 374.681093 -180.218625) (xy 374.694935 -180.271568) (xy 374.7019 -180.325846) (xy 374.702324 -180.353208)
			(xy 374.701826 -180.38238) (xy 374.693882 -180.44018) (xy 374.678141 -180.49636) (xy 374.654897 -180.549873)
			(xy 374.624583 -180.599723) (xy 374.587763 -180.644981) (xy 374.545123 -180.684804) (xy 374.497458 -180.718449)
			(xy 374.445656 -180.745291) (xy 374.390681 -180.764829) (xy 374.333558 -180.776699) (xy 374.27535 -180.780681)
			(xy 374.217142 -180.776699) (xy 374.160019 -180.764829) (xy 374.105044 -180.745291) (xy 374.053242 -180.718449)
			(xy 374.005577 -180.684804) (xy 373.962937 -180.644981) (xy 373.926117 -180.599723) (xy 373.895803 -180.549873)
			(xy 373.872559 -180.49636) (xy 373.856818 -180.44018) (xy 373.848874 -180.38238) (xy 373.848376 -180.353208)
			(xy 373.666004 -180.353208) (xy 373.666004 -181.685438) (xy 373.666468 -181.695313) (xy 373.673917 -181.713606)
			(xy 373.680482 -181.720998) (xy 373.680736 -181.721252) (xy 373.763286 -181.803802) (xy 373.763794 -181.80431)
			(xy 373.771175 -181.810891) (xy 373.789475 -181.818333) (xy 373.799354 -181.818788) (xy 374.104408 -181.818788)
		)
		(stroke
			(width 0)
			(type solid)
		)
		(fill yes)
		(layer "B.Cu")
		(net "P3V3_AUX")
	)
	(gr_poly
		(pts
			(xy 334.490314 -220.878654) (xy 334.497172 -220.873066) (xy 334.503268 -220.867986) (xy 334.510316 -220.862488)
			(xy 334.527101 -220.856371) (xy 334.536034 -220.856048) (xy 335.20126 -220.856048) (xy 335.20761 -220.854524)
			(xy 335.224361 -220.850367) (xy 335.258462 -220.845027) (xy 335.275682 -220.843856) (xy 335.28508 -220.843348)
			(xy 335.293462 -220.839538) (xy 335.297664 -220.83756) (xy 335.305324 -220.832312) (xy 335.308702 -220.829124)
			(xy 335.314544 -220.80093) (xy 335.298034 -220.759782) (xy 335.29426 -220.751406) (xy 335.281856 -220.737871)
			(xy 335.26547 -220.729594) (xy 335.256378 -220.728286) (xy 335.231472 -220.725109) (xy 335.182897 -220.712413)
			(xy 335.136689 -220.692777) (xy 335.093833 -220.666621) (xy 335.055243 -220.634503) (xy 335.021743 -220.597108)
			(xy 334.994045 -220.555232) (xy 334.972741 -220.509768) (xy 334.958286 -220.461687) (xy 334.950987 -220.412014)
			(xy 334.950562 -220.38691) (xy 334.95109 -220.359923) (xy 334.959532 -220.306615) (xy 334.976208 -220.255283)
			(xy 335.000709 -220.207191) (xy 335.032432 -220.163524) (xy 335.070594 -220.125358) (xy 335.114257 -220.09363)
			(xy 335.162346 -220.069124) (xy 335.213676 -220.052441) (xy 335.266984 -220.043994) (xy 335.29397 -220.043502)
			(xy 335.29397 -220.043248) (xy 335.320152 -220.043739) (xy 335.371909 -220.051685) (xy 335.42186 -220.067399)
			(xy 335.468845 -220.090514) (xy 335.511776 -220.120496) (xy 335.549657 -220.156649) (xy 335.566004 -220.177106)
			(xy 335.569306 -220.181424) (xy 335.573878 -220.185234) (xy 335.582768 -220.191076) (xy 335.60385 -220.201998)
			(xy 335.609025 -220.204257) (xy 335.620049 -220.20669) (xy 335.625694 -220.206824) (xy 335.715356 -220.206824)
			(xy 335.721794 -220.206632) (xy 335.734263 -220.203414) (xy 335.739994 -220.200474) (xy 335.760568 -220.189044)
			(xy 335.778094 -220.173042) (xy 335.79379 -220.150694) (xy 335.83054 -220.110301) (xy 335.872672 -220.075557)
			(xy 335.919324 -220.04717) (xy 335.969544 -220.025721) (xy 336.022309 -220.011646) (xy 336.049366 -220.007942)
			(xy 336.060034 -220.006672) (xy 336.09407 -220.005148) (xy 336.119718 -220.005582) (xy 336.170547 -220.012489)
			(xy 336.219993 -220.026142) (xy 336.267165 -220.046295) (xy 336.311212 -220.072585) (xy 336.351341 -220.104538)
			(xy 336.369406 -220.12275) (xy 336.376518 -220.129862) (xy 336.403442 -220.1418) (xy 336.408221 -220.143783)
			(xy 336.418336 -220.145961) (xy 336.423508 -220.146118) (xy 336.619342 -220.146118) (xy 336.624096 -220.146025)
			(xy 336.633436 -220.144242) (xy 336.637884 -220.142562) (xy 336.662776 -220.13291) (xy 336.667602 -220.128846)
			(xy 336.669126 -220.127322) (xy 336.669634 -220.127068) (xy 336.688444 -220.111392) (xy 336.729668 -220.084971)
			(xy 336.774228 -220.064674) (xy 336.821219 -220.050913) (xy 336.869688 -220.043967) (xy 336.89417 -220.043502)
			(xy 336.921159 -220.044002) (xy 336.974472 -220.052441) (xy 337.025808 -220.069118) (xy 337.073903 -220.09362)
			(xy 337.117573 -220.125346) (xy 337.155741 -220.163512) (xy 337.187469 -220.20718) (xy 337.211974 -220.255274)
			(xy 337.228654 -220.306609) (xy 337.237097 -220.359921) (xy 337.237578 -220.38691) (xy 337.237144 -220.411407)
			(xy 337.230189 -220.459904) (xy 337.216421 -220.506923) (xy 337.196119 -220.551512) (xy 337.169694 -220.592768)
			(xy 337.13768 -220.629856) (xy 337.119468 -220.646244) (xy 337.096862 -220.666056) (xy 337.09483 -220.673422)
			(xy 337.099656 -220.6879) (xy 337.100418 -220.689932) (xy 337.103466 -220.698314) (xy 337.134962 -220.780356)
			(xy 337.136994 -220.784674) (xy 337.141674 -220.792529) (xy 337.155451 -220.804533) (xy 337.172562 -220.810942)
			(xy 337.181698 -220.811344) (xy 337.406488 -220.811344) (xy 337.415629 -220.810965) (xy 337.432751 -220.804557)
			(xy 337.446537 -220.792549) (xy 337.451192 -220.784674) (xy 337.453224 -220.780356) (xy 337.48472 -220.698314)
			(xy 337.487768 -220.689932) (xy 337.48853 -220.6879) (xy 337.493356 -220.673422) (xy 337.491324 -220.666056)
			(xy 337.468718 -220.646244) (xy 337.450515 -220.629842) (xy 337.418482 -220.592768) (xy 337.392041 -220.551519)
			(xy 337.37173 -220.506931) (xy 337.35796 -220.459909) (xy 337.351011 -220.411408) (xy 337.350608 -220.38691)
			(xy 337.351088 -220.361211) (xy 337.358749 -220.310387) (xy 337.373898 -220.261273) (xy 337.396199 -220.214965)
			(xy 337.425152 -220.172498) (xy 337.460112 -220.134821) (xy 337.500296 -220.102775) (xy 337.544808 -220.077076)
			(xy 337.592653 -220.058299) (xy 337.642762 -220.046861) (xy 337.694016 -220.043021) (xy 337.74527 -220.046861)
			(xy 337.795379 -220.058299) (xy 337.843224 -220.077076) (xy 337.887736 -220.102775) (xy 337.92792 -220.134821)
			(xy 337.96288 -220.172498) (xy 337.991833 -220.214965) (xy 338.014134 -220.261273) (xy 338.029283 -220.310387)
			(xy 338.036944 -220.361211) (xy 338.037424 -220.38691) (xy 338.03699 -220.411406) (xy 338.030034 -220.459902)
			(xy 338.016264 -220.50692) (xy 337.99596 -220.551507) (xy 337.969532 -220.592761) (xy 337.937516 -220.629845)
			(xy 337.919314 -220.646244) (xy 337.896708 -220.666056) (xy 337.894676 -220.673422) (xy 337.899502 -220.6879)
			(xy 337.900264 -220.689932) (xy 337.903312 -220.698314) (xy 337.934808 -220.780356) (xy 337.93684 -220.784674)
			(xy 337.941522 -220.792524) (xy 337.955301 -220.804516) (xy 337.972411 -220.81091) (xy 337.981544 -220.811344)
			(xy 338.206588 -220.811344) (xy 338.215729 -220.810965) (xy 338.232851 -220.804557) (xy 338.246637 -220.792549)
			(xy 338.251292 -220.784674) (xy 338.253324 -220.780356) (xy 338.28482 -220.698314) (xy 338.287868 -220.689932)
			(xy 338.28863 -220.6879) (xy 338.293456 -220.673422) (xy 338.291424 -220.666056) (xy 338.268818 -220.646244)
			(xy 338.250615 -220.629842) (xy 338.218582 -220.592768) (xy 338.192141 -220.551519) (xy 338.17183 -220.506931)
			(xy 338.15806 -220.459909) (xy 338.151111 -220.411408) (xy 338.150708 -220.38691) (xy 338.151188 -220.361211)
			(xy 338.158849 -220.310387) (xy 338.173998 -220.261273) (xy 338.196299 -220.214965) (xy 338.225252 -220.172498)
			(xy 338.260212 -220.134821) (xy 338.300396 -220.102775) (xy 338.344908 -220.077076) (xy 338.392753 -220.058299)
			(xy 338.442862 -220.046861) (xy 338.494116 -220.043021) (xy 338.54537 -220.046861) (xy 338.595479 -220.058299)
			(xy 338.643324 -220.077076) (xy 338.687836 -220.102775) (xy 338.72802 -220.134821) (xy 338.76298 -220.172498)
			(xy 338.791933 -220.214965) (xy 338.814234 -220.261273) (xy 338.829383 -220.310387) (xy 338.837044 -220.361211)
			(xy 338.837524 -220.38691) (xy 338.83709 -220.411406) (xy 338.830134 -220.459902) (xy 338.816364 -220.50692)
			(xy 338.79606 -220.551507) (xy 338.769632 -220.592761) (xy 338.737616 -220.629845) (xy 338.719414 -220.646244)
			(xy 338.696808 -220.666056) (xy 338.694776 -220.673422) (xy 338.699602 -220.6879) (xy 338.700364 -220.689932)
			(xy 338.703412 -220.698314) (xy 338.734908 -220.780356) (xy 338.73694 -220.784674) (xy 338.741622 -220.792524)
			(xy 338.755401 -220.804516) (xy 338.772511 -220.81091) (xy 338.781644 -220.811344) (xy 339.041486 -220.811344)
			(xy 339.045804 -220.81109) (xy 339.053772 -220.809882) (xy 339.068404 -220.803147) (xy 339.074506 -220.797882)
			(xy 339.075014 -220.797374) (xy 339.075522 -220.796866) (xy 339.08111 -220.791278) (xy 339.101474 -220.771844)
			(xy 339.147915 -220.740049) (xy 339.199407 -220.717326) (xy 339.226652 -220.710252) (xy 339.243241 -220.706575)
			(xy 339.276975 -220.702506) (xy 339.293962 -220.702124) (xy 339.294216 -220.702124) (xy 339.30463 -220.70187)
			(xy 339.313266 -220.698314) (xy 339.317629 -220.696336) (xy 339.325564 -220.69097) (xy 339.329014 -220.687646)
			(xy 339.358224 -220.658436) (xy 339.358224 -220.648022) (xy 339.520276 -220.48597) (xy 339.522983 -220.483191)
			(xy 339.527572 -220.476935) (xy 339.52942 -220.473524) (xy 339.531717 -220.468801) (xy 339.53454 -220.458688)
			(xy 339.535008 -220.453458) (xy 339.535008 -220.263212) (xy 339.535429 -220.253141) (xy 339.543141 -220.234534)
			(xy 339.549994 -220.227144) (xy 339.58784 -220.189298) (xy 339.595241 -220.182458) (xy 339.613839 -220.174739)
			(xy 339.623908 -220.174312) (xy 339.772752 -220.174312) (xy 339.78215 -220.173296) (xy 339.782658 -220.173296)
			(xy 339.791802 -220.170502) (xy 339.822028 -220.156786) (xy 339.828886 -220.148912) (xy 339.84184 -220.13545)
			(xy 339.842348 -220.134942) (xy 339.861144 -220.117416) (xy 339.869018 -220.110558) (xy 339.880194 -220.087952)
			(xy 339.882654 -220.082626) (xy 339.885346 -220.07121) (xy 339.885528 -220.065346) (xy 339.885528 -219.254578)
			(xy 339.884628 -219.245153) (xy 339.876791 -219.227933) (xy 339.870288 -219.22105) (xy 339.862668 -219.2147)
			(xy 339.861144 -219.213938) (xy 339.819234 -219.192856) (xy 339.809328 -219.18803) (xy 339.80374 -219.182442)
			(xy 339.803232 -219.181934) (xy 339.789262 -219.16771) (xy 339.788754 -219.167202) (xy 339.779356 -219.157804)
			(xy 339.778848 -219.157296) (xy 339.765894 -219.143834) (xy 339.762592 -219.140532) (xy 339.744942 -219.121911)
			(xy 339.715523 -219.079884) (xy 339.693577 -219.033514) (xy 339.686138 -219.00896) (xy 339.682836 -218.998292)
			(xy 339.669882 -218.98864) (xy 339.66444 -218.984748) (xy 339.652093 -218.979608) (xy 339.645498 -218.97848)
			(xy 339.60562 -218.97848) (xy 339.5472 -218.886532) (xy 339.5472 -218.729306) (xy 339.546321 -218.724699)
			(xy 339.543122 -218.715884) (xy 339.54085 -218.71178) (xy 339.54085 -218.711272) (xy 339.535008 -218.703144)
			(xy 339.532722 -218.700604) (xy 339.401404 -218.569286) (xy 339.396181 -218.56443) (xy 339.383674 -218.557595)
			(xy 339.376766 -218.555824) (xy 339.370162 -218.554554) (xy 339.369654 -218.554554) (xy 339.367368 -218.5543)
			(xy 338.906104 -218.5543) (xy 338.899064 -218.554521) (xy 338.885525 -218.558383) (xy 338.879434 -218.56192)
			(xy 338.875453 -218.564513) (xy 338.86842 -218.570901) (xy 338.865464 -218.57462) (xy 338.863432 -218.577414)
			(xy 338.82584 -218.62923) (xy 338.823709 -218.632299) (xy 338.820271 -218.638931) (xy 338.818982 -218.642438)
			(xy 338.818982 -218.675204) (xy 338.819744 -218.677744) (xy 338.828055 -218.70428) (xy 338.836988 -218.759162)
			(xy 338.837524 -218.786964) (xy 338.837524 -218.793314) (xy 338.836551 -218.819988) (xy 338.82737 -218.872565)
			(xy 338.810165 -218.923089) (xy 338.785349 -218.970343) (xy 338.753521 -219.013188) (xy 338.715447 -219.050591)
			(xy 338.672043 -219.081654) (xy 338.624357 -219.105626) (xy 338.573535 -219.121932) (xy 338.520803 -219.130177)
			(xy 338.494116 -219.130626) (xy 338.46713 -219.130098) (xy 338.413821 -219.121657) (xy 338.362489 -219.104981)
			(xy 338.314397 -219.08048) (xy 338.270731 -219.048758) (xy 338.232564 -219.010595) (xy 338.200838 -218.966932)
			(xy 338.176332 -218.918843) (xy 338.159651 -218.867512) (xy 338.151205 -218.814204) (xy 338.150708 -218.787218)
			(xy 338.151273 -218.758673) (xy 338.160717 -218.702369) (xy 338.169504 -218.675204) (xy 338.176362 -218.655392)
			(xy 338.177124 -218.652852) (xy 338.177632 -218.651836) (xy 338.17179 -218.641676) (xy 338.12353 -218.575382)
			(xy 338.119212 -218.569794) (xy 338.112689 -218.563545) (xy 338.096418 -218.555727) (xy 338.087462 -218.554554)
			(xy 338.082382 -218.5543) (xy 338.057998 -218.5543) (xy 338.049362 -218.555062) (xy 338.038651 -218.557507)
			(xy 338.020623 -218.570025) (xy 338.014564 -218.579192) (xy 337.99907 -218.604846) (xy 337.99399 -218.618054)
			(xy 338.004404 -218.640152) (xy 338.01477 -218.663048) (xy 338.029429 -218.711121) (xy 338.036902 -218.76082)
			(xy 338.037424 -218.785948) (xy 338.037424 -218.792552) (xy 338.036499 -218.81926) (xy 338.027399 -218.871917)
			(xy 338.010251 -218.922528) (xy 337.985469 -218.969872) (xy 337.953652 -219.012805) (xy 337.915568 -219.050291)
			(xy 337.872136 -219.081424) (xy 337.824406 -219.105453) (xy 337.773529 -219.121798) (xy 337.720735 -219.130064)
			(xy 337.694016 -219.130626) (xy 337.66703 -219.130098) (xy 337.613721 -219.121657) (xy 337.562389 -219.104981)
			(xy 337.514297 -219.08048) (xy 337.470631 -219.048758) (xy 337.432464 -219.010595) (xy 337.400738 -218.966932)
			(xy 337.376232 -218.918843) (xy 337.359551 -218.867512) (xy 337.351105 -218.814204) (xy 337.350608 -218.787218)
			(xy 337.351173 -218.758673) (xy 337.360617 -218.702369) (xy 337.369404 -218.675204) (xy 337.376262 -218.655392)
			(xy 337.377024 -218.652852) (xy 337.377532 -218.651836) (xy 337.37169 -218.641676) (xy 337.32343 -218.575382)
			(xy 337.319112 -218.569794) (xy 337.312589 -218.563545) (xy 337.296318 -218.555727) (xy 337.287362 -218.554554)
			(xy 337.282282 -218.5543) (xy 337.258152 -218.5543) (xy 337.249516 -218.555062) (xy 337.238798 -218.557498)
			(xy 337.220754 -218.570007) (xy 337.214718 -218.579192) (xy 337.199224 -218.604846) (xy 337.194144 -218.618054)
			(xy 337.204558 -218.640152) (xy 337.214925 -218.663047) (xy 337.229587 -218.71112) (xy 337.23706 -218.76082)
			(xy 337.237578 -218.785948) (xy 337.237578 -218.792552) (xy 337.236653 -218.819261) (xy 337.227553 -218.871921)
			(xy 337.210406 -218.922536) (xy 337.185625 -218.969884) (xy 337.153809 -219.012822) (xy 337.115726 -219.050313)
			(xy 337.072295 -219.081452) (xy 337.024564 -219.105488) (xy 336.973687 -219.12184) (xy 336.92089 -219.130114)
			(xy 336.89417 -219.130626) (xy 336.867186 -219.130095) (xy 336.813883 -219.121648) (xy 336.762557 -219.104968)
			(xy 336.714472 -219.080465) (xy 336.670811 -219.048741) (xy 336.632651 -219.010579) (xy 336.600929 -218.966918)
			(xy 336.576427 -218.918832) (xy 336.559749 -218.867506) (xy 336.551305 -218.814202) (xy 336.550762 -218.787218)
			(xy 336.551327 -218.758673) (xy 336.56077 -218.702369) (xy 336.569558 -218.675204) (xy 336.576416 -218.655392)
			(xy 336.577178 -218.652852) (xy 336.577686 -218.651836) (xy 336.571844 -218.641676) (xy 336.523584 -218.575382)
			(xy 336.519266 -218.569794) (xy 336.51274 -218.563551) (xy 336.496468 -218.555748) (xy 336.487516 -218.554554)
			(xy 336.482436 -218.5543) (xy 336.458052 -218.5543) (xy 336.449416 -218.555062) (xy 336.438698 -218.557498)
			(xy 336.420654 -218.570007) (xy 336.414618 -218.579192) (xy 336.399124 -218.604846) (xy 336.394044 -218.618054)
			(xy 336.404458 -218.640152) (xy 336.414825 -218.663047) (xy 336.429487 -218.71112) (xy 336.43696 -218.76082)
			(xy 336.437478 -218.785948) (xy 336.437478 -218.792552) (xy 336.436619 -218.818837) (xy 336.427836 -218.870688)
			(xy 336.411234 -218.920588) (xy 336.399632 -218.94419) (xy 336.398616 -218.945714) (xy 336.397092 -218.948508)
			(xy 336.396584 -218.949524) (xy 336.38236 -218.973654) (xy 336.382614 -218.973654) (xy 336.367705 -218.995772)
			(xy 336.332161 -219.035541) (xy 336.290899 -219.06934) (xy 336.244909 -219.096358) (xy 336.195298 -219.115945)
			(xy 336.143256 -219.127631) (xy 336.116676 -219.129864) (xy 336.10296 -219.131134) (xy 336.096864 -219.13596)
			(xy 336.07883 -219.154756) (xy 336.07342 -219.16152) (xy 336.067054 -219.177617) (xy 336.066384 -219.186252)
			(xy 336.066384 -219.361258) (xy 336.06595 -219.371323) (xy 336.058219 -219.389911) (xy 336.051398 -219.397326)
			(xy 335.872328 -219.576396) (xy 335.86492 -219.583085) (xy 335.846484 -219.590678) (xy 335.836514 -219.591128)
			(xy 335.582514 -219.591128) (xy 335.572553 -219.590639) (xy 335.554131 -219.583049) (xy 335.5467 -219.576396)
			(xy 335.391506 -219.421202) (xy 335.387777 -219.417678) (xy 335.379205 -219.412044) (xy 335.374488 -219.410026)
			(xy 335.365852 -219.40647) (xy 335.192878 -219.40647) (xy 335.18281 -219.406042) (xy 335.164214 -219.398319)
			(xy 335.15681 -219.391484) (xy 335.127854 -219.362528) (xy 335.121013 -219.355128) (xy 335.113296 -219.336529)
			(xy 335.112868 -219.32646) (xy 335.112868 -219.165932) (xy 335.113371 -219.15588) (xy 335.121089 -219.137316)
			(xy 335.127854 -219.129864) (xy 335.161382 -219.096336) (xy 335.168783 -219.089498) (xy 335.187382 -219.081788)
			(xy 335.19745 -219.08135) (xy 335.336896 -219.08135) (xy 335.345024 -219.080588) (xy 335.345532 -219.080588)
			(xy 335.35305 -219.078987) (xy 335.366737 -219.072009) (xy 335.372456 -219.066872) (xy 335.5467 -218.892628)
			(xy 335.554108 -218.885941) (xy 335.572545 -218.878355) (xy 335.582514 -218.877896) (xy 335.64068 -218.877896)
			(xy 335.646689 -218.877725) (xy 335.658368 -218.874895) (xy 335.663794 -218.872308) (xy 335.6737 -218.865704)
			(xy 335.737454 -218.802204) (xy 335.742788 -218.7956) (xy 335.742788 -218.795092) (xy 335.746197 -218.789666)
			(xy 335.750448 -218.777582) (xy 335.75117 -218.771216) (xy 335.75117 -218.769946) (xy 335.752795 -218.745846)
			(xy 335.761974 -218.698424) (xy 335.769458 -218.675458) (xy 335.777586 -218.651836) (xy 335.77149 -218.641422)
			(xy 335.723738 -218.575382) (xy 335.718404 -218.569286) (xy 335.71815 -218.569032) (xy 335.711871 -218.563297)
			(xy 335.696575 -218.555893) (xy 335.688178 -218.554554) (xy 335.687416 -218.554554) (xy 335.682336 -218.5543)
			(xy 334.906112 -218.5543) (xy 334.899072 -218.55452) (xy 334.885531 -218.55838) (xy 334.879442 -218.56192)
			(xy 334.875465 -218.564518) (xy 334.868443 -218.570913) (xy 334.865472 -218.57462) (xy 334.816704 -218.641676)
			(xy 334.811624 -218.650058) (xy 334.80756 -218.663266) (xy 334.805528 -218.67495) (xy 334.809338 -218.686888)
			(xy 334.816462 -218.710841) (xy 334.82424 -218.760203) (xy 334.824832 -218.785186) (xy 334.824832 -218.791536)
			(xy 334.824001 -218.817298) (xy 334.815337 -218.868106) (xy 334.798894 -218.916954) (xy 334.775071 -218.96266)
			(xy 334.744445 -219.004115) (xy 334.707757 -219.040317) (xy 334.665896 -219.070387) (xy 334.619877 -219.093598)
			(xy 334.570814 -219.109388) (xy 334.519895 -219.117373) (xy 334.494124 -219.117926) (xy 334.468404 -219.117432)
			(xy 334.417585 -219.109458) (xy 334.368612 -219.093714) (xy 334.322667 -219.07058) (xy 334.280856 -219.040613)
			(xy 334.244187 -219.004536) (xy 334.213545 -218.963217) (xy 334.189667 -218.917654) (xy 334.17313 -218.868944)
			(xy 334.164331 -218.818261) (xy 334.163416 -218.792552) (xy 334.163416 -218.78671) (xy 334.163923 -218.761345)
			(xy 334.171706 -218.711214) (xy 334.17891 -218.686888) (xy 334.180688 -218.681046) (xy 334.182072 -218.671178)
			(xy 334.178032 -218.651687) (xy 334.172814 -218.6432) (xy 334.158336 -218.623134) (xy 334.123538 -218.575382)
			(xy 334.11922 -218.569794) (xy 334.112697 -218.563544) (xy 334.096427 -218.555723) (xy 334.08747 -218.554554)
			(xy 334.08239 -218.5543) (xy 334.058514 -218.5543) (xy 334.049721 -218.554666) (xy 334.033172 -218.560612)
			(xy 334.019612 -218.571808) (xy 334.014826 -218.579192) (xy 333.999078 -218.605608) (xy 333.995764 -218.611634)
			(xy 333.992151 -218.624896) (xy 333.991966 -218.63177) (xy 333.993998 -218.641422) (xy 333.996284 -218.65209)
			(xy 333.998316 -218.656662) (xy 334.006688 -218.677264) (xy 334.01846 -218.720148) (xy 334.024389 -218.764221)
			(xy 334.024732 -218.786456) (xy 334.024732 -218.793822) (xy 334.02372 -218.819456) (xy 334.014754 -218.869967)
			(xy 333.998096 -218.918487) (xy 333.974146 -218.963853) (xy 333.943478 -219.004976) (xy 333.906827 -219.04087)
			(xy 333.865073 -219.070674) (xy 333.819217 -219.093673) (xy 333.77036 -219.109315) (xy 333.719674 -219.117225)
			(xy 333.694024 -219.117672) (xy 333.668249 -219.117181) (xy 333.617324 -219.109188) (xy 333.568255 -219.093391)
			(xy 333.52223 -219.070173) (xy 333.480365 -219.040097) (xy 333.443672 -219.00389) (xy 333.41304 -218.962429)
			(xy 333.389211 -218.916718) (xy 333.372762 -218.867863) (xy 333.364091 -218.817049) (xy 333.363316 -218.791282)
			(xy 333.363316 -218.786456) (xy 333.363835 -218.761946) (xy 333.371233 -218.713485) (xy 333.378048 -218.689936)
			(xy 333.37881 -218.686634) (xy 333.37881 -218.68638) (xy 333.379064 -218.685618) (xy 333.382366 -218.675204)
			(xy 333.380588 -218.66352) (xy 333.379468 -218.657641) (xy 333.374836 -218.646608) (xy 333.371444 -218.641676)
			(xy 333.35214 -218.615006) (xy 333.322168 -218.573858) (xy 333.319374 -218.570556) (xy 333.317088 -218.56827)
			(xy 333.310808 -218.562753) (xy 333.295643 -218.55575) (xy 333.28737 -218.554554) (xy 333.282544 -218.5543)
			(xy 332.55458 -218.5543) (xy 332.544511 -218.553873) (xy 332.525912 -218.546154) (xy 332.518512 -218.539314)
			(xy 332.480412 -218.501214) (xy 332.470252 -218.497404) (xy 332.450437 -218.48939) (xy 332.413061 -218.468656)
			(xy 332.378932 -218.442925) (xy 332.363572 -218.428062) (xy 331.80274 -217.86723) (xy 331.79989 -217.864522)
			(xy 331.793514 -217.859925) (xy 331.79004 -217.858086) (xy 331.784613 -217.855505) (xy 331.772933 -217.852686)
			(xy 331.766926 -217.852498) (xy 331.638402 -217.852498) (xy 331.632394 -217.852671) (xy 331.620717 -217.855504)
			(xy 331.615288 -217.858086) (xy 331.611813 -217.859925) (xy 331.605433 -217.864517) (xy 331.602588 -217.86723)
			(xy 331.535532 -217.934286) (xy 331.532826 -217.937137) (xy 331.528231 -217.943514) (xy 331.526388 -217.946986)
			(xy 331.52381 -217.952414) (xy 331.520997 -217.964094) (xy 331.5208 -217.9701) (xy 331.5208 -218.11869)
			(xy 331.52334 -218.120468) (xy 331.52334 -218.29649) (xy 331.5208 -218.298268) (xy 331.5208 -218.613482)
			(xy 331.520362 -218.623546) (xy 331.512626 -218.642128) (xy 331.505814 -218.64955) (xy 330.978256 -219.177108)
			(xy 330.97555 -219.179959) (xy 330.970956 -219.186337) (xy 330.969112 -219.189808) (xy 330.966525 -219.195234)
			(xy 330.963692 -219.206914) (xy 330.963524 -219.212922) (xy 330.963524 -219.803218) (xy 330.963778 -219.808044)
			(xy 330.963778 -219.808298) (xy 330.964733 -219.815026) (xy 330.969753 -219.827648) (xy 330.973684 -219.83319)
			(xy 330.978256 -219.838524) (xy 331.012038 -219.872306) (xy 331.018381 -219.878196) (xy 331.033962 -219.885714)
			(xy 331.042518 -219.887038) (xy 331.045312 -219.887292) (xy 331.474572 -219.887292) (xy 331.501937 -219.887884)
			(xy 331.555838 -219.897373) (xy 331.607275 -219.916068) (xy 331.63129 -219.929202) (xy 331.632306 -219.929964)
			(xy 331.633576 -219.930472) (xy 331.64272 -219.934536) (xy 331.646022 -219.935806) (xy 331.648816 -219.936568)
			(xy 331.65923 -219.939616) (xy 331.6732 -219.941648) (xy 332.694534 -219.941648) (xy 332.702662 -219.940886)
			(xy 332.715616 -219.938346) (xy 332.733214 -219.919064) (xy 332.772906 -219.885158) (xy 332.816982 -219.857186)
			(xy 332.864561 -219.835705) (xy 332.914692 -219.821146) (xy 332.966375 -219.813798) (xy 332.992476 -219.813378)
			(xy 333.018823 -219.813824) (xy 333.070982 -219.82132) (xy 333.121542 -219.836162) (xy 333.169476 -219.85805)
			(xy 333.213807 -219.886536) (xy 333.253632 -219.921041) (xy 333.288141 -219.960863) (xy 333.316632 -220.005191)
			(xy 333.338524 -220.053122) (xy 333.353372 -220.103681) (xy 333.360873 -220.155839) (xy 333.361284 -220.182186)
			(xy 333.360817 -220.209139) (xy 333.352967 -220.262471) (xy 333.337432 -220.314091) (xy 333.314544 -220.362898)
			(xy 333.30007 -220.38564) (xy 333.29499 -220.393514) (xy 333.292958 -220.40215) (xy 333.291989 -220.40685)
			(xy 333.29166 -220.415104) (xy 333.575152 -220.415104) (xy 333.575152 -220.189552) (xy 333.575591 -220.179484)
			(xy 333.583301 -220.160885) (xy 333.590138 -220.153484) (xy 333.73695 -220.006926) (xy 333.743764 -219.999505)
			(xy 333.751501 -219.980922) (xy 333.751936 -219.970858) (xy 333.751936 -219.817696) (xy 333.752155 -219.810512)
			(xy 333.756168 -219.796715) (xy 333.75981 -219.790518) (xy 333.79537 -219.734638) (xy 333.80023 -219.727601)
			(xy 333.813614 -219.716972) (xy 333.829751 -219.711344) (xy 333.838296 -219.711016) (xy 333.958438 -219.711016)
			(xy 333.96696 -219.711318) (xy 333.983072 -219.716873) (xy 333.996481 -219.727393) (xy 334.001364 -219.734384)
			(xy 334.037178 -219.790518) (xy 334.040809 -219.796719) (xy 334.044806 -219.810515) (xy 334.045052 -219.817696)
			(xy 334.045052 -219.971112) (xy 334.045457 -219.981184) (xy 334.05319 -219.999782) (xy 334.060038 -220.00718)
			(xy 334.098392 -220.045534) (xy 334.105797 -220.052368) (xy 334.124393 -220.06009) (xy 334.13446 -220.06052)
			(xy 334.386682 -220.06052) (xy 334.394048 -220.058488) (xy 334.418477 -220.051509) (xy 334.468722 -220.043981)
			(xy 334.494124 -220.043502) (xy 334.519822 -220.043964) (xy 334.570645 -220.051627) (xy 334.619758 -220.06678)
			(xy 334.666064 -220.089082) (xy 334.708529 -220.118037) (xy 334.746204 -220.152997) (xy 334.778248 -220.193182)
			(xy 334.803946 -220.237694) (xy 334.822722 -220.285538) (xy 334.834159 -220.335647) (xy 334.838 -220.3869)
			(xy 334.834159 -220.438153) (xy 334.822722 -220.488262) (xy 334.803946 -220.536106) (xy 334.778248 -220.580618)
			(xy 334.746204 -220.620803) (xy 334.708529 -220.655763) (xy 334.666064 -220.684718) (xy 334.619758 -220.70702)
			(xy 334.570645 -220.722173) (xy 334.519822 -220.729836) (xy 334.494124 -220.730318) (xy 334.46922 -220.729869)
			(xy 334.419936 -220.722658) (xy 334.372212 -220.7084) (xy 334.32705 -220.687392) (xy 334.285399 -220.660078)
			(xy 334.248134 -220.627029) (xy 334.216037 -220.588941) (xy 334.202532 -220.568012) (xy 334.197691 -220.560885)
			(xy 334.184217 -220.550162) (xy 334.167962 -220.544474) (xy 334.159352 -220.544136) (xy 334.134714 -220.544136)
			(xy 334.124644 -220.544559) (xy 334.106046 -220.55228) (xy 334.098646 -220.559122) (xy 334.047338 -220.61043)
			(xy 334.039922 -220.61725) (xy 334.021335 -220.624981) (xy 334.01127 -220.625416) (xy 333.785464 -220.625416)
			(xy 333.77539 -220.625032) (xy 333.756791 -220.617285) (xy 333.749396 -220.61043) (xy 333.590138 -220.451172)
			(xy 333.583299 -220.443771) (xy 333.575577 -220.425173) (xy 333.575152 -220.415104) (xy 333.29166 -220.415104)
			(xy 333.291607 -220.416437) (xy 333.292196 -220.4212) (xy 333.295752 -220.446346) (xy 333.295752 -220.446854)
			(xy 333.296435 -220.450811) (xy 333.29886 -220.458465) (xy 333.300578 -220.462094) (xy 333.313532 -220.486224)
			(xy 333.316326 -220.488764) (xy 333.32293 -220.49486) (xy 333.323692 -220.495622) (xy 333.3242 -220.49613)
			(xy 333.325216 -220.497146) (xy 333.325724 -220.497654) (xy 333.327502 -220.499432) (xy 333.693516 -220.865192)
			(xy 333.700926 -220.871875) (xy 333.719362 -220.879452) (xy 333.72933 -220.879924) (xy 334.488536 -220.879924)
		)
		(stroke
			(width 0)
			(type solid)
		)
		(fill yes)
		(layer "B.Cu")
		(net "P3V3_FPGA_VCCIO4")
	)
	(gr_poly
		(pts
			(xy 324.76948 -113.963958) (xy 324.800644 -113.953514) (xy 324.865397 -113.942281) (xy 324.898258 -113.941606)
			(xy 324.931118 -113.942291) (xy 324.99587 -113.953523) (xy 325.027036 -113.963958) (xy 325.035418 -113.967006)
			(xy 325.265288 -113.967006) (xy 325.291196 -113.94948) (xy 325.296784 -113.935002) (xy 325.307835 -113.908659)
			(xy 325.336609 -113.85931) (xy 325.372398 -113.814786) (xy 325.39305 -113.795048) (xy 325.400506 -113.787559)
			(xy 325.409062 -113.768264) (xy 325.40956 -113.75771) (xy 325.40956 -113.683034) (xy 325.408975 -113.672499)
			(xy 325.400444 -113.653224) (xy 325.39305 -113.645696) (xy 325.373989 -113.627546) (xy 325.340535 -113.586914)
			(xy 325.312977 -113.542072) (xy 325.29184 -113.49387) (xy 325.277523 -113.443223) (xy 325.270298 -113.391088)
			(xy 325.26986 -113.364772) (xy 325.270346 -113.337521) (xy 325.278102 -113.283573) (xy 325.293457 -113.231278)
			(xy 325.316099 -113.181701) (xy 325.345565 -113.135851) (xy 325.381256 -113.09466) (xy 325.422447 -113.058969)
			(xy 325.468297 -113.029503) (xy 325.517874 -113.006861) (xy 325.570169 -112.991506) (xy 325.624117 -112.98375)
			(xy 325.678619 -112.98375) (xy 325.732567 -112.991506) (xy 325.784862 -113.006861) (xy 325.834439 -113.029503)
			(xy 325.880289 -113.058969) (xy 325.92148 -113.09466) (xy 325.957171 -113.135851) (xy 325.986637 -113.181701)
			(xy 326.009279 -113.231278) (xy 326.024634 -113.283573) (xy 326.03239 -113.337521) (xy 326.032876 -113.364772)
			(xy 326.032456 -113.391092) (xy 326.025257 -113.443235) (xy 326.010953 -113.493893) (xy 325.989814 -113.5421)
			(xy 325.962243 -113.586941) (xy 325.928765 -113.627561) (xy 325.909686 -113.645696) (xy 325.902245 -113.653191)
			(xy 325.893717 -113.672486) (xy 325.893176 -113.683034) (xy 325.893176 -113.75771) (xy 325.893749 -113.768252)
			(xy 325.902257 -113.78755) (xy 325.909686 -113.795048) (xy 325.930372 -113.814756) (xy 325.966183 -113.859271)
			(xy 325.994937 -113.90864) (xy 326.005952 -113.935002) (xy 326.01154 -113.94948) (xy 326.037448 -113.967006)
			(xy 327.297288 -113.967006) (xy 327.323196 -113.94948) (xy 327.328784 -113.935002) (xy 327.339835 -113.908659)
			(xy 327.368609 -113.85931) (xy 327.404398 -113.814786) (xy 327.42505 -113.795048) (xy 327.432506 -113.787559)
			(xy 327.441062 -113.768264) (xy 327.44156 -113.75771) (xy 327.44156 -113.683034) (xy 327.440975 -113.672499)
			(xy 327.432444 -113.653224) (xy 327.42505 -113.645696) (xy 327.405989 -113.627546) (xy 327.372535 -113.586914)
			(xy 327.344977 -113.542072) (xy 327.32384 -113.49387) (xy 327.309523 -113.443223) (xy 327.302298 -113.391088)
			(xy 327.30186 -113.364772) (xy 327.302346 -113.337521) (xy 327.310102 -113.283573) (xy 327.325457 -113.231278)
			(xy 327.348099 -113.181701) (xy 327.377565 -113.135851) (xy 327.413256 -113.09466) (xy 327.454447 -113.058969)
			(xy 327.500297 -113.029503) (xy 327.549874 -113.006861) (xy 327.602169 -112.991506) (xy 327.656117 -112.98375)
			(xy 327.710619 -112.98375) (xy 327.764567 -112.991506) (xy 327.816862 -113.006861) (xy 327.866439 -113.029503)
			(xy 327.912289 -113.058969) (xy 327.95348 -113.09466) (xy 327.989171 -113.135851) (xy 328.018637 -113.181701)
			(xy 328.041279 -113.231278) (xy 328.056634 -113.283573) (xy 328.06439 -113.337521) (xy 328.064876 -113.364772)
			(xy 328.064456 -113.391092) (xy 328.057257 -113.443235) (xy 328.042953 -113.493893) (xy 328.021814 -113.5421)
			(xy 327.994243 -113.586941) (xy 327.960765 -113.627561) (xy 327.941686 -113.645696) (xy 327.934245 -113.653191)
			(xy 327.925717 -113.672486) (xy 327.925176 -113.683034) (xy 327.925176 -113.75771) (xy 327.925749 -113.768252)
			(xy 327.934257 -113.78755) (xy 327.941686 -113.795048) (xy 327.962372 -113.814756) (xy 327.998183 -113.859271)
			(xy 328.026937 -113.90864) (xy 328.037952 -113.935002) (xy 328.04354 -113.94948) (xy 328.069448 -113.967006)
			(xy 329.971654 -113.967006) (xy 329.98156 -113.962434) (xy 330.006305 -113.951814) (xy 330.058034 -113.936863)
			(xy 330.111354 -113.929346) (xy 330.138278 -113.928906) (xy 330.165201 -113.929351) (xy 330.218519 -113.936877)
			(xy 330.270252 -113.951813) (xy 330.294996 -113.962434) (xy 330.304902 -113.967006) (xy 332.509876 -113.967006)
			(xy 332.519782 -113.962434) (xy 332.544527 -113.951815) (xy 332.596257 -113.936867) (xy 332.649576 -113.929353)
			(xy 332.6765 -113.928906) (xy 332.703423 -113.929352) (xy 332.75674 -113.936882) (xy 332.808471 -113.95182)
			(xy 332.833218 -113.962434) (xy 332.843124 -113.967006) (xy 335.774792 -113.967006) (xy 335.784863 -113.966585)
			(xy 335.80347 -113.958873) (xy 335.81086 -113.95202) (xy 336.3976 -113.36528) (xy 336.405011 -113.358598)
			(xy 336.423446 -113.351019) (xy 336.433414 -113.350548) (xy 338.090764 -113.350548) (xy 338.10078 -113.350067)
			(xy 338.119292 -113.342415) (xy 338.133468 -113.328263) (xy 338.14115 -113.309763) (xy 338.141564 -113.299748)
			(xy 338.141564 -109.65561) (xy 338.141027 -109.645623) (xy 338.133312 -109.627191) (xy 338.126578 -109.619796)
			(xy 338.091272 -109.58449) (xy 338.083876 -109.577638) (xy 338.065277 -109.5699) (xy 338.055204 -109.569504)
			(xy 335.759552 -109.569504) (xy 335.749486 -109.569072) (xy 335.730894 -109.561346) (xy 335.723484 -109.554518)
			(xy 335.554066 -109.3851) (xy 335.547212 -109.377705) (xy 335.539467 -109.359106) (xy 335.53908 -109.349032)
			(xy 335.53908 -108.456984) (xy 335.538653 -108.446916) (xy 335.530933 -108.428317) (xy 335.524094 -108.420916)
			(xy 335.416144 -108.312966) (xy 335.408746 -108.306121) (xy 335.390147 -108.298397) (xy 335.380076 -108.29798)
			(xy 330.884022 -108.29798) (xy 330.873959 -108.297542) (xy 330.855377 -108.289806) (xy 330.847954 -108.282994)
			(xy 330.725526 -108.160566) (xy 330.718682 -108.153167) (xy 330.710956 -108.134569) (xy 330.71054 -108.124498)
			(xy 330.71054 -105.469182) (xy 330.709524 -105.468166) (xy 330.709524 -101.793294) (xy 330.709949 -101.783225)
			(xy 330.717667 -101.764624) (xy 330.72451 -101.757226) (xy 331.234288 -101.247448) (xy 331.241128 -101.240047)
			(xy 331.248845 -101.221449) (xy 331.249274 -101.21138) (xy 331.249274 -101.049328) (xy 331.248859 -101.039305)
			(xy 331.241193 -101.020783) (xy 331.227019 -101.006608) (xy 331.208497 -100.998942) (xy 331.198474 -100.998528)
			(xy 330.699618 -100.998528) (xy 330.689656 -100.99804) (xy 330.671234 -100.990451) (xy 330.663804 -100.983796)
			(xy 329.232006 -99.551998) (xy 329.225195 -99.544653) (xy 329.217462 -99.526191) (xy 329.21702 -99.516184)
			(xy 329.21702 -99.117658) (xy 329.216525 -99.107654) (xy 329.208859 -99.089173) (xy 329.194708 -99.075029)
			(xy 329.176224 -99.06737) (xy 329.16622 -99.066858) (xy 326.698864 -99.066858) (xy 326.689831 -99.067162)
			(xy 326.672859 -99.073337) (xy 326.659104 -99.085042) (xy 326.654414 -99.092766) (xy 326.604122 -99.18192)
			(xy 326.60463 -99.209098) (xy 326.611996 -99.221036) (xy 326.62772 -99.24801) (xy 326.652518 -99.305309)
			(xy 326.669299 -99.365447) (xy 326.677753 -99.427308) (xy 326.67829 -99.458526) (xy 326.6778 -99.488494)
			(xy 326.669977 -99.547916) (xy 326.654464 -99.605809) (xy 326.631528 -99.661182) (xy 326.601561 -99.713088)
			(xy 326.565074 -99.760638) (xy 326.522694 -99.803018) (xy 326.475144 -99.839505) (xy 326.423238 -99.869472)
			(xy 326.367865 -99.892408) (xy 326.309972 -99.907921) (xy 326.25055 -99.915744) (xy 326.190614 -99.915744)
			(xy 326.131192 -99.907921) (xy 326.073299 -99.892408) (xy 326.017926 -99.869472) (xy 325.96602 -99.839505)
			(xy 325.91847 -99.803018) (xy 325.87609 -99.760638) (xy 325.839603 -99.713088) (xy 325.809636 -99.661182)
			(xy 325.7867 -99.605809) (xy 325.771187 -99.547916) (xy 325.763364 -99.488494) (xy 325.762874 -99.458526)
			(xy 325.763382 -99.427306) (xy 325.77183 -99.36544) (xy 325.788612 -99.305298) (xy 325.813418 -99.247997)
			(xy 325.829168 -99.221036) (xy 325.836534 -99.209098) (xy 325.837042 -99.18192) (xy 325.78675 -99.092766)
			(xy 325.782003 -99.085088) (xy 325.768253 -99.07341) (xy 325.75132 -99.06719) (xy 325.7423 -99.066858)
			(xy 319.441576 -99.066858) (xy 319.431509 -99.067287) (xy 319.412916 -99.075014) (xy 319.405508 -99.081844)
			(xy 319.02527 -99.462082) (xy 319.018429 -99.469482) (xy 319.010713 -99.488081) (xy 319.010284 -99.49815)
			(xy 319.010284 -99.614482) (xy 322.539866 -99.614482) (xy 322.543937 -99.55886) (xy 322.556063 -99.504423)
			(xy 322.575986 -99.452332) (xy 322.603282 -99.403697) (xy 322.637368 -99.359554) (xy 322.677517 -99.320845)
			(xy 322.722875 -99.288394) (xy 322.772475 -99.262893) (xy 322.825259 -99.244886) (xy 322.880102 -99.234756)
			(xy 322.935836 -99.232719) (xy 322.991273 -99.238819) (xy 323.04523 -99.252925) (xy 323.096559 -99.274737)
			(xy 323.144165 -99.303791) (xy 323.187033 -99.339466) (xy 323.22425 -99.381003) (xy 323.255023 -99.427516)
			(xy 323.278695 -99.478013) (xy 323.294763 -99.53142) (xy 323.302883 -99.586596) (xy 323.303392 -99.614482)
			(xy 323.303183 -99.625912) (xy 323.706742 -99.625912) (xy 323.710813 -99.57029) (xy 323.722939 -99.515853)
			(xy 323.742862 -99.463762) (xy 323.770158 -99.415127) (xy 323.804244 -99.370984) (xy 323.844393 -99.332275)
			(xy 323.889751 -99.299824) (xy 323.939351 -99.274323) (xy 323.992135 -99.256316) (xy 324.046978 -99.246186)
			(xy 324.102712 -99.244149) (xy 324.158149 -99.250249) (xy 324.212106 -99.264355) (xy 324.263435 -99.286167)
			(xy 324.311041 -99.315221) (xy 324.353909 -99.350896) (xy 324.391126 -99.392433) (xy 324.421899 -99.438946)
			(xy 324.445571 -99.489443) (xy 324.461639 -99.54285) (xy 324.469759 -99.598026) (xy 324.470268 -99.625912)
			(xy 324.469759 -99.653798) (xy 324.461639 -99.708974) (xy 324.445571 -99.762381) (xy 324.421899 -99.812878)
			(xy 324.391126 -99.859391) (xy 324.353909 -99.900928) (xy 324.311041 -99.936603) (xy 324.263435 -99.965657)
			(xy 324.212106 -99.987469) (xy 324.158149 -100.001575) (xy 324.102712 -100.007675) (xy 324.046978 -100.005638)
			(xy 323.992135 -99.995508) (xy 323.939351 -99.977501) (xy 323.889751 -99.952) (xy 323.844393 -99.919549)
			(xy 323.804244 -99.88084) (xy 323.770158 -99.836697) (xy 323.742862 -99.788062) (xy 323.722939 -99.735971)
			(xy 323.710813 -99.681534) (xy 323.706742 -99.625912) (xy 323.303183 -99.625912) (xy 323.302883 -99.642368)
			(xy 323.294763 -99.697544) (xy 323.278695 -99.750951) (xy 323.255023 -99.801448) (xy 323.22425 -99.847961)
			(xy 323.187033 -99.889498) (xy 323.144165 -99.925173) (xy 323.096559 -99.954227) (xy 323.04523 -99.976039)
			(xy 322.991273 -99.990145) (xy 322.935836 -99.996245) (xy 322.880102 -99.994208) (xy 322.825259 -99.984078)
			(xy 322.772475 -99.966071) (xy 322.722875 -99.94057) (xy 322.677517 -99.908119) (xy 322.637368 -99.86941)
			(xy 322.603282 -99.825267) (xy 322.575986 -99.776632) (xy 322.556063 -99.724541) (xy 322.543937 -99.670104)
			(xy 322.539866 -99.614482) (xy 319.010284 -99.614482) (xy 319.010284 -100.392992) (xy 327.573892 -100.392992)
			(xy 327.577963 -100.33737) (xy 327.590089 -100.282933) (xy 327.610012 -100.230842) (xy 327.637308 -100.182207)
			(xy 327.671394 -100.138064) (xy 327.711543 -100.099355) (xy 327.756901 -100.066904) (xy 327.806501 -100.041403)
			(xy 327.859285 -100.023396) (xy 327.914128 -100.013266) (xy 327.969862 -100.011229) (xy 328.025299 -100.017329)
			(xy 328.079256 -100.031435) (xy 328.130585 -100.053247) (xy 328.178191 -100.082301) (xy 328.221059 -100.117976)
			(xy 328.258276 -100.159513) (xy 328.289049 -100.206026) (xy 328.312721 -100.256523) (xy 328.328789 -100.30993)
			(xy 328.336909 -100.365106) (xy 328.337418 -100.392992) (xy 328.336909 -100.420878) (xy 328.328789 -100.476054)
			(xy 328.312721 -100.529461) (xy 328.289049 -100.579958) (xy 328.258276 -100.626471) (xy 328.221059 -100.668008)
			(xy 328.178191 -100.703683) (xy 328.130585 -100.732737) (xy 328.079256 -100.754549) (xy 328.025299 -100.768655)
			(xy 327.969862 -100.774755) (xy 327.914128 -100.772718) (xy 327.859285 -100.762588) (xy 327.806501 -100.744581)
			(xy 327.756901 -100.71908) (xy 327.711543 -100.686629) (xy 327.671394 -100.64792) (xy 327.637308 -100.603777)
			(xy 327.610012 -100.555142) (xy 327.590089 -100.503051) (xy 327.577963 -100.448614) (xy 327.573892 -100.392992)
			(xy 319.010284 -100.392992) (xy 319.010284 -100.803964) (xy 322.551296 -100.803964) (xy 322.555367 -100.748342)
			(xy 322.567493 -100.693905) (xy 322.587416 -100.641814) (xy 322.614712 -100.593179) (xy 322.648798 -100.549036)
			(xy 322.688947 -100.510327) (xy 322.734305 -100.477876) (xy 322.783905 -100.452375) (xy 322.836689 -100.434368)
			(xy 322.891532 -100.424238) (xy 322.947266 -100.422201) (xy 323.002703 -100.428301) (xy 323.05666 -100.442407)
			(xy 323.107989 -100.464219) (xy 323.155595 -100.493273) (xy 323.198463 -100.528948) (xy 323.23568 -100.570485)
			(xy 323.266453 -100.616998) (xy 323.290125 -100.667495) (xy 323.306193 -100.720902) (xy 323.314313 -100.776078)
			(xy 323.314822 -100.803964) (xy 323.717918 -100.803964) (xy 323.721989 -100.748342) (xy 323.734115 -100.693905)
			(xy 323.754038 -100.641814) (xy 323.781334 -100.593179) (xy 323.81542 -100.549036) (xy 323.855569 -100.510327)
			(xy 323.900927 -100.477876) (xy 323.950527 -100.452375) (xy 324.003311 -100.434368) (xy 324.058154 -100.424238)
			(xy 324.113888 -100.422201) (xy 324.169325 -100.428301) (xy 324.223282 -100.442407) (xy 324.274611 -100.464219)
			(xy 324.322217 -100.493273) (xy 324.365085 -100.528948) (xy 324.402302 -100.570485) (xy 324.433075 -100.616998)
			(xy 324.456747 -100.667495) (xy 324.472815 -100.720902) (xy 324.480935 -100.776078) (xy 324.481444 -100.803964)
			(xy 324.480935 -100.83185) (xy 324.472815 -100.887026) (xy 324.456747 -100.940433) (xy 324.433075 -100.99093)
			(xy 324.402302 -101.037443) (xy 324.365085 -101.07898) (xy 324.322217 -101.114655) (xy 324.274611 -101.143709)
			(xy 324.223282 -101.165521) (xy 324.169325 -101.179627) (xy 324.113888 -101.185727) (xy 324.058154 -101.18369)
			(xy 324.003311 -101.17356) (xy 323.950527 -101.155553) (xy 323.900927 -101.130052) (xy 323.855569 -101.097601)
			(xy 323.81542 -101.058892) (xy 323.781334 -101.014749) (xy 323.754038 -100.966114) (xy 323.734115 -100.914023)
			(xy 323.721989 -100.859586) (xy 323.717918 -100.803964) (xy 323.314822 -100.803964) (xy 323.314313 -100.83185)
			(xy 323.306193 -100.887026) (xy 323.290125 -100.940433) (xy 323.266453 -100.99093) (xy 323.23568 -101.037443)
			(xy 323.198463 -101.07898) (xy 323.155595 -101.114655) (xy 323.107989 -101.143709) (xy 323.05666 -101.165521)
			(xy 323.002703 -101.179627) (xy 322.947266 -101.185727) (xy 322.891532 -101.18369) (xy 322.836689 -101.17356)
			(xy 322.783905 -101.155553) (xy 322.734305 -101.130052) (xy 322.688947 -101.097601) (xy 322.648798 -101.058892)
			(xy 322.614712 -101.014749) (xy 322.587416 -100.966114) (xy 322.567493 -100.914023) (xy 322.555367 -100.859586)
			(xy 322.551296 -100.803964) (xy 319.010284 -100.803964) (xy 319.010284 -101.60914) (xy 319.895456 -101.60914)
			(xy 319.895456 -101.549204) (xy 319.903279 -101.489782) (xy 319.918792 -101.431889) (xy 319.941728 -101.376516)
			(xy 319.971695 -101.32461) (xy 320.008182 -101.27706) (xy 320.050562 -101.23468) (xy 320.098112 -101.198193)
			(xy 320.150018 -101.168226) (xy 320.205391 -101.14529) (xy 320.263284 -101.129777) (xy 320.322706 -101.121954)
			(xy 320.382642 -101.121954) (xy 320.442064 -101.129777) (xy 320.499957 -101.14529) (xy 320.55533 -101.168226)
			(xy 320.607236 -101.198193) (xy 320.654786 -101.23468) (xy 320.697166 -101.27706) (xy 320.733653 -101.32461)
			(xy 320.76362 -101.376516) (xy 320.786556 -101.431889) (xy 320.802069 -101.489782) (xy 320.809892 -101.549204)
			(xy 320.810382 -101.579172) (xy 320.809892 -101.60914) (xy 320.802069 -101.668562) (xy 320.786556 -101.726455)
			(xy 320.76362 -101.781828) (xy 320.733653 -101.833734) (xy 320.705238 -101.870764) (xy 325.439022 -101.870764)
			(xy 325.443093 -101.815142) (xy 325.455219 -101.760705) (xy 325.475142 -101.708614) (xy 325.502438 -101.659979)
			(xy 325.536524 -101.615836) (xy 325.576673 -101.577127) (xy 325.622031 -101.544676) (xy 325.671631 -101.519175)
			(xy 325.724415 -101.501168) (xy 325.779258 -101.491038) (xy 325.834992 -101.489001) (xy 325.890429 -101.495101)
			(xy 325.944386 -101.509207) (xy 325.995715 -101.531019) (xy 326.043321 -101.560073) (xy 326.086189 -101.595748)
			(xy 326.123406 -101.637285) (xy 326.154179 -101.683798) (xy 326.177851 -101.734295) (xy 326.193919 -101.787702)
			(xy 326.202039 -101.842878) (xy 326.202548 -101.870764) (xy 326.202039 -101.89865) (xy 326.193919 -101.953826)
			(xy 326.177851 -102.007233) (xy 326.154179 -102.05773) (xy 326.123406 -102.104243) (xy 326.086189 -102.14578)
			(xy 326.043321 -102.181455) (xy 325.995715 -102.210509) (xy 325.944386 -102.232321) (xy 325.890429 -102.246427)
			(xy 325.834992 -102.252527) (xy 325.779258 -102.25049) (xy 325.724415 -102.24036) (xy 325.671631 -102.222353)
			(xy 325.622031 -102.196852) (xy 325.576673 -102.164401) (xy 325.536524 -102.125692) (xy 325.502438 -102.081549)
			(xy 325.475142 -102.032914) (xy 325.455219 -101.980823) (xy 325.443093 -101.926386) (xy 325.439022 -101.870764)
			(xy 320.705238 -101.870764) (xy 320.697166 -101.881284) (xy 320.654786 -101.923664) (xy 320.607236 -101.960151)
			(xy 320.55533 -101.990118) (xy 320.499957 -102.013054) (xy 320.442064 -102.028567) (xy 320.382642 -102.03639)
			(xy 320.322706 -102.03639) (xy 320.263284 -102.028567) (xy 320.205391 -102.013054) (xy 320.150018 -101.990118)
			(xy 320.098112 -101.960151) (xy 320.050562 -101.923664) (xy 320.008182 -101.881284) (xy 319.971695 -101.833734)
			(xy 319.941728 -101.781828) (xy 319.918792 -101.726455) (xy 319.903279 -101.668562) (xy 319.895456 -101.60914)
			(xy 319.010284 -101.60914) (xy 319.010284 -102.328218) (xy 323.57136 -102.328218) (xy 323.575431 -102.272596)
			(xy 323.587557 -102.218159) (xy 323.60748 -102.166068) (xy 323.634776 -102.117433) (xy 323.668862 -102.07329)
			(xy 323.709011 -102.034581) (xy 323.754369 -102.00213) (xy 323.803969 -101.976629) (xy 323.856753 -101.958622)
			(xy 323.911596 -101.948492) (xy 323.96733 -101.946455) (xy 324.022767 -101.952555) (xy 324.076724 -101.966661)
			(xy 324.128053 -101.988473) (xy 324.175659 -102.017527) (xy 324.218527 -102.053202) (xy 324.255744 -102.094739)
			(xy 324.286517 -102.141252) (xy 324.310189 -102.191749) (xy 324.326257 -102.245156) (xy 324.334377 -102.300332)
			(xy 324.334886 -102.328218) (xy 324.334377 -102.356104) (xy 324.326257 -102.41128) (xy 324.310189 -102.464687)
			(xy 324.286517 -102.515184) (xy 324.255744 -102.561697) (xy 324.218527 -102.603234) (xy 324.175659 -102.638909)
			(xy 324.128053 -102.667963) (xy 324.076724 -102.689775) (xy 324.022767 -102.703881) (xy 323.96733 -102.709981)
			(xy 323.911596 -102.707944) (xy 323.856753 -102.697814) (xy 323.803969 -102.679807) (xy 323.754369 -102.654306)
			(xy 323.709011 -102.621855) (xy 323.668862 -102.583146) (xy 323.634776 -102.539003) (xy 323.60748 -102.490368)
			(xy 323.587557 -102.438277) (xy 323.575431 -102.38384) (xy 323.57136 -102.328218) (xy 319.010284 -102.328218)
			(xy 319.010284 -102.700328) (xy 319.010712 -102.710396) (xy 319.018431 -102.728995) (xy 319.02527 -102.736396)
			(xy 319.458082 -103.169208) (xy 321.6318 -103.169208) (xy 321.6318 -103.109272) (xy 321.639623 -103.04985)
			(xy 321.655136 -102.991957) (xy 321.678072 -102.936584) (xy 321.708039 -102.884678) (xy 321.744526 -102.837128)
			(xy 321.786906 -102.794748) (xy 321.834456 -102.758261) (xy 321.886362 -102.728294) (xy 321.941735 -102.705358)
			(xy 321.999628 -102.689845) (xy 322.05905 -102.682022) (xy 322.118986 -102.682022) (xy 322.178408 -102.689845)
			(xy 322.236301 -102.705358) (xy 322.291674 -102.728294) (xy 322.34358 -102.758261) (xy 322.39113 -102.794748)
			(xy 322.43351 -102.837128) (xy 322.469997 -102.884678) (xy 322.499964 -102.936584) (xy 322.5229 -102.991957)
			(xy 322.538413 -103.04985) (xy 322.546236 -103.109272) (xy 322.546726 -103.13924) (xy 322.546236 -103.169208)
			(xy 322.538413 -103.22863) (xy 322.5229 -103.286523) (xy 322.499964 -103.341896) (xy 322.469997 -103.393802)
			(xy 322.43351 -103.441352) (xy 322.39113 -103.483732) (xy 322.34358 -103.520219) (xy 322.291674 -103.550186)
			(xy 322.236301 -103.573122) (xy 322.178408 -103.588635) (xy 322.118986 -103.596458) (xy 322.05905 -103.596458)
			(xy 321.999628 -103.588635) (xy 321.941735 -103.573122) (xy 321.886362 -103.550186) (xy 321.834456 -103.520219)
			(xy 321.786906 -103.483732) (xy 321.744526 -103.441352) (xy 321.708039 -103.393802) (xy 321.678072 -103.341896)
			(xy 321.655136 -103.286523) (xy 321.639623 -103.22863) (xy 321.6318 -103.169208) (xy 319.458082 -103.169208)
			(xy 320.002154 -103.71328) (xy 320.009555 -103.72012) (xy 320.028153 -103.727838) (xy 320.038222 -103.728266)
			(xy 322.431664 -103.728266) (xy 322.441728 -103.728703) (xy 322.460309 -103.736441) (xy 322.467732 -103.743252)
			(xy 322.618608 -103.894128) (xy 324.413878 -103.894128) (xy 324.417949 -103.838506) (xy 324.430075 -103.784069)
			(xy 324.449998 -103.731978) (xy 324.477294 -103.683343) (xy 324.51138 -103.6392) (xy 324.551529 -103.600491)
			(xy 324.596887 -103.56804) (xy 324.646487 -103.542539) (xy 324.699271 -103.524532) (xy 324.754114 -103.514402)
			(xy 324.809848 -103.512365) (xy 324.865285 -103.518465) (xy 324.919242 -103.532571) (xy 324.970571 -103.554383)
			(xy 325.018177 -103.583437) (xy 325.061045 -103.619112) (xy 325.098262 -103.660649) (xy 325.129035 -103.707162)
			(xy 325.152707 -103.757659) (xy 325.168775 -103.811066) (xy 325.176895 -103.866242) (xy 325.177404 -103.894128)
			(xy 325.176931 -103.920032) (xy 325.363822 -103.920032) (xy 325.363822 -103.860096) (xy 325.371645 -103.800674)
			(xy 325.387158 -103.742781) (xy 325.410094 -103.687408) (xy 325.440061 -103.635502) (xy 325.476548 -103.587952)
			(xy 325.518928 -103.545572) (xy 325.566478 -103.509085) (xy 325.618384 -103.479118) (xy 325.673757 -103.456182)
			(xy 325.73165 -103.440669) (xy 325.791072 -103.432846) (xy 325.851008 -103.432846) (xy 325.91043 -103.440669)
			(xy 325.968323 -103.456182) (xy 326.023696 -103.479118) (xy 326.075602 -103.509085) (xy 326.123152 -103.545572)
			(xy 326.165532 -103.587952) (xy 326.202019 -103.635502) (xy 326.231986 -103.687408) (xy 326.254922 -103.742781)
			(xy 326.270435 -103.800674) (xy 326.278258 -103.860096) (xy 326.278748 -103.890064) (xy 326.278258 -103.920032)
			(xy 326.270435 -103.979454) (xy 326.254922 -104.037347) (xy 326.231986 -104.09272) (xy 326.202019 -104.144626)
			(xy 326.165532 -104.192176) (xy 326.123152 -104.234556) (xy 326.075602 -104.271043) (xy 326.023696 -104.30101)
			(xy 325.968323 -104.323946) (xy 325.91043 -104.339459) (xy 325.851008 -104.347282) (xy 325.791072 -104.347282)
			(xy 325.73165 -104.339459) (xy 325.673757 -104.323946) (xy 325.618384 -104.30101) (xy 325.566478 -104.271043)
			(xy 325.518928 -104.234556) (xy 325.476548 -104.192176) (xy 325.440061 -104.144626) (xy 325.410094 -104.09272)
			(xy 325.387158 -104.037347) (xy 325.371645 -103.979454) (xy 325.363822 -103.920032) (xy 325.176931 -103.920032)
			(xy 325.176895 -103.922014) (xy 325.168775 -103.97719) (xy 325.152707 -104.030597) (xy 325.129035 -104.081094)
			(xy 325.098262 -104.127607) (xy 325.061045 -104.169144) (xy 325.018177 -104.204819) (xy 324.970571 -104.233873)
			(xy 324.919242 -104.255685) (xy 324.865285 -104.269791) (xy 324.809848 -104.275891) (xy 324.754114 -104.273854)
			(xy 324.699271 -104.263724) (xy 324.646487 -104.245717) (xy 324.596887 -104.220216) (xy 324.551529 -104.187765)
			(xy 324.51138 -104.149056) (xy 324.477294 -104.104913) (xy 324.449998 -104.056278) (xy 324.430075 -104.004187)
			(xy 324.417949 -103.94975) (xy 324.413878 -103.894128) (xy 322.618608 -103.894128) (xy 322.698618 -103.974138)
			(xy 322.705467 -103.981535) (xy 322.713201 -104.000134) (xy 322.713604 -104.010206) (xy 322.713604 -111.333026)
			(xy 322.714019 -111.342908) (xy 322.721418 -111.361231) (xy 322.735217 -111.375376) (xy 322.744084 -111.379762)
			(xy 322.843144 -111.423196) (xy 322.872862 -111.418116) (xy 322.884038 -111.407956) (xy 322.905286 -111.38906)
			(xy 322.952333 -111.35713) (xy 323.003601 -111.332541) (xy 323.057952 -111.31584) (xy 323.11418 -111.307397)
			(xy 323.14261 -111.306864) (xy 323.169862 -111.30735) (xy 323.22381 -111.315108) (xy 323.276105 -111.330464)
			(xy 323.325683 -111.353105) (xy 323.371534 -111.382571) (xy 323.412725 -111.418262) (xy 323.448418 -111.459452)
			(xy 323.477886 -111.505302) (xy 323.50053 -111.554878) (xy 323.515888 -111.607173) (xy 323.523648 -111.661121)
			(xy 323.524118 -111.688372) (xy 323.523697 -111.714691) (xy 323.516499 -111.766834) (xy 323.502192 -111.81749)
			(xy 323.481051 -111.865696) (xy 323.453477 -111.910533) (xy 323.419996 -111.951149) (xy 323.400928 -111.969296)
			(xy 323.393481 -111.976788) (xy 323.384947 -111.996084) (xy 323.384418 -112.006634) (xy 323.384418 -112.08131)
			(xy 323.384992 -112.091851) (xy 323.393505 -112.111144) (xy 323.400928 -112.118648) (xy 323.419987 -112.136799)
			(xy 323.453439 -112.177431) (xy 323.480993 -112.222273) (xy 323.502126 -112.270475) (xy 323.516438 -112.321123)
			(xy 323.523658 -112.373256) (xy 323.524118 -112.399572) (xy 323.523657 -112.426826) (xy 323.515903 -112.480781)
			(xy 323.50055 -112.533083) (xy 323.477909 -112.582667) (xy 323.448442 -112.628525) (xy 323.412748 -112.669721)
			(xy 323.371555 -112.705419) (xy 323.325701 -112.734891) (xy 323.276118 -112.757537) (xy 323.223818 -112.772895)
			(xy 323.169864 -112.780654) (xy 323.14261 -112.78108) (xy 323.113578 -112.780531) (xy 323.056187 -112.771722)
			(xy 323.000791 -112.754323) (xy 322.94867 -112.728734) (xy 322.901027 -112.695546) (xy 322.858959 -112.655524)
			(xy 322.823439 -112.609593) (xy 322.808854 -112.584484) (xy 322.801996 -112.572292) (xy 322.778374 -112.558068)
			(xy 322.764404 -112.558068) (xy 322.754393 -112.558555) (xy 322.735895 -112.566213) (xy 322.721733 -112.580365)
			(xy 322.714062 -112.598858) (xy 322.713604 -112.608868) (xy 322.713604 -112.716056) (xy 322.714038 -112.726122)
			(xy 322.721767 -112.744711) (xy 322.72859 -112.752124) (xy 323.206618 -113.230152) (xy 323.2404 -113.234724)
			(xy 323.255386 -113.226342) (xy 323.276912 -113.214624) (xy 323.322326 -113.196196) (xy 323.369726 -113.183736)
			(xy 323.418333 -113.17745) (xy 323.442838 -113.177066) (xy 323.470088 -113.177554) (xy 323.524033 -113.185315)
			(xy 323.576325 -113.200673) (xy 323.625899 -113.223316) (xy 323.671746 -113.252783) (xy 323.712934 -113.288474)
			(xy 323.748624 -113.329663) (xy 323.77809 -113.375512) (xy 323.800731 -113.425086) (xy 323.816087 -113.477379)
			(xy 323.823847 -113.531324) (xy 323.824346 -113.558574) (xy 323.823969 -113.58308) (xy 323.817689 -113.631689)
			(xy 323.805231 -113.679091) (xy 323.786798 -113.724505) (xy 323.77507 -113.746026) (xy 323.766688 -113.761012)
			(xy 323.77126 -113.794794) (xy 323.93255 -113.956084) (xy 323.959474 -113.962688) (xy 323.97319 -113.95837)
			(xy 324.000592 -113.950531) (xy 324.056961 -113.942116) (xy 324.085458 -113.941606) (xy 324.118318 -113.942291)
			(xy 324.18307 -113.953523) (xy 324.214236 -113.963958) (xy 324.222618 -113.967006) (xy 324.761098 -113.967006)
		)
		(stroke
			(width 0)
			(type solid)
		)
		(fill yes)
		(layer "B.Cu")
		(net "P12V_NIC5_R")
	)
	(gr_poly
		(pts
			(xy 92.569538 -113.963958) (xy 92.600701 -113.95351) (xy 92.665455 -113.94227) (xy 92.698316 -113.941606)
			(xy 92.731175 -113.942296) (xy 92.795924 -113.953538) (xy 92.827094 -113.963958) (xy 92.835476 -113.967006)
			(xy 93.065346 -113.967006) (xy 93.091254 -113.94948) (xy 93.096842 -113.935002) (xy 93.107892 -113.908658)
			(xy 93.136664 -113.859307) (xy 93.17245 -113.81478) (xy 93.193108 -113.795048) (xy 93.200557 -113.787556)
			(xy 93.209102 -113.768261) (xy 93.209618 -113.75771) (xy 93.209618 -113.683034) (xy 93.209034 -113.672497)
			(xy 93.200511 -113.653216) (xy 93.193108 -113.645696) (xy 93.174045 -113.627547) (xy 93.140585 -113.586917)
			(xy 93.113024 -113.542076) (xy 93.091883 -113.493874) (xy 93.077564 -113.443225) (xy 93.070338 -113.391089)
			(xy 93.069918 -113.364772) (xy 93.070404 -113.337521) (xy 93.07816 -113.283573) (xy 93.093515 -113.231278)
			(xy 93.116157 -113.181701) (xy 93.145623 -113.135851) (xy 93.181314 -113.09466) (xy 93.222505 -113.058969)
			(xy 93.268355 -113.029503) (xy 93.317932 -113.006861) (xy 93.370227 -112.991506) (xy 93.424175 -112.98375)
			(xy 93.478677 -112.98375) (xy 93.532625 -112.991506) (xy 93.58492 -113.006861) (xy 93.634497 -113.029503)
			(xy 93.680347 -113.058969) (xy 93.721538 -113.09466) (xy 93.757229 -113.135851) (xy 93.786695 -113.181701)
			(xy 93.809337 -113.231278) (xy 93.824692 -113.283573) (xy 93.832448 -113.337521) (xy 93.832934 -113.364772)
			(xy 93.832513 -113.391091) (xy 93.825315 -113.443234) (xy 93.811009 -113.493891) (xy 93.789869 -113.542097)
			(xy 93.762296 -113.586935) (xy 93.728815 -113.627552) (xy 93.709744 -113.645696) (xy 93.702296 -113.653188)
			(xy 93.693758 -113.672483) (xy 93.693234 -113.683034) (xy 93.693234 -113.75771) (xy 93.693809 -113.76825)
			(xy 93.702324 -113.787542) (xy 93.709744 -113.795048) (xy 93.730431 -113.814754) (xy 93.766246 -113.859268)
			(xy 93.795003 -113.908636) (xy 93.80601 -113.935002) (xy 93.811598 -113.94948) (xy 93.837506 -113.967006)
			(xy 95.097346 -113.967006) (xy 95.123254 -113.94948) (xy 95.128842 -113.935002) (xy 95.139892 -113.908658)
			(xy 95.168664 -113.859307) (xy 95.20445 -113.81478) (xy 95.225108 -113.795048) (xy 95.232557 -113.787556)
			(xy 95.241102 -113.768261) (xy 95.241618 -113.75771) (xy 95.241618 -113.683034) (xy 95.241034 -113.672497)
			(xy 95.232511 -113.653216) (xy 95.225108 -113.645696) (xy 95.206045 -113.627547) (xy 95.172585 -113.586917)
			(xy 95.145024 -113.542076) (xy 95.123883 -113.493874) (xy 95.109564 -113.443225) (xy 95.102338 -113.391089)
			(xy 95.101918 -113.364772) (xy 95.102404 -113.337521) (xy 95.11016 -113.283573) (xy 95.125515 -113.231278)
			(xy 95.148157 -113.181701) (xy 95.177623 -113.135851) (xy 95.213314 -113.09466) (xy 95.254505 -113.058969)
			(xy 95.300355 -113.029503) (xy 95.349932 -113.006861) (xy 95.402227 -112.991506) (xy 95.456175 -112.98375)
			(xy 95.510677 -112.98375) (xy 95.564625 -112.991506) (xy 95.61692 -113.006861) (xy 95.666497 -113.029503)
			(xy 95.712347 -113.058969) (xy 95.753538 -113.09466) (xy 95.789229 -113.135851) (xy 95.818695 -113.181701)
			(xy 95.841337 -113.231278) (xy 95.856692 -113.283573) (xy 95.864448 -113.337521) (xy 95.864934 -113.364772)
			(xy 95.864513 -113.391091) (xy 95.857315 -113.443234) (xy 95.843009 -113.493891) (xy 95.821869 -113.542097)
			(xy 95.794296 -113.586935) (xy 95.760815 -113.627552) (xy 95.741744 -113.645696) (xy 95.734296 -113.653188)
			(xy 95.725758 -113.672483) (xy 95.725234 -113.683034) (xy 95.725234 -113.75771) (xy 95.725809 -113.76825)
			(xy 95.734324 -113.787542) (xy 95.741744 -113.795048) (xy 95.762431 -113.814754) (xy 95.798246 -113.859268)
			(xy 95.827003 -113.908636) (xy 95.83801 -113.935002) (xy 95.843598 -113.94948) (xy 95.869506 -113.967006)
			(xy 97.771712 -113.967006) (xy 97.781618 -113.962434) (xy 97.806362 -113.951811) (xy 97.858091 -113.936854)
			(xy 97.911411 -113.929331) (xy 97.938336 -113.928906) (xy 97.965258 -113.929355) (xy 98.018573 -113.936889)
			(xy 98.070303 -113.951832) (xy 98.095054 -113.962434) (xy 98.10496 -113.967006) (xy 100.309934 -113.967006)
			(xy 100.31984 -113.962434) (xy 100.344585 -113.951813) (xy 100.396314 -113.936859) (xy 100.449634 -113.929339)
			(xy 100.476558 -113.928906) (xy 100.50348 -113.929356) (xy 100.556794 -113.936893) (xy 100.608522 -113.951839)
			(xy 100.633276 -113.962434) (xy 100.643182 -113.967006) (xy 104.909112 -113.967006) (xy 104.936798 -113.944908)
			(xy 104.940608 -113.927382) (xy 104.947935 -113.897393) (xy 104.969565 -113.839571) (xy 104.998766 -113.785179)
			(xy 105.035008 -113.735202) (xy 105.077633 -113.690545) (xy 105.125871 -113.652018) (xy 105.178846 -113.620319)
			(xy 105.235599 -113.596022) (xy 105.2951 -113.579568) (xy 105.356273 -113.571255) (xy 105.38714 -113.570766)
			(xy 105.417997 -113.571267) (xy 105.479153 -113.579551) (xy 105.538642 -113.595977) (xy 105.595384 -113.620248)
			(xy 105.64835 -113.651922) (xy 105.69658 -113.690425) (xy 105.739199 -113.73506) (xy 105.757726 -113.759742)
			(xy 105.767378 -113.773204) (xy 105.79862 -113.783364) (xy 105.906316 -113.748312) (xy 105.916276 -113.744473)
			(xy 105.932104 -113.730189) (xy 105.940775 -113.710712) (xy 105.941368 -113.700052) (xy 105.941368 -109.65561)
			(xy 105.940895 -109.645642) (xy 105.933323 -109.627201) (xy 105.926636 -109.619796) (xy 105.89133 -109.58449)
			(xy 105.883932 -109.577645) (xy 105.865333 -109.569922) (xy 105.855262 -109.569504) (xy 103.55961 -109.569504)
			(xy 103.549539 -109.569083) (xy 103.530932 -109.561371) (xy 103.523542 -109.554518) (xy 103.354124 -109.3851)
			(xy 103.347275 -109.377703) (xy 103.339537 -109.359104) (xy 103.339138 -109.349032) (xy 103.339138 -108.456984)
			(xy 103.33871 -108.446916) (xy 103.330985 -108.428322) (xy 103.324152 -108.420916) (xy 103.216202 -108.312966)
			(xy 103.208807 -108.306112) (xy 103.190208 -108.298366) (xy 103.180134 -108.29798) (xy 98.68408 -108.29798)
			(xy 98.674012 -108.297553) (xy 98.655415 -108.289831) (xy 98.648012 -108.282994) (xy 98.525584 -108.160566)
			(xy 98.518734 -108.15317) (xy 98.510998 -108.134571) (xy 98.510598 -108.124498) (xy 98.510598 -105.469182)
			(xy 98.509582 -105.468166) (xy 98.509582 -101.793294) (xy 98.510006 -101.783224) (xy 98.51772 -101.764619)
			(xy 98.524568 -101.757226) (xy 99.034346 -101.247448) (xy 99.04119 -101.240049) (xy 99.048914 -101.22145)
			(xy 99.049332 -101.21138) (xy 99.049332 -101.049328) (xy 99.048849 -101.039314) (xy 99.041196 -101.020807)
			(xy 99.027043 -101.006638) (xy 99.008545 -100.998963) (xy 98.998532 -100.998528) (xy 98.499676 -100.998528)
			(xy 98.48971 -100.99805) (xy 98.471272 -100.990476) (xy 98.463862 -100.983796) (xy 97.032064 -99.551998)
			(xy 97.025384 -99.544587) (xy 97.017808 -99.526151) (xy 97.017332 -99.516184) (xy 97.017332 -99.117658)
			(xy 97.016837 -99.107654) (xy 97.009171 -99.089171) (xy 96.995021 -99.075023) (xy 96.976537 -99.067361)
			(xy 96.966532 -99.066858) (xy 94.498922 -99.066858) (xy 94.489893 -99.067169) (xy 94.472932 -99.073353)
			(xy 94.459189 -99.085061) (xy 94.454472 -99.092766) (xy 94.40418 -99.18192) (xy 94.404688 -99.209098)
			(xy 94.412054 -99.221036) (xy 94.42778 -99.248009) (xy 94.452579 -99.305309) (xy 94.469362 -99.365447)
			(xy 94.477817 -99.427308) (xy 94.478348 -99.458526) (xy 94.477858 -99.488494) (xy 94.470035 -99.547916)
			(xy 94.454522 -99.605809) (xy 94.431586 -99.661182) (xy 94.401619 -99.713088) (xy 94.365132 -99.760638)
			(xy 94.322752 -99.803018) (xy 94.275202 -99.839505) (xy 94.223296 -99.869472) (xy 94.167923 -99.892408)
			(xy 94.11003 -99.907921) (xy 94.050608 -99.915744) (xy 93.990672 -99.915744) (xy 93.93125 -99.907921)
			(xy 93.873357 -99.892408) (xy 93.817984 -99.869472) (xy 93.766078 -99.839505) (xy 93.718528 -99.803018)
			(xy 93.676148 -99.760638) (xy 93.639661 -99.713088) (xy 93.609694 -99.661182) (xy 93.586758 -99.605809)
			(xy 93.571245 -99.547916) (xy 93.563422 -99.488494) (xy 93.562932 -99.458526) (xy 93.56344 -99.427306)
			(xy 93.571887 -99.365439) (xy 93.588668 -99.305297) (xy 93.613472 -99.247994) (xy 93.629226 -99.221036)
			(xy 93.636592 -99.209098) (xy 93.6371 -99.18192) (xy 93.586808 -99.092766) (xy 93.582059 -99.085093)
			(xy 93.568307 -99.073426) (xy 93.551375 -99.067219) (xy 93.542358 -99.066858) (xy 87.241634 -99.066858)
			(xy 87.23157 -99.067295) (xy 87.212989 -99.075033) (xy 87.205566 -99.081844) (xy 86.825328 -99.462082)
			(xy 86.818491 -99.469484) (xy 86.810782 -99.488082) (xy 86.810342 -99.49815) (xy 86.810342 -99.614482)
			(xy 90.339924 -99.614482) (xy 90.343995 -99.55886) (xy 90.356121 -99.504423) (xy 90.376044 -99.452332)
			(xy 90.40334 -99.403697) (xy 90.437426 -99.359554) (xy 90.477575 -99.320845) (xy 90.522933 -99.288394)
			(xy 90.572533 -99.262893) (xy 90.625317 -99.244886) (xy 90.68016 -99.234756) (xy 90.735894 -99.232719)
			(xy 90.791331 -99.238819) (xy 90.845288 -99.252925) (xy 90.896617 -99.274737) (xy 90.944223 -99.303791)
			(xy 90.987091 -99.339466) (xy 91.024308 -99.381003) (xy 91.055081 -99.427516) (xy 91.078753 -99.478013)
			(xy 91.094821 -99.53142) (xy 91.102941 -99.586596) (xy 91.10345 -99.614482) (xy 91.103241 -99.625912)
			(xy 91.5068 -99.625912) (xy 91.510871 -99.57029) (xy 91.522997 -99.515853) (xy 91.54292 -99.463762)
			(xy 91.570216 -99.415127) (xy 91.604302 -99.370984) (xy 91.644451 -99.332275) (xy 91.689809 -99.299824)
			(xy 91.739409 -99.274323) (xy 91.792193 -99.256316) (xy 91.847036 -99.246186) (xy 91.90277 -99.244149)
			(xy 91.958207 -99.250249) (xy 92.012164 -99.264355) (xy 92.063493 -99.286167) (xy 92.111099 -99.315221)
			(xy 92.153967 -99.350896) (xy 92.191184 -99.392433) (xy 92.221957 -99.438946) (xy 92.245629 -99.489443)
			(xy 92.261697 -99.54285) (xy 92.269817 -99.598026) (xy 92.270326 -99.625912) (xy 92.269817 -99.653798)
			(xy 92.261697 -99.708974) (xy 92.245629 -99.762381) (xy 92.221957 -99.812878) (xy 92.191184 -99.859391)
			(xy 92.153967 -99.900928) (xy 92.111099 -99.936603) (xy 92.063493 -99.965657) (xy 92.012164 -99.987469)
			(xy 91.958207 -100.001575) (xy 91.90277 -100.007675) (xy 91.847036 -100.005638) (xy 91.792193 -99.995508)
			(xy 91.739409 -99.977501) (xy 91.689809 -99.952) (xy 91.644451 -99.919549) (xy 91.604302 -99.88084)
			(xy 91.570216 -99.836697) (xy 91.54292 -99.788062) (xy 91.522997 -99.735971) (xy 91.510871 -99.681534)
			(xy 91.5068 -99.625912) (xy 91.103241 -99.625912) (xy 91.102941 -99.642368) (xy 91.094821 -99.697544)
			(xy 91.078753 -99.750951) (xy 91.055081 -99.801448) (xy 91.024308 -99.847961) (xy 90.987091 -99.889498)
			(xy 90.944223 -99.925173) (xy 90.896617 -99.954227) (xy 90.845288 -99.976039) (xy 90.791331 -99.990145)
			(xy 90.735894 -99.996245) (xy 90.68016 -99.994208) (xy 90.625317 -99.984078) (xy 90.572533 -99.966071)
			(xy 90.522933 -99.94057) (xy 90.477575 -99.908119) (xy 90.437426 -99.86941) (xy 90.40334 -99.825267)
			(xy 90.376044 -99.776632) (xy 90.356121 -99.724541) (xy 90.343995 -99.670104) (xy 90.339924 -99.614482)
			(xy 86.810342 -99.614482) (xy 86.810342 -100.392992) (xy 95.37395 -100.392992) (xy 95.378021 -100.33737)
			(xy 95.390147 -100.282933) (xy 95.41007 -100.230842) (xy 95.437366 -100.182207) (xy 95.471452 -100.138064)
			(xy 95.511601 -100.099355) (xy 95.556959 -100.066904) (xy 95.606559 -100.041403) (xy 95.659343 -100.023396)
			(xy 95.714186 -100.013266) (xy 95.76992 -100.011229) (xy 95.825357 -100.017329) (xy 95.879314 -100.031435)
			(xy 95.930643 -100.053247) (xy 95.978249 -100.082301) (xy 96.021117 -100.117976) (xy 96.058334 -100.159513)
			(xy 96.089107 -100.206026) (xy 96.112779 -100.256523) (xy 96.128847 -100.30993) (xy 96.136967 -100.365106)
			(xy 96.137476 -100.392992) (xy 96.136967 -100.420878) (xy 96.128847 -100.476054) (xy 96.112779 -100.529461)
			(xy 96.089107 -100.579958) (xy 96.058334 -100.626471) (xy 96.021117 -100.668008) (xy 95.978249 -100.703683)
			(xy 95.930643 -100.732737) (xy 95.879314 -100.754549) (xy 95.825357 -100.768655) (xy 95.76992 -100.774755)
			(xy 95.714186 -100.772718) (xy 95.659343 -100.762588) (xy 95.606559 -100.744581) (xy 95.556959 -100.71908)
			(xy 95.511601 -100.686629) (xy 95.471452 -100.64792) (xy 95.437366 -100.603777) (xy 95.41007 -100.555142)
			(xy 95.390147 -100.503051) (xy 95.378021 -100.448614) (xy 95.37395 -100.392992) (xy 86.810342 -100.392992)
			(xy 86.810342 -100.803964) (xy 90.351354 -100.803964) (xy 90.355425 -100.748342) (xy 90.367551 -100.693905)
			(xy 90.387474 -100.641814) (xy 90.41477 -100.593179) (xy 90.448856 -100.549036) (xy 90.489005 -100.510327)
			(xy 90.534363 -100.477876) (xy 90.583963 -100.452375) (xy 90.636747 -100.434368) (xy 90.69159 -100.424238)
			(xy 90.747324 -100.422201) (xy 90.802761 -100.428301) (xy 90.856718 -100.442407) (xy 90.908047 -100.464219)
			(xy 90.955653 -100.493273) (xy 90.998521 -100.528948) (xy 91.035738 -100.570485) (xy 91.066511 -100.616998)
			(xy 91.090183 -100.667495) (xy 91.106251 -100.720902) (xy 91.114371 -100.776078) (xy 91.11488 -100.803964)
			(xy 91.517976 -100.803964) (xy 91.522047 -100.748342) (xy 91.534173 -100.693905) (xy 91.554096 -100.641814)
			(xy 91.581392 -100.593179) (xy 91.615478 -100.549036) (xy 91.655627 -100.510327) (xy 91.700985 -100.477876)
			(xy 91.750585 -100.452375) (xy 91.803369 -100.434368) (xy 91.858212 -100.424238) (xy 91.913946 -100.422201)
			(xy 91.969383 -100.428301) (xy 92.02334 -100.442407) (xy 92.074669 -100.464219) (xy 92.122275 -100.493273)
			(xy 92.165143 -100.528948) (xy 92.20236 -100.570485) (xy 92.233133 -100.616998) (xy 92.256805 -100.667495)
			(xy 92.272873 -100.720902) (xy 92.280993 -100.776078) (xy 92.281502 -100.803964) (xy 92.280993 -100.83185)
			(xy 92.272873 -100.887026) (xy 92.256805 -100.940433) (xy 92.233133 -100.99093) (xy 92.20236 -101.037443)
			(xy 92.165143 -101.07898) (xy 92.122275 -101.114655) (xy 92.074669 -101.143709) (xy 92.02334 -101.165521)
			(xy 91.969383 -101.179627) (xy 91.913946 -101.185727) (xy 91.858212 -101.18369) (xy 91.803369 -101.17356)
			(xy 91.750585 -101.155553) (xy 91.700985 -101.130052) (xy 91.655627 -101.097601) (xy 91.615478 -101.058892)
			(xy 91.581392 -101.014749) (xy 91.554096 -100.966114) (xy 91.534173 -100.914023) (xy 91.522047 -100.859586)
			(xy 91.517976 -100.803964) (xy 91.11488 -100.803964) (xy 91.114371 -100.83185) (xy 91.106251 -100.887026)
			(xy 91.090183 -100.940433) (xy 91.066511 -100.99093) (xy 91.035738 -101.037443) (xy 90.998521 -101.07898)
			(xy 90.955653 -101.114655) (xy 90.908047 -101.143709) (xy 90.856718 -101.165521) (xy 90.802761 -101.179627)
			(xy 90.747324 -101.185727) (xy 90.69159 -101.18369) (xy 90.636747 -101.17356) (xy 90.583963 -101.155553)
			(xy 90.534363 -101.130052) (xy 90.489005 -101.097601) (xy 90.448856 -101.058892) (xy 90.41477 -101.014749)
			(xy 90.387474 -100.966114) (xy 90.367551 -100.914023) (xy 90.355425 -100.859586) (xy 90.351354 -100.803964)
			(xy 86.810342 -100.803964) (xy 86.810342 -101.60914) (xy 87.695514 -101.60914) (xy 87.695514 -101.549204)
			(xy 87.703337 -101.489782) (xy 87.71885 -101.431889) (xy 87.741786 -101.376516) (xy 87.771753 -101.32461)
			(xy 87.80824 -101.27706) (xy 87.85062 -101.23468) (xy 87.89817 -101.198193) (xy 87.950076 -101.168226)
			(xy 88.005449 -101.14529) (xy 88.063342 -101.129777) (xy 88.122764 -101.121954) (xy 88.1827 -101.121954)
			(xy 88.242122 -101.129777) (xy 88.300015 -101.14529) (xy 88.355388 -101.168226) (xy 88.407294 -101.198193)
			(xy 88.454844 -101.23468) (xy 88.497224 -101.27706) (xy 88.533711 -101.32461) (xy 88.563678 -101.376516)
			(xy 88.586614 -101.431889) (xy 88.602127 -101.489782) (xy 88.60995 -101.549204) (xy 88.61044 -101.579172)
			(xy 88.60995 -101.60914) (xy 88.602127 -101.668562) (xy 88.586614 -101.726455) (xy 88.563678 -101.781828)
			(xy 88.533711 -101.833734) (xy 88.505296 -101.870764) (xy 93.23908 -101.870764) (xy 93.243151 -101.815142)
			(xy 93.255277 -101.760705) (xy 93.2752 -101.708614) (xy 93.302496 -101.659979) (xy 93.336582 -101.615836)
			(xy 93.376731 -101.577127) (xy 93.422089 -101.544676) (xy 93.471689 -101.519175) (xy 93.524473 -101.501168)
			(xy 93.579316 -101.491038) (xy 93.63505 -101.489001) (xy 93.690487 -101.495101) (xy 93.744444 -101.509207)
			(xy 93.795773 -101.531019) (xy 93.843379 -101.560073) (xy 93.886247 -101.595748) (xy 93.923464 -101.637285)
			(xy 93.954237 -101.683798) (xy 93.977909 -101.734295) (xy 93.993977 -101.787702) (xy 94.002097 -101.842878)
			(xy 94.002606 -101.870764) (xy 94.002097 -101.89865) (xy 93.993977 -101.953826) (xy 93.977909 -102.007233)
			(xy 93.954237 -102.05773) (xy 93.923464 -102.104243) (xy 93.886247 -102.14578) (xy 93.843379 -102.181455)
			(xy 93.795773 -102.210509) (xy 93.744444 -102.232321) (xy 93.690487 -102.246427) (xy 93.63505 -102.252527)
			(xy 93.579316 -102.25049) (xy 93.524473 -102.24036) (xy 93.471689 -102.222353) (xy 93.422089 -102.196852)
			(xy 93.376731 -102.164401) (xy 93.336582 -102.125692) (xy 93.302496 -102.081549) (xy 93.2752 -102.032914)
			(xy 93.255277 -101.980823) (xy 93.243151 -101.926386) (xy 93.23908 -101.870764) (xy 88.505296 -101.870764)
			(xy 88.497224 -101.881284) (xy 88.454844 -101.923664) (xy 88.407294 -101.960151) (xy 88.355388 -101.990118)
			(xy 88.300015 -102.013054) (xy 88.242122 -102.028567) (xy 88.1827 -102.03639) (xy 88.122764 -102.03639)
			(xy 88.063342 -102.028567) (xy 88.005449 -102.013054) (xy 87.950076 -101.990118) (xy 87.89817 -101.960151)
			(xy 87.85062 -101.923664) (xy 87.80824 -101.881284) (xy 87.771753 -101.833734) (xy 87.741786 -101.781828)
			(xy 87.71885 -101.726455) (xy 87.703337 -101.668562) (xy 87.695514 -101.60914) (xy 86.810342 -101.60914)
			(xy 86.810342 -102.328218) (xy 91.371418 -102.328218) (xy 91.375489 -102.272596) (xy 91.387615 -102.218159)
			(xy 91.407538 -102.166068) (xy 91.434834 -102.117433) (xy 91.46892 -102.07329) (xy 91.509069 -102.034581)
			(xy 91.554427 -102.00213) (xy 91.604027 -101.976629) (xy 91.656811 -101.958622) (xy 91.711654 -101.948492)
			(xy 91.767388 -101.946455) (xy 91.822825 -101.952555) (xy 91.876782 -101.966661) (xy 91.928111 -101.988473)
			(xy 91.975717 -102.017527) (xy 92.018585 -102.053202) (xy 92.055802 -102.094739) (xy 92.086575 -102.141252)
			(xy 92.110247 -102.191749) (xy 92.126315 -102.245156) (xy 92.134435 -102.300332) (xy 92.134944 -102.328218)
			(xy 92.134435 -102.356104) (xy 92.126315 -102.41128) (xy 92.110247 -102.464687) (xy 92.086575 -102.515184)
			(xy 92.055802 -102.561697) (xy 92.018585 -102.603234) (xy 91.975717 -102.638909) (xy 91.928111 -102.667963)
			(xy 91.876782 -102.689775) (xy 91.822825 -102.703881) (xy 91.767388 -102.709981) (xy 91.711654 -102.707944)
			(xy 91.656811 -102.697814) (xy 91.604027 -102.679807) (xy 91.554427 -102.654306) (xy 91.509069 -102.621855)
			(xy 91.46892 -102.583146) (xy 91.434834 -102.539003) (xy 91.407538 -102.490368) (xy 91.387615 -102.438277)
			(xy 91.375489 -102.38384) (xy 91.371418 -102.328218) (xy 86.810342 -102.328218) (xy 86.810342 -102.700328)
			(xy 86.810772 -102.710395) (xy 86.818498 -102.728988) (xy 86.825328 -102.736396) (xy 87.25814 -103.169208)
			(xy 89.431858 -103.169208) (xy 89.431858 -103.109272) (xy 89.439681 -103.04985) (xy 89.455194 -102.991957)
			(xy 89.47813 -102.936584) (xy 89.508097 -102.884678) (xy 89.544584 -102.837128) (xy 89.586964 -102.794748)
			(xy 89.634514 -102.758261) (xy 89.68642 -102.728294) (xy 89.741793 -102.705358) (xy 89.799686 -102.689845)
			(xy 89.859108 -102.682022) (xy 89.919044 -102.682022) (xy 89.978466 -102.689845) (xy 90.036359 -102.705358)
			(xy 90.091732 -102.728294) (xy 90.143638 -102.758261) (xy 90.191188 -102.794748) (xy 90.233568 -102.837128)
			(xy 90.270055 -102.884678) (xy 90.300022 -102.936584) (xy 90.322958 -102.991957) (xy 90.338471 -103.04985)
			(xy 90.346294 -103.109272) (xy 90.346784 -103.13924) (xy 90.346294 -103.169208) (xy 90.338471 -103.22863)
			(xy 90.322958 -103.286523) (xy 90.300022 -103.341896) (xy 90.270055 -103.393802) (xy 90.233568 -103.441352)
			(xy 90.191188 -103.483732) (xy 90.143638 -103.520219) (xy 90.091732 -103.550186) (xy 90.036359 -103.573122)
			(xy 89.978466 -103.588635) (xy 89.919044 -103.596458) (xy 89.859108 -103.596458) (xy 89.799686 -103.588635)
			(xy 89.741793 -103.573122) (xy 89.68642 -103.550186) (xy 89.634514 -103.520219) (xy 89.586964 -103.483732)
			(xy 89.544584 -103.441352) (xy 89.508097 -103.393802) (xy 89.47813 -103.341896) (xy 89.455194 -103.286523)
			(xy 89.439681 -103.22863) (xy 89.431858 -103.169208) (xy 87.25814 -103.169208) (xy 87.802212 -103.71328)
			(xy 87.80961 -103.720127) (xy 87.828208 -103.72786) (xy 87.83828 -103.728266) (xy 90.231722 -103.728266)
			(xy 90.241789 -103.728695) (xy 90.260381 -103.736422) (xy 90.26779 -103.743252) (xy 90.418666 -103.894128)
			(xy 92.213936 -103.894128) (xy 92.218007 -103.838506) (xy 92.230133 -103.784069) (xy 92.250056 -103.731978)
			(xy 92.277352 -103.683343) (xy 92.311438 -103.6392) (xy 92.351587 -103.600491) (xy 92.396945 -103.56804)
			(xy 92.446545 -103.542539) (xy 92.499329 -103.524532) (xy 92.554172 -103.514402) (xy 92.609906 -103.512365)
			(xy 92.665343 -103.518465) (xy 92.7193 -103.532571) (xy 92.770629 -103.554383) (xy 92.818235 -103.583437)
			(xy 92.861103 -103.619112) (xy 92.89832 -103.660649) (xy 92.929093 -103.707162) (xy 92.952765 -103.757659)
			(xy 92.968833 -103.811066) (xy 92.976953 -103.866242) (xy 92.977462 -103.894128) (xy 92.976989 -103.920032)
			(xy 93.16388 -103.920032) (xy 93.16388 -103.860096) (xy 93.171703 -103.800674) (xy 93.187216 -103.742781)
			(xy 93.210152 -103.687408) (xy 93.240119 -103.635502) (xy 93.276606 -103.587952) (xy 93.318986 -103.545572)
			(xy 93.366536 -103.509085) (xy 93.418442 -103.479118) (xy 93.473815 -103.456182) (xy 93.531708 -103.440669)
			(xy 93.59113 -103.432846) (xy 93.651066 -103.432846) (xy 93.710488 -103.440669) (xy 93.768381 -103.456182)
			(xy 93.823754 -103.479118) (xy 93.87566 -103.509085) (xy 93.92321 -103.545572) (xy 93.96559 -103.587952)
			(xy 94.002077 -103.635502) (xy 94.032044 -103.687408) (xy 94.05498 -103.742781) (xy 94.070493 -103.800674)
			(xy 94.078316 -103.860096) (xy 94.078806 -103.890064) (xy 94.078316 -103.920032) (xy 94.070493 -103.979454)
			(xy 94.05498 -104.037347) (xy 94.032044 -104.09272) (xy 94.002077 -104.144626) (xy 93.96559 -104.192176)
			(xy 93.92321 -104.234556) (xy 93.87566 -104.271043) (xy 93.823754 -104.30101) (xy 93.768381 -104.323946)
			(xy 93.710488 -104.339459) (xy 93.651066 -104.347282) (xy 93.59113 -104.347282) (xy 93.531708 -104.339459)
			(xy 93.473815 -104.323946) (xy 93.418442 -104.30101) (xy 93.366536 -104.271043) (xy 93.318986 -104.234556)
			(xy 93.276606 -104.192176) (xy 93.240119 -104.144626) (xy 93.210152 -104.09272) (xy 93.187216 -104.037347)
			(xy 93.171703 -103.979454) (xy 93.16388 -103.920032) (xy 92.976989 -103.920032) (xy 92.976953 -103.922014)
			(xy 92.968833 -103.97719) (xy 92.952765 -104.030597) (xy 92.929093 -104.081094) (xy 92.89832 -104.127607)
			(xy 92.861103 -104.169144) (xy 92.818235 -104.204819) (xy 92.770629 -104.233873) (xy 92.7193 -104.255685)
			(xy 92.665343 -104.269791) (xy 92.609906 -104.275891) (xy 92.554172 -104.273854) (xy 92.499329 -104.263724)
			(xy 92.446545 -104.245717) (xy 92.396945 -104.220216) (xy 92.351587 -104.187765) (xy 92.311438 -104.149056)
			(xy 92.277352 -104.104913) (xy 92.250056 -104.056278) (xy 92.230133 -104.004187) (xy 92.218007 -103.94975)
			(xy 92.213936 -103.894128) (xy 90.418666 -103.894128) (xy 90.498676 -103.974138) (xy 90.505519 -103.981537)
			(xy 90.513244 -104.000136) (xy 90.513662 -104.010206) (xy 90.513662 -111.333026) (xy 90.514078 -111.342906)
			(xy 90.521482 -111.361222) (xy 90.535287 -111.375353) (xy 90.544142 -111.379762) (xy 90.643202 -111.423196)
			(xy 90.67292 -111.418116) (xy 90.684096 -111.407956) (xy 90.705343 -111.389058) (xy 90.752389 -111.357122)
			(xy 90.803656 -111.332528) (xy 90.858008 -111.315821) (xy 90.914237 -111.307371) (xy 90.942668 -111.306864)
			(xy 90.969923 -111.307325) (xy 91.023879 -111.315078) (xy 91.076182 -111.330431) (xy 91.125768 -111.353071)
			(xy 91.171628 -111.382538) (xy 91.212826 -111.418231) (xy 91.248526 -111.459424) (xy 91.278 -111.505279)
			(xy 91.300648 -111.554861) (xy 91.316009 -111.607162) (xy 91.323771 -111.661117) (xy 91.324176 -111.688372)
			(xy 91.323756 -111.714692) (xy 91.316557 -111.766835) (xy 91.302253 -111.817493) (xy 91.281114 -111.8657)
			(xy 91.253543 -111.910541) (xy 91.220065 -111.951161) (xy 91.200986 -111.969296) (xy 91.193545 -111.976791)
			(xy 91.185017 -111.996086) (xy 91.184476 -112.006634) (xy 91.184476 -112.08131) (xy 91.185049 -112.091852)
			(xy 91.193557 -112.11115) (xy 91.200986 -112.118648) (xy 91.220047 -112.136797) (xy 91.253503 -112.177429)
			(xy 91.281059 -112.22227) (xy 91.302195 -112.270473) (xy 91.316509 -112.321121) (xy 91.323729 -112.373256)
			(xy 91.324176 -112.399572) (xy 91.323715 -112.426825) (xy 91.315961 -112.480778) (xy 91.300607 -112.533077)
			(xy 91.277965 -112.582659) (xy 91.248498 -112.628513) (xy 91.212803 -112.669706) (xy 91.17161 -112.7054)
			(xy 91.125755 -112.734867) (xy 91.076173 -112.757508) (xy 91.023874 -112.772861) (xy 90.969921 -112.780615)
			(xy 90.942668 -112.78108) (xy 90.913634 -112.780535) (xy 90.856237 -112.771734) (xy 90.800835 -112.754341)
			(xy 90.748707 -112.728756) (xy 90.701057 -112.695571) (xy 90.658982 -112.65555) (xy 90.623456 -112.609618)
			(xy 90.608912 -112.584484) (xy 90.602054 -112.572292) (xy 90.578432 -112.558068) (xy 90.564462 -112.558068)
			(xy 90.554457 -112.558562) (xy 90.535973 -112.566227) (xy 90.521824 -112.580378) (xy 90.514161 -112.598863)
			(xy 90.513662 -112.608868) (xy 90.513662 -112.716056) (xy 90.514097 -112.72612) (xy 90.521833 -112.744704)
			(xy 90.528648 -112.752124) (xy 90.996008 -113.219484) (xy 91.030806 -113.223548) (xy 91.046046 -113.21415)
			(xy 91.068797 -113.200552) (xy 91.117257 -113.179086) (xy 91.168223 -113.164537) (xy 91.220713 -113.157186)
			(xy 91.247214 -113.156746) (xy 91.274466 -113.157233) (xy 91.328414 -113.164991) (xy 91.38071 -113.180346)
			(xy 91.430289 -113.202988) (xy 91.47614 -113.232454) (xy 91.517333 -113.268145) (xy 91.553027 -113.309334)
			(xy 91.582497 -113.355183) (xy 91.605142 -113.40476) (xy 91.620503 -113.457054) (xy 91.628265 -113.511002)
			(xy 91.628722 -113.538254) (xy 91.628269 -113.564755) (xy 91.620931 -113.617247) (xy 91.606391 -113.668216)
			(xy 91.584928 -113.716678) (xy 91.571318 -113.739422) (xy 91.56192 -113.754662) (xy 91.565984 -113.78946)
			(xy 91.732608 -113.956084) (xy 91.759532 -113.962688) (xy 91.773248 -113.95837) (xy 91.80065 -113.950528)
			(xy 91.857019 -113.942107) (xy 91.885516 -113.941606) (xy 91.918375 -113.942296) (xy 91.983124 -113.953538)
			(xy 92.014294 -113.963958) (xy 92.022676 -113.967006) (xy 92.561156 -113.967006)
		)
		(stroke
			(width 0)
			(type solid)
		)
		(fill yes)
		(layer "B.Cu")
		(net "P12V_NIC1_R")
	)
	(gr_poly
		(pts
			(xy 440.869578 -113.963958) (xy 440.900742 -113.953513) (xy 440.965495 -113.94228) (xy 440.998356 -113.941606)
			(xy 441.031216 -113.94229) (xy 441.095968 -113.953523) (xy 441.127134 -113.963958) (xy 441.135516 -113.967006)
			(xy 441.365386 -113.967006) (xy 441.391294 -113.94948) (xy 441.396882 -113.935002) (xy 441.407933 -113.908659)
			(xy 441.436707 -113.85931) (xy 441.472496 -113.814786) (xy 441.493148 -113.795048) (xy 441.500604 -113.787559)
			(xy 441.50916 -113.768264) (xy 441.509658 -113.75771) (xy 441.509658 -113.683034) (xy 441.509073 -113.672499)
			(xy 441.500542 -113.653224) (xy 441.493148 -113.645696) (xy 441.474087 -113.627546) (xy 441.440633 -113.586914)
			(xy 441.413076 -113.542072) (xy 441.391938 -113.49387) (xy 441.377622 -113.443222) (xy 441.370397 -113.391088)
			(xy 441.369958 -113.364772) (xy 441.370444 -113.337521) (xy 441.3782 -113.283573) (xy 441.393555 -113.231278)
			(xy 441.416197 -113.181701) (xy 441.445663 -113.135851) (xy 441.481354 -113.09466) (xy 441.522545 -113.058969)
			(xy 441.568395 -113.029503) (xy 441.617972 -113.006861) (xy 441.670267 -112.991506) (xy 441.724215 -112.98375)
			(xy 441.778717 -112.98375) (xy 441.832665 -112.991506) (xy 441.88496 -113.006861) (xy 441.934537 -113.029503)
			(xy 441.980387 -113.058969) (xy 442.021578 -113.09466) (xy 442.057269 -113.135851) (xy 442.086735 -113.181701)
			(xy 442.109377 -113.231278) (xy 442.124732 -113.283573) (xy 442.132488 -113.337521) (xy 442.132974 -113.364772)
			(xy 442.132554 -113.391092) (xy 442.125355 -113.443235) (xy 442.111051 -113.493893) (xy 442.089912 -113.5421)
			(xy 442.062341 -113.58694) (xy 442.028862 -113.62756) (xy 442.009784 -113.645696) (xy 442.002343 -113.653191)
			(xy 441.993816 -113.672486) (xy 441.993274 -113.683034) (xy 441.993274 -113.75771) (xy 441.993847 -113.768252)
			(xy 442.002355 -113.78755) (xy 442.009784 -113.795048) (xy 442.03047 -113.814756) (xy 442.066281 -113.859271)
			(xy 442.095035 -113.90864) (xy 442.10605 -113.935002) (xy 442.111638 -113.94948) (xy 442.137546 -113.967006)
			(xy 443.397386 -113.967006) (xy 443.423294 -113.94948) (xy 443.428882 -113.935002) (xy 443.439933 -113.908659)
			(xy 443.468707 -113.85931) (xy 443.504496 -113.814786) (xy 443.525148 -113.795048) (xy 443.532604 -113.787559)
			(xy 443.54116 -113.768264) (xy 443.541658 -113.75771) (xy 443.541658 -113.683034) (xy 443.541073 -113.672499)
			(xy 443.532542 -113.653224) (xy 443.525148 -113.645696) (xy 443.506087 -113.627546) (xy 443.472633 -113.586914)
			(xy 443.445076 -113.542072) (xy 443.423938 -113.49387) (xy 443.409622 -113.443222) (xy 443.402397 -113.391088)
			(xy 443.401958 -113.364772) (xy 443.402444 -113.337521) (xy 443.4102 -113.283573) (xy 443.425555 -113.231278)
			(xy 443.448197 -113.181701) (xy 443.477663 -113.135851) (xy 443.513354 -113.09466) (xy 443.554545 -113.058969)
			(xy 443.600395 -113.029503) (xy 443.649972 -113.006861) (xy 443.702267 -112.991506) (xy 443.756215 -112.98375)
			(xy 443.810717 -112.98375) (xy 443.864665 -112.991506) (xy 443.91696 -113.006861) (xy 443.966537 -113.029503)
			(xy 444.012387 -113.058969) (xy 444.053578 -113.09466) (xy 444.089269 -113.135851) (xy 444.118735 -113.181701)
			(xy 444.141377 -113.231278) (xy 444.156732 -113.283573) (xy 444.164488 -113.337521) (xy 444.164974 -113.364772)
			(xy 444.164554 -113.391092) (xy 444.157355 -113.443235) (xy 444.143051 -113.493893) (xy 444.121912 -113.5421)
			(xy 444.094341 -113.58694) (xy 444.060862 -113.62756) (xy 444.041784 -113.645696) (xy 444.034343 -113.653191)
			(xy 444.025816 -113.672486) (xy 444.025274 -113.683034) (xy 444.025274 -113.75771) (xy 444.025847 -113.768252)
			(xy 444.034355 -113.78755) (xy 444.041784 -113.795048) (xy 444.06247 -113.814756) (xy 444.098281 -113.859271)
			(xy 444.127035 -113.90864) (xy 444.13805 -113.935002) (xy 444.143638 -113.94948) (xy 444.169546 -113.967006)
			(xy 446.071752 -113.967006) (xy 446.081658 -113.962434) (xy 446.106403 -113.951814) (xy 446.158132 -113.936862)
			(xy 446.211452 -113.929345) (xy 446.238376 -113.928906) (xy 446.265299 -113.92935) (xy 446.318617 -113.936877)
			(xy 446.370351 -113.951813) (xy 446.395094 -113.962434) (xy 446.405 -113.967006) (xy 448.609974 -113.967006)
			(xy 448.61988 -113.962434) (xy 448.644625 -113.951815) (xy 448.696355 -113.936867) (xy 448.749674 -113.929352)
			(xy 448.776598 -113.928906) (xy 448.803521 -113.929352) (xy 448.856838 -113.936881) (xy 448.90857 -113.95182)
			(xy 448.933316 -113.962434) (xy 448.943222 -113.967006) (xy 453.209152 -113.967006) (xy 453.236838 -113.944908)
			(xy 453.240648 -113.927382) (xy 453.247972 -113.897394) (xy 453.2696 -113.839575) (xy 453.298799 -113.785187)
			(xy 453.335041 -113.735215) (xy 453.377669 -113.690565) (xy 453.425909 -113.652047) (xy 453.478886 -113.620359)
			(xy 453.535641 -113.596077) (xy 453.595143 -113.579639) (xy 453.656314 -113.571346) (xy 453.718046 -113.571346)
			(xy 453.779217 -113.579639) (xy 453.838719 -113.596077) (xy 453.895474 -113.620359) (xy 453.948451 -113.652047)
			(xy 453.996691 -113.690565) (xy 454.039319 -113.735215) (xy 454.075561 -113.785187) (xy 454.10476 -113.839575)
			(xy 454.126388 -113.897394) (xy 454.133712 -113.927382) (xy 454.137522 -113.944908) (xy 454.165208 -113.967006)
			(xy 454.642728 -113.967006) (xy 454.652796 -113.966578) (xy 454.671394 -113.958857) (xy 454.678796 -113.95202)
			(xy 454.86574 -113.765076) (xy 454.872589 -113.757679) (xy 454.880324 -113.73908) (xy 454.880726 -113.729008)
			(xy 454.880726 -113.446814) (xy 454.881165 -113.436751) (xy 454.888905 -113.418172) (xy 454.895712 -113.410746)
			(xy 454.897744 -113.408714) (xy 454.904583 -113.401313) (xy 454.912295 -113.382715) (xy 454.91273 -113.372646)
			(xy 454.91273 -109.700568) (xy 454.912302 -109.6905) (xy 454.904583 -109.671901) (xy 454.897744 -109.6645)
			(xy 454.817734 -109.58449) (xy 454.810336 -109.577644) (xy 454.791737 -109.56992) (xy 454.781666 -109.569504)
			(xy 451.85965 -109.569504) (xy 451.849584 -109.569072) (xy 451.830992 -109.561345) (xy 451.823582 -109.554518)
			(xy 451.654164 -109.3851) (xy 451.64731 -109.377705) (xy 451.639566 -109.359106) (xy 451.639178 -109.349032)
			(xy 451.639178 -108.456984) (xy 451.638751 -108.446916) (xy 451.63103 -108.428317) (xy 451.624192 -108.420916)
			(xy 451.516242 -108.312966) (xy 451.508844 -108.306121) (xy 451.490245 -108.298398) (xy 451.480174 -108.29798)
			(xy 446.98412 -108.29798) (xy 446.974057 -108.297542) (xy 446.955475 -108.289805) (xy 446.948052 -108.282994)
			(xy 446.825624 -108.160566) (xy 446.81878 -108.153167) (xy 446.811054 -108.134568) (xy 446.810638 -108.124498)
			(xy 446.810638 -105.469182) (xy 446.809622 -105.468166) (xy 446.809622 -101.793294) (xy 446.810047 -101.783225)
			(xy 446.817765 -101.764624) (xy 446.824608 -101.757226) (xy 447.334386 -101.247448) (xy 447.341226 -101.240047)
			(xy 447.348944 -101.221449) (xy 447.349372 -101.21138) (xy 447.349372 -100.248212) (xy 447.34895 -100.238141)
			(xy 447.341236 -100.219536) (xy 447.334386 -100.212144) (xy 447.316098 -100.193856) (xy 447.308702 -100.187004)
			(xy 447.290103 -100.179261) (xy 447.28003 -100.17887) (xy 447.027046 -100.17887) (xy 447.016981 -100.178436)
			(xy 446.998393 -100.170705) (xy 446.990978 -100.163884) (xy 445.908938 -99.081844) (xy 445.901538 -99.075003)
			(xy 445.88294 -99.067284) (xy 445.87287 -99.066858) (xy 442.798962 -99.066858) (xy 442.789929 -99.067162)
			(xy 442.772957 -99.073338) (xy 442.759204 -99.085043) (xy 442.754512 -99.092766) (xy 442.70422 -99.18192)
			(xy 442.704728 -99.209098) (xy 442.712094 -99.221036) (xy 442.727818 -99.24801) (xy 442.752616 -99.305309)
			(xy 442.769397 -99.365447) (xy 442.777851 -99.427308) (xy 442.778388 -99.458526) (xy 442.777898 -99.488494)
			(xy 442.770075 -99.547916) (xy 442.754562 -99.605809) (xy 442.731626 -99.661182) (xy 442.701659 -99.713088)
			(xy 442.665172 -99.760638) (xy 442.622792 -99.803018) (xy 442.575242 -99.839505) (xy 442.523336 -99.869472)
			(xy 442.467963 -99.892408) (xy 442.41007 -99.907921) (xy 442.350648 -99.915744) (xy 442.290712 -99.915744)
			(xy 442.23129 -99.907921) (xy 442.173397 -99.892408) (xy 442.118024 -99.869472) (xy 442.066118 -99.839505)
			(xy 442.018568 -99.803018) (xy 441.976188 -99.760638) (xy 441.939701 -99.713088) (xy 441.909734 -99.661182)
			(xy 441.886798 -99.605809) (xy 441.871285 -99.547916) (xy 441.863462 -99.488494) (xy 441.862972 -99.458526)
			(xy 441.86348 -99.427306) (xy 441.871928 -99.36544) (xy 441.88871 -99.305298) (xy 441.913516 -99.247997)
			(xy 441.929266 -99.221036) (xy 441.936632 -99.209098) (xy 441.93714 -99.18192) (xy 441.886848 -99.092766)
			(xy 441.8821 -99.085089) (xy 441.868351 -99.073411) (xy 441.851418 -99.067191) (xy 441.842398 -99.066858)
			(xy 435.541674 -99.066858) (xy 435.531607 -99.067287) (xy 435.513015 -99.075015) (xy 435.505606 -99.081844)
			(xy 435.125368 -99.462082) (xy 435.118527 -99.469482) (xy 435.110812 -99.488081) (xy 435.110382 -99.49815)
			(xy 435.110382 -99.614482) (xy 438.639964 -99.614482) (xy 438.644035 -99.55886) (xy 438.656161 -99.504423)
			(xy 438.676084 -99.452332) (xy 438.70338 -99.403697) (xy 438.737466 -99.359554) (xy 438.777615 -99.320845)
			(xy 438.822973 -99.288394) (xy 438.872573 -99.262893) (xy 438.925357 -99.244886) (xy 438.9802 -99.234756)
			(xy 439.035934 -99.232719) (xy 439.091371 -99.238819) (xy 439.145328 -99.252925) (xy 439.196657 -99.274737)
			(xy 439.244263 -99.303791) (xy 439.287131 -99.339466) (xy 439.324348 -99.381003) (xy 439.355121 -99.427516)
			(xy 439.378793 -99.478013) (xy 439.394861 -99.53142) (xy 439.402981 -99.586596) (xy 439.40349 -99.614482)
			(xy 439.403281 -99.625912) (xy 439.80684 -99.625912) (xy 439.810911 -99.57029) (xy 439.823037 -99.515853)
			(xy 439.84296 -99.463762) (xy 439.870256 -99.415127) (xy 439.904342 -99.370984) (xy 439.944491 -99.332275)
			(xy 439.989849 -99.299824) (xy 440.039449 -99.274323) (xy 440.092233 -99.256316) (xy 440.147076 -99.246186)
			(xy 440.20281 -99.244149) (xy 440.258247 -99.250249) (xy 440.312204 -99.264355) (xy 440.363533 -99.286167)
			(xy 440.411139 -99.315221) (xy 440.454007 -99.350896) (xy 440.491224 -99.392433) (xy 440.521997 -99.438946)
			(xy 440.545669 -99.489443) (xy 440.561737 -99.54285) (xy 440.569857 -99.598026) (xy 440.570366 -99.625912)
			(xy 440.569857 -99.653798) (xy 440.561737 -99.708974) (xy 440.545669 -99.762381) (xy 440.521997 -99.812878)
			(xy 440.491224 -99.859391) (xy 440.454007 -99.900928) (xy 440.411139 -99.936603) (xy 440.363533 -99.965657)
			(xy 440.312204 -99.987469) (xy 440.258247 -100.001575) (xy 440.20281 -100.007675) (xy 440.147076 -100.005638)
			(xy 440.092233 -99.995508) (xy 440.039449 -99.977501) (xy 439.989849 -99.952) (xy 439.944491 -99.919549)
			(xy 439.904342 -99.88084) (xy 439.870256 -99.836697) (xy 439.84296 -99.788062) (xy 439.823037 -99.735971)
			(xy 439.810911 -99.681534) (xy 439.80684 -99.625912) (xy 439.403281 -99.625912) (xy 439.402981 -99.642368)
			(xy 439.394861 -99.697544) (xy 439.378793 -99.750951) (xy 439.355121 -99.801448) (xy 439.324348 -99.847961)
			(xy 439.287131 -99.889498) (xy 439.244263 -99.925173) (xy 439.196657 -99.954227) (xy 439.145328 -99.976039)
			(xy 439.091371 -99.990145) (xy 439.035934 -99.996245) (xy 438.9802 -99.994208) (xy 438.925357 -99.984078)
			(xy 438.872573 -99.966071) (xy 438.822973 -99.94057) (xy 438.777615 -99.908119) (xy 438.737466 -99.86941)
			(xy 438.70338 -99.825267) (xy 438.676084 -99.776632) (xy 438.656161 -99.724541) (xy 438.644035 -99.670104)
			(xy 438.639964 -99.614482) (xy 435.110382 -99.614482) (xy 435.110382 -100.392992) (xy 443.67399 -100.392992)
			(xy 443.678061 -100.33737) (xy 443.690187 -100.282933) (xy 443.71011 -100.230842) (xy 443.737406 -100.182207)
			(xy 443.771492 -100.138064) (xy 443.811641 -100.099355) (xy 443.856999 -100.066904) (xy 443.906599 -100.041403)
			(xy 443.959383 -100.023396) (xy 444.014226 -100.013266) (xy 444.06996 -100.011229) (xy 444.125397 -100.017329)
			(xy 444.179354 -100.031435) (xy 444.230683 -100.053247) (xy 444.278289 -100.082301) (xy 444.321157 -100.117976)
			(xy 444.358374 -100.159513) (xy 444.389147 -100.206026) (xy 444.412819 -100.256523) (xy 444.428887 -100.30993)
			(xy 444.437007 -100.365106) (xy 444.437516 -100.392992) (xy 444.437007 -100.420878) (xy 444.428887 -100.476054)
			(xy 444.412819 -100.529461) (xy 444.389147 -100.579958) (xy 444.358374 -100.626471) (xy 444.321157 -100.668008)
			(xy 444.278289 -100.703683) (xy 444.230683 -100.732737) (xy 444.179354 -100.754549) (xy 444.125397 -100.768655)
			(xy 444.06996 -100.774755) (xy 444.014226 -100.772718) (xy 443.959383 -100.762588) (xy 443.906599 -100.744581)
			(xy 443.856999 -100.71908) (xy 443.811641 -100.686629) (xy 443.771492 -100.64792) (xy 443.737406 -100.603777)
			(xy 443.71011 -100.555142) (xy 443.690187 -100.503051) (xy 443.678061 -100.448614) (xy 443.67399 -100.392992)
			(xy 435.110382 -100.392992) (xy 435.110382 -100.803964) (xy 438.651394 -100.803964) (xy 438.655465 -100.748342)
			(xy 438.667591 -100.693905) (xy 438.687514 -100.641814) (xy 438.71481 -100.593179) (xy 438.748896 -100.549036)
			(xy 438.789045 -100.510327) (xy 438.834403 -100.477876) (xy 438.884003 -100.452375) (xy 438.936787 -100.434368)
			(xy 438.99163 -100.424238) (xy 439.047364 -100.422201) (xy 439.102801 -100.428301) (xy 439.156758 -100.442407)
			(xy 439.208087 -100.464219) (xy 439.255693 -100.493273) (xy 439.298561 -100.528948) (xy 439.335778 -100.570485)
			(xy 439.366551 -100.616998) (xy 439.390223 -100.667495) (xy 439.406291 -100.720902) (xy 439.414411 -100.776078)
			(xy 439.41492 -100.803964) (xy 439.818016 -100.803964) (xy 439.822087 -100.748342) (xy 439.834213 -100.693905)
			(xy 439.854136 -100.641814) (xy 439.881432 -100.593179) (xy 439.915518 -100.549036) (xy 439.955667 -100.510327)
			(xy 440.001025 -100.477876) (xy 440.050625 -100.452375) (xy 440.103409 -100.434368) (xy 440.158252 -100.424238)
			(xy 440.213986 -100.422201) (xy 440.269423 -100.428301) (xy 440.32338 -100.442407) (xy 440.374709 -100.464219)
			(xy 440.422315 -100.493273) (xy 440.465183 -100.528948) (xy 440.5024 -100.570485) (xy 440.533173 -100.616998)
			(xy 440.556845 -100.667495) (xy 440.572913 -100.720902) (xy 440.581033 -100.776078) (xy 440.581542 -100.803964)
			(xy 440.581033 -100.83185) (xy 440.572913 -100.887026) (xy 440.556845 -100.940433) (xy 440.533173 -100.99093)
			(xy 440.5024 -101.037443) (xy 440.465183 -101.07898) (xy 440.422315 -101.114655) (xy 440.374709 -101.143709)
			(xy 440.32338 -101.165521) (xy 440.269423 -101.179627) (xy 440.213986 -101.185727) (xy 440.158252 -101.18369)
			(xy 440.103409 -101.17356) (xy 440.050625 -101.155553) (xy 440.001025 -101.130052) (xy 439.955667 -101.097601)
			(xy 439.915518 -101.058892) (xy 439.881432 -101.014749) (xy 439.854136 -100.966114) (xy 439.834213 -100.914023)
			(xy 439.822087 -100.859586) (xy 439.818016 -100.803964) (xy 439.41492 -100.803964) (xy 439.414411 -100.83185)
			(xy 439.406291 -100.887026) (xy 439.390223 -100.940433) (xy 439.366551 -100.99093) (xy 439.335778 -101.037443)
			(xy 439.298561 -101.07898) (xy 439.255693 -101.114655) (xy 439.208087 -101.143709) (xy 439.156758 -101.165521)
			(xy 439.102801 -101.179627) (xy 439.047364 -101.185727) (xy 438.99163 -101.18369) (xy 438.936787 -101.17356)
			(xy 438.884003 -101.155553) (xy 438.834403 -101.130052) (xy 438.789045 -101.097601) (xy 438.748896 -101.058892)
			(xy 438.71481 -101.014749) (xy 438.687514 -100.966114) (xy 438.667591 -100.914023) (xy 438.655465 -100.859586)
			(xy 438.651394 -100.803964) (xy 435.110382 -100.803964) (xy 435.110382 -101.60914) (xy 435.995554 -101.60914)
			(xy 435.995554 -101.549204) (xy 436.003377 -101.489782) (xy 436.01889 -101.431889) (xy 436.041826 -101.376516)
			(xy 436.071793 -101.32461) (xy 436.10828 -101.27706) (xy 436.15066 -101.23468) (xy 436.19821 -101.198193)
			(xy 436.250116 -101.168226) (xy 436.305489 -101.14529) (xy 436.363382 -101.129777) (xy 436.422804 -101.121954)
			(xy 436.48274 -101.121954) (xy 436.542162 -101.129777) (xy 436.600055 -101.14529) (xy 436.655428 -101.168226)
			(xy 436.707334 -101.198193) (xy 436.754884 -101.23468) (xy 436.797264 -101.27706) (xy 436.833751 -101.32461)
			(xy 436.863718 -101.376516) (xy 436.886654 -101.431889) (xy 436.902167 -101.489782) (xy 436.90999 -101.549204)
			(xy 436.91048 -101.579172) (xy 436.90999 -101.60914) (xy 436.902167 -101.668562) (xy 436.886654 -101.726455)
			(xy 436.863718 -101.781828) (xy 436.833751 -101.833734) (xy 436.805336 -101.870764) (xy 441.53912 -101.870764)
			(xy 441.543191 -101.815142) (xy 441.555317 -101.760705) (xy 441.57524 -101.708614) (xy 441.602536 -101.659979)
			(xy 441.636622 -101.615836) (xy 441.676771 -101.577127) (xy 441.722129 -101.544676) (xy 441.771729 -101.519175)
			(xy 441.824513 -101.501168) (xy 441.879356 -101.491038) (xy 441.93509 -101.489001) (xy 441.990527 -101.495101)
			(xy 442.044484 -101.509207) (xy 442.095813 -101.531019) (xy 442.143419 -101.560073) (xy 442.186287 -101.595748)
			(xy 442.223504 -101.637285) (xy 442.254277 -101.683798) (xy 442.277949 -101.734295) (xy 442.294017 -101.787702)
			(xy 442.302137 -101.842878) (xy 442.302646 -101.870764) (xy 442.302137 -101.89865) (xy 442.294017 -101.953826)
			(xy 442.277949 -102.007233) (xy 442.254277 -102.05773) (xy 442.223504 -102.104243) (xy 442.186287 -102.14578)
			(xy 442.143419 -102.181455) (xy 442.095813 -102.210509) (xy 442.044484 -102.232321) (xy 441.990527 -102.246427)
			(xy 441.93509 -102.252527) (xy 441.879356 -102.25049) (xy 441.824513 -102.24036) (xy 441.771729 -102.222353)
			(xy 441.722129 -102.196852) (xy 441.676771 -102.164401) (xy 441.636622 -102.125692) (xy 441.602536 -102.081549)
			(xy 441.57524 -102.032914) (xy 441.555317 -101.980823) (xy 441.543191 -101.926386) (xy 441.53912 -101.870764)
			(xy 436.805336 -101.870764) (xy 436.797264 -101.881284) (xy 436.754884 -101.923664) (xy 436.707334 -101.960151)
			(xy 436.655428 -101.990118) (xy 436.600055 -102.013054) (xy 436.542162 -102.028567) (xy 436.48274 -102.03639)
			(xy 436.422804 -102.03639) (xy 436.363382 -102.028567) (xy 436.305489 -102.013054) (xy 436.250116 -101.990118)
			(xy 436.19821 -101.960151) (xy 436.15066 -101.923664) (xy 436.10828 -101.881284) (xy 436.071793 -101.833734)
			(xy 436.041826 -101.781828) (xy 436.01889 -101.726455) (xy 436.003377 -101.668562) (xy 435.995554 -101.60914)
			(xy 435.110382 -101.60914) (xy 435.110382 -102.328218) (xy 439.671458 -102.328218) (xy 439.675529 -102.272596)
			(xy 439.687655 -102.218159) (xy 439.707578 -102.166068) (xy 439.734874 -102.117433) (xy 439.76896 -102.07329)
			(xy 439.809109 -102.034581) (xy 439.854467 -102.00213) (xy 439.904067 -101.976629) (xy 439.956851 -101.958622)
			(xy 440.011694 -101.948492) (xy 440.067428 -101.946455) (xy 440.122865 -101.952555) (xy 440.176822 -101.966661)
			(xy 440.228151 -101.988473) (xy 440.275757 -102.017527) (xy 440.318625 -102.053202) (xy 440.355842 -102.094739)
			(xy 440.386615 -102.141252) (xy 440.410287 -102.191749) (xy 440.426355 -102.245156) (xy 440.434475 -102.300332)
			(xy 440.434984 -102.328218) (xy 440.434475 -102.356104) (xy 440.426355 -102.41128) (xy 440.410287 -102.464687)
			(xy 440.386615 -102.515184) (xy 440.355842 -102.561697) (xy 440.318625 -102.603234) (xy 440.275757 -102.638909)
			(xy 440.228151 -102.667963) (xy 440.176822 -102.689775) (xy 440.122865 -102.703881) (xy 440.067428 -102.709981)
			(xy 440.011694 -102.707944) (xy 439.956851 -102.697814) (xy 439.904067 -102.679807) (xy 439.854467 -102.654306)
			(xy 439.809109 -102.621855) (xy 439.76896 -102.583146) (xy 439.734874 -102.539003) (xy 439.707578 -102.490368)
			(xy 439.687655 -102.438277) (xy 439.675529 -102.38384) (xy 439.671458 -102.328218) (xy 435.110382 -102.328218)
			(xy 435.110382 -102.700328) (xy 435.11081 -102.710396) (xy 435.118529 -102.728995) (xy 435.125368 -102.736396)
			(xy 435.55818 -103.169208) (xy 437.731898 -103.169208) (xy 437.731898 -103.109272) (xy 437.739721 -103.04985)
			(xy 437.755234 -102.991957) (xy 437.77817 -102.936584) (xy 437.808137 -102.884678) (xy 437.844624 -102.837128)
			(xy 437.887004 -102.794748) (xy 437.934554 -102.758261) (xy 437.98646 -102.728294) (xy 438.041833 -102.705358)
			(xy 438.099726 -102.689845) (xy 438.159148 -102.682022) (xy 438.219084 -102.682022) (xy 438.278506 -102.689845)
			(xy 438.336399 -102.705358) (xy 438.391772 -102.728294) (xy 438.443678 -102.758261) (xy 438.491228 -102.794748)
			(xy 438.533608 -102.837128) (xy 438.570095 -102.884678) (xy 438.600062 -102.936584) (xy 438.622998 -102.991957)
			(xy 438.638511 -103.04985) (xy 438.646334 -103.109272) (xy 438.646824 -103.13924) (xy 438.646334 -103.169208)
			(xy 438.638511 -103.22863) (xy 438.622998 -103.286523) (xy 438.600062 -103.341896) (xy 438.570095 -103.393802)
			(xy 438.533608 -103.441352) (xy 438.491228 -103.483732) (xy 438.443678 -103.520219) (xy 438.391772 -103.550186)
			(xy 438.336399 -103.573122) (xy 438.278506 -103.588635) (xy 438.219084 -103.596458) (xy 438.159148 -103.596458)
			(xy 438.099726 -103.588635) (xy 438.041833 -103.573122) (xy 437.98646 -103.550186) (xy 437.934554 -103.520219)
			(xy 437.887004 -103.483732) (xy 437.844624 -103.441352) (xy 437.808137 -103.393802) (xy 437.77817 -103.341896)
			(xy 437.755234 -103.286523) (xy 437.739721 -103.22863) (xy 437.731898 -103.169208) (xy 435.55818 -103.169208)
			(xy 436.102252 -103.71328) (xy 436.109652 -103.720121) (xy 436.128251 -103.727839) (xy 436.13832 -103.728266)
			(xy 438.531762 -103.728266) (xy 438.541826 -103.728702) (xy 438.560408 -103.73644) (xy 438.56783 -103.743252)
			(xy 438.718706 -103.894128) (xy 440.513976 -103.894128) (xy 440.518047 -103.838506) (xy 440.530173 -103.784069)
			(xy 440.550096 -103.731978) (xy 440.577392 -103.683343) (xy 440.611478 -103.6392) (xy 440.651627 -103.600491)
			(xy 440.696985 -103.56804) (xy 440.746585 -103.542539) (xy 440.799369 -103.524532) (xy 440.854212 -103.514402)
			(xy 440.909946 -103.512365) (xy 440.965383 -103.518465) (xy 441.01934 -103.532571) (xy 441.070669 -103.554383)
			(xy 441.118275 -103.583437) (xy 441.161143 -103.619112) (xy 441.19836 -103.660649) (xy 441.229133 -103.707162)
			(xy 441.252805 -103.757659) (xy 441.268873 -103.811066) (xy 441.276993 -103.866242) (xy 441.277502 -103.894128)
			(xy 441.277029 -103.920032) (xy 441.46392 -103.920032) (xy 441.46392 -103.860096) (xy 441.471743 -103.800674)
			(xy 441.487256 -103.742781) (xy 441.510192 -103.687408) (xy 441.540159 -103.635502) (xy 441.576646 -103.587952)
			(xy 441.619026 -103.545572) (xy 441.666576 -103.509085) (xy 441.718482 -103.479118) (xy 441.773855 -103.456182)
			(xy 441.831748 -103.440669) (xy 441.89117 -103.432846) (xy 441.951106 -103.432846) (xy 442.010528 -103.440669)
			(xy 442.068421 -103.456182) (xy 442.123794 -103.479118) (xy 442.1757 -103.509085) (xy 442.22325 -103.545572)
			(xy 442.26563 -103.587952) (xy 442.302117 -103.635502) (xy 442.332084 -103.687408) (xy 442.35502 -103.742781)
			(xy 442.370533 -103.800674) (xy 442.378356 -103.860096) (xy 442.378846 -103.890064) (xy 442.378356 -103.920032)
			(xy 442.370533 -103.979454) (xy 442.35502 -104.037347) (xy 442.332084 -104.09272) (xy 442.302117 -104.144626)
			(xy 442.26563 -104.192176) (xy 442.22325 -104.234556) (xy 442.1757 -104.271043) (xy 442.123794 -104.30101)
			(xy 442.068421 -104.323946) (xy 442.010528 -104.339459) (xy 441.951106 -104.347282) (xy 441.89117 -104.347282)
			(xy 441.831748 -104.339459) (xy 441.773855 -104.323946) (xy 441.718482 -104.30101) (xy 441.666576 -104.271043)
			(xy 441.619026 -104.234556) (xy 441.576646 -104.192176) (xy 441.540159 -104.144626) (xy 441.510192 -104.09272)
			(xy 441.487256 -104.037347) (xy 441.471743 -103.979454) (xy 441.46392 -103.920032) (xy 441.277029 -103.920032)
			(xy 441.276993 -103.922014) (xy 441.268873 -103.97719) (xy 441.252805 -104.030597) (xy 441.229133 -104.081094)
			(xy 441.19836 -104.127607) (xy 441.161143 -104.169144) (xy 441.118275 -104.204819) (xy 441.070669 -104.233873)
			(xy 441.01934 -104.255685) (xy 440.965383 -104.269791) (xy 440.909946 -104.275891) (xy 440.854212 -104.273854)
			(xy 440.799369 -104.263724) (xy 440.746585 -104.245717) (xy 440.696985 -104.220216) (xy 440.651627 -104.187765)
			(xy 440.611478 -104.149056) (xy 440.577392 -104.104913) (xy 440.550096 -104.056278) (xy 440.530173 -104.004187)
			(xy 440.518047 -103.94975) (xy 440.513976 -103.894128) (xy 438.718706 -103.894128) (xy 438.798716 -103.974138)
			(xy 438.805566 -103.981534) (xy 438.8133 -104.000134) (xy 438.813702 -104.010206) (xy 438.813702 -111.333026)
			(xy 438.814117 -111.342909) (xy 438.821516 -111.361231) (xy 438.835314 -111.375377) (xy 438.844182 -111.379762)
			(xy 438.943242 -111.423196) (xy 438.97296 -111.418116) (xy 438.984136 -111.407956) (xy 439.005384 -111.38906)
			(xy 439.052431 -111.35713) (xy 439.103698 -111.332541) (xy 439.158049 -111.315839) (xy 439.214278 -111.307395)
			(xy 439.242708 -111.306864) (xy 439.26996 -111.30735) (xy 439.323908 -111.315108) (xy 439.376203 -111.330463)
			(xy 439.425781 -111.353104) (xy 439.471633 -111.38257) (xy 439.512824 -111.418262) (xy 439.548518 -111.459451)
			(xy 439.577986 -111.505301) (xy 439.60063 -111.554878) (xy 439.615988 -111.607172) (xy 439.623748 -111.66112)
			(xy 439.624216 -111.688372) (xy 439.623795 -111.714691) (xy 439.616596 -111.766834) (xy 439.60229 -111.81749)
			(xy 439.581149 -111.865695) (xy 439.553575 -111.910533) (xy 439.520093 -111.951149) (xy 439.501026 -111.969296)
			(xy 439.49358 -111.976788) (xy 439.485045 -111.996084) (xy 439.484516 -112.006634) (xy 439.484516 -112.08131)
			(xy 439.48509 -112.091851) (xy 439.493603 -112.111144) (xy 439.501026 -112.118648) (xy 439.520085 -112.136798)
			(xy 439.553538 -112.177431) (xy 439.581091 -112.222273) (xy 439.602225 -112.270475) (xy 439.616537 -112.321123)
			(xy 439.623756 -112.373256) (xy 439.624216 -112.399572) (xy 439.623755 -112.426826) (xy 439.616001 -112.480781)
			(xy 439.600647 -112.533082) (xy 439.578007 -112.582667) (xy 439.548539 -112.628524) (xy 439.512846 -112.66972)
			(xy 439.471653 -112.705418) (xy 439.425798 -112.734889) (xy 439.376216 -112.757535) (xy 439.323916 -112.772893)
			(xy 439.269962 -112.780652) (xy 439.242708 -112.78108) (xy 439.213676 -112.78053) (xy 439.156285 -112.771722)
			(xy 439.10089 -112.754323) (xy 439.048769 -112.728734) (xy 439.001125 -112.695545) (xy 438.959058 -112.655524)
			(xy 438.923539 -112.609592) (xy 438.908952 -112.584484) (xy 438.902094 -112.572292) (xy 438.878472 -112.558068)
			(xy 438.864502 -112.558068) (xy 438.854492 -112.558555) (xy 438.835994 -112.566213) (xy 438.821832 -112.580365)
			(xy 438.814162 -112.598858) (xy 438.813702 -112.608868) (xy 438.813702 -112.716056) (xy 438.814136 -112.726122)
			(xy 438.821864 -112.744711) (xy 438.828688 -112.752124) (xy 439.320686 -113.244122) (xy 439.35142 -113.24971)
			(xy 439.366152 -113.243106) (xy 439.390859 -113.232505) (xy 439.442504 -113.217566) (xy 439.495735 -113.210023)
			(xy 439.522616 -113.209578) (xy 439.549867 -113.210065) (xy 439.603814 -113.217823) (xy 439.656107 -113.23318)
			(xy 439.705683 -113.255821) (xy 439.751533 -113.285288) (xy 439.792722 -113.320979) (xy 439.828413 -113.362169)
			(xy 439.85788 -113.408018) (xy 439.880521 -113.457595) (xy 439.895877 -113.509888) (xy 439.903635 -113.563835)
			(xy 439.904124 -113.591086) (xy 439.903667 -113.617967) (xy 439.89613 -113.671198) (xy 439.881201 -113.722846)
			(xy 439.870596 -113.74755) (xy 439.863992 -113.762282) (xy 439.86958 -113.793016) (xy 440.032648 -113.956084)
			(xy 440.059572 -113.962688) (xy 440.073288 -113.95837) (xy 440.10069 -113.950531) (xy 440.157059 -113.942116)
			(xy 440.185556 -113.941606) (xy 440.218416 -113.94229) (xy 440.283168 -113.953523) (xy 440.314334 -113.963958)
			(xy 440.322716 -113.967006) (xy 440.861196 -113.967006)
		)
		(stroke
			(width 0)
			(type solid)
		)
		(fill yes)
		(layer "B.Cu")
		(net "P12V_NIC7_R")
	)
	(gr_poly
		(pts
			(xy 112.710976 -263.64946) (xy 112.72085 -263.648991) (xy 112.739139 -263.641539) (xy 112.746536 -263.634982)
			(xy 112.74679 -263.634728) (xy 113.25098 -263.130538) (xy 113.251488 -263.13003) (xy 113.258064 -263.122646)
			(xy 113.265503 -263.104348) (xy 113.265966 -263.09447) (xy 113.265966 -262.677148) (xy 113.265533 -262.667083)
			(xy 113.257801 -262.648495) (xy 113.25098 -262.64108) (xy 112.925098 -262.315198) (xy 112.917986 -262.307832)
			(xy 112.89919 -262.300212) (xy 112.397286 -262.300212) (xy 112.387217 -262.299787) (xy 112.368615 -262.29207)
			(xy 112.361218 -262.285226) (xy 111.990886 -261.914894) (xy 111.984031 -261.907499) (xy 111.976285 -261.8889)
			(xy 111.9759 -261.878826) (xy 111.9759 -256.420366) (xy 111.976329 -256.410299) (xy 111.984053 -256.391703)
			(xy 111.990886 -256.384298) (xy 113.206276 -255.168908) (xy 113.213678 -255.162073) (xy 113.232277 -255.154365)
			(xy 113.242344 -255.153922) (xy 113.984024 -255.153922) (xy 114.011964 -255.13157) (xy 114.015774 -255.114044)
			(xy 114.022788 -255.084776) (xy 114.043645 -255.02832) (xy 114.071921 -254.975191) (xy 114.107102 -254.926358)
			(xy 114.148544 -254.882714) (xy 114.195491 -254.845054) (xy 114.247086 -254.814067) (xy 114.302387 -254.790317)
			(xy 114.360385 -254.774239) (xy 114.420021 -254.766126) (xy 114.480207 -254.766126) (xy 114.539843 -254.774239)
			(xy 114.597841 -254.790317) (xy 114.653142 -254.814067) (xy 114.704737 -254.845054) (xy 114.751684 -254.882714)
			(xy 114.793126 -254.926358) (xy 114.828307 -254.975191) (xy 114.856583 -255.02832) (xy 114.87744 -255.084776)
			(xy 114.884454 -255.114044) (xy 114.888264 -255.13157) (xy 114.916204 -255.153922) (xy 115.261898 -255.153922)
			(xy 115.271777 -255.153466) (xy 115.290083 -255.146031) (xy 115.297458 -255.139444) (xy 115.297712 -255.13919)
			(xy 115.299236 -255.137666) (xy 115.562888 -254.874268) (xy 115.587324 -254.850719) (xy 115.64202 -254.81055)
			(xy 115.702175 -254.779142) (xy 115.734084 -254.767588) (xy 115.768424 -254.756598) (xy 115.839517 -254.744601)
			(xy 115.875562 -254.743712) (xy 115.881912 -254.743712) (xy 115.907895 -254.744358) (xy 115.959448 -254.750972)
			(xy 116.009876 -254.763559) (xy 116.034312 -254.772414) (xy 116.04625 -254.776732) (xy 116.070888 -254.773938)
			(xy 116.149882 -254.719074) (xy 116.159554 -254.711462) (xy 116.170972 -254.689702) (xy 116.171726 -254.677418)
			(xy 116.171726 -252.165358) (xy 116.172157 -252.155292) (xy 116.179885 -252.136701) (xy 116.186712 -252.12929)
			(xy 116.646198 -251.669804) (xy 116.653596 -251.662957) (xy 116.672194 -251.655221) (xy 116.682266 -251.654818)
			(xy 120.640094 -251.654818) (xy 120.654572 -251.654564) (xy 120.66905 -251.654818) (xy 122.84964 -251.654818)
			(xy 122.859707 -251.655249) (xy 122.878299 -251.662976) (xy 122.885708 -251.669804) (xy 124.633732 -253.417828)
			(xy 126.167878 -253.417828) (xy 126.167878 -253.357892) (xy 126.175701 -253.29847) (xy 126.191214 -253.240577)
			(xy 126.21415 -253.185204) (xy 126.244117 -253.133298) (xy 126.280604 -253.085748) (xy 126.322984 -253.043368)
			(xy 126.370534 -253.006881) (xy 126.42244 -252.976914) (xy 126.477813 -252.953978) (xy 126.535706 -252.938465)
			(xy 126.595128 -252.930642) (xy 126.655064 -252.930642) (xy 126.714486 -252.938465) (xy 126.772379 -252.953978)
			(xy 126.827752 -252.976914) (xy 126.879658 -253.006881) (xy 126.927208 -253.043368) (xy 126.969588 -253.085748)
			(xy 127.006075 -253.133298) (xy 127.032209 -253.178564) (xy 130.349242 -253.178564) (xy 130.353313 -253.122942)
			(xy 130.365439 -253.068505) (xy 130.385362 -253.016414) (xy 130.412658 -252.967779) (xy 130.446744 -252.923636)
			(xy 130.486893 -252.884927) (xy 130.532251 -252.852476) (xy 130.581851 -252.826975) (xy 130.634635 -252.808968)
			(xy 130.689478 -252.798838) (xy 130.745212 -252.796801) (xy 130.800649 -252.802901) (xy 130.854606 -252.817007)
			(xy 130.905935 -252.838819) (xy 130.953541 -252.867873) (xy 130.996409 -252.903548) (xy 131.033626 -252.945085)
			(xy 131.064399 -252.991598) (xy 131.088071 -253.042095) (xy 131.104139 -253.095502) (xy 131.112259 -253.150678)
			(xy 131.112768 -253.178564) (xy 131.112259 -253.20645) (xy 131.104139 -253.261626) (xy 131.088071 -253.315033)
			(xy 131.064399 -253.36553) (xy 131.033626 -253.412043) (xy 130.996409 -253.45358) (xy 130.953541 -253.489255)
			(xy 130.905935 -253.518309) (xy 130.854606 -253.540121) (xy 130.800649 -253.554227) (xy 130.745212 -253.560327)
			(xy 130.689478 -253.55829) (xy 130.634635 -253.54816) (xy 130.581851 -253.530153) (xy 130.532251 -253.504652)
			(xy 130.486893 -253.472201) (xy 130.446744 -253.433492) (xy 130.412658 -253.389349) (xy 130.385362 -253.340714)
			(xy 130.365439 -253.288623) (xy 130.353313 -253.234186) (xy 130.349242 -253.178564) (xy 127.032209 -253.178564)
			(xy 127.036042 -253.185204) (xy 127.058978 -253.240577) (xy 127.074491 -253.29847) (xy 127.082314 -253.357892)
			(xy 127.082804 -253.38786) (xy 127.082314 -253.417828) (xy 127.074491 -253.47725) (xy 127.058978 -253.535143)
			(xy 127.036042 -253.590516) (xy 127.006075 -253.642422) (xy 126.969588 -253.689972) (xy 126.927208 -253.732352)
			(xy 126.879658 -253.768839) (xy 126.827752 -253.798806) (xy 126.772379 -253.821742) (xy 126.714486 -253.837255)
			(xy 126.655064 -253.845078) (xy 126.595128 -253.845078) (xy 126.535706 -253.837255) (xy 126.477813 -253.821742)
			(xy 126.42244 -253.798806) (xy 126.370534 -253.768839) (xy 126.322984 -253.732352) (xy 126.280604 -253.689972)
			(xy 126.244117 -253.642422) (xy 126.21415 -253.590516) (xy 126.191214 -253.535143) (xy 126.175701 -253.47725)
			(xy 126.167878 -253.417828) (xy 124.633732 -253.417828) (xy 125.410468 -254.194564) (xy 128.285746 -254.194564)
			(xy 128.289817 -254.138942) (xy 128.301943 -254.084505) (xy 128.321866 -254.032414) (xy 128.349162 -253.983779)
			(xy 128.383248 -253.939636) (xy 128.423397 -253.900927) (xy 128.468755 -253.868476) (xy 128.518355 -253.842975)
			(xy 128.571139 -253.824968) (xy 128.625982 -253.814838) (xy 128.681716 -253.812801) (xy 128.737153 -253.818901)
			(xy 128.79111 -253.833007) (xy 128.842439 -253.854819) (xy 128.890045 -253.883873) (xy 128.932913 -253.919548)
			(xy 128.97013 -253.961085) (xy 129.000903 -254.007598) (xy 129.024575 -254.058095) (xy 129.040643 -254.111502)
			(xy 129.048763 -254.166678) (xy 129.049272 -254.194564) (xy 129.048763 -254.22245) (xy 129.040643 -254.277626)
			(xy 129.024575 -254.331033) (xy 129.000903 -254.38153) (xy 128.97013 -254.428043) (xy 128.932913 -254.46958)
			(xy 128.890045 -254.505255) (xy 128.842439 -254.534309) (xy 128.79111 -254.556121) (xy 128.737153 -254.570227)
			(xy 128.681716 -254.576327) (xy 128.625982 -254.57429) (xy 128.571139 -254.56416) (xy 128.518355 -254.546153)
			(xy 128.468755 -254.520652) (xy 128.423397 -254.488201) (xy 128.383248 -254.449492) (xy 128.349162 -254.405349)
			(xy 128.321866 -254.356714) (xy 128.301943 -254.304623) (xy 128.289817 -254.250186) (xy 128.285746 -254.194564)
			(xy 125.410468 -254.194564) (xy 126.426468 -255.210564) (xy 128.285746 -255.210564) (xy 128.289817 -255.154942)
			(xy 128.301943 -255.100505) (xy 128.321866 -255.048414) (xy 128.349162 -254.999779) (xy 128.383248 -254.955636)
			(xy 128.423397 -254.916927) (xy 128.468755 -254.884476) (xy 128.518355 -254.858975) (xy 128.571139 -254.840968)
			(xy 128.625982 -254.830838) (xy 128.681716 -254.828801) (xy 128.737153 -254.834901) (xy 128.79111 -254.849007)
			(xy 128.842439 -254.870819) (xy 128.890045 -254.899873) (xy 128.932913 -254.935548) (xy 128.97013 -254.977085)
			(xy 129.000903 -255.023598) (xy 129.024575 -255.074095) (xy 129.040643 -255.127502) (xy 129.048763 -255.182678)
			(xy 129.049272 -255.210564) (xy 130.349242 -255.210564) (xy 130.353313 -255.154942) (xy 130.365439 -255.100505)
			(xy 130.385362 -255.048414) (xy 130.412658 -254.999779) (xy 130.446744 -254.955636) (xy 130.486893 -254.916927)
			(xy 130.532251 -254.884476) (xy 130.581851 -254.858975) (xy 130.634635 -254.840968) (xy 130.689478 -254.830838)
			(xy 130.745212 -254.828801) (xy 130.800649 -254.834901) (xy 130.854606 -254.849007) (xy 130.905935 -254.870819)
			(xy 130.953541 -254.899873) (xy 130.996409 -254.935548) (xy 131.033626 -254.977085) (xy 131.064399 -255.023598)
			(xy 131.088071 -255.074095) (xy 131.104139 -255.127502) (xy 131.112259 -255.182678) (xy 131.112768 -255.210564)
			(xy 131.112259 -255.23845) (xy 131.104139 -255.293626) (xy 131.088071 -255.347033) (xy 131.064399 -255.39753)
			(xy 131.033626 -255.444043) (xy 130.996409 -255.48558) (xy 130.953541 -255.521255) (xy 130.905935 -255.550309)
			(xy 130.854606 -255.572121) (xy 130.800649 -255.586227) (xy 130.745212 -255.592327) (xy 130.689478 -255.59029)
			(xy 130.634635 -255.58016) (xy 130.581851 -255.562153) (xy 130.532251 -255.536652) (xy 130.486893 -255.504201)
			(xy 130.446744 -255.465492) (xy 130.412658 -255.421349) (xy 130.385362 -255.372714) (xy 130.365439 -255.320623)
			(xy 130.353313 -255.266186) (xy 130.349242 -255.210564) (xy 129.049272 -255.210564) (xy 129.048763 -255.23845)
			(xy 129.040643 -255.293626) (xy 129.024575 -255.347033) (xy 129.000903 -255.39753) (xy 128.97013 -255.444043)
			(xy 128.932913 -255.48558) (xy 128.890045 -255.521255) (xy 128.842439 -255.550309) (xy 128.79111 -255.572121)
			(xy 128.737153 -255.586227) (xy 128.681716 -255.592327) (xy 128.625982 -255.59029) (xy 128.571139 -255.58016)
			(xy 128.518355 -255.562153) (xy 128.468755 -255.536652) (xy 128.423397 -255.504201) (xy 128.383248 -255.465492)
			(xy 128.349162 -255.421349) (xy 128.321866 -255.372714) (xy 128.301943 -255.320623) (xy 128.289817 -255.266186)
			(xy 128.285746 -255.210564) (xy 126.426468 -255.210564) (xy 127.528574 -256.31267) (xy 127.535412 -256.320071)
			(xy 127.543125 -256.33867) (xy 127.54356 -256.348738) (xy 127.54356 -258.131564) (xy 128.285746 -258.131564)
			(xy 128.289817 -258.075942) (xy 128.301943 -258.021505) (xy 128.321866 -257.969414) (xy 128.349162 -257.920779)
			(xy 128.383248 -257.876636) (xy 128.423397 -257.837927) (xy 128.468755 -257.805476) (xy 128.518355 -257.779975)
			(xy 128.571139 -257.761968) (xy 128.625982 -257.751838) (xy 128.681716 -257.749801) (xy 128.737153 -257.755901)
			(xy 128.79111 -257.770007) (xy 128.842439 -257.791819) (xy 128.890045 -257.820873) (xy 128.932913 -257.856548)
			(xy 128.97013 -257.898085) (xy 129.000903 -257.944598) (xy 129.024575 -257.995095) (xy 129.040643 -258.048502)
			(xy 129.048763 -258.103678) (xy 129.049272 -258.131564) (xy 129.048763 -258.15945) (xy 129.040643 -258.214626)
			(xy 129.024575 -258.268033) (xy 129.000903 -258.31853) (xy 128.97013 -258.365043) (xy 128.932913 -258.40658)
			(xy 128.890045 -258.442255) (xy 128.842439 -258.471309) (xy 128.79111 -258.493121) (xy 128.737153 -258.507227)
			(xy 128.681716 -258.513327) (xy 128.625982 -258.51129) (xy 128.571139 -258.50116) (xy 128.518355 -258.483153)
			(xy 128.468755 -258.457652) (xy 128.423397 -258.425201) (xy 128.383248 -258.386492) (xy 128.349162 -258.342349)
			(xy 128.321866 -258.293714) (xy 128.301943 -258.241623) (xy 128.289817 -258.187186) (xy 128.285746 -258.131564)
			(xy 127.54356 -258.131564) (xy 127.54356 -259.147564) (xy 130.338828 -259.147564) (xy 130.342899 -259.091942)
			(xy 130.355025 -259.037505) (xy 130.374948 -258.985414) (xy 130.402244 -258.936779) (xy 130.43633 -258.892636)
			(xy 130.476479 -258.853927) (xy 130.521837 -258.821476) (xy 130.571437 -258.795975) (xy 130.624221 -258.777968)
			(xy 130.679064 -258.767838) (xy 130.734798 -258.765801) (xy 130.790235 -258.771901) (xy 130.844192 -258.786007)
			(xy 130.895521 -258.807819) (xy 130.943127 -258.836873) (xy 130.985995 -258.872548) (xy 131.023212 -258.914085)
			(xy 131.053985 -258.960598) (xy 131.077657 -259.011095) (xy 131.093725 -259.064502) (xy 131.101845 -259.119678)
			(xy 131.102354 -259.147564) (xy 131.101845 -259.17545) (xy 131.093725 -259.230626) (xy 131.077657 -259.284033)
			(xy 131.053985 -259.33453) (xy 131.023212 -259.381043) (xy 130.985995 -259.42258) (xy 130.943127 -259.458255)
			(xy 130.895521 -259.487309) (xy 130.844192 -259.509121) (xy 130.790235 -259.523227) (xy 130.734798 -259.529327)
			(xy 130.679064 -259.52729) (xy 130.624221 -259.51716) (xy 130.571437 -259.499153) (xy 130.521837 -259.473652)
			(xy 130.476479 -259.441201) (xy 130.43633 -259.402492) (xy 130.402244 -259.358349) (xy 130.374948 -259.309714)
			(xy 130.355025 -259.257623) (xy 130.342899 -259.203186) (xy 130.338828 -259.147564) (xy 127.54356 -259.147564)
			(xy 127.54356 -261.318756) (xy 127.543971 -261.328786) (xy 127.551632 -261.347325) (xy 127.565804 -261.361521)
			(xy 127.584331 -261.369212) (xy 127.59436 -261.369556) (xy 128.667764 -261.369556) (xy 128.696903 -261.37003)
			(xy 128.754682 -261.377632) (xy 128.810974 -261.392711) (xy 128.864817 -261.415008) (xy 128.915289 -261.444142)
			(xy 128.961526 -261.479615) (xy 129.002737 -261.52082) (xy 129.038218 -261.567052) (xy 129.06736 -261.617519)
			(xy 129.089666 -261.671358) (xy 129.104754 -261.727648) (xy 129.112365 -261.785426) (xy 129.112772 -261.814564)
			(xy 129.112297 -261.843488) (xy 129.104771 -261.900844) (xy 129.089868 -261.956738) (xy 129.067839 -262.010227)
			(xy 129.053844 -262.035544) (xy 129.046732 -262.04799) (xy 129.047494 -262.07593) (xy 129.061718 -262.098536)
			(xy 129.062988 -262.100314) (xy 129.070551 -262.109945) (xy 129.092171 -262.121367) (xy 129.10439 -262.122158)
			(xy 130.333242 -262.122158) (xy 130.333496 -262.122158) (xy 130.345721 -262.121384) (xy 130.367344 -262.10996)
			(xy 130.374898 -262.100314) (xy 130.376168 -262.098536) (xy 130.429 -262.014716) (xy 130.430524 -261.989062)
			(xy 130.424936 -261.977124) (xy 130.413372 -261.951385) (xy 130.397114 -261.897351) (xy 130.389008 -261.841509)
			(xy 130.388614 -261.813294) (xy 130.388614 -261.809484) (xy 130.389439 -261.782467) (xy 130.39777 -261.729063)
			(xy 130.413556 -261.677368) (xy 130.436479 -261.628419) (xy 130.466081 -261.583196) (xy 130.50177 -261.542603)
			(xy 130.542831 -261.507453) (xy 130.588441 -261.478451) (xy 130.637689 -261.456176) (xy 130.689587 -261.441075)
			(xy 130.743097 -261.433449) (xy 130.770122 -261.433056) (xy 130.797076 -261.433522) (xy 130.850447 -261.441111)
			(xy 130.902219 -261.456135) (xy 130.951361 -261.478294) (xy 130.996897 -261.507149) (xy 131.037919 -261.542124)
			(xy 131.073611 -261.582524) (xy 131.103262 -261.627544) (xy 131.126284 -261.676289) (xy 131.142217 -261.727788)
			(xy 131.150744 -261.781018) (xy 131.15163 -261.80796) (xy 131.15163 -261.813802) (xy 131.151246 -261.839902)
			(xy 131.144261 -261.891631) (xy 131.130297 -261.941927) (xy 131.109615 -261.989853) (xy 131.096512 -262.01243)
			(xy 131.092956 -262.018018) (xy 131.088384 -262.033512) (xy 131.086087 -262.042884) (xy 131.087922 -262.062076)
			(xy 131.09194 -262.07085) (xy 131.103878 -262.094472) (xy 131.108523 -262.102611) (xy 131.122475 -262.115095)
			(xy 131.139981 -262.121735) (xy 131.149344 -262.122158) (xy 131.154932 -262.122158) (xy 131.164809 -262.121697)
			(xy 131.183109 -262.114256) (xy 131.190492 -262.10768) (xy 131.190746 -262.107426) (xy 131.368546 -261.929626)
			(xy 131.369054 -261.929118) (xy 131.375632 -261.921735) (xy 131.383072 -261.903436) (xy 131.383532 -261.893558)
			(xy 131.383532 -249.163586) (xy 131.383107 -249.153516) (xy 131.375393 -249.134912) (xy 131.368546 -249.127518)
			(xy 131.07162 -248.830592) (xy 131.064508 -248.823226) (xy 131.045712 -248.815606) (xy 129.077974 -248.815606)
			(xy 129.069019 -248.815955) (xy 129.052198 -248.822104) (xy 129.038506 -248.833648) (xy 129.033778 -248.84126)
			(xy 129.020136 -248.864333) (xy 128.987379 -248.906758) (xy 128.949003 -248.944178) (xy 128.905765 -248.975855)
			(xy 128.858517 -249.001164) (xy 128.80819 -249.019607) (xy 128.755776 -249.03082) (xy 128.702308 -249.034583)
			(xy 128.64884 -249.03082) (xy 128.596426 -249.019607) (xy 128.546099 -249.001164) (xy 128.498851 -248.975855)
			(xy 128.455613 -248.944178) (xy 128.417237 -248.906758) (xy 128.38448 -248.864333) (xy 128.370838 -248.84126)
			(xy 128.36398 -248.829322) (xy 128.340358 -248.815606) (xy 128.325118 -248.815606) (xy 128.314906 -248.816053)
			(xy 128.296106 -248.824027) (xy 128.281946 -248.838742) (xy 128.277874 -248.848118) (xy 128.237742 -248.951242)
			(xy 128.244854 -248.981468) (xy 128.256538 -248.992136) (xy 128.275701 -249.010282) (xy 128.309347 -249.050939)
			(xy 128.337069 -249.095845) (xy 128.358339 -249.144143) (xy 128.372749 -249.194911) (xy 128.380026 -249.247181)
			(xy 128.38049 -249.273568) (xy 128.380004 -249.300819) (xy 128.376034 -249.328432) (xy 129.023616 -249.328432)
			(xy 129.027687 -249.27281) (xy 129.039813 -249.218373) (xy 129.059736 -249.166282) (xy 129.087032 -249.117647)
			(xy 129.121118 -249.073504) (xy 129.161267 -249.034795) (xy 129.206625 -249.002344) (xy 129.256225 -248.976843)
			(xy 129.309009 -248.958836) (xy 129.363852 -248.948706) (xy 129.419586 -248.946669) (xy 129.475023 -248.952769)
			(xy 129.52898 -248.966875) (xy 129.580309 -248.988687) (xy 129.627915 -249.017741) (xy 129.670783 -249.053416)
			(xy 129.708 -249.094953) (xy 129.738773 -249.141466) (xy 129.762445 -249.191963) (xy 129.778513 -249.24537)
			(xy 129.786633 -249.300546) (xy 129.787142 -249.328432) (xy 129.786633 -249.356318) (xy 129.778513 -249.411494)
			(xy 129.762445 -249.464901) (xy 129.738773 -249.515398) (xy 129.708 -249.561911) (xy 129.670783 -249.603448)
			(xy 129.627915 -249.639123) (xy 129.580309 -249.668177) (xy 129.52898 -249.689989) (xy 129.475023 -249.704095)
			(xy 129.419586 -249.710195) (xy 129.363852 -249.708158) (xy 129.309009 -249.698028) (xy 129.256225 -249.680021)
			(xy 129.206625 -249.65452) (xy 129.161267 -249.622069) (xy 129.121118 -249.58336) (xy 129.087032 -249.539217)
			(xy 129.059736 -249.490582) (xy 129.039813 -249.438491) (xy 129.027687 -249.384054) (xy 129.023616 -249.328432)
			(xy 128.376034 -249.328432) (xy 128.372248 -249.354767) (xy 128.356893 -249.407062) (xy 128.334251 -249.456639)
			(xy 128.304785 -249.502489) (xy 128.269094 -249.54368) (xy 128.227903 -249.579371) (xy 128.182053 -249.608837)
			(xy 128.132476 -249.631479) (xy 128.080181 -249.646834) (xy 128.026233 -249.65459) (xy 127.971731 -249.65459)
			(xy 127.917783 -249.646834) (xy 127.865488 -249.631479) (xy 127.815911 -249.608837) (xy 127.770061 -249.579371)
			(xy 127.72887 -249.54368) (xy 127.693179 -249.502489) (xy 127.663713 -249.456639) (xy 127.641071 -249.407062)
			(xy 127.625716 -249.354767) (xy 127.61796 -249.300819) (xy 127.617474 -249.273568) (xy 127.617923 -249.247181)
			(xy 127.625203 -249.194912) (xy 127.639619 -249.144146) (xy 127.660896 -249.095852) (xy 127.688627 -249.050952)
			(xy 127.722284 -249.010304) (xy 127.741426 -248.992136) (xy 127.75311 -248.981468) (xy 127.760222 -248.951242)
			(xy 127.72009 -248.848118) (xy 127.715968 -248.838784) (xy 127.701782 -248.824141) (xy 127.683036 -248.816126)
			(xy 127.672846 -248.815606) (xy 118.187978 -248.815606) (xy 118.178785 -248.815993) (xy 118.161593 -248.822506)
			(xy 118.15445 -248.828306) (xy 118.132331 -248.847222) (xy 118.084361 -248.880181) (xy 118.032777 -248.907136)
			(xy 117.978327 -248.927695) (xy 117.921802 -248.941562) (xy 117.864019 -248.948535) (xy 117.834918 -248.948956)
			(xy 114.2619 -248.948956) (xy 114.251914 -248.949495) (xy 114.233487 -248.957215) (xy 114.226086 -248.963942)
			(xy 112.926462 -250.263656) (xy 129.64971 -250.263656) (xy 129.64971 -250.20372) (xy 129.657533 -250.144298)
			(xy 129.673046 -250.086405) (xy 129.695982 -250.031032) (xy 129.725949 -249.979126) (xy 129.762436 -249.931576)
			(xy 129.804816 -249.889196) (xy 129.852366 -249.852709) (xy 129.904272 -249.822742) (xy 129.959645 -249.799806)
			(xy 130.017538 -249.784293) (xy 130.07696 -249.77647) (xy 130.136896 -249.77647) (xy 130.196318 -249.784293)
			(xy 130.254211 -249.799806) (xy 130.309584 -249.822742) (xy 130.36149 -249.852709) (xy 130.40904 -249.889196)
			(xy 130.45142 -249.931576) (xy 130.487907 -249.979126) (xy 130.517874 -250.031032) (xy 130.54081 -250.086405)
			(xy 130.556323 -250.144298) (xy 130.564146 -250.20372) (xy 130.564636 -250.233688) (xy 130.564146 -250.263656)
			(xy 130.556323 -250.323078) (xy 130.54081 -250.380971) (xy 130.517874 -250.436344) (xy 130.487907 -250.48825)
			(xy 130.45142 -250.5358) (xy 130.40904 -250.57818) (xy 130.36149 -250.614667) (xy 130.309584 -250.644634)
			(xy 130.254211 -250.66757) (xy 130.196318 -250.683083) (xy 130.136896 -250.690906) (xy 130.07696 -250.690906)
			(xy 130.017538 -250.683083) (xy 129.959645 -250.66757) (xy 129.904272 -250.644634) (xy 129.852366 -250.614667)
			(xy 129.804816 -250.57818) (xy 129.762436 -250.5358) (xy 129.725949 -250.48825) (xy 129.695982 -250.436344)
			(xy 129.673046 -250.380971) (xy 129.657533 -250.323078) (xy 129.64971 -250.263656) (xy 112.926462 -250.263656)
			(xy 111.817241 -251.372953) (xy 123.340055 -251.372953) (xy 123.340055 -251.318447) (xy 123.347813 -251.264494)
			(xy 123.363169 -251.212195) (xy 123.385813 -251.162614) (xy 123.415282 -251.116761) (xy 123.450977 -251.075568)
			(xy 123.492172 -251.039874) (xy 123.538027 -251.010406) (xy 123.587609 -250.987765) (xy 123.639908 -250.97241)
			(xy 123.69386 -250.964654) (xy 123.721114 -250.964192) (xy 123.749111 -250.96468) (xy 123.804503 -250.972872)
			(xy 123.858105 -250.989065) (xy 123.908768 -251.012911) (xy 123.955406 -251.043899) (xy 123.997019 -251.081365)
			(xy 124.015246 -251.102622) (xy 124.022612 -251.111766) (xy 124.043948 -251.121418) (xy 124.147326 -251.118878)
			(xy 124.1679 -251.107956) (xy 124.175012 -251.098558) (xy 124.191266 -251.07745) (xy 124.228504 -251.039347)
			(xy 124.270455 -251.006506) (xy 124.316382 -250.979504) (xy 124.365478 -250.958817) (xy 124.41688 -250.944807)
			(xy 124.469684 -250.937721) (xy 124.496322 -250.937268) (xy 124.526059 -250.937845) (xy 124.584878 -250.946649)
			(xy 124.641751 -250.964047) (xy 124.69543 -250.989655) (xy 124.744736 -251.022914) (xy 124.788588 -251.063091)
			(xy 124.807726 -251.085858) (xy 124.814838 -251.094494) (xy 124.83465 -251.1044) (xy 124.934218 -251.10694)
			(xy 124.954538 -251.098304) (xy 124.962158 -251.089922) (xy 124.980299 -251.070488) (xy 125.021071 -251.036369)
			(xy 125.066186 -251.008245) (xy 125.114771 -250.986661) (xy 125.165884 -250.972035) (xy 125.218532 -250.964652)
			(xy 125.245114 -250.964192) (xy 125.272365 -250.964679) (xy 125.326311 -250.972437) (xy 125.378604 -250.987793)
			(xy 125.428179 -251.010435) (xy 125.474028 -251.039902) (xy 125.515217 -251.075593) (xy 125.550907 -251.116783)
			(xy 125.580372 -251.162633) (xy 125.603012 -251.212209) (xy 125.618366 -251.264503) (xy 125.626122 -251.318449)
			(xy 125.626122 -251.372951) (xy 125.618366 -251.426897) (xy 125.603012 -251.479191) (xy 125.580372 -251.528767)
			(xy 125.550907 -251.574617) (xy 125.515217 -251.615807) (xy 125.474028 -251.651498) (xy 125.428179 -251.680965)
			(xy 125.378604 -251.703607) (xy 125.326311 -251.718963) (xy 125.272365 -251.726721) (xy 125.245114 -251.727208)
			(xy 125.217899 -251.726764) (xy 125.16402 -251.719028) (xy 125.111788 -251.703713) (xy 125.062264 -251.681128)
			(xy 125.016454 -251.651732) (xy 124.975287 -251.616123) (xy 124.957078 -251.59589) (xy 124.949712 -251.587508)
			(xy 124.929646 -251.578364) (xy 124.830078 -251.578872) (xy 124.810012 -251.58827) (xy 124.802646 -251.596906)
			(xy 124.783512 -251.618803) (xy 124.739998 -251.657376) (xy 124.691369 -251.689259) (xy 124.638645 -251.713783)
			(xy 124.582931 -251.730436) (xy 124.525396 -251.738866) (xy 124.496322 -251.7394) (xy 124.465872 -251.738823)
			(xy 124.405672 -251.729613) (xy 124.347559 -251.711401) (xy 124.29287 -251.684606) (xy 124.242864 -251.649846)
			(xy 124.198692 -251.607921) (xy 124.179584 -251.584206) (xy 124.172218 -251.574808) (xy 124.15139 -251.564394)
			(xy 124.048012 -251.563886) (xy 124.02693 -251.574046) (xy 124.019818 -251.58319) (xy 124.001607 -251.605251)
			(xy 123.959704 -251.644189) (xy 123.91246 -251.676441) (xy 123.860934 -251.701284) (xy 123.806278 -251.718162)
			(xy 123.749715 -251.726698) (xy 123.721114 -251.727208) (xy 123.69386 -251.726746) (xy 123.639908 -251.71899)
			(xy 123.587609 -251.703635) (xy 123.538027 -251.680994) (xy 123.492172 -251.651526) (xy 123.450977 -251.615832)
			(xy 123.415282 -251.574639) (xy 123.385813 -251.528786) (xy 123.363169 -251.479205) (xy 123.347813 -251.426906)
			(xy 123.340055 -251.372953) (xy 111.817241 -251.372953) (xy 110.591596 -252.598682) (xy 113.663728 -252.598682)
			(xy 113.667799 -252.54306) (xy 113.679925 -252.488623) (xy 113.699848 -252.436532) (xy 113.727144 -252.387897)
			(xy 113.76123 -252.343754) (xy 113.801379 -252.305045) (xy 113.846737 -252.272594) (xy 113.896337 -252.247093)
			(xy 113.949121 -252.229086) (xy 114.003964 -252.218956) (xy 114.059698 -252.216919) (xy 114.115135 -252.223019)
			(xy 114.169092 -252.237125) (xy 114.220421 -252.258937) (xy 114.268027 -252.287991) (xy 114.310895 -252.323666)
			(xy 114.348112 -252.365203) (xy 114.378885 -252.411716) (xy 114.402557 -252.462213) (xy 114.418625 -252.51562)
			(xy 114.426745 -252.570796) (xy 114.427254 -252.598682) (xy 114.426745 -252.626568) (xy 114.418625 -252.681744)
			(xy 114.402557 -252.735151) (xy 114.378885 -252.785648) (xy 114.348112 -252.832161) (xy 114.310895 -252.873698)
			(xy 114.268027 -252.909373) (xy 114.220421 -252.938427) (xy 114.169092 -252.960239) (xy 114.115135 -252.974345)
			(xy 114.059698 -252.980445) (xy 114.003964 -252.978408) (xy 113.949121 -252.968278) (xy 113.896337 -252.950271)
			(xy 113.846737 -252.92477) (xy 113.801379 -252.892319) (xy 113.76123 -252.85361) (xy 113.727144 -252.809467)
			(xy 113.699848 -252.760832) (xy 113.679925 -252.708741) (xy 113.667799 -252.654304) (xy 113.663728 -252.598682)
			(xy 110.591596 -252.598682) (xy 110.538006 -252.652276) (xy 110.531207 -252.659625) (xy 110.523501 -252.678088)
			(xy 110.52302 -252.68809) (xy 110.52302 -254.244452) (xy 113.850648 -254.244452) (xy 113.850648 -254.189948)
			(xy 113.858404 -254.135998) (xy 113.873759 -254.083701) (xy 113.8964 -254.034122) (xy 113.925866 -253.988269)
			(xy 113.961558 -253.947076) (xy 114.002748 -253.911382) (xy 114.048599 -253.881913) (xy 114.098177 -253.859268)
			(xy 114.150473 -253.84391) (xy 114.204422 -253.83615) (xy 114.231674 -253.835662) (xy 114.259831 -253.836187)
			(xy 114.315532 -253.844482) (xy 114.369406 -253.860881) (xy 114.420281 -253.885028) (xy 114.467051 -253.916396)
			(xy 114.488214 -253.934976) (xy 114.49558 -253.94158) (xy 114.513106 -253.948184) (xy 114.602006 -253.947168)
			(xy 114.619532 -253.940056) (xy 114.626644 -253.933452) (xy 114.648003 -253.913898) (xy 114.695563 -253.880863)
			(xy 114.747571 -253.855399) (xy 114.802831 -253.838092) (xy 114.860072 -253.82934) (xy 114.889026 -253.828804)
			(xy 114.916277 -253.829268) (xy 114.970224 -253.837027) (xy 115.022517 -253.852385) (xy 115.072092 -253.875029)
			(xy 115.117941 -253.904496) (xy 115.159129 -253.940189) (xy 115.194819 -253.98138) (xy 115.224284 -254.027231)
			(xy 115.246924 -254.076808) (xy 115.262278 -254.129102) (xy 115.270034 -254.183049) (xy 115.270034 -254.237551)
			(xy 115.262278 -254.291498) (xy 115.246924 -254.343792) (xy 115.224284 -254.393369) (xy 115.194819 -254.43922)
			(xy 115.159129 -254.480411) (xy 115.117941 -254.516104) (xy 115.072092 -254.545571) (xy 115.022517 -254.568215)
			(xy 114.970224 -254.583573) (xy 114.916277 -254.591332) (xy 114.889026 -254.59182) (xy 114.860868 -254.5913)
			(xy 114.805168 -254.583004) (xy 114.751293 -254.566604) (xy 114.700418 -254.542456) (xy 114.653649 -254.511087)
			(xy 114.632486 -254.492506) (xy 114.62512 -254.485902) (xy 114.607594 -254.479298) (xy 114.518694 -254.480314)
			(xy 114.501168 -254.487426) (xy 114.494056 -254.49403) (xy 114.472694 -254.513581) (xy 114.425136 -254.546617)
			(xy 114.373129 -254.572082) (xy 114.317869 -254.589389) (xy 114.260627 -254.598142) (xy 114.231674 -254.598678)
			(xy 114.204422 -254.59825) (xy 114.150473 -254.59049) (xy 114.098177 -254.575132) (xy 114.048599 -254.552487)
			(xy 114.002748 -254.523018) (xy 113.961558 -254.487324) (xy 113.925866 -254.446131) (xy 113.8964 -254.400278)
			(xy 113.873759 -254.350699) (xy 113.858404 -254.298402) (xy 113.850648 -254.244452) (xy 110.52302 -254.244452)
			(xy 110.52302 -262.753602) (xy 110.523477 -262.76348) (xy 110.530919 -262.781781) (xy 110.537498 -262.789162)
			(xy 110.537752 -262.789416) (xy 111.38281 -263.634474) (xy 111.383318 -263.634982) (xy 111.390699 -263.641567)
			(xy 111.408997 -263.649025) (xy 111.418878 -263.64946)
		)
		(stroke
			(width 0)
			(type solid)
		)
		(fill yes)
		(layer "B.Cu")
		(net "P3V3_AUX")
	)
	(gr_poly
		(pts
			(xy 102.183438 -247.847104) (xy 102.194393 -247.846526) (xy 102.214277 -247.837314) (xy 102.221792 -247.829324)
			(xy 102.27945 -247.762268) (xy 102.285546 -247.740932) (xy 102.283768 -247.73001) (xy 102.281632 -247.715436)
			(xy 102.279343 -247.686065) (xy 102.279196 -247.671336) (xy 102.279714 -247.642596) (xy 102.288332 -247.585765)
			(xy 102.305378 -247.530871) (xy 102.330466 -247.479155) (xy 102.363029 -247.431788) (xy 102.38232 -247.410478)
			(xy 102.388924 -247.403366) (xy 102.396036 -247.38584) (xy 102.396036 -247.296432) (xy 102.388924 -247.278906)
			(xy 102.38232 -247.271794) (xy 102.363047 -247.250468) (xy 102.330478 -247.203106) (xy 102.305382 -247.151395)
			(xy 102.288327 -247.096504) (xy 102.279699 -247.039676) (xy 102.279196 -247.010936) (xy 102.279672 -246.983568)
			(xy 102.287504 -246.929394) (xy 102.302998 -246.876895) (xy 102.325836 -246.82715) (xy 102.355549 -246.78118)
			(xy 102.373176 -246.760238) (xy 102.379272 -246.753126) (xy 102.385622 -246.736108) (xy 102.385622 -246.650764)
			(xy 102.379272 -246.633746) (xy 102.373176 -246.626634) (xy 102.355533 -246.605703) (xy 102.325805 -246.559737)
			(xy 102.302959 -246.50999) (xy 102.287465 -246.457487) (xy 102.279642 -246.403307) (xy 102.279196 -246.375936)
			(xy 102.279682 -246.348685) (xy 102.287438 -246.294737) (xy 102.302793 -246.242442) (xy 102.325435 -246.192865)
			(xy 102.354901 -246.147015) (xy 102.390592 -246.105824) (xy 102.431783 -246.070133) (xy 102.477633 -246.040667)
			(xy 102.52721 -246.018025) (xy 102.579505 -246.00267) (xy 102.633453 -245.994914) (xy 102.687955 -245.994914)
			(xy 102.741903 -246.00267) (xy 102.794198 -246.018025) (xy 102.843775 -246.040667) (xy 102.889625 -246.070133)
			(xy 102.930816 -246.105824) (xy 102.966507 -246.147015) (xy 102.995973 -246.192865) (xy 103.018615 -246.242442)
			(xy 103.03397 -246.294737) (xy 103.041726 -246.348685) (xy 103.042212 -246.375936) (xy 103.041738 -246.403305)
			(xy 103.03391 -246.457481) (xy 103.018419 -246.509982) (xy 102.995584 -246.55973) (xy 102.965874 -246.605704)
			(xy 102.948232 -246.626634) (xy 102.942136 -246.633746) (xy 102.935786 -246.650764) (xy 102.935786 -246.736108)
			(xy 102.942136 -246.753126) (xy 102.948232 -246.760238) (xy 102.965871 -246.781171) (xy 102.99559 -246.827139)
			(xy 103.018426 -246.876886) (xy 103.033909 -246.929389) (xy 103.041722 -246.983567) (xy 103.042212 -247.010936)
			(xy 103.041688 -247.039674) (xy 103.033061 -247.096499) (xy 103.016007 -247.151388) (xy 102.990913 -247.203097)
			(xy 102.958346 -247.250456) (xy 102.939088 -247.271794) (xy 102.932484 -247.278906) (xy 102.925372 -247.296432)
			(xy 102.925372 -247.38584) (xy 102.932484 -247.403366) (xy 102.939088 -247.410478) (xy 102.958362 -247.431804)
			(xy 102.990934 -247.479165) (xy 103.016034 -247.530876) (xy 103.033092 -247.585767) (xy 103.041724 -247.642596)
			(xy 103.042212 -247.671336) (xy 103.042059 -247.686065) (xy 103.039768 -247.715434) (xy 103.03764 -247.73001)
			(xy 103.035862 -247.740932) (xy 103.041958 -247.762268) (xy 103.099616 -247.829324) (xy 103.107139 -247.837303)
			(xy 103.127019 -247.84651) (xy 103.13797 -247.847104) (xy 110.397036 -247.847104) (xy 110.407103 -247.846674)
			(xy 110.425699 -247.838951) (xy 110.433104 -247.832118) (xy 111.114078 -247.151398) (xy 111.131759 -247.134367)
			(xy 111.17143 -247.105452) (xy 111.215113 -247.083055) (xy 111.238284 -247.074944) (xy 111.254032 -247.069864)
			(xy 111.273336 -247.043194) (xy 111.273336 -233.390948) (xy 111.272902 -233.380883) (xy 111.265167 -233.362299)
			(xy 111.25835 -233.35488) (xy 110.74781 -232.84434) (xy 110.740414 -232.837488) (xy 110.721816 -232.829743)
			(xy 110.711742 -232.829354) (xy 96.044004 -232.829354) (xy 96.033935 -232.829778) (xy 96.015334 -232.837497)
			(xy 96.007936 -232.84434) (xy 95.849948 -233.002328) (xy 95.843101 -233.009726) (xy 95.835369 -233.028324)
			(xy 95.834962 -233.038396) (xy 95.834962 -239.009682) (xy 98.707448 -239.009682) (xy 98.707448 -237.571026)
			(xy 98.707888 -237.561019) (xy 98.715622 -237.542556) (xy 98.722434 -237.535212) (xy 98.968814 -237.288832)
			(xy 98.976243 -237.282176) (xy 98.994666 -237.274587) (xy 99.004628 -237.2741) (xy 108.190284 -237.2741)
			(xy 108.200253 -237.274559) (xy 108.21869 -237.282145) (xy 108.226098 -237.288832) (xy 108.472478 -237.535212)
			(xy 108.479219 -237.542602) (xy 108.48693 -237.561037) (xy 108.487464 -237.571026) (xy 108.487464 -238.882682)
			(xy 108.487025 -238.892689) (xy 108.47929 -238.911151) (xy 108.472478 -238.918496) (xy 108.099098 -239.291876)
			(xy 108.091665 -239.298527) (xy 108.073245 -239.306119) (xy 108.063284 -239.306608) (xy 99.004628 -239.306608)
			(xy 98.99466 -239.306141) (xy 98.976223 -239.29856) (xy 98.968814 -239.291876) (xy 98.722434 -239.045496)
			(xy 98.715698 -239.038102) (xy 98.707984 -239.01967) (xy 98.707448 -239.009682) (xy 95.834962 -239.009682)
			(xy 95.834962 -241.272564) (xy 96.044494 -241.272564) (xy 96.044494 -241.212628) (xy 96.052317 -241.153206)
			(xy 96.06783 -241.095313) (xy 96.090766 -241.03994) (xy 96.120733 -240.988034) (xy 96.15722 -240.940484)
			(xy 96.1996 -240.898104) (xy 96.24715 -240.861617) (xy 96.299056 -240.83165) (xy 96.354429 -240.808714)
			(xy 96.412322 -240.793201) (xy 96.471744 -240.785378) (xy 96.53168 -240.785378) (xy 96.591102 -240.793201)
			(xy 96.648995 -240.808714) (xy 96.673022 -240.818666) (xy 97.296206 -240.818666) (xy 97.296206 -240.75873)
			(xy 97.304029 -240.699308) (xy 97.319542 -240.641415) (xy 97.342478 -240.586042) (xy 97.372445 -240.534136)
			(xy 97.408932 -240.486586) (xy 97.451312 -240.444206) (xy 97.498862 -240.407719) (xy 97.550768 -240.377752)
			(xy 97.606141 -240.354816) (xy 97.664034 -240.339303) (xy 97.723456 -240.33148) (xy 97.783392 -240.33148)
			(xy 97.842814 -240.339303) (xy 97.900707 -240.354816) (xy 97.95608 -240.377752) (xy 98.007986 -240.407719)
			(xy 98.055536 -240.444206) (xy 98.097916 -240.486586) (xy 98.134403 -240.534136) (xy 98.16437 -240.586042)
			(xy 98.187306 -240.641415) (xy 98.202819 -240.699308) (xy 98.210642 -240.75873) (xy 98.211132 -240.788698)
			(xy 98.210642 -240.818666) (xy 98.202819 -240.878088) (xy 98.189406 -240.928144) (xy 99.417122 -240.928144)
			(xy 99.421193 -240.872522) (xy 99.433319 -240.818085) (xy 99.453242 -240.765994) (xy 99.480538 -240.717359)
			(xy 99.514624 -240.673216) (xy 99.554773 -240.634507) (xy 99.600131 -240.602056) (xy 99.649731 -240.576555)
			(xy 99.702515 -240.558548) (xy 99.757358 -240.548418) (xy 99.813092 -240.546381) (xy 99.868529 -240.552481)
			(xy 99.922486 -240.566587) (xy 99.973815 -240.588399) (xy 100.021421 -240.617453) (xy 100.064289 -240.653128)
			(xy 100.101506 -240.694665) (xy 100.132279 -240.741178) (xy 100.155951 -240.791675) (xy 100.172019 -240.845082)
			(xy 100.180139 -240.900258) (xy 100.180648 -240.928144) (xy 101.89972 -240.928144) (xy 101.900206 -240.900893)
			(xy 101.907962 -240.846945) (xy 101.923317 -240.79465) (xy 101.945959 -240.745073) (xy 101.975425 -240.699223)
			(xy 102.011116 -240.658032) (xy 102.052307 -240.622341) (xy 102.098157 -240.592875) (xy 102.147734 -240.570233)
			(xy 102.200029 -240.554878) (xy 102.253977 -240.547122) (xy 102.308479 -240.547122) (xy 102.362427 -240.554878)
			(xy 102.414722 -240.570233) (xy 102.464299 -240.592875) (xy 102.510149 -240.622341) (xy 102.55134 -240.658032)
			(xy 102.587031 -240.699223) (xy 102.616497 -240.745073) (xy 102.639139 -240.79465) (xy 102.654494 -240.846945)
			(xy 102.66225 -240.900893) (xy 102.662736 -240.928144) (xy 102.66227 -240.954485) (xy 102.655022 -241.006665)
			(xy 102.640668 -241.057354) (xy 102.619482 -241.105587) (xy 102.591866 -241.15045) (xy 102.558344 -241.191091)
			(xy 102.519554 -241.226737) (xy 102.498144 -241.242088) (xy 102.486333 -241.250801) (xy 102.467897 -241.273622)
			(xy 102.456711 -241.300744) (xy 102.453701 -241.329927) (xy 102.459115 -241.35876) (xy 102.472506 -241.384864)
			(xy 102.492768 -241.406081) (xy 102.505256 -241.413792) (xy 102.529804 -241.428466) (xy 102.574559 -241.464075)
			(xy 102.613499 -241.505963) (xy 102.645752 -241.553193) (xy 102.670595 -241.604707) (xy 102.687474 -241.659352)
			(xy 102.696008 -241.715904) (xy 102.696518 -241.7445) (xy 102.696032 -241.771751) (xy 102.688276 -241.825699)
			(xy 102.672921 -241.877994) (xy 102.650279 -241.927571) (xy 102.620813 -241.973421) (xy 102.585122 -242.014612)
			(xy 102.543931 -242.050303) (xy 102.498081 -242.079769) (xy 102.448504 -242.102411) (xy 102.396209 -242.117766)
			(xy 102.342261 -242.125522) (xy 102.287759 -242.125522) (xy 102.233811 -242.117766) (xy 102.181516 -242.102411)
			(xy 102.131939 -242.079769) (xy 102.086089 -242.050303) (xy 102.044898 -242.014612) (xy 102.009207 -241.973421)
			(xy 101.979741 -241.927571) (xy 101.957099 -241.877994) (xy 101.941744 -241.825699) (xy 101.933988 -241.771751)
			(xy 101.933502 -241.7445) (xy 101.933909 -241.718157) (xy 101.941166 -241.665973) (xy 101.955529 -241.615283)
			(xy 101.976724 -241.567048) (xy 102.00435 -241.522186) (xy 102.03788 -241.481548) (xy 102.07668 -241.445905)
			(xy 102.098094 -241.430556) (xy 102.109855 -241.421783) (xy 102.128283 -241.398974) (xy 102.139466 -241.371867)
			(xy 102.14248 -241.342699) (xy 102.137077 -241.313877) (xy 102.123702 -241.287782) (xy 102.10346 -241.266566)
			(xy 102.090982 -241.258852) (xy 102.066462 -241.244133) (xy 102.021705 -241.208533) (xy 101.982763 -241.166653)
			(xy 101.950506 -241.119431) (xy 101.925658 -241.067923) (xy 101.908774 -241.013285) (xy 101.900233 -240.956738)
			(xy 101.89972 -240.928144) (xy 100.180648 -240.928144) (xy 100.180139 -240.95603) (xy 100.172019 -241.011206)
			(xy 100.155951 -241.064613) (xy 100.132279 -241.11511) (xy 100.101506 -241.161623) (xy 100.064289 -241.20316)
			(xy 100.021421 -241.238835) (xy 99.973815 -241.267889) (xy 99.922486 -241.289701) (xy 99.868529 -241.303807)
			(xy 99.813092 -241.309907) (xy 99.757358 -241.30787) (xy 99.702515 -241.29774) (xy 99.649731 -241.279733)
			(xy 99.600131 -241.254232) (xy 99.554773 -241.221781) (xy 99.514624 -241.183072) (xy 99.480538 -241.138929)
			(xy 99.453242 -241.090294) (xy 99.433319 -241.038203) (xy 99.421193 -240.983766) (xy 99.417122 -240.928144)
			(xy 98.189406 -240.928144) (xy 98.187306 -240.935981) (xy 98.16437 -240.991354) (xy 98.134403 -241.04326)
			(xy 98.097916 -241.09081) (xy 98.055536 -241.13319) (xy 98.007986 -241.169677) (xy 97.95608 -241.199644)
			(xy 97.900707 -241.22258) (xy 97.842814 -241.238093) (xy 97.783392 -241.245916) (xy 97.723456 -241.245916)
			(xy 97.664034 -241.238093) (xy 97.606141 -241.22258) (xy 97.550768 -241.199644) (xy 97.498862 -241.169677)
			(xy 97.451312 -241.13319) (xy 97.408932 -241.09081) (xy 97.372445 -241.04326) (xy 97.342478 -240.991354)
			(xy 97.319542 -240.935981) (xy 97.304029 -240.878088) (xy 97.296206 -240.818666) (xy 96.673022 -240.818666)
			(xy 96.704368 -240.83165) (xy 96.756274 -240.861617) (xy 96.803824 -240.898104) (xy 96.846204 -240.940484)
			(xy 96.882691 -240.988034) (xy 96.912658 -241.03994) (xy 96.935594 -241.095313) (xy 96.951107 -241.153206)
			(xy 96.95893 -241.212628) (xy 96.95942 -241.242596) (xy 96.95893 -241.272564) (xy 96.951107 -241.331986)
			(xy 96.935594 -241.389879) (xy 96.912658 -241.445252) (xy 96.882691 -241.497158) (xy 96.846204 -241.544708)
			(xy 96.803824 -241.587088) (xy 96.756274 -241.623575) (xy 96.704368 -241.653542) (xy 96.648995 -241.676478)
			(xy 96.591102 -241.691991) (xy 96.53168 -241.699814) (xy 96.471744 -241.699814) (xy 96.412322 -241.691991)
			(xy 96.354429 -241.676478) (xy 96.299056 -241.653542) (xy 96.24715 -241.623575) (xy 96.1996 -241.587088)
			(xy 96.15722 -241.544708) (xy 96.120733 -241.497158) (xy 96.090766 -241.445252) (xy 96.06783 -241.389879)
			(xy 96.052317 -241.331986) (xy 96.044494 -241.272564) (xy 95.834962 -241.272564) (xy 95.834962 -241.76736)
			(xy 95.835485 -241.778803) (xy 95.845403 -241.799427) (xy 95.854012 -241.806984) (xy 95.925132 -241.86388)
			(xy 95.947484 -241.86896) (xy 95.95866 -241.86642) (xy 95.979281 -241.862109) (xy 96.021161 -241.857529)
			(xy 96.042226 -241.857276) (xy 96.069476 -241.857764) (xy 96.123422 -241.865523) (xy 96.175715 -241.88088)
			(xy 96.22529 -241.903523) (xy 96.271138 -241.932989) (xy 96.312326 -241.968681) (xy 96.348017 -242.00987)
			(xy 96.377482 -242.055719) (xy 96.400123 -242.105295) (xy 96.415479 -242.157588) (xy 96.423237 -242.211534)
			(xy 96.423734 -242.238784) (xy 96.423213 -242.26731) (xy 96.41468 -242.32372) (xy 96.397832 -242.378228)
			(xy 96.385888 -242.404138) (xy 96.381062 -242.414552) (xy 96.380808 -242.436904) (xy 96.422464 -242.528598)
			(xy 96.439482 -242.54333) (xy 96.450404 -242.546124) (xy 96.478965 -242.554552) (xy 96.533792 -242.57779)
			(xy 96.585146 -242.607937) (xy 96.63216 -242.644484) (xy 96.647931 -242.660424) (xy 97.53803 -242.660424)
			(xy 97.542101 -242.604802) (xy 97.554227 -242.550365) (xy 97.57415 -242.498274) (xy 97.601446 -242.449639)
			(xy 97.635532 -242.405496) (xy 97.675681 -242.366787) (xy 97.721039 -242.334336) (xy 97.770639 -242.308835)
			(xy 97.823423 -242.290828) (xy 97.878266 -242.280698) (xy 97.934 -242.278661) (xy 97.989437 -242.284761)
			(xy 98.043394 -242.298867) (xy 98.094723 -242.320679) (xy 98.142329 -242.349733) (xy 98.185197 -242.385408)
			(xy 98.222414 -242.426945) (xy 98.253187 -242.473458) (xy 98.276859 -242.523955) (xy 98.292927 -242.577362)
			(xy 98.301047 -242.632538) (xy 98.301352 -242.649248) (xy 98.716082 -242.649248) (xy 98.720153 -242.593626)
			(xy 98.732279 -242.539189) (xy 98.752202 -242.487098) (xy 98.779498 -242.438463) (xy 98.813584 -242.39432)
			(xy 98.853733 -242.355611) (xy 98.899091 -242.32316) (xy 98.948691 -242.297659) (xy 99.001475 -242.279652)
			(xy 99.056318 -242.269522) (xy 99.112052 -242.267485) (xy 99.167489 -242.273585) (xy 99.221446 -242.287691)
			(xy 99.272775 -242.309503) (xy 99.320381 -242.338557) (xy 99.363249 -242.374232) (xy 99.400466 -242.415769)
			(xy 99.431239 -242.462282) (xy 99.454911 -242.512779) (xy 99.470979 -242.566186) (xy 99.479099 -242.621362)
			(xy 99.479608 -242.649248) (xy 99.479099 -242.677134) (xy 99.470979 -242.73231) (xy 99.454911 -242.785717)
			(xy 99.453873 -242.787932) (xy 100.24821 -242.787932) (xy 100.252281 -242.73231) (xy 100.264407 -242.677873)
			(xy 100.28433 -242.625782) (xy 100.311626 -242.577147) (xy 100.345712 -242.533004) (xy 100.385861 -242.494295)
			(xy 100.431219 -242.461844) (xy 100.480819 -242.436343) (xy 100.533603 -242.418336) (xy 100.588446 -242.408206)
			(xy 100.64418 -242.406169) (xy 100.699617 -242.412269) (xy 100.753574 -242.426375) (xy 100.804903 -242.448187)
			(xy 100.852509 -242.477241) (xy 100.895377 -242.512916) (xy 100.932594 -242.554453) (xy 100.963367 -242.600966)
			(xy 100.987039 -242.651463) (xy 101.003107 -242.70487) (xy 101.011227 -242.760046) (xy 101.011736 -242.787932)
			(xy 101.011227 -242.815818) (xy 101.003107 -242.870994) (xy 100.987039 -242.924401) (xy 100.963367 -242.974898)
			(xy 100.932594 -243.021411) (xy 100.895377 -243.062948) (xy 100.852509 -243.098623) (xy 100.804903 -243.127677)
			(xy 100.753574 -243.149489) (xy 100.699617 -243.163595) (xy 100.64418 -243.169695) (xy 100.588446 -243.167658)
			(xy 100.533603 -243.157528) (xy 100.480819 -243.139521) (xy 100.431219 -243.11402) (xy 100.385861 -243.081569)
			(xy 100.345712 -243.04286) (xy 100.311626 -242.998717) (xy 100.28433 -242.950082) (xy 100.264407 -242.897991)
			(xy 100.252281 -242.843554) (xy 100.24821 -242.787932) (xy 99.453873 -242.787932) (xy 99.431239 -242.836214)
			(xy 99.400466 -242.882727) (xy 99.363249 -242.924264) (xy 99.320381 -242.959939) (xy 99.272775 -242.988993)
			(xy 99.221446 -243.010805) (xy 99.167489 -243.024911) (xy 99.112052 -243.031011) (xy 99.056318 -243.028974)
			(xy 99.001475 -243.018844) (xy 98.948691 -243.000837) (xy 98.899091 -242.975336) (xy 98.853733 -242.942885)
			(xy 98.813584 -242.904176) (xy 98.779498 -242.860033) (xy 98.752202 -242.811398) (xy 98.732279 -242.759307)
			(xy 98.720153 -242.70487) (xy 98.716082 -242.649248) (xy 98.301352 -242.649248) (xy 98.301556 -242.660424)
			(xy 98.301047 -242.68831) (xy 98.292927 -242.743486) (xy 98.276859 -242.796893) (xy 98.253187 -242.84739)
			(xy 98.222414 -242.893903) (xy 98.185197 -242.93544) (xy 98.142329 -242.971115) (xy 98.094723 -243.000169)
			(xy 98.043394 -243.021981) (xy 97.989437 -243.036087) (xy 97.934 -243.042187) (xy 97.878266 -243.04015)
			(xy 97.823423 -243.03002) (xy 97.770639 -243.012013) (xy 97.721039 -242.986512) (xy 97.675681 -242.954061)
			(xy 97.635532 -242.915352) (xy 97.601446 -242.871209) (xy 97.57415 -242.822574) (xy 97.554227 -242.770483)
			(xy 97.542101 -242.716046) (xy 97.53803 -242.660424) (xy 96.647931 -242.660424) (xy 96.674042 -242.686815)
			(xy 96.710086 -242.734217) (xy 96.739684 -242.785889) (xy 96.762336 -242.840961) (xy 96.777661 -242.898504)
			(xy 96.7854 -242.957548) (xy 96.785938 -242.987322) (xy 96.785447 -243.017289) (xy 96.777621 -243.076711)
			(xy 96.762107 -243.134603) (xy 96.73917 -243.189976) (xy 96.709202 -243.24188) (xy 96.672716 -243.28943)
			(xy 96.630336 -243.331811) (xy 96.582787 -243.368298) (xy 96.530883 -243.398267) (xy 96.475511 -243.421205)
			(xy 96.417619 -243.43672) (xy 96.358197 -243.444546) (xy 96.32823 -243.44503) (xy 96.298623 -243.444559)
			(xy 96.239906 -243.436912) (xy 96.182665 -243.421756) (xy 96.127858 -243.399344) (xy 96.076399 -243.370049)
			(xy 96.029148 -243.334362) (xy 96.007682 -243.313966) (xy 95.99676 -243.303298) (xy 95.966788 -243.297456)
			(xy 95.866204 -243.33962) (xy 95.857109 -243.343851) (xy 95.842959 -243.358047) (xy 95.835342 -243.376587)
			(xy 95.834962 -243.38661) (xy 95.834962 -243.8273) (xy 97.5266 -243.8273) (xy 97.530671 -243.771678)
			(xy 97.542797 -243.717241) (xy 97.56272 -243.66515) (xy 97.590016 -243.616515) (xy 97.624102 -243.572372)
			(xy 97.664251 -243.533663) (xy 97.709609 -243.501212) (xy 97.759209 -243.475711) (xy 97.811993 -243.457704)
			(xy 97.866836 -243.447574) (xy 97.92257 -243.445537) (xy 97.978007 -243.451637) (xy 98.031964 -243.465743)
			(xy 98.083293 -243.487555) (xy 98.130899 -243.516609) (xy 98.173767 -243.552284) (xy 98.210984 -243.593821)
			(xy 98.241757 -243.640334) (xy 98.265429 -243.690831) (xy 98.281497 -243.744238) (xy 98.289617 -243.799414)
			(xy 98.289917 -243.81587) (xy 98.716082 -243.81587) (xy 98.720153 -243.760248) (xy 98.732279 -243.705811)
			(xy 98.752202 -243.65372) (xy 98.779498 -243.605085) (xy 98.813584 -243.560942) (xy 98.853733 -243.522233)
			(xy 98.899091 -243.489782) (xy 98.948691 -243.464281) (xy 99.001475 -243.446274) (xy 99.056318 -243.436144)
			(xy 99.112052 -243.434107) (xy 99.167489 -243.440207) (xy 99.221446 -243.454313) (xy 99.272775 -243.476125)
			(xy 99.320381 -243.505179) (xy 99.363249 -243.540854) (xy 99.400466 -243.582391) (xy 99.431239 -243.628904)
			(xy 99.454911 -243.679401) (xy 99.470979 -243.732808) (xy 99.479099 -243.787984) (xy 99.479608 -243.81587)
			(xy 99.479099 -243.843756) (xy 99.470979 -243.898932) (xy 99.454911 -243.952339) (xy 99.431239 -244.002836)
			(xy 99.400466 -244.049349) (xy 99.363249 -244.090886) (xy 99.320381 -244.126561) (xy 99.272775 -244.155615)
			(xy 99.221446 -244.177427) (xy 99.167489 -244.191533) (xy 99.112052 -244.197633) (xy 99.056318 -244.195596)
			(xy 99.001475 -244.185466) (xy 98.948691 -244.167459) (xy 98.899091 -244.141958) (xy 98.853733 -244.109507)
			(xy 98.813584 -244.070798) (xy 98.779498 -244.026655) (xy 98.752202 -243.97802) (xy 98.732279 -243.925929)
			(xy 98.720153 -243.871492) (xy 98.716082 -243.81587) (xy 98.289917 -243.81587) (xy 98.290126 -243.8273)
			(xy 98.289617 -243.855186) (xy 98.281497 -243.910362) (xy 98.265429 -243.963769) (xy 98.241757 -244.014266)
			(xy 98.210984 -244.060779) (xy 98.173767 -244.102316) (xy 98.130899 -244.137991) (xy 98.083293 -244.167045)
			(xy 98.031964 -244.188857) (xy 97.978007 -244.202963) (xy 97.92257 -244.209063) (xy 97.866836 -244.207026)
			(xy 97.811993 -244.196896) (xy 97.759209 -244.178889) (xy 97.709609 -244.153388) (xy 97.664251 -244.120937)
			(xy 97.624102 -244.082228) (xy 97.590016 -244.038085) (xy 97.56272 -243.98945) (xy 97.542797 -243.937359)
			(xy 97.530671 -243.882922) (xy 97.5266 -243.8273) (xy 95.834962 -243.8273) (xy 95.834962 -243.839492)
			(xy 95.835324 -243.848539) (xy 95.841606 -243.865507) (xy 95.853389 -243.879237) (xy 95.861124 -243.883942)
			(xy 95.951294 -243.933726) (xy 95.978726 -243.932964) (xy 95.990664 -243.925344) (xy 96.018156 -243.90873)
			(xy 96.076799 -243.882518) (xy 96.138528 -243.86475) (xy 96.202133 -243.855775) (xy 96.23425 -243.85524)
			(xy 96.264218 -243.855706) (xy 96.323642 -243.863523) (xy 96.381537 -243.87903) (xy 96.436912 -243.901962)
			(xy 96.488821 -243.931927) (xy 96.536373 -243.96841) (xy 96.578757 -244.010789) (xy 96.615246 -244.058338)
			(xy 96.645216 -244.110243) (xy 96.668154 -244.165616) (xy 96.683667 -244.223509) (xy 96.691491 -244.282932)
			(xy 96.691491 -244.342868) (xy 96.683667 -244.402291) (xy 96.668154 -244.460184) (xy 96.645216 -244.515557)
			(xy 96.615246 -244.567462) (xy 96.592838 -244.596662) (xy 100.44479 -244.596662) (xy 100.44479 -244.536726)
			(xy 100.452613 -244.477304) (xy 100.468126 -244.419411) (xy 100.491062 -244.364038) (xy 100.521029 -244.312132)
			(xy 100.557516 -244.264582) (xy 100.599896 -244.222202) (xy 100.647446 -244.185715) (xy 100.699352 -244.155748)
			(xy 100.754725 -244.132812) (xy 100.812618 -244.117299) (xy 100.87204 -244.109476) (xy 100.931976 -244.109476)
			(xy 100.991398 -244.117299) (xy 101.049291 -244.132812) (xy 101.104664 -244.155748) (xy 101.15657 -244.185715)
			(xy 101.20412 -244.222202) (xy 101.2465 -244.264582) (xy 101.282987 -244.312132) (xy 101.312954 -244.364038)
			(xy 101.33589 -244.419411) (xy 101.341824 -244.441555) (xy 104.256749 -244.441555) (xy 104.256749 -244.387045)
			(xy 104.264508 -244.33309) (xy 104.279866 -244.280788) (xy 104.302512 -244.231204) (xy 104.331984 -244.185348)
			(xy 104.367682 -244.144154) (xy 104.40888 -244.10846) (xy 104.454739 -244.078992) (xy 104.504325 -244.056352)
			(xy 104.556629 -244.040999) (xy 104.610585 -244.033247) (xy 104.63784 -244.032786) (xy 104.66658 -244.033289)
			(xy 104.723408 -244.041917) (xy 104.778299 -244.058972) (xy 104.83001 -244.084068) (xy 104.877372 -244.116638)
			(xy 104.898698 -244.13591) (xy 104.90581 -244.142514) (xy 104.923336 -244.149626) (xy 105.012744 -244.149626)
			(xy 105.03027 -244.142514) (xy 105.037382 -244.13591) (xy 105.058709 -244.11664) (xy 105.106072 -244.084075)
			(xy 105.157783 -244.058984) (xy 105.212674 -244.041934) (xy 105.269501 -244.033312) (xy 105.326979 -244.033312)
			(xy 105.383806 -244.041934) (xy 105.438697 -244.058984) (xy 105.490408 -244.084075) (xy 105.537771 -244.11664)
			(xy 105.559098 -244.13591) (xy 105.56621 -244.142514) (xy 105.583736 -244.149626) (xy 105.673144 -244.149626)
			(xy 105.69067 -244.142514) (xy 105.697782 -244.13591) (xy 105.719089 -244.116616) (xy 105.766457 -244.084054)
			(xy 105.818174 -244.058966) (xy 105.873069 -244.041921) (xy 105.9299 -244.033304) (xy 105.95864 -244.032786)
			(xy 105.985889 -244.033286) (xy 106.039832 -244.041048) (xy 106.092121 -244.056406) (xy 106.141692 -244.079049)
			(xy 106.187537 -244.108516) (xy 106.228722 -244.144207) (xy 106.264408 -244.185395) (xy 106.29387 -244.231243)
			(xy 106.316508 -244.280817) (xy 106.331861 -244.333108) (xy 106.339616 -244.387051) (xy 106.339616 -244.441549)
			(xy 106.331861 -244.495492) (xy 106.316508 -244.547783) (xy 106.29387 -244.597357) (xy 106.264408 -244.643205)
			(xy 106.228722 -244.684393) (xy 106.187537 -244.720084) (xy 106.141692 -244.749551) (xy 106.092121 -244.772194)
			(xy 106.039832 -244.787552) (xy 105.985889 -244.795314) (xy 105.95864 -244.795802) (xy 105.9299 -244.795314)
			(xy 105.873071 -244.786683) (xy 105.81818 -244.769624) (xy 105.766469 -244.744525) (xy 105.719108 -244.711952)
			(xy 105.697782 -244.692678) (xy 105.69067 -244.686074) (xy 105.673144 -244.678962) (xy 105.583736 -244.678962)
			(xy 105.56621 -244.686074) (xy 105.559098 -244.692678) (xy 105.537771 -244.711948) (xy 105.490408 -244.744513)
			(xy 105.438697 -244.769604) (xy 105.383806 -244.786654) (xy 105.326979 -244.795276) (xy 105.269501 -244.795276)
			(xy 105.212674 -244.786654) (xy 105.157783 -244.769604) (xy 105.106072 -244.744513) (xy 105.058709 -244.711948)
			(xy 105.037382 -244.692678) (xy 105.03027 -244.686074) (xy 105.012744 -244.678962) (xy 104.923336 -244.678962)
			(xy 104.90581 -244.686074) (xy 104.898698 -244.692678) (xy 104.877357 -244.711932) (xy 104.829998 -244.7445)
			(xy 104.77829 -244.769596) (xy 104.723403 -244.78665) (xy 104.666578 -244.795278) (xy 104.63784 -244.795802)
			(xy 104.610585 -244.795353) (xy 104.556629 -244.787601) (xy 104.504325 -244.772248) (xy 104.454739 -244.749608)
			(xy 104.40888 -244.72014) (xy 104.367682 -244.684446) (xy 104.331984 -244.643252) (xy 104.302512 -244.597396)
			(xy 104.279866 -244.547812) (xy 104.264508 -244.49551) (xy 104.256749 -244.441555) (xy 101.341824 -244.441555)
			(xy 101.351403 -244.477304) (xy 101.359226 -244.536726) (xy 101.359716 -244.566694) (xy 101.359226 -244.596662)
			(xy 101.351403 -244.656084) (xy 101.33589 -244.713977) (xy 101.312954 -244.76935) (xy 101.282987 -244.821256)
			(xy 101.2465 -244.868806) (xy 101.20412 -244.911186) (xy 101.15657 -244.947673) (xy 101.104664 -244.97764)
			(xy 101.049291 -245.000576) (xy 100.991398 -245.016089) (xy 100.931976 -245.023912) (xy 100.87204 -245.023912)
			(xy 100.812618 -245.016089) (xy 100.754725 -245.000576) (xy 100.699352 -244.97764) (xy 100.647446 -244.947673)
			(xy 100.599896 -244.911186) (xy 100.557516 -244.868806) (xy 100.521029 -244.821256) (xy 100.491062 -244.76935)
			(xy 100.468126 -244.713977) (xy 100.452613 -244.656084) (xy 100.44479 -244.596662) (xy 96.592838 -244.596662)
			(xy 96.578757 -244.615011) (xy 96.536373 -244.65739) (xy 96.488821 -244.693873) (xy 96.436913 -244.723838)
			(xy 96.381537 -244.74677) (xy 96.323642 -244.762277) (xy 96.264218 -244.770094) (xy 96.23425 -244.770656)
			(xy 96.20213 -244.770136) (xy 96.138517 -244.76119) (xy 96.076783 -244.743424) (xy 96.018144 -244.717189)
			(xy 95.990664 -244.700552) (xy 95.978726 -244.692932) (xy 95.951294 -244.69217) (xy 95.861124 -244.741954)
			(xy 95.853391 -244.746659) (xy 95.841611 -244.760388) (xy 95.835348 -244.777358) (xy 95.834962 -244.786404)
			(xy 95.834962 -245.359428) (xy 95.835368 -245.368623) (xy 95.841864 -245.38583) (xy 95.853984 -245.399663)
			(xy 95.861886 -245.404386) (xy 95.953326 -245.453154) (xy 95.981266 -245.451884) (xy 95.99295 -245.44401)
			(xy 96.021359 -245.425705) (xy 96.082422 -245.396751) (xy 96.147078 -245.377087) (xy 96.213922 -245.367141)
			(xy 96.247712 -245.36654) (xy 96.277676 -245.367031) (xy 96.337091 -245.374854) (xy 96.394977 -245.390366)
			(xy 96.450343 -245.413301) (xy 96.502241 -245.443266) (xy 96.549785 -245.479748) (xy 96.59216 -245.522124)
			(xy 96.628641 -245.569669) (xy 96.658605 -245.621568) (xy 96.681538 -245.676935) (xy 96.697048 -245.734821)
			(xy 96.70487 -245.794236) (xy 96.70487 -245.854164) (xy 96.697048 -245.913579) (xy 96.681538 -245.971465)
			(xy 96.680129 -245.974866) (xy 100.297216 -245.974866) (xy 100.297216 -245.91493) (xy 100.305039 -245.855508)
			(xy 100.320552 -245.797615) (xy 100.343488 -245.742242) (xy 100.373455 -245.690336) (xy 100.409942 -245.642786)
			(xy 100.452322 -245.600406) (xy 100.499872 -245.563919) (xy 100.551778 -245.533952) (xy 100.607151 -245.511016)
			(xy 100.665044 -245.495503) (xy 100.724466 -245.48768) (xy 100.784402 -245.48768) (xy 100.843824 -245.495503)
			(xy 100.901717 -245.511016) (xy 100.95709 -245.533952) (xy 101.008996 -245.563919) (xy 101.056546 -245.600406)
			(xy 101.098926 -245.642786) (xy 101.135413 -245.690336) (xy 101.16538 -245.742242) (xy 101.188316 -245.797615)
			(xy 101.203829 -245.855508) (xy 101.211652 -245.91493) (xy 101.212142 -245.944898) (xy 101.211652 -245.974866)
			(xy 101.203829 -246.034288) (xy 101.188316 -246.092181) (xy 101.16538 -246.147554) (xy 101.135413 -246.19946)
			(xy 101.098926 -246.24701) (xy 101.056546 -246.28939) (xy 101.008996 -246.325877) (xy 100.95709 -246.355844)
			(xy 100.901717 -246.37878) (xy 100.843824 -246.394293) (xy 100.784402 -246.402116) (xy 100.724466 -246.402116)
			(xy 100.665044 -246.394293) (xy 100.607151 -246.37878) (xy 100.551778 -246.355844) (xy 100.499872 -246.325877)
			(xy 100.452322 -246.28939) (xy 100.409942 -246.24701) (xy 100.373455 -246.19946) (xy 100.343488 -246.147554)
			(xy 100.320552 -246.092181) (xy 100.305039 -246.034288) (xy 100.297216 -245.974866) (xy 96.680129 -245.974866)
			(xy 96.658605 -246.026832) (xy 96.628641 -246.078731) (xy 96.59216 -246.126276) (xy 96.549785 -246.168652)
			(xy 96.502241 -246.205134) (xy 96.450343 -246.235099) (xy 96.394977 -246.258034) (xy 96.337091 -246.273546)
			(xy 96.277676 -246.281369) (xy 96.247712 -246.281956) (xy 96.213922 -246.281351) (xy 96.147077 -246.271412)
			(xy 96.08242 -246.251749) (xy 96.021359 -246.22279) (xy 95.99295 -246.204486) (xy 95.981266 -246.196612)
			(xy 95.953326 -246.195342) (xy 95.861886 -246.24411) (xy 95.853929 -246.248768) (xy 95.841763 -246.262601)
			(xy 95.835308 -246.279855) (xy 95.834962 -246.289068) (xy 95.834962 -247.249442) (xy 95.835394 -247.259507)
			(xy 95.843127 -247.278095) (xy 95.849948 -247.28551) (xy 96.396556 -247.832118) (xy 96.403954 -247.838964)
			(xy 96.422553 -247.846691) (xy 96.432624 -247.847104)
		)
		(stroke
			(width 0)
			(type solid)
		)
		(fill yes)
		(layer "B.Cu")
		(net "P1V8_PEX_R")
	)
	(gr_poly
		(pts
			(xy 253.296928 -290.081716) (xy 253.306996 -290.081288) (xy 253.325595 -290.073569) (xy 253.332996 -290.06673)
			(xy 254.389128 -289.010598) (xy 254.395982 -289.003203) (xy 254.403727 -288.984604) (xy 254.404114 -288.97453)
			(xy 254.404114 -285.903924) (xy 254.404003 -285.898827) (xy 254.401958 -285.88884) (xy 254.40005 -285.884112)
			(xy 251.588778 -279.228296) (xy 251.584652 -279.219621) (xy 251.571211 -279.205916) (xy 251.562616 -279.201626)
			(xy 251.489972 -279.169368) (xy 251.471176 -279.168606) (xy 251.461778 -279.171654) (xy 251.431361 -279.181576)
			(xy 251.368289 -279.192292) (xy 251.336302 -279.19299) (xy 251.30905 -279.192527) (xy 251.255099 -279.18477)
			(xy 251.202802 -279.169414) (xy 251.153223 -279.146771) (xy 251.107371 -279.117303) (xy 251.06618 -279.081609)
			(xy 251.030487 -279.040416) (xy 251.001021 -278.994563) (xy 250.97838 -278.944983) (xy 250.963027 -278.892685)
			(xy 250.955272 -278.838734) (xy 250.954794 -278.811482) (xy 250.955242 -278.785091) (xy 250.962516 -278.732813)
			(xy 250.976925 -278.682035) (xy 250.998192 -278.633727) (xy 251.025912 -278.58881) (xy 251.059557 -278.548141)
			(xy 251.098484 -278.512495) (xy 251.141951 -278.482553) (xy 251.16536 -278.47036) (xy 251.17425 -278.466042)
			(xy 251.18695 -278.451818) (xy 251.214382 -278.377396) (xy 251.217363 -278.368261) (xy 251.216965 -278.349067)
			(xy 251.21362 -278.340058) (xy 249.645932 -274.628864) (xy 249.641682 -274.61973) (xy 249.627404 -274.605541)
			(xy 249.608757 -274.597962) (xy 249.598688 -274.597622) (xy 249.489468 -274.598638) (xy 249.463814 -274.61591)
			(xy 249.458226 -274.630134) (xy 249.447148 -274.656207) (xy 249.418414 -274.705026) (xy 249.382777 -274.749059)
			(xy 249.341018 -274.787338) (xy 249.294058 -274.819019) (xy 249.242929 -274.843407) (xy 249.188755 -274.859965)
			(xy 249.132728 -274.868329) (xy 249.104404 -274.868894) (xy 249.077152 -274.868431) (xy 249.023203 -274.860675)
			(xy 248.970906 -274.84532) (xy 248.921327 -274.822678) (xy 248.875475 -274.793211) (xy 248.834284 -274.757519)
			(xy 248.798591 -274.716328) (xy 248.769124 -274.670476) (xy 248.746482 -274.620898) (xy 248.731126 -274.568601)
			(xy 248.723369 -274.514652) (xy 248.723369 -274.460148) (xy 248.731126 -274.406199) (xy 248.746482 -274.353902)
			(xy 248.769124 -274.304324) (xy 248.798591 -274.258472) (xy 248.834284 -274.217281) (xy 248.875475 -274.181589)
			(xy 248.921327 -274.152122) (xy 248.970906 -274.12948) (xy 249.023203 -274.114125) (xy 249.077152 -274.106369)
			(xy 249.104404 -274.105878) (xy 249.129067 -274.106251) (xy 249.177987 -274.11257) (xy 249.225689 -274.125128)
			(xy 249.248676 -274.134072) (xy 249.2629 -274.139914) (xy 249.293126 -274.133818) (xy 249.370088 -274.056094)
			(xy 249.376806 -274.048661) (xy 249.384295 -274.030094) (xy 249.384089 -274.010075) (xy 249.380502 -274.000722)
			(xy 249.317764 -273.851624) (xy 249.283474 -273.83486) (xy 249.265186 -273.83994) (xy 249.240876 -273.846029)
			(xy 249.191184 -273.852524) (xy 249.166126 -273.852894) (xy 249.138872 -273.852432) (xy 249.084919 -273.844678)
			(xy 249.032619 -273.829324) (xy 248.983037 -273.806683) (xy 248.937181 -273.777216) (xy 248.895987 -273.741522)
			(xy 248.860291 -273.700328) (xy 248.830823 -273.654474) (xy 248.80818 -273.604892) (xy 248.792824 -273.552592)
			(xy 248.785068 -273.49864) (xy 248.784618 -273.471386) (xy 248.785125 -273.443189) (xy 248.793425 -273.38741)
			(xy 248.809842 -273.33346) (xy 248.834018 -273.282512) (xy 248.865428 -273.235676) (xy 248.903387 -273.193971)
			(xy 248.94707 -273.158306) (xy 248.971054 -273.143472) (xy 248.987564 -273.13382) (xy 248.999248 -273.097752)
			(xy 246.585486 -267.383006) (xy 246.583616 -267.378267) (xy 246.58157 -267.368287) (xy 246.581422 -267.363194)
			(xy 246.581422 -256.963672) (xy 246.580994 -256.953604) (xy 246.573275 -256.935004) (xy 246.566436 -256.927604)
			(xy 244.838474 -255.199642) (xy 244.831076 -255.192795) (xy 244.812478 -255.185063) (xy 244.802406 -255.184656)
			(xy 231.86009 -255.184656) (xy 231.850022 -255.185082) (xy 231.831425 -255.192806) (xy 231.824022 -255.199642)
			(xy 231.538272 -255.485392) (xy 231.531416 -255.492787) (xy 231.523668 -255.511385) (xy 231.523286 -255.52146)
			(xy 231.523286 -256.135378) (xy 231.52354 -256.13741) (xy 231.524556 -256.168144) (xy 231.52354 -256.198878)
			(xy 231.523286 -256.20091) (xy 231.523286 -271.575022) (xy 231.523713 -271.585091) (xy 231.531431 -271.603691)
			(xy 231.538272 -271.61109) (xy 231.877616 -271.950434) (xy 231.885012 -271.957285) (xy 231.903611 -271.965024)
			(xy 231.913684 -271.96542) (xy 232.824274 -271.96542) (xy 232.829293 -271.965515) (xy 232.839142 -271.96744)
			(xy 232.843832 -271.96923) (xy 232.861104 -271.976596) (xy 232.865791 -271.978394) (xy 232.875643 -271.980312)
			(xy 232.880662 -271.980406) (xy 235.890816 -271.980406) (xy 235.895896 -271.980152) (xy 235.994956 -271.881092)
			(xy 235.994956 -261.992872) (xy 235.99521 -261.985252) (xy 235.99521 -261.456932) (xy 235.995646 -261.446868)
			(xy 236.003379 -261.428282) (xy 236.010196 -261.420864) (xy 236.299502 -261.131558) (xy 236.306898 -261.124705)
			(xy 236.325496 -261.116963) (xy 236.33557 -261.116572) (xy 242.772692 -261.116572) (xy 242.782763 -261.116993)
			(xy 242.801373 -261.124702) (xy 242.80876 -261.131558) (xy 243.305838 -261.628636) (xy 243.312685 -261.636033)
			(xy 243.320417 -261.654632) (xy 243.320824 -261.664704) (xy 243.320824 -274.126198) (xy 243.32121 -274.135662)
			(xy 243.328089 -274.153294) (xy 243.340907 -274.167221) (xy 243.35791 -274.175535) (xy 243.367306 -274.176744)
			(xy 243.398011 -274.179953) (xy 243.458225 -274.193579) (xy 243.51606 -274.215176) (xy 243.570468 -274.244351)
			(xy 243.62046 -274.280574) (xy 243.66513 -274.323188) (xy 243.703667 -274.37142) (xy 243.73537 -274.424394)
			(xy 243.759666 -274.481148) (xy 243.776112 -274.540654) (xy 243.78441 -274.60183) (xy 243.784411 -274.663566)
			(xy 243.776113 -274.724742) (xy 243.759667 -274.784247) (xy 243.75377 -274.798024) (xy 244.999746 -274.798024)
			(xy 244.999746 -274.738088) (xy 245.007569 -274.678666) (xy 245.023082 -274.620773) (xy 245.046018 -274.5654)
			(xy 245.075985 -274.513494) (xy 245.112472 -274.465944) (xy 245.154852 -274.423564) (xy 245.202402 -274.387077)
			(xy 245.254308 -274.35711) (xy 245.309681 -274.334174) (xy 245.367574 -274.318661) (xy 245.426996 -274.310838)
			(xy 245.486932 -274.310838) (xy 245.546354 -274.318661) (xy 245.604247 -274.334174) (xy 245.65962 -274.35711)
			(xy 245.711526 -274.387077) (xy 245.759076 -274.423564) (xy 245.801456 -274.465944) (xy 245.837943 -274.513494)
			(xy 245.86791 -274.5654) (xy 245.890846 -274.620773) (xy 245.906359 -274.678666) (xy 245.914182 -274.738088)
			(xy 245.914672 -274.768056) (xy 245.914182 -274.798024) (xy 245.906359 -274.857446) (xy 245.890846 -274.915339)
			(xy 245.86791 -274.970712) (xy 245.837943 -275.022618) (xy 245.801456 -275.070168) (xy 245.759076 -275.112548)
			(xy 245.711526 -275.149035) (xy 245.65962 -275.179002) (xy 245.604247 -275.201938) (xy 245.546354 -275.217451)
			(xy 245.486932 -275.225274) (xy 245.426996 -275.225274) (xy 245.367574 -275.217451) (xy 245.309681 -275.201938)
			(xy 245.254308 -275.179002) (xy 245.202402 -275.149035) (xy 245.154852 -275.112548) (xy 245.112472 -275.070168)
			(xy 245.075985 -275.022618) (xy 245.046018 -274.970712) (xy 245.023082 -274.915339) (xy 245.007569 -274.857446)
			(xy 244.999746 -274.798024) (xy 243.75377 -274.798024) (xy 243.735372 -274.841002) (xy 243.703669 -274.893976)
			(xy 243.665133 -274.942209) (xy 243.620464 -274.984823) (xy 243.570472 -275.021047) (xy 243.516064 -275.050222)
			(xy 243.458229 -275.071819) (xy 243.398016 -275.085447) (xy 243.367306 -275.088604) (xy 243.357913 -275.089799)
			(xy 243.340932 -275.098145) (xy 243.328122 -275.112072) (xy 243.321222 -275.12969) (xy 243.320824 -275.13915)
			(xy 243.320824 -275.234904) (xy 246.495552 -275.234904) (xy 246.495552 -275.174968) (xy 246.503375 -275.115546)
			(xy 246.518888 -275.057653) (xy 246.541824 -275.00228) (xy 246.571791 -274.950374) (xy 246.608278 -274.902824)
			(xy 246.650658 -274.860444) (xy 246.698208 -274.823957) (xy 246.750114 -274.79399) (xy 246.805487 -274.771054)
			(xy 246.86338 -274.755541) (xy 246.922802 -274.747718) (xy 246.982738 -274.747718) (xy 247.04216 -274.755541)
			(xy 247.100053 -274.771054) (xy 247.155426 -274.79399) (xy 247.207332 -274.823957) (xy 247.254882 -274.860444)
			(xy 247.297262 -274.902824) (xy 247.333749 -274.950374) (xy 247.363716 -275.00228) (xy 247.386652 -275.057653)
			(xy 247.402165 -275.115546) (xy 247.409988 -275.174968) (xy 247.410478 -275.204936) (xy 247.409988 -275.234904)
			(xy 247.402165 -275.294326) (xy 247.386652 -275.352219) (xy 247.363716 -275.407592) (xy 247.333749 -275.459498)
			(xy 247.300072 -275.503386) (xy 248.722386 -275.503386) (xy 248.726457 -275.447764) (xy 248.738583 -275.393327)
			(xy 248.758506 -275.341236) (xy 248.785802 -275.292601) (xy 248.819888 -275.248458) (xy 248.860037 -275.209749)
			(xy 248.905395 -275.177298) (xy 248.954995 -275.151797) (xy 249.007779 -275.13379) (xy 249.062622 -275.12366)
			(xy 249.118356 -275.121623) (xy 249.173793 -275.127723) (xy 249.22775 -275.141829) (xy 249.279079 -275.163641)
			(xy 249.326685 -275.192695) (xy 249.369553 -275.22837) (xy 249.40677 -275.269907) (xy 249.437543 -275.31642)
			(xy 249.461215 -275.366917) (xy 249.477283 -275.420324) (xy 249.485403 -275.4755) (xy 249.485912 -275.503386)
			(xy 249.485403 -275.531272) (xy 249.477283 -275.586448) (xy 249.461215 -275.639855) (xy 249.437543 -275.690352)
			(xy 249.40677 -275.736865) (xy 249.369553 -275.778402) (xy 249.326685 -275.814077) (xy 249.279079 -275.843131)
			(xy 249.22775 -275.864943) (xy 249.173793 -275.879049) (xy 249.118356 -275.885149) (xy 249.062622 -275.883112)
			(xy 249.007779 -275.872982) (xy 248.954995 -275.854975) (xy 248.905395 -275.829474) (xy 248.860037 -275.797023)
			(xy 248.819888 -275.758314) (xy 248.785802 -275.714171) (xy 248.758506 -275.665536) (xy 248.738583 -275.613445)
			(xy 248.726457 -275.559008) (xy 248.722386 -275.503386) (xy 247.300072 -275.503386) (xy 247.297262 -275.507048)
			(xy 247.254882 -275.549428) (xy 247.207332 -275.585915) (xy 247.155426 -275.615882) (xy 247.100053 -275.638818)
			(xy 247.04216 -275.654331) (xy 246.982738 -275.662154) (xy 246.922802 -275.662154) (xy 246.86338 -275.654331)
			(xy 246.805487 -275.638818) (xy 246.750114 -275.615882) (xy 246.698208 -275.585915) (xy 246.650658 -275.549428)
			(xy 246.608278 -275.507048) (xy 246.571791 -275.459498) (xy 246.541824 -275.407592) (xy 246.518888 -275.352219)
			(xy 246.503375 -275.294326) (xy 246.495552 -275.234904) (xy 243.320824 -275.234904) (xy 243.320824 -276.549354)
			(xy 246.627886 -276.549354) (xy 246.627886 -276.489418) (xy 246.635709 -276.429996) (xy 246.651222 -276.372103)
			(xy 246.674158 -276.31673) (xy 246.704125 -276.264824) (xy 246.740612 -276.217274) (xy 246.782992 -276.174894)
			(xy 246.830542 -276.138407) (xy 246.882448 -276.10844) (xy 246.937821 -276.085504) (xy 246.995714 -276.069991)
			(xy 247.055136 -276.062168) (xy 247.115072 -276.062168) (xy 247.174494 -276.069991) (xy 247.232387 -276.085504)
			(xy 247.28776 -276.10844) (xy 247.339666 -276.138407) (xy 247.387216 -276.174894) (xy 247.429596 -276.217274)
			(xy 247.466083 -276.264824) (xy 247.49605 -276.31673) (xy 247.518986 -276.372103) (xy 247.534499 -276.429996)
			(xy 247.542322 -276.489418) (xy 247.542812 -276.519386) (xy 248.722386 -276.519386) (xy 248.726457 -276.463764)
			(xy 248.738583 -276.409327) (xy 248.758506 -276.357236) (xy 248.785802 -276.308601) (xy 248.819888 -276.264458)
			(xy 248.860037 -276.225749) (xy 248.905395 -276.193298) (xy 248.954995 -276.167797) (xy 249.007779 -276.14979)
			(xy 249.062622 -276.13966) (xy 249.118356 -276.137623) (xy 249.173793 -276.143723) (xy 249.22775 -276.157829)
			(xy 249.279079 -276.179641) (xy 249.326685 -276.208695) (xy 249.369553 -276.24437) (xy 249.40677 -276.285907)
			(xy 249.437543 -276.33242) (xy 249.461215 -276.382917) (xy 249.477283 -276.436324) (xy 249.485403 -276.4915)
			(xy 249.485912 -276.519386) (xy 249.485403 -276.547272) (xy 249.477283 -276.602448) (xy 249.461215 -276.655855)
			(xy 249.437543 -276.706352) (xy 249.40677 -276.752865) (xy 249.369553 -276.794402) (xy 249.326685 -276.830077)
			(xy 249.279079 -276.859131) (xy 249.22775 -276.880943) (xy 249.173793 -276.895049) (xy 249.118356 -276.901149)
			(xy 249.062622 -276.899112) (xy 249.007779 -276.888982) (xy 248.954995 -276.870975) (xy 248.905395 -276.845474)
			(xy 248.860037 -276.813023) (xy 248.819888 -276.774314) (xy 248.785802 -276.730171) (xy 248.758506 -276.681536)
			(xy 248.738583 -276.629445) (xy 248.726457 -276.575008) (xy 248.722386 -276.519386) (xy 247.542812 -276.519386)
			(xy 247.542322 -276.549354) (xy 247.534499 -276.608776) (xy 247.518986 -276.666669) (xy 247.49605 -276.722042)
			(xy 247.466083 -276.773948) (xy 247.429596 -276.821498) (xy 247.387216 -276.863878) (xy 247.339666 -276.900365)
			(xy 247.28776 -276.930332) (xy 247.232387 -276.953268) (xy 247.174494 -276.968781) (xy 247.115072 -276.976604)
			(xy 247.055136 -276.976604) (xy 246.995714 -276.968781) (xy 246.937821 -276.953268) (xy 246.882448 -276.930332)
			(xy 246.830542 -276.900365) (xy 246.782992 -276.863878) (xy 246.740612 -276.821498) (xy 246.704125 -276.773948)
			(xy 246.674158 -276.722042) (xy 246.651222 -276.666669) (xy 246.635709 -276.608776) (xy 246.627886 -276.549354)
			(xy 243.320824 -276.549354) (xy 243.320824 -277.213314) (xy 243.720364 -277.213314) (xy 243.724435 -277.157692)
			(xy 243.736561 -277.103255) (xy 243.756484 -277.051164) (xy 243.78378 -277.002529) (xy 243.817866 -276.958386)
			(xy 243.858015 -276.919677) (xy 243.903373 -276.887226) (xy 243.952973 -276.861725) (xy 244.005757 -276.843718)
			(xy 244.0606 -276.833588) (xy 244.116334 -276.831551) (xy 244.171771 -276.837651) (xy 244.225728 -276.851757)
			(xy 244.277057 -276.873569) (xy 244.324663 -276.902623) (xy 244.367531 -276.938298) (xy 244.404748 -276.979835)
			(xy 244.435521 -277.026348) (xy 244.459193 -277.076845) (xy 244.475261 -277.130252) (xy 244.483381 -277.185428)
			(xy 244.483681 -277.201884) (xy 244.909846 -277.201884) (xy 244.913917 -277.146262) (xy 244.926043 -277.091825)
			(xy 244.945966 -277.039734) (xy 244.973262 -276.991099) (xy 245.007348 -276.946956) (xy 245.047497 -276.908247)
			(xy 245.092855 -276.875796) (xy 245.142455 -276.850295) (xy 245.195239 -276.832288) (xy 245.250082 -276.822158)
			(xy 245.305816 -276.820121) (xy 245.361253 -276.826221) (xy 245.41521 -276.840327) (xy 245.466539 -276.862139)
			(xy 245.514145 -276.891193) (xy 245.557013 -276.926868) (xy 245.59423 -276.968405) (xy 245.625003 -277.014918)
			(xy 245.648675 -277.065415) (xy 245.664743 -277.118822) (xy 245.672863 -277.173998) (xy 245.673372 -277.201884)
			(xy 245.672863 -277.22977) (xy 245.664743 -277.284946) (xy 245.648675 -277.338353) (xy 245.625003 -277.38885)
			(xy 245.59423 -277.435363) (xy 245.557013 -277.4769) (xy 245.514145 -277.512575) (xy 245.466539 -277.541629)
			(xy 245.41521 -277.563441) (xy 245.361253 -277.577547) (xy 245.305816 -277.583647) (xy 245.250082 -277.58161)
			(xy 245.195239 -277.57148) (xy 245.142455 -277.553473) (xy 245.092855 -277.527972) (xy 245.047497 -277.495521)
			(xy 245.007348 -277.456812) (xy 244.973262 -277.412669) (xy 244.945966 -277.364034) (xy 244.926043 -277.311943)
			(xy 244.913917 -277.257506) (xy 244.909846 -277.201884) (xy 244.483681 -277.201884) (xy 244.48389 -277.213314)
			(xy 244.483381 -277.2412) (xy 244.475261 -277.296376) (xy 244.459193 -277.349783) (xy 244.435521 -277.40028)
			(xy 244.404748 -277.446793) (xy 244.367531 -277.48833) (xy 244.324663 -277.524005) (xy 244.277057 -277.553059)
			(xy 244.225728 -277.574871) (xy 244.171771 -277.588977) (xy 244.116334 -277.595077) (xy 244.0606 -277.59304)
			(xy 244.005757 -277.58291) (xy 243.952973 -277.564903) (xy 243.903373 -277.539402) (xy 243.858015 -277.506951)
			(xy 243.817866 -277.468242) (xy 243.78378 -277.424099) (xy 243.756484 -277.375464) (xy 243.736561 -277.323373)
			(xy 243.724435 -277.268936) (xy 243.720364 -277.213314) (xy 243.320824 -277.213314) (xy 243.320824 -277.789386)
			(xy 246.627396 -277.789386) (xy 246.627886 -277.759418) (xy 246.635709 -277.699996) (xy 246.651222 -277.642103)
			(xy 246.674158 -277.58673) (xy 246.704125 -277.534824) (xy 246.740612 -277.487274) (xy 246.782992 -277.444894)
			(xy 246.830542 -277.408407) (xy 246.882448 -277.37844) (xy 246.937821 -277.355504) (xy 246.995714 -277.339991)
			(xy 247.055136 -277.332168) (xy 247.115072 -277.332168) (xy 247.174494 -277.339991) (xy 247.232387 -277.355504)
			(xy 247.28776 -277.37844) (xy 247.339666 -277.408407) (xy 247.387216 -277.444894) (xy 247.429596 -277.487274)
			(xy 247.466083 -277.534824) (xy 247.467141 -277.536656) (xy 248.722386 -277.536656) (xy 248.726457 -277.481034)
			(xy 248.738583 -277.426597) (xy 248.758506 -277.374506) (xy 248.785802 -277.325871) (xy 248.819888 -277.281728)
			(xy 248.860037 -277.243019) (xy 248.905395 -277.210568) (xy 248.954995 -277.185067) (xy 249.007779 -277.16706)
			(xy 249.062622 -277.15693) (xy 249.118356 -277.154893) (xy 249.173793 -277.160993) (xy 249.22775 -277.175099)
			(xy 249.279079 -277.196911) (xy 249.326685 -277.225965) (xy 249.369553 -277.26164) (xy 249.40677 -277.303177)
			(xy 249.437543 -277.34969) (xy 249.461215 -277.400187) (xy 249.477283 -277.453594) (xy 249.485403 -277.50877)
			(xy 249.485912 -277.536656) (xy 249.485403 -277.564542) (xy 249.477283 -277.619718) (xy 249.461215 -277.673125)
			(xy 249.437543 -277.723622) (xy 249.40677 -277.770135) (xy 249.369553 -277.811672) (xy 249.326685 -277.847347)
			(xy 249.279079 -277.876401) (xy 249.22775 -277.898213) (xy 249.173793 -277.912319) (xy 249.118356 -277.918419)
			(xy 249.062622 -277.916382) (xy 249.007779 -277.906252) (xy 248.954995 -277.888245) (xy 248.905395 -277.862744)
			(xy 248.860037 -277.830293) (xy 248.819888 -277.791584) (xy 248.785802 -277.747441) (xy 248.758506 -277.698806)
			(xy 248.738583 -277.646715) (xy 248.726457 -277.592278) (xy 248.722386 -277.536656) (xy 247.467141 -277.536656)
			(xy 247.49605 -277.58673) (xy 247.518986 -277.642103) (xy 247.534499 -277.699996) (xy 247.542322 -277.759418)
			(xy 247.542812 -277.789386) (xy 247.542388 -277.818349) (xy 247.535066 -277.875811) (xy 247.520549 -277.93189)
			(xy 247.49907 -277.985687) (xy 247.470972 -278.036343) (xy 247.436705 -278.083048) (xy 247.396818 -278.125053)
			(xy 247.374664 -278.143716) (xy 247.366536 -278.150574) (xy 247.356884 -278.169116) (xy 247.35028 -278.264112)
			(xy 247.357392 -278.283924) (xy 247.364504 -278.291544) (xy 247.383582 -278.312852) (xy 247.415838 -278.360081)
			(xy 247.440684 -278.411594) (xy 247.457564 -278.466238) (xy 247.466101 -278.52279) (xy 247.466612 -278.551386)
			(xy 247.466126 -278.578637) (xy 247.45837 -278.632585) (xy 247.443015 -278.68488) (xy 247.420373 -278.734457)
			(xy 247.390907 -278.780307) (xy 247.355216 -278.821498) (xy 247.314025 -278.857189) (xy 247.268175 -278.886655)
			(xy 247.218598 -278.909297) (xy 247.166303 -278.924652) (xy 247.112355 -278.932408) (xy 247.057853 -278.932408)
			(xy 247.003905 -278.924652) (xy 246.95161 -278.909297) (xy 246.902033 -278.886655) (xy 246.856183 -278.857189)
			(xy 246.814992 -278.821498) (xy 246.779301 -278.780307) (xy 246.749835 -278.734457) (xy 246.727193 -278.68488)
			(xy 246.711838 -278.632585) (xy 246.704082 -278.578637) (xy 246.703596 -278.551386) (xy 246.704097 -278.522789)
			(xy 246.712642 -278.466238) (xy 246.729524 -278.411593) (xy 246.754366 -278.360077) (xy 246.786612 -278.31284)
			(xy 246.805704 -278.291544) (xy 246.812816 -278.283924) (xy 246.819928 -278.264112) (xy 246.813324 -278.169116)
			(xy 246.803672 -278.150574) (xy 246.795544 -278.143716) (xy 246.773383 -278.125062) (xy 246.733495 -278.083057)
			(xy 246.69923 -278.036351) (xy 246.671135 -277.985693) (xy 246.649662 -277.931893) (xy 246.635153 -277.875813)
			(xy 246.627841 -277.818349) (xy 246.627396 -277.789386) (xy 243.320824 -277.789386) (xy 243.320824 -278.379936)
			(xy 243.720364 -278.379936) (xy 243.724435 -278.324314) (xy 243.736561 -278.269877) (xy 243.756484 -278.217786)
			(xy 243.78378 -278.169151) (xy 243.817866 -278.125008) (xy 243.858015 -278.086299) (xy 243.903373 -278.053848)
			(xy 243.952973 -278.028347) (xy 244.005757 -278.01034) (xy 244.0606 -278.00021) (xy 244.116334 -277.998173)
			(xy 244.171771 -278.004273) (xy 244.225728 -278.018379) (xy 244.277057 -278.040191) (xy 244.324663 -278.069245)
			(xy 244.367531 -278.10492) (xy 244.404748 -278.146457) (xy 244.435521 -278.19297) (xy 244.459193 -278.243467)
			(xy 244.475261 -278.296874) (xy 244.483381 -278.35205) (xy 244.483686 -278.36876) (xy 244.898416 -278.36876)
			(xy 244.902487 -278.313138) (xy 244.914613 -278.258701) (xy 244.934536 -278.20661) (xy 244.961832 -278.157975)
			(xy 244.995918 -278.113832) (xy 245.036067 -278.075123) (xy 245.081425 -278.042672) (xy 245.131025 -278.017171)
			(xy 245.183809 -277.999164) (xy 245.238652 -277.989034) (xy 245.294386 -277.986997) (xy 245.349823 -277.993097)
			(xy 245.40378 -278.007203) (xy 245.455109 -278.029015) (xy 245.502715 -278.058069) (xy 245.545583 -278.093744)
			(xy 245.5828 -278.135281) (xy 245.613573 -278.181794) (xy 245.637245 -278.232291) (xy 245.653313 -278.285698)
			(xy 245.661433 -278.340874) (xy 245.661942 -278.36876) (xy 245.661433 -278.396646) (xy 245.653313 -278.451822)
			(xy 245.637245 -278.505229) (xy 245.613573 -278.555726) (xy 245.5828 -278.602239) (xy 245.545583 -278.643776)
			(xy 245.502715 -278.679451) (xy 245.455109 -278.708505) (xy 245.40378 -278.730317) (xy 245.349823 -278.744423)
			(xy 245.294386 -278.750523) (xy 245.238652 -278.748486) (xy 245.183809 -278.738356) (xy 245.131025 -278.720349)
			(xy 245.081425 -278.694848) (xy 245.036067 -278.662397) (xy 244.995918 -278.623688) (xy 244.961832 -278.579545)
			(xy 244.934536 -278.53091) (xy 244.914613 -278.478819) (xy 244.902487 -278.424382) (xy 244.898416 -278.36876)
			(xy 244.483686 -278.36876) (xy 244.48389 -278.379936) (xy 244.483381 -278.407822) (xy 244.475261 -278.462998)
			(xy 244.459193 -278.516405) (xy 244.435521 -278.566902) (xy 244.404748 -278.613415) (xy 244.367531 -278.654952)
			(xy 244.324663 -278.690627) (xy 244.277057 -278.719681) (xy 244.225728 -278.741493) (xy 244.171771 -278.755599)
			(xy 244.116334 -278.761699) (xy 244.0606 -278.759662) (xy 244.005757 -278.749532) (xy 243.952973 -278.731525)
			(xy 243.903373 -278.706024) (xy 243.858015 -278.673573) (xy 243.817866 -278.634864) (xy 243.78378 -278.590721)
			(xy 243.756484 -278.542086) (xy 243.736561 -278.489995) (xy 243.724435 -278.435558) (xy 243.720364 -278.379936)
			(xy 243.320824 -278.379936) (xy 243.320824 -279.490424) (xy 243.321252 -279.500492) (xy 243.328975 -279.519088)
			(xy 243.33581 -279.526492) (xy 243.406672 -279.597354) (xy 246.627886 -279.597354) (xy 246.627886 -279.537418)
			(xy 246.635709 -279.477996) (xy 246.651222 -279.420103) (xy 246.674158 -279.36473) (xy 246.704125 -279.312824)
			(xy 246.740612 -279.265274) (xy 246.782992 -279.222894) (xy 246.830542 -279.186407) (xy 246.882448 -279.15644)
			(xy 246.937821 -279.133504) (xy 246.995714 -279.117991) (xy 247.055136 -279.110168) (xy 247.115072 -279.110168)
			(xy 247.174494 -279.117991) (xy 247.232387 -279.133504) (xy 247.28776 -279.15644) (xy 247.339666 -279.186407)
			(xy 247.387216 -279.222894) (xy 247.429596 -279.265274) (xy 247.466083 -279.312824) (xy 247.49605 -279.36473)
			(xy 247.518986 -279.420103) (xy 247.534499 -279.477996) (xy 247.542322 -279.537418) (xy 247.542812 -279.567386)
			(xy 247.542322 -279.597354) (xy 247.534499 -279.656776) (xy 247.518986 -279.714669) (xy 247.49605 -279.770042)
			(xy 247.466083 -279.821948) (xy 247.429596 -279.869498) (xy 247.387216 -279.911878) (xy 247.339666 -279.948365)
			(xy 247.28776 -279.978332) (xy 247.232387 -280.001268) (xy 247.174494 -280.016781) (xy 247.115072 -280.024604)
			(xy 247.055136 -280.024604) (xy 246.995714 -280.016781) (xy 246.937821 -280.001268) (xy 246.882448 -279.978332)
			(xy 246.830542 -279.948365) (xy 246.782992 -279.911878) (xy 246.740612 -279.869498) (xy 246.704125 -279.821948)
			(xy 246.674158 -279.770042) (xy 246.651222 -279.714669) (xy 246.635709 -279.656776) (xy 246.627886 -279.597354)
			(xy 243.406672 -279.597354) (xy 244.339868 -280.53055) (xy 244.990602 -280.53055) (xy 244.990602 -280.470614)
			(xy 244.998425 -280.411192) (xy 245.013938 -280.353299) (xy 245.036874 -280.297926) (xy 245.066841 -280.24602)
			(xy 245.103328 -280.19847) (xy 245.145708 -280.15609) (xy 245.193258 -280.119603) (xy 245.245164 -280.089636)
			(xy 245.300537 -280.0667) (xy 245.35843 -280.051187) (xy 245.417852 -280.043364) (xy 245.477788 -280.043364)
			(xy 245.53721 -280.051187) (xy 245.595103 -280.0667) (xy 245.650476 -280.089636) (xy 245.702382 -280.119603)
			(xy 245.749932 -280.15609) (xy 245.792312 -280.19847) (xy 245.828799 -280.24602) (xy 245.858766 -280.297926)
			(xy 245.881702 -280.353299) (xy 245.897215 -280.411192) (xy 245.905038 -280.470614) (xy 245.905528 -280.500582)
			(xy 245.905038 -280.53055) (xy 245.898082 -280.583386) (xy 248.722896 -280.583386) (xy 248.723344 -280.557488)
			(xy 248.730348 -280.506168) (xy 248.744227 -280.456266) (xy 248.764725 -280.408699) (xy 248.791465 -280.364339)
			(xy 248.823957 -280.324002) (xy 248.861604 -280.288428) (xy 248.882408 -280.272998) (xy 248.891044 -280.266902)
			(xy 248.901966 -280.248868) (xy 248.914412 -280.154126) (xy 248.90857 -280.13406) (xy 248.901712 -280.125932)
			(xy 248.885274 -280.105359) (xy 248.857678 -280.060508) (xy 248.836521 -280.012284) (xy 248.822206 -279.961606)
			(xy 248.815008 -279.909439) (xy 248.81459 -279.883108) (xy 248.814996 -279.856894) (xy 248.82217 -279.80496)
			(xy 248.836383 -279.754496) (xy 248.857368 -279.706452) (xy 248.884731 -279.661732) (xy 248.917956 -279.621177)
			(xy 248.956419 -279.58555) (xy 248.977658 -279.57018) (xy 248.988834 -279.56256) (xy 249.000264 -279.538684)
			(xy 248.992136 -279.424384) (xy 248.977404 -279.402286) (xy 248.965212 -279.39619) (xy 248.941836 -279.383984)
			(xy 248.89841 -279.354065) (xy 248.859521 -279.318446) (xy 248.825911 -279.277809) (xy 248.798222 -279.232927)
			(xy 248.776983 -279.184659) (xy 248.762597 -279.133923) (xy 248.755341 -279.08169) (xy 248.7549 -279.055322)
			(xy 248.755386 -279.028071) (xy 248.763142 -278.974123) (xy 248.778497 -278.921828) (xy 248.801139 -278.872251)
			(xy 248.830605 -278.826401) (xy 248.866296 -278.78521) (xy 248.907487 -278.749519) (xy 248.953337 -278.720053)
			(xy 249.002914 -278.697411) (xy 249.055209 -278.682056) (xy 249.109157 -278.6743) (xy 249.163659 -278.6743)
			(xy 249.217607 -278.682056) (xy 249.269902 -278.697411) (xy 249.319479 -278.720053) (xy 249.365329 -278.749519)
			(xy 249.40652 -278.78521) (xy 249.442211 -278.826401) (xy 249.471677 -278.872251) (xy 249.494319 -278.921828)
			(xy 249.509674 -278.974123) (xy 249.51743 -279.028071) (xy 249.517916 -279.055322) (xy 249.517455 -279.081534)
			(xy 249.510291 -279.133466) (xy 249.496087 -279.183928) (xy 249.47511 -279.231972) (xy 249.447756 -279.276693)
			(xy 249.414539 -279.31725) (xy 249.376084 -279.352879) (xy 249.354848 -279.36825) (xy 249.343672 -279.37587)
			(xy 249.332242 -279.399746) (xy 249.34037 -279.514046) (xy 249.355102 -279.536144) (xy 249.367294 -279.54224)
			(xy 249.390684 -279.554421) (xy 249.434111 -279.584344) (xy 249.472999 -279.619966) (xy 249.506608 -279.660607)
			(xy 249.534295 -279.705492) (xy 249.555532 -279.753764) (xy 249.569914 -279.804503) (xy 249.577167 -279.856739)
			(xy 249.577606 -279.883108) (xy 249.577153 -279.909006) (xy 249.570149 -279.960326) (xy 249.556271 -280.010227)
			(xy 249.535775 -280.057795) (xy 249.509035 -280.102154) (xy 249.476544 -280.142491) (xy 249.438897 -280.178066)
			(xy 249.418094 -280.193496) (xy 249.409458 -280.199592) (xy 249.398536 -280.217626) (xy 249.38609 -280.312368)
			(xy 249.391932 -280.332434) (xy 249.39879 -280.340562) (xy 249.415225 -280.361137) (xy 249.442822 -280.405988)
			(xy 249.46398 -280.454211) (xy 249.478295 -280.504889) (xy 249.485494 -280.557055) (xy 249.485912 -280.583386)
			(xy 249.485426 -280.610637) (xy 249.47767 -280.664585) (xy 249.462315 -280.71688) (xy 249.439673 -280.766457)
			(xy 249.410207 -280.812307) (xy 249.374516 -280.853498) (xy 249.333325 -280.889189) (xy 249.287475 -280.918655)
			(xy 249.237898 -280.941297) (xy 249.185603 -280.956652) (xy 249.131655 -280.964408) (xy 249.077153 -280.964408)
			(xy 249.023205 -280.956652) (xy 248.97091 -280.941297) (xy 248.921333 -280.918655) (xy 248.875483 -280.889189)
			(xy 248.834292 -280.853498) (xy 248.798601 -280.812307) (xy 248.769135 -280.766457) (xy 248.746493 -280.71688)
			(xy 248.731138 -280.664585) (xy 248.723382 -280.610637) (xy 248.722896 -280.583386) (xy 245.898082 -280.583386)
			(xy 245.897215 -280.589972) (xy 245.881702 -280.647865) (xy 245.858766 -280.703238) (xy 245.828799 -280.755144)
			(xy 245.792312 -280.802694) (xy 245.749932 -280.845074) (xy 245.702382 -280.881561) (xy 245.650476 -280.911528)
			(xy 245.595103 -280.934464) (xy 245.53721 -280.949977) (xy 245.477788 -280.9578) (xy 245.417852 -280.9578)
			(xy 245.35843 -280.949977) (xy 245.300537 -280.934464) (xy 245.245164 -280.911528) (xy 245.193258 -280.881561)
			(xy 245.145708 -280.845074) (xy 245.103328 -280.802694) (xy 245.066841 -280.755144) (xy 245.036874 -280.703238)
			(xy 245.013938 -280.647865) (xy 244.998425 -280.589972) (xy 244.990602 -280.53055) (xy 244.339868 -280.53055)
			(xy 245.262654 -281.453336) (xy 245.2695 -281.460734) (xy 245.277228 -281.479333) (xy 245.27764 -281.489404)
			(xy 245.27764 -281.55011) (xy 250.225812 -281.55011) (xy 250.229883 -281.494488) (xy 250.242009 -281.440051)
			(xy 250.261932 -281.38796) (xy 250.289228 -281.339325) (xy 250.323314 -281.295182) (xy 250.363463 -281.256473)
			(xy 250.408821 -281.224022) (xy 250.458421 -281.198521) (xy 250.511205 -281.180514) (xy 250.566048 -281.170384)
			(xy 250.621782 -281.168347) (xy 250.677219 -281.174447) (xy 250.731176 -281.188553) (xy 250.782505 -281.210365)
			(xy 250.830111 -281.239419) (xy 250.872979 -281.275094) (xy 250.910196 -281.316631) (xy 250.940969 -281.363144)
			(xy 250.964641 -281.413641) (xy 250.980709 -281.467048) (xy 250.988829 -281.522224) (xy 250.989338 -281.55011)
			(xy 250.988829 -281.577996) (xy 250.980709 -281.633172) (xy 250.964641 -281.686579) (xy 250.940969 -281.737076)
			(xy 250.910196 -281.783589) (xy 250.872979 -281.825126) (xy 250.830111 -281.860801) (xy 250.782505 -281.889855)
			(xy 250.731176 -281.911667) (xy 250.677219 -281.925773) (xy 250.621782 -281.931873) (xy 250.566048 -281.929836)
			(xy 250.511205 -281.919706) (xy 250.458421 -281.901699) (xy 250.408821 -281.876198) (xy 250.363463 -281.843747)
			(xy 250.323314 -281.805038) (xy 250.289228 -281.760895) (xy 250.261932 -281.71226) (xy 250.242009 -281.660169)
			(xy 250.229883 -281.605732) (xy 250.225812 -281.55011) (xy 245.27764 -281.55011) (xy 245.27764 -282.138882)
			(xy 245.278079 -282.148945) (xy 245.285819 -282.167524) (xy 245.292626 -282.17495) (xy 245.519448 -282.401772)
			(xy 245.526848 -282.408614) (xy 245.545446 -282.416335) (xy 245.555516 -282.416758) (xy 248.02211 -282.416758)
			(xy 248.032178 -282.417185) (xy 248.050774 -282.424908) (xy 248.058178 -282.431744) (xy 248.581418 -282.954984)
			(xy 248.58826 -282.962383) (xy 248.595977 -282.980982) (xy 248.596404 -282.991052) (xy 248.596404 -289.44824)
			(xy 248.596835 -289.458307) (xy 248.60456 -289.4769) (xy 248.61139 -289.484308) (xy 249.193812 -290.06673)
			(xy 249.201208 -290.073582) (xy 249.219807 -290.081323) (xy 249.22988 -290.081716)
		)
		(stroke
			(width 0)
			(type solid)
		)
		(fill yes)
		(layer "B.Cu")
		(net "P1V25_SERDES_VDDPLL_PEX2")
	)
	(gr_poly
		(pts
			(xy 197.142608 -415.425382) (xy 197.152677 -415.424957) (xy 197.171278 -415.417239) (xy 197.178676 -415.410396)
			(xy 198.221346 -414.367726) (xy 198.228187 -414.360326) (xy 198.235903 -414.341727) (xy 198.236332 -414.331658)
			(xy 198.236332 -411.155642) (xy 198.23583 -411.14559) (xy 198.228115 -411.127023) (xy 198.221346 -411.119574)
			(xy 197.21576 -410.113988) (xy 197.208909 -410.106592) (xy 197.201169 -410.087993) (xy 197.200774 -410.07792)
			(xy 197.200774 -409.138374) (xy 197.200371 -409.128889) (xy 197.193468 -409.111218) (xy 197.180642 -409.097238)
			(xy 197.172326 -409.092654) (xy 197.145493 -409.07905) (xy 197.095329 -409.045836) (xy 197.049952 -409.006334)
			(xy 197.010145 -408.961225) (xy 196.976594 -408.911287) (xy 196.949878 -408.857382) (xy 196.930458 -408.80044)
			(xy 196.91867 -408.741444) (xy 196.914717 -408.681412) (xy 196.918667 -408.62138) (xy 196.930452 -408.562383)
			(xy 196.949868 -408.505441) (xy 196.976581 -408.451534) (xy 197.01013 -408.401594) (xy 197.049935 -408.356483)
			(xy 197.09531 -408.316978) (xy 197.145472 -408.283763) (xy 197.172326 -408.270202) (xy 197.180699 -408.26569)
			(xy 197.193571 -408.251707) (xy 197.200441 -408.233986) (xy 197.200774 -408.224482) (xy 197.200774 -407.004012)
			(xy 197.200299 -406.994078) (xy 197.192736 -406.975705) (xy 197.178745 -406.961598) (xy 197.169786 -406.957276)
			(xy 197.069456 -406.914858) (xy 197.039484 -406.920446) (xy 197.028562 -406.931114) (xy 197.00709 -406.951162)
			(xy 196.95913 -406.985083) (xy 196.906537 -407.011249) (xy 196.850553 -407.02904) (xy 196.792504 -407.038037)
			(xy 196.763132 -407.038556) (xy 196.735874 -407.038095) (xy 196.681913 -407.030341) (xy 196.629605 -407.014986)
			(xy 196.580014 -406.992342) (xy 196.534151 -406.962871) (xy 196.49295 -406.927173) (xy 196.457248 -406.885974)
			(xy 196.427773 -406.840114) (xy 196.405125 -406.790525) (xy 196.389766 -406.738218) (xy 196.382007 -406.684258)
			(xy 196.382007 -406.629742) (xy 196.389766 -406.575782) (xy 196.405125 -406.523475) (xy 196.427773 -406.473886)
			(xy 196.457248 -406.428026) (xy 196.49295 -406.386827) (xy 196.534151 -406.351129) (xy 196.580014 -406.321658)
			(xy 196.629605 -406.299014) (xy 196.681913 -406.283659) (xy 196.735874 -406.275905) (xy 196.763132 -406.27554)
			(xy 196.792501 -406.276082) (xy 196.850546 -406.285087) (xy 196.906526 -406.302878) (xy 196.959119 -406.329036)
			(xy 197.007084 -406.362943) (xy 197.028562 -406.382982) (xy 197.039484 -406.39365) (xy 197.069456 -406.399238)
			(xy 197.169786 -406.35682) (xy 197.178744 -406.352504) (xy 197.192714 -406.338382) (xy 197.200281 -406.320015)
			(xy 197.200774 -406.310084) (xy 197.200774 -405.558752) (xy 197.200442 -405.549858) (xy 197.194364 -405.533141)
			(xy 197.182925 -405.51952) (xy 197.175374 -405.51481) (xy 197.150949 -405.500067) (xy 197.106373 -405.464464)
			(xy 197.067595 -405.422621) (xy 197.035481 -405.375469) (xy 197.010747 -405.324061) (xy 196.993945 -405.269542)
			(xy 196.985448 -405.213129) (xy 196.985448 -405.156081) (xy 196.993943 -405.099668) (xy 197.010744 -405.045149)
			(xy 197.035476 -404.99374) (xy 197.067589 -404.946587) (xy 197.106366 -404.904743) (xy 197.150941 -404.869139)
			(xy 197.175374 -404.85441) (xy 197.182877 -404.849636) (xy 197.194313 -404.836036) (xy 197.200426 -404.819351)
			(xy 197.200774 -404.810468) (xy 197.200774 -404.673054) (xy 197.200342 -404.662988) (xy 197.192613 -404.644398)
			(xy 197.185788 -404.636986) (xy 196.369432 -403.82063) (xy 196.362031 -403.813791) (xy 196.343433 -403.806077)
			(xy 196.333364 -403.805644) (xy 194.498976 -403.805644) (xy 194.488992 -403.806187) (xy 194.47057 -403.813912)
			(xy 194.463162 -403.82063) (xy 194.412362 -403.87143) (xy 194.40555 -403.878774) (xy 194.397818 -403.897237)
			(xy 194.397376 -403.907244) (xy 194.396886 -403.937212) (xy 194.389063 -403.996634) (xy 194.37355 -404.054527)
			(xy 194.350614 -404.1099) (xy 194.320647 -404.161806) (xy 194.28416 -404.209356) (xy 194.24178 -404.251736)
			(xy 194.19423 -404.288223) (xy 194.142324 -404.31819) (xy 194.086951 -404.341126) (xy 194.029058 -404.356639)
			(xy 193.969636 -404.364462) (xy 193.9097 -404.364462) (xy 193.850278 -404.356639) (xy 193.792385 -404.341126)
			(xy 193.737012 -404.31819) (xy 193.685106 -404.288223) (xy 193.637556 -404.251736) (xy 193.595176 -404.209356)
			(xy 193.558689 -404.161806) (xy 193.528722 -404.1099) (xy 193.505786 -404.054527) (xy 193.490273 -403.996634)
			(xy 193.48245 -403.937212) (xy 193.48196 -403.907244) (xy 193.481429 -403.897254) (xy 193.473723 -403.878814)
			(xy 193.466974 -403.87143) (xy 193.416174 -403.82063) (xy 193.408829 -403.81382) (xy 193.390366 -403.806092)
			(xy 193.38036 -403.805644) (xy 193.375788 -403.805644) (xy 193.35242 -403.81936) (xy 193.330576 -403.857968)
			(xy 193.324984 -403.869267) (xy 193.324461 -403.894443) (xy 193.32956 -403.905974) (xy 193.342662 -403.932998)
			(xy 193.361213 -403.990115) (xy 193.370607 -404.049429) (xy 193.371216 -404.079456) (xy 193.37073 -404.106707)
			(xy 193.362974 -404.160655) (xy 193.347619 -404.21295) (xy 193.324977 -404.262527) (xy 193.295511 -404.308377)
			(xy 193.25982 -404.349568) (xy 193.218629 -404.385259) (xy 193.172779 -404.414725) (xy 193.123202 -404.437367)
			(xy 193.070907 -404.452722) (xy 193.016959 -404.460478) (xy 192.962457 -404.460478) (xy 192.908509 -404.452722)
			(xy 192.856214 -404.437367) (xy 192.806637 -404.414725) (xy 192.760787 -404.385259) (xy 192.719596 -404.349568)
			(xy 192.683905 -404.308377) (xy 192.654439 -404.262527) (xy 192.631797 -404.21295) (xy 192.616442 -404.160655)
			(xy 192.608686 -404.106707) (xy 192.6082 -404.079456) (xy 192.608552 -404.056287) (xy 192.614194 -404.010293)
			(xy 192.625377 -403.965324) (xy 192.633346 -403.943566) (xy 192.637918 -403.931628) (xy 192.63487 -403.90699)
			(xy 192.58026 -403.827742) (xy 192.572733 -403.817846) (xy 192.550767 -403.806258) (xy 192.53835 -403.805644)
			(xy 190.998602 -403.805644) (xy 190.987582 -403.806182) (xy 190.967559 -403.815394) (xy 190.959994 -403.823424)
			(xy 190.90259 -403.890226) (xy 190.896494 -403.911562) (xy 190.898272 -403.922484) (xy 190.900687 -403.939589)
			(xy 190.903232 -403.974044) (xy 190.903352 -403.991318) (xy 190.902862 -404.021286) (xy 190.895039 -404.080708)
			(xy 190.879526 -404.138601) (xy 190.85659 -404.193974) (xy 190.826623 -404.24588) (xy 190.790136 -404.29343)
			(xy 190.747756 -404.33581) (xy 190.700206 -404.372297) (xy 190.6483 -404.402264) (xy 190.592927 -404.4252)
			(xy 190.535034 -404.440713) (xy 190.475612 -404.448536) (xy 190.415676 -404.448536) (xy 190.356254 -404.440713)
			(xy 190.298361 -404.4252) (xy 190.242988 -404.402264) (xy 190.191082 -404.372297) (xy 190.143532 -404.33581)
			(xy 190.101152 -404.29343) (xy 190.064665 -404.24588) (xy 190.034698 -404.193974) (xy 190.011762 -404.138601)
			(xy 189.996249 -404.080708) (xy 189.988426 -404.021286) (xy 189.987936 -403.991318) (xy 189.988069 -403.974044)
			(xy 189.990611 -403.93959) (xy 189.993016 -403.922484) (xy 189.994794 -403.911562) (xy 189.988698 -403.890226)
			(xy 189.931294 -403.823424) (xy 189.923723 -403.815398) (xy 189.903706 -403.806176) (xy 189.892686 -403.805644)
			(xy 185.43651 -403.805644) (xy 185.42644 -403.806067) (xy 185.407837 -403.813783) (xy 185.400442 -403.82063)
			(xy 184.709562 -404.51151) (xy 184.70271 -404.518906) (xy 184.69497 -404.537505) (xy 184.694576 -404.547578)
			(xy 184.694576 -405.887932) (xy 187.191632 -405.887932) (xy 187.191632 -405.827996) (xy 187.199455 -405.768574)
			(xy 187.214968 -405.710681) (xy 187.237904 -405.655308) (xy 187.267871 -405.603402) (xy 187.304358 -405.555852)
			(xy 187.346738 -405.513472) (xy 187.394288 -405.476985) (xy 187.446194 -405.447018) (xy 187.501567 -405.424082)
			(xy 187.55946 -405.408569) (xy 187.618882 -405.400746) (xy 187.678818 -405.400746) (xy 187.73824 -405.408569)
			(xy 187.796133 -405.424082) (xy 187.851506 -405.447018) (xy 187.903412 -405.476985) (xy 187.950962 -405.513472)
			(xy 187.993342 -405.555852) (xy 188.029829 -405.603402) (xy 188.059796 -405.655308) (xy 188.082732 -405.710681)
			(xy 188.098245 -405.768574) (xy 188.106068 -405.827996) (xy 188.106558 -405.857964) (xy 188.106068 -405.887932)
			(xy 188.098245 -405.947354) (xy 188.082732 -406.005247) (xy 188.059796 -406.06062) (xy 188.029829 -406.112526)
			(xy 187.993342 -406.160076) (xy 187.950962 -406.202456) (xy 187.931195 -406.217624) (xy 194.439522 -406.217624)
			(xy 194.439522 -406.157688) (xy 194.447345 -406.098266) (xy 194.462858 -406.040373) (xy 194.485794 -405.985)
			(xy 194.515761 -405.933094) (xy 194.552248 -405.885544) (xy 194.594628 -405.843164) (xy 194.642178 -405.806677)
			(xy 194.694084 -405.77671) (xy 194.749457 -405.753774) (xy 194.80735 -405.738261) (xy 194.866772 -405.730438)
			(xy 194.926708 -405.730438) (xy 194.98613 -405.738261) (xy 195.044023 -405.753774) (xy 195.099396 -405.77671)
			(xy 195.151302 -405.806677) (xy 195.198852 -405.843164) (xy 195.241232 -405.885544) (xy 195.277719 -405.933094)
			(xy 195.307686 -405.985) (xy 195.330622 -406.040373) (xy 195.346135 -406.098266) (xy 195.353958 -406.157688)
			(xy 195.354448 -406.187656) (xy 195.353958 -406.217624) (xy 195.346135 -406.277046) (xy 195.330622 -406.334939)
			(xy 195.307686 -406.390312) (xy 195.277719 -406.442218) (xy 195.241232 -406.489768) (xy 195.198852 -406.532148)
			(xy 195.151302 -406.568635) (xy 195.099396 -406.598602) (xy 195.044023 -406.621538) (xy 194.98613 -406.637051)
			(xy 194.926708 -406.644874) (xy 194.866772 -406.644874) (xy 194.80735 -406.637051) (xy 194.749457 -406.621538)
			(xy 194.694084 -406.598602) (xy 194.642178 -406.568635) (xy 194.594628 -406.532148) (xy 194.552248 -406.489768)
			(xy 194.515761 -406.442218) (xy 194.485794 -406.390312) (xy 194.462858 -406.334939) (xy 194.447345 -406.277046)
			(xy 194.439522 -406.217624) (xy 187.931195 -406.217624) (xy 187.903412 -406.238943) (xy 187.851506 -406.26891)
			(xy 187.796133 -406.291846) (xy 187.73824 -406.307359) (xy 187.678818 -406.315182) (xy 187.618882 -406.315182)
			(xy 187.55946 -406.307359) (xy 187.501567 -406.291846) (xy 187.446194 -406.26891) (xy 187.394288 -406.238943)
			(xy 187.346738 -406.202456) (xy 187.304358 -406.160076) (xy 187.267871 -406.112526) (xy 187.237904 -406.06062)
			(xy 187.214968 -406.005247) (xy 187.199455 -405.947354) (xy 187.191632 -405.887932) (xy 184.694576 -405.887932)
			(xy 184.694576 -408.622242) (xy 189.967598 -408.622242) (xy 189.967598 -408.562306) (xy 189.975421 -408.502884)
			(xy 189.990934 -408.444991) (xy 190.01387 -408.389618) (xy 190.043837 -408.337712) (xy 190.080324 -408.290162)
			(xy 190.122704 -408.247782) (xy 190.170254 -408.211295) (xy 190.22216 -408.181328) (xy 190.277533 -408.158392)
			(xy 190.335426 -408.142879) (xy 190.394848 -408.135056) (xy 190.454784 -408.135056) (xy 190.514206 -408.142879)
			(xy 190.572099 -408.158392) (xy 190.627472 -408.181328) (xy 190.679378 -408.211295) (xy 190.726928 -408.247782)
			(xy 190.769308 -408.290162) (xy 190.805795 -408.337712) (xy 190.835762 -408.389618) (xy 190.858698 -408.444991)
			(xy 190.874211 -408.502884) (xy 190.882034 -408.562306) (xy 190.882524 -408.592274) (xy 190.882034 -408.622242)
			(xy 190.874211 -408.681664) (xy 190.858698 -408.739557) (xy 190.835762 -408.79493) (xy 190.805795 -408.846836)
			(xy 190.769308 -408.894386) (xy 190.726928 -408.936766) (xy 190.679378 -408.973253) (xy 190.648552 -408.99105)
			(xy 194.706476 -408.99105) (xy 194.706476 -408.931114) (xy 194.714299 -408.871692) (xy 194.729812 -408.813799)
			(xy 194.752748 -408.758426) (xy 194.782715 -408.70652) (xy 194.819202 -408.65897) (xy 194.861582 -408.61659)
			(xy 194.909132 -408.580103) (xy 194.961038 -408.550136) (xy 195.016411 -408.5272) (xy 195.074304 -408.511687)
			(xy 195.133726 -408.503864) (xy 195.193662 -408.503864) (xy 195.253084 -408.511687) (xy 195.310977 -408.5272)
			(xy 195.36635 -408.550136) (xy 195.418256 -408.580103) (xy 195.465806 -408.61659) (xy 195.508186 -408.65897)
			(xy 195.544673 -408.70652) (xy 195.57464 -408.758426) (xy 195.597576 -408.813799) (xy 195.613089 -408.871692)
			(xy 195.620912 -408.931114) (xy 195.621402 -408.961082) (xy 195.620912 -408.99105) (xy 195.613089 -409.050472)
			(xy 195.597576 -409.108365) (xy 195.57464 -409.163738) (xy 195.544673 -409.215644) (xy 195.508186 -409.263194)
			(xy 195.465806 -409.305574) (xy 195.418256 -409.342061) (xy 195.36635 -409.372028) (xy 195.310977 -409.394964)
			(xy 195.253084 -409.410477) (xy 195.193662 -409.4183) (xy 195.133726 -409.4183) (xy 195.074304 -409.410477)
			(xy 195.016411 -409.394964) (xy 194.961038 -409.372028) (xy 194.909132 -409.342061) (xy 194.861582 -409.305574)
			(xy 194.819202 -409.263194) (xy 194.782715 -409.215644) (xy 194.752748 -409.163738) (xy 194.729812 -409.108365)
			(xy 194.714299 -409.050472) (xy 194.706476 -408.99105) (xy 190.648552 -408.99105) (xy 190.627472 -409.00322)
			(xy 190.572099 -409.026156) (xy 190.514206 -409.041669) (xy 190.454784 -409.049492) (xy 190.394848 -409.049492)
			(xy 190.335426 -409.041669) (xy 190.277533 -409.026156) (xy 190.22216 -409.00322) (xy 190.170254 -408.973253)
			(xy 190.122704 -408.936766) (xy 190.080324 -408.894386) (xy 190.043837 -408.846836) (xy 190.01387 -408.79493)
			(xy 189.990934 -408.739557) (xy 189.975421 -408.681664) (xy 189.967598 -408.622242) (xy 184.694576 -408.622242)
			(xy 184.694576 -409.450536) (xy 186.5038 -409.450536) (xy 186.5038 -409.3906) (xy 186.511623 -409.331178)
			(xy 186.527136 -409.273285) (xy 186.550072 -409.217912) (xy 186.580039 -409.166006) (xy 186.616526 -409.118456)
			(xy 186.658906 -409.076076) (xy 186.706456 -409.039589) (xy 186.758362 -409.009622) (xy 186.813735 -408.986686)
			(xy 186.871628 -408.971173) (xy 186.93105 -408.96335) (xy 186.990986 -408.96335) (xy 187.050408 -408.971173)
			(xy 187.108301 -408.986686) (xy 187.163674 -409.009622) (xy 187.21558 -409.039589) (xy 187.26313 -409.076076)
			(xy 187.30551 -409.118456) (xy 187.341997 -409.166006) (xy 187.371964 -409.217912) (xy 187.3949 -409.273285)
			(xy 187.410413 -409.331178) (xy 187.418236 -409.3906) (xy 187.418726 -409.420568) (xy 187.418236 -409.450536)
			(xy 187.410413 -409.509958) (xy 187.3949 -409.567851) (xy 187.371964 -409.623224) (xy 187.341997 -409.67513)
			(xy 187.30551 -409.72268) (xy 187.26313 -409.76506) (xy 187.21558 -409.801547) (xy 187.163674 -409.831514)
			(xy 187.108301 -409.85445) (xy 187.050408 -409.869963) (xy 186.990986 -409.877786) (xy 186.93105 -409.877786)
			(xy 186.871628 -409.869963) (xy 186.813735 -409.85445) (xy 186.758362 -409.831514) (xy 186.706456 -409.801547)
			(xy 186.658906 -409.76506) (xy 186.616526 -409.72268) (xy 186.580039 -409.67513) (xy 186.550072 -409.623224)
			(xy 186.527136 -409.567851) (xy 186.511623 -409.509958) (xy 186.5038 -409.450536) (xy 184.694576 -409.450536)
			(xy 184.694576 -411.068008) (xy 185.538854 -411.068008) (xy 185.538854 -411.008072) (xy 185.546677 -410.94865)
			(xy 185.56219 -410.890757) (xy 185.585126 -410.835384) (xy 185.615093 -410.783478) (xy 185.65158 -410.735928)
			(xy 185.69396 -410.693548) (xy 185.74151 -410.657061) (xy 185.793416 -410.627094) (xy 185.848789 -410.604158)
			(xy 185.906682 -410.588645) (xy 185.966104 -410.580822) (xy 186.02604 -410.580822) (xy 186.085462 -410.588645)
			(xy 186.143355 -410.604158) (xy 186.198728 -410.627094) (xy 186.250634 -410.657061) (xy 186.298184 -410.693548)
			(xy 186.325176 -410.72054) (xy 186.530994 -410.72054) (xy 186.535065 -410.664918) (xy 186.547191 -410.610481)
			(xy 186.567114 -410.55839) (xy 186.59441 -410.509755) (xy 186.628496 -410.465612) (xy 186.668645 -410.426903)
			(xy 186.714003 -410.394452) (xy 186.763603 -410.368951) (xy 186.816387 -410.350944) (xy 186.87123 -410.340814)
			(xy 186.926964 -410.338777) (xy 186.982401 -410.344877) (xy 187.036358 -410.358983) (xy 187.087687 -410.380795)
			(xy 187.135293 -410.409849) (xy 187.178161 -410.445524) (xy 187.215378 -410.487061) (xy 187.246151 -410.533574)
			(xy 187.269823 -410.584071) (xy 187.285891 -410.637478) (xy 187.294011 -410.692654) (xy 187.29452 -410.72054)
			(xy 187.294011 -410.748426) (xy 187.285891 -410.803602) (xy 187.269823 -410.857009) (xy 187.250567 -410.898086)
			(xy 188.828678 -410.898086) (xy 188.832749 -410.842464) (xy 188.844875 -410.788027) (xy 188.864798 -410.735936)
			(xy 188.892094 -410.687301) (xy 188.92618 -410.643158) (xy 188.966329 -410.604449) (xy 189.011687 -410.571998)
			(xy 189.061287 -410.546497) (xy 189.114071 -410.52849) (xy 189.168914 -410.51836) (xy 189.224648 -410.516323)
			(xy 189.280085 -410.522423) (xy 189.334042 -410.536529) (xy 189.385371 -410.558341) (xy 189.432977 -410.587395)
			(xy 189.475845 -410.62307) (xy 189.513062 -410.664607) (xy 189.543835 -410.71112) (xy 189.567507 -410.761617)
			(xy 189.583575 -410.815024) (xy 189.591695 -410.8702) (xy 189.592204 -410.898086) (xy 189.844678 -410.898086)
			(xy 189.848749 -410.842464) (xy 189.860875 -410.788027) (xy 189.880798 -410.735936) (xy 189.908094 -410.687301)
			(xy 189.94218 -410.643158) (xy 189.982329 -410.604449) (xy 190.027687 -410.571998) (xy 190.077287 -410.546497)
			(xy 190.130071 -410.52849) (xy 190.184914 -410.51836) (xy 190.240648 -410.516323) (xy 190.296085 -410.522423)
			(xy 190.350042 -410.536529) (xy 190.401371 -410.558341) (xy 190.448977 -410.587395) (xy 190.491845 -410.62307)
			(xy 190.529062 -410.664607) (xy 190.559835 -410.71112) (xy 190.567226 -410.726886) (xy 191.657714 -410.726886)
			(xy 191.657714 -410.66695) (xy 191.665537 -410.607528) (xy 191.68105 -410.549635) (xy 191.703986 -410.494262)
			(xy 191.733953 -410.442356) (xy 191.77044 -410.394806) (xy 191.81282 -410.352426) (xy 191.86037 -410.315939)
			(xy 191.912276 -410.285972) (xy 191.967649 -410.263036) (xy 192.025542 -410.247523) (xy 192.084964 -410.2397)
			(xy 192.1449 -410.2397) (xy 192.204322 -410.247523) (xy 192.262215 -410.263036) (xy 192.317588 -410.285972)
			(xy 192.369494 -410.315939) (xy 192.417044 -410.352426) (xy 192.459424 -410.394806) (xy 192.495911 -410.442356)
			(xy 192.525878 -410.494262) (xy 192.548814 -410.549635) (xy 192.564327 -410.607528) (xy 192.57215 -410.66695)
			(xy 192.57264 -410.696918) (xy 195.549264 -410.696918) (xy 195.553335 -410.641296) (xy 195.565461 -410.586859)
			(xy 195.585384 -410.534768) (xy 195.61268 -410.486133) (xy 195.646766 -410.44199) (xy 195.686915 -410.403281)
			(xy 195.732273 -410.37083) (xy 195.781873 -410.345329) (xy 195.834657 -410.327322) (xy 195.8895 -410.317192)
			(xy 195.945234 -410.315155) (xy 196.000671 -410.321255) (xy 196.054628 -410.335361) (xy 196.105957 -410.357173)
			(xy 196.153563 -410.386227) (xy 196.196431 -410.421902) (xy 196.233648 -410.463439) (xy 196.264421 -410.509952)
			(xy 196.288093 -410.560449) (xy 196.304161 -410.613856) (xy 196.312281 -410.669032) (xy 196.31279 -410.696918)
			(xy 196.312281 -410.724804) (xy 196.304161 -410.77998) (xy 196.288093 -410.833387) (xy 196.264421 -410.883884)
			(xy 196.233648 -410.930397) (xy 196.196431 -410.971934) (xy 196.153563 -411.007609) (xy 196.105957 -411.036663)
			(xy 196.054628 -411.058475) (xy 196.000671 -411.072581) (xy 195.945234 -411.078681) (xy 195.8895 -411.076644)
			(xy 195.834657 -411.066514) (xy 195.781873 -411.048507) (xy 195.732273 -411.023006) (xy 195.686915 -410.990555)
			(xy 195.646766 -410.951846) (xy 195.61268 -410.907703) (xy 195.585384 -410.859068) (xy 195.565461 -410.806977)
			(xy 195.553335 -410.75254) (xy 195.549264 -410.696918) (xy 192.57264 -410.696918) (xy 192.57215 -410.726886)
			(xy 192.564327 -410.786308) (xy 192.548814 -410.844201) (xy 192.525878 -410.899574) (xy 192.495911 -410.95148)
			(xy 192.459424 -410.99903) (xy 192.417044 -411.04141) (xy 192.369494 -411.077897) (xy 192.317588 -411.107864)
			(xy 192.262215 -411.1308) (xy 192.204322 -411.146313) (xy 192.1449 -411.154136) (xy 192.084964 -411.154136)
			(xy 192.025542 -411.146313) (xy 191.967649 -411.1308) (xy 191.912276 -411.107864) (xy 191.86037 -411.077897)
			(xy 191.81282 -411.04141) (xy 191.77044 -410.99903) (xy 191.733953 -410.95148) (xy 191.703986 -410.899574)
			(xy 191.68105 -410.844201) (xy 191.665537 -410.786308) (xy 191.657714 -410.726886) (xy 190.567226 -410.726886)
			(xy 190.583507 -410.761617) (xy 190.599575 -410.815024) (xy 190.607695 -410.8702) (xy 190.608204 -410.898086)
			(xy 190.607695 -410.925972) (xy 190.599575 -410.981148) (xy 190.583507 -411.034555) (xy 190.559835 -411.085052)
			(xy 190.529062 -411.131565) (xy 190.491845 -411.173102) (xy 190.448977 -411.208777) (xy 190.401371 -411.237831)
			(xy 190.350042 -411.259643) (xy 190.296085 -411.273749) (xy 190.240648 -411.279849) (xy 190.184914 -411.277812)
			(xy 190.130071 -411.267682) (xy 190.077287 -411.249675) (xy 190.027687 -411.224174) (xy 189.982329 -411.191723)
			(xy 189.94218 -411.153014) (xy 189.908094 -411.108871) (xy 189.880798 -411.060236) (xy 189.860875 -411.008145)
			(xy 189.848749 -410.953708) (xy 189.844678 -410.898086) (xy 189.592204 -410.898086) (xy 189.591695 -410.925972)
			(xy 189.583575 -410.981148) (xy 189.567507 -411.034555) (xy 189.543835 -411.085052) (xy 189.513062 -411.131565)
			(xy 189.475845 -411.173102) (xy 189.432977 -411.208777) (xy 189.385371 -411.237831) (xy 189.334042 -411.259643)
			(xy 189.280085 -411.273749) (xy 189.224648 -411.279849) (xy 189.168914 -411.277812) (xy 189.114071 -411.267682)
			(xy 189.061287 -411.249675) (xy 189.011687 -411.224174) (xy 188.966329 -411.191723) (xy 188.92618 -411.153014)
			(xy 188.892094 -411.108871) (xy 188.864798 -411.060236) (xy 188.844875 -411.008145) (xy 188.832749 -410.953708)
			(xy 188.828678 -410.898086) (xy 187.250567 -410.898086) (xy 187.246151 -410.907506) (xy 187.215378 -410.954019)
			(xy 187.178161 -410.995556) (xy 187.135293 -411.031231) (xy 187.087687 -411.060285) (xy 187.036358 -411.082097)
			(xy 186.982401 -411.096203) (xy 186.926964 -411.102303) (xy 186.87123 -411.100266) (xy 186.816387 -411.090136)
			(xy 186.763603 -411.072129) (xy 186.714003 -411.046628) (xy 186.668645 -411.014177) (xy 186.628496 -410.975468)
			(xy 186.59441 -410.931325) (xy 186.567114 -410.88269) (xy 186.547191 -410.830599) (xy 186.535065 -410.776162)
			(xy 186.530994 -410.72054) (xy 186.325176 -410.72054) (xy 186.340564 -410.735928) (xy 186.377051 -410.783478)
			(xy 186.407018 -410.835384) (xy 186.429954 -410.890757) (xy 186.445467 -410.94865) (xy 186.45329 -411.008072)
			(xy 186.45378 -411.03804) (xy 186.45329 -411.068008) (xy 186.445467 -411.12743) (xy 186.429954 -411.185323)
			(xy 186.407018 -411.240696) (xy 186.377051 -411.292602) (xy 186.340564 -411.340152) (xy 186.298184 -411.382532)
			(xy 186.250634 -411.419019) (xy 186.198728 -411.448986) (xy 186.143355 -411.471922) (xy 186.085462 -411.487435)
			(xy 186.02604 -411.495258) (xy 185.966104 -411.495258) (xy 185.906682 -411.487435) (xy 185.848789 -411.471922)
			(xy 185.793416 -411.448986) (xy 185.74151 -411.419019) (xy 185.69396 -411.382532) (xy 185.65158 -411.340152)
			(xy 185.615093 -411.292602) (xy 185.585126 -411.240696) (xy 185.56219 -411.185323) (xy 185.546677 -411.12743)
			(xy 185.538854 -411.068008) (xy 184.694576 -411.068008) (xy 184.694576 -411.432502) (xy 184.694999 -411.442573)
			(xy 184.702711 -411.461179) (xy 184.709562 -411.46857) (xy 185.367422 -412.12643) (xy 197.241922 -412.12643)
			(xy 197.242384 -412.099826) (xy 197.249762 -412.047133) (xy 197.264393 -411.995978) (xy 197.285994 -411.947352)
			(xy 197.314143 -411.902202) (xy 197.348296 -411.861403) (xy 197.387788 -411.825747) (xy 197.409562 -411.810454)
			(xy 197.421065 -411.802147) (xy 197.439276 -411.780399) (xy 197.450796 -411.754479) (xy 197.454736 -411.726389)
			(xy 197.45079 -411.698299) (xy 197.439264 -411.672382) (xy 197.421048 -411.650638) (xy 197.409562 -411.642306)
			(xy 197.387791 -411.627012) (xy 197.348311 -411.591347) (xy 197.314167 -411.550543) (xy 197.286021 -411.505393)
			(xy 197.264419 -411.456771) (xy 197.249779 -411.405621) (xy 197.242385 -411.352932) (xy 197.241922 -411.32633)
			(xy 197.242408 -411.299079) (xy 197.250164 -411.245131) (xy 197.265519 -411.192836) (xy 197.288161 -411.143259)
			(xy 197.317627 -411.097409) (xy 197.353318 -411.056218) (xy 197.394509 -411.020527) (xy 197.440359 -410.991061)
			(xy 197.489936 -410.968419) (xy 197.542231 -410.953064) (xy 197.596179 -410.945308) (xy 197.650681 -410.945308)
			(xy 197.704629 -410.953064) (xy 197.756924 -410.968419) (xy 197.806501 -410.991061) (xy 197.852351 -411.020527)
			(xy 197.893542 -411.056218) (xy 197.929233 -411.097409) (xy 197.958699 -411.143259) (xy 197.981341 -411.192836)
			(xy 197.996696 -411.245131) (xy 198.004452 -411.299079) (xy 198.004938 -411.32633) (xy 198.004463 -411.352933)
			(xy 197.99709 -411.405627) (xy 197.982462 -411.456783) (xy 197.960864 -411.505409) (xy 197.932716 -411.55056)
			(xy 197.898564 -411.591359) (xy 197.859072 -411.627014) (xy 197.837298 -411.642306) (xy 197.825838 -411.650665)
			(xy 197.807635 -411.672403) (xy 197.796117 -411.698311) (xy 197.792175 -411.726389) (xy 197.796111 -411.754467)
			(xy 197.807623 -411.780377) (xy 197.825821 -411.80212) (xy 197.837298 -411.810454) (xy 197.859064 -411.825754)
			(xy 197.898542 -411.861421) (xy 197.932684 -411.902224) (xy 197.960829 -411.947373) (xy 197.982432 -411.995993)
			(xy 197.997075 -412.047142) (xy 198.004472 -412.099828) (xy 198.004938 -412.12643) (xy 198.004452 -412.153681)
			(xy 197.996696 -412.207629) (xy 197.981341 -412.259924) (xy 197.958699 -412.309501) (xy 197.929233 -412.355351)
			(xy 197.893542 -412.396542) (xy 197.852351 -412.432233) (xy 197.806501 -412.461699) (xy 197.756924 -412.484341)
			(xy 197.704629 -412.499696) (xy 197.650681 -412.507452) (xy 197.596179 -412.507452) (xy 197.542231 -412.499696)
			(xy 197.489936 -412.484341) (xy 197.440359 -412.461699) (xy 197.394509 -412.432233) (xy 197.353318 -412.396542)
			(xy 197.317627 -412.355351) (xy 197.288161 -412.309501) (xy 197.265519 -412.259924) (xy 197.250164 -412.207629)
			(xy 197.242408 -412.153681) (xy 197.241922 -412.12643) (xy 185.367422 -412.12643) (xy 185.835798 -412.594806)
			(xy 185.842644 -412.602205) (xy 185.850376 -412.620803) (xy 185.850784 -412.630874) (xy 185.850784 -413.479234)
			(xy 188.424056 -413.479234) (xy 188.428127 -413.423612) (xy 188.440253 -413.369175) (xy 188.460176 -413.317084)
			(xy 188.487472 -413.268449) (xy 188.521558 -413.224306) (xy 188.561707 -413.185597) (xy 188.607065 -413.153146)
			(xy 188.656665 -413.127645) (xy 188.709449 -413.109638) (xy 188.764292 -413.099508) (xy 188.820026 -413.097471)
			(xy 188.875463 -413.103571) (xy 188.92942 -413.117677) (xy 188.980749 -413.139489) (xy 189.028355 -413.168543)
			(xy 189.071223 -413.204218) (xy 189.10844 -413.245755) (xy 189.139213 -413.292268) (xy 189.162885 -413.342765)
			(xy 189.178953 -413.396172) (xy 189.187073 -413.451348) (xy 189.187582 -413.479234) (xy 189.505842 -413.479234)
			(xy 189.509913 -413.423612) (xy 189.522039 -413.369175) (xy 189.541962 -413.317084) (xy 189.569258 -413.268449)
			(xy 189.603344 -413.224306) (xy 189.643493 -413.185597) (xy 189.688851 -413.153146) (xy 189.738451 -413.127645)
			(xy 189.791235 -413.109638) (xy 189.846078 -413.099508) (xy 189.901812 -413.097471) (xy 189.957249 -413.103571)
			(xy 190.011206 -413.117677) (xy 190.062535 -413.139489) (xy 190.110141 -413.168543) (xy 190.153009 -413.204218)
			(xy 190.190226 -413.245755) (xy 190.220999 -413.292268) (xy 190.244671 -413.342765) (xy 190.260739 -413.396172)
			(xy 190.268859 -413.451348) (xy 190.269368 -413.479234) (xy 190.664082 -413.479234) (xy 190.668153 -413.423612)
			(xy 190.680279 -413.369175) (xy 190.700202 -413.317084) (xy 190.727498 -413.268449) (xy 190.761584 -413.224306)
			(xy 190.801733 -413.185597) (xy 190.847091 -413.153146) (xy 190.896691 -413.127645) (xy 190.949475 -413.109638)
			(xy 191.004318 -413.099508) (xy 191.060052 -413.097471) (xy 191.115489 -413.103571) (xy 191.169446 -413.117677)
			(xy 191.220775 -413.139489) (xy 191.268381 -413.168543) (xy 191.311249 -413.204218) (xy 191.348466 -413.245755)
			(xy 191.379239 -413.292268) (xy 191.402911 -413.342765) (xy 191.409351 -413.364172) (xy 196.16877 -413.364172)
			(xy 196.172841 -413.30855) (xy 196.184967 -413.254113) (xy 196.20489 -413.202022) (xy 196.232186 -413.153387)
			(xy 196.266272 -413.109244) (xy 196.306421 -413.070535) (xy 196.351779 -413.038084) (xy 196.401379 -413.012583)
			(xy 196.454163 -412.994576) (xy 196.509006 -412.984446) (xy 196.56474 -412.982409) (xy 196.620177 -412.988509)
			(xy 196.674134 -413.002615) (xy 196.725463 -413.024427) (xy 196.773069 -413.053481) (xy 196.815937 -413.089156)
			(xy 196.853154 -413.130693) (xy 196.883927 -413.177206) (xy 196.907599 -413.227703) (xy 196.923667 -413.28111)
			(xy 196.931787 -413.336286) (xy 196.932296 -413.364172) (xy 196.931787 -413.392058) (xy 196.923667 -413.447234)
			(xy 196.907599 -413.500641) (xy 196.883927 -413.551138) (xy 196.853154 -413.597651) (xy 196.815937 -413.639188)
			(xy 196.773069 -413.674863) (xy 196.725463 -413.703917) (xy 196.674134 -413.725729) (xy 196.620177 -413.739835)
			(xy 196.56474 -413.745935) (xy 196.509006 -413.743898) (xy 196.454163 -413.733768) (xy 196.401379 -413.715761)
			(xy 196.351779 -413.69026) (xy 196.306421 -413.657809) (xy 196.266272 -413.6191) (xy 196.232186 -413.574957)
			(xy 196.20489 -413.526322) (xy 196.184967 -413.474231) (xy 196.172841 -413.419794) (xy 196.16877 -413.364172)
			(xy 191.409351 -413.364172) (xy 191.418979 -413.396172) (xy 191.427099 -413.451348) (xy 191.427608 -413.479234)
			(xy 191.427099 -413.50712) (xy 191.418979 -413.562296) (xy 191.402911 -413.615703) (xy 191.379239 -413.6662)
			(xy 191.348466 -413.712713) (xy 191.311249 -413.75425) (xy 191.268381 -413.789925) (xy 191.220775 -413.818979)
			(xy 191.169446 -413.840791) (xy 191.115489 -413.854897) (xy 191.060052 -413.860997) (xy 191.004318 -413.85896)
			(xy 190.949475 -413.84883) (xy 190.896691 -413.830823) (xy 190.847091 -413.805322) (xy 190.801733 -413.772871)
			(xy 190.761584 -413.734162) (xy 190.727498 -413.690019) (xy 190.700202 -413.641384) (xy 190.680279 -413.589293)
			(xy 190.668153 -413.534856) (xy 190.664082 -413.479234) (xy 190.269368 -413.479234) (xy 190.268859 -413.50712)
			(xy 190.260739 -413.562296) (xy 190.244671 -413.615703) (xy 190.220999 -413.6662) (xy 190.190226 -413.712713)
			(xy 190.153009 -413.75425) (xy 190.110141 -413.789925) (xy 190.062535 -413.818979) (xy 190.011206 -413.840791)
			(xy 189.957249 -413.854897) (xy 189.901812 -413.860997) (xy 189.846078 -413.85896) (xy 189.791235 -413.84883)
			(xy 189.738451 -413.830823) (xy 189.688851 -413.805322) (xy 189.643493 -413.772871) (xy 189.603344 -413.734162)
			(xy 189.569258 -413.690019) (xy 189.541962 -413.641384) (xy 189.522039 -413.589293) (xy 189.509913 -413.534856)
			(xy 189.505842 -413.479234) (xy 189.187582 -413.479234) (xy 189.187073 -413.50712) (xy 189.178953 -413.562296)
			(xy 189.162885 -413.615703) (xy 189.139213 -413.6662) (xy 189.10844 -413.712713) (xy 189.071223 -413.75425)
			(xy 189.028355 -413.789925) (xy 188.980749 -413.818979) (xy 188.92942 -413.840791) (xy 188.875463 -413.854897)
			(xy 188.820026 -413.860997) (xy 188.764292 -413.85896) (xy 188.709449 -413.84883) (xy 188.656665 -413.830823)
			(xy 188.607065 -413.805322) (xy 188.561707 -413.772871) (xy 188.521558 -413.734162) (xy 188.487472 -413.690019)
			(xy 188.460176 -413.641384) (xy 188.440253 -413.589293) (xy 188.428127 -413.534856) (xy 188.424056 -413.479234)
			(xy 185.850784 -413.479234) (xy 185.850784 -413.868108) (xy 185.850923 -413.87141) (xy 193.363086 -413.87141)
			(xy 193.367157 -413.815788) (xy 193.379283 -413.761351) (xy 193.399206 -413.70926) (xy 193.426502 -413.660625)
			(xy 193.460588 -413.616482) (xy 193.500737 -413.577773) (xy 193.546095 -413.545322) (xy 193.595695 -413.519821)
			(xy 193.648479 -413.501814) (xy 193.703322 -413.491684) (xy 193.759056 -413.489647) (xy 193.814493 -413.495747)
			(xy 193.86845 -413.509853) (xy 193.919779 -413.531665) (xy 193.967385 -413.560719) (xy 194.010253 -413.596394)
			(xy 194.04747 -413.637931) (xy 194.078243 -413.684444) (xy 194.101915 -413.734941) (xy 194.117983 -413.788348)
			(xy 194.126103 -413.843524) (xy 194.126612 -413.87141) (xy 194.126103 -413.899296) (xy 194.117983 -413.954472)
			(xy 194.101915 -414.007879) (xy 194.078243 -414.058376) (xy 194.04747 -414.104889) (xy 194.010253 -414.146426)
			(xy 193.967385 -414.182101) (xy 193.919779 -414.211155) (xy 193.86845 -414.232967) (xy 193.814493 -414.247073)
			(xy 193.759056 -414.253173) (xy 193.703322 -414.251136) (xy 193.648479 -414.241006) (xy 193.595695 -414.222999)
			(xy 193.546095 -414.197498) (xy 193.500737 -414.165047) (xy 193.460588 -414.126338) (xy 193.426502 -414.082195)
			(xy 193.399206 -414.03356) (xy 193.379283 -413.981469) (xy 193.367157 -413.927032) (xy 193.363086 -413.87141)
			(xy 185.850923 -413.87141) (xy 185.851208 -413.878178) (xy 185.858923 -413.896782) (xy 185.86577 -413.904176)
			(xy 187.37199 -415.410396) (xy 187.379388 -415.417245) (xy 187.397986 -415.424983) (xy 187.408058 -415.425382)
		)
		(stroke
			(width 0)
			(type solid)
		)
		(fill yes)
		(layer "B.Cu")
		(net "P3V3_AUX")
	)
	(gr_poly
		(pts
			(xy 282.497784 -416.760406) (xy 282.507848 -416.759968) (xy 282.526431 -416.752233) (xy 282.533852 -416.74542)
			(xy 283.076396 -416.202876) (xy 283.083239 -416.195476) (xy 283.090965 -416.176878) (xy 283.091382 -416.166808)
			(xy 283.091382 -391.624566) (xy 283.090952 -391.614499) (xy 283.083227 -391.595905) (xy 283.076396 -391.588498)
			(xy 282.65882 -391.170922) (xy 282.651418 -391.164086) (xy 282.63282 -391.156377) (xy 282.622752 -391.155936)
			(xy 281.661108 -391.155936) (xy 281.651088 -391.156355) (xy 281.632575 -391.164025) (xy 281.618409 -391.178198)
			(xy 281.610749 -391.196716) (xy 281.610308 -391.206736) (xy 281.610308 -397.743172) (xy 281.609752 -397.773153)
			(xy 281.600371 -397.832376) (xy 281.581838 -397.889401) (xy 281.554607 -397.942822) (xy 281.519351 -397.991324)
			(xy 281.498548 -398.01292) (xy 280.6954 -398.816068) (xy 280.673785 -398.836847) (xy 280.62528 -398.872082)
			(xy 280.571861 -398.899299) (xy 280.514843 -398.917828) (xy 280.455628 -398.927211) (xy 280.425652 -398.927828)
			(xy 277.450804 -398.927828) (xy 277.420824 -398.92727) (xy 277.361602 -398.917887) (xy 277.304579 -398.899351)
			(xy 277.251159 -398.87212) (xy 277.202659 -398.836863) (xy 277.181056 -398.816068) (xy 275.094192 -396.729204)
			(xy 275.073415 -396.707589) (xy 275.038182 -396.659082) (xy 275.010968 -396.605663) (xy 274.992441 -396.548645)
			(xy 274.983058 -396.489432) (xy 274.982432 -396.459456) (xy 274.982432 -394.43533) (xy 274.981941 -394.42533)
			(xy 274.974314 -394.406839) (xy 274.960232 -394.392635) (xy 274.95119 -394.38834) (xy 274.936712 -394.382498)
			(xy 274.906994 -394.38834) (xy 270.639794 -398.65554) (xy 270.632398 -398.662392) (xy 270.613799 -398.670134)
			(xy 270.603726 -398.670526) (xy 266.295124 -398.670526) (xy 266.285073 -398.670021) (xy 266.266511 -398.662301)
			(xy 266.259056 -398.65554) (xy 260.528308 -392.924792) (xy 260.520909 -392.917945) (xy 260.502312 -392.910209)
			(xy 260.49224 -392.909806) (xy 255.18364 -392.909806) (xy 255.173575 -392.91024) (xy 255.154987 -392.917971)
			(xy 255.147572 -392.924792) (xy 254.616204 -393.45616) (xy 254.609366 -393.463562) (xy 254.601653 -393.48216)
			(xy 254.601218 -393.492228) (xy 254.601218 -398.121886) (xy 254.60078 -398.13195) (xy 254.593045 -398.150533)
			(xy 254.586232 -398.157954) (xy 253.358142 -399.386044) (xy 253.350743 -399.392887) (xy 253.332144 -399.40061)
			(xy 253.322074 -399.40103) (xy 247.246902 -399.40103) (xy 247.236832 -399.401453) (xy 247.21823 -399.409171)
			(xy 247.210834 -399.416016) (xy 245.453662 -401.173188) (xy 277.04415 -401.173188) (xy 277.04464 -401.14322)
			(xy 277.052463 -401.083798) (xy 277.067976 -401.025905) (xy 277.090912 -400.970532) (xy 277.120879 -400.918626)
			(xy 277.157366 -400.871076) (xy 277.199746 -400.828696) (xy 277.247296 -400.792209) (xy 277.299202 -400.762242)
			(xy 277.354575 -400.739306) (xy 277.412468 -400.723793) (xy 277.47189 -400.71597) (xy 277.531826 -400.71597)
			(xy 277.591248 -400.723793) (xy 277.649141 -400.739306) (xy 277.704514 -400.762242) (xy 277.75642 -400.792209)
			(xy 277.80397 -400.828696) (xy 277.84635 -400.871076) (xy 277.882837 -400.918626) (xy 277.912804 -400.970532)
			(xy 277.93574 -401.025905) (xy 277.951253 -401.083798) (xy 277.959076 -401.14322) (xy 277.959566 -401.173188)
			(xy 277.959503 -401.17674) (xy 279.063686 -401.17674) (xy 279.063686 -401.116804) (xy 279.071509 -401.057382)
			(xy 279.087022 -400.999489) (xy 279.109958 -400.944116) (xy 279.139925 -400.89221) (xy 279.176412 -400.84466)
			(xy 279.218792 -400.80228) (xy 279.266342 -400.765793) (xy 279.318248 -400.735826) (xy 279.373621 -400.71289)
			(xy 279.431514 -400.697377) (xy 279.490936 -400.689554) (xy 279.550872 -400.689554) (xy 279.610294 -400.697377)
			(xy 279.668187 -400.71289) (xy 279.72356 -400.735826) (xy 279.775466 -400.765793) (xy 279.823016 -400.80228)
			(xy 279.865396 -400.84466) (xy 279.901883 -400.89221) (xy 279.93185 -400.944116) (xy 279.954786 -400.999489)
			(xy 279.970299 -401.057382) (xy 279.978122 -401.116804) (xy 279.978612 -401.146772) (xy 279.978122 -401.17674)
			(xy 279.970299 -401.236162) (xy 279.954786 -401.294055) (xy 279.93185 -401.349428) (xy 279.901883 -401.401334)
			(xy 279.865396 -401.448884) (xy 279.823016 -401.491264) (xy 279.775466 -401.527751) (xy 279.72356 -401.557718)
			(xy 279.668187 -401.580654) (xy 279.610294 -401.596167) (xy 279.550872 -401.60399) (xy 279.490936 -401.60399)
			(xy 279.431514 -401.596167) (xy 279.373621 -401.580654) (xy 279.318248 -401.557718) (xy 279.266342 -401.527751)
			(xy 279.218792 -401.491264) (xy 279.176412 -401.448884) (xy 279.139925 -401.401334) (xy 279.109958 -401.349428)
			(xy 279.087022 -401.294055) (xy 279.071509 -401.236162) (xy 279.063686 -401.17674) (xy 277.959503 -401.17674)
			(xy 277.958966 -401.207167) (xy 277.948949 -401.274383) (xy 277.929091 -401.339374) (xy 277.899829 -401.400709)
			(xy 277.881334 -401.42922) (xy 277.87473 -401.438872) (xy 277.871428 -401.461478) (xy 277.902924 -401.560284)
			(xy 277.918672 -401.576794) (xy 277.929848 -401.580858) (xy 277.956671 -401.59157) (xy 278.007012 -401.619877)
			(xy 278.052514 -401.655444) (xy 278.09214 -401.697461) (xy 278.124984 -401.744967) (xy 278.150297 -401.796878)
			(xy 278.167501 -401.85201) (xy 278.176204 -401.909105) (xy 278.176736 -401.937982) (xy 278.17625 -401.965233)
			(xy 278.168494 -402.019181) (xy 278.153139 -402.071476) (xy 278.130497 -402.121053) (xy 278.101031 -402.166903)
			(xy 278.06534 -402.208094) (xy 278.024149 -402.243785) (xy 277.978299 -402.273251) (xy 277.928722 -402.295893)
			(xy 277.876427 -402.311248) (xy 277.822479 -402.319004) (xy 277.767977 -402.319004) (xy 277.714029 -402.311248)
			(xy 277.661734 -402.295893) (xy 277.612157 -402.273251) (xy 277.566307 -402.243785) (xy 277.525116 -402.208094)
			(xy 277.489425 -402.166903) (xy 277.459959 -402.121053) (xy 277.437317 -402.071476) (xy 277.421962 -402.019181)
			(xy 277.414206 -401.965233) (xy 277.41372 -401.937982) (xy 277.414306 -401.907572) (xy 277.42393 -401.84752)
			(xy 277.442949 -401.789751) (xy 277.456392 -401.762468) (xy 277.46198 -401.752054) (xy 277.462488 -401.729194)
			(xy 277.42007 -401.634706) (xy 277.402544 -401.620228) (xy 277.39086 -401.61718) (xy 277.361546 -401.609294)
			(xy 277.305113 -401.586932) (xy 277.252131 -401.557305) (xy 277.203533 -401.520932) (xy 277.160171 -401.478452)
			(xy 277.122807 -401.430612) (xy 277.092097 -401.378251) (xy 277.06858 -401.322289) (xy 277.052669 -401.263709)
			(xy 277.044644 -401.203539) (xy 277.04415 -401.173188) (xy 245.453662 -401.173188) (xy 244.435376 -402.191474)
			(xy 244.427977 -402.19832) (xy 244.409379 -402.206049) (xy 244.399308 -402.20646) (xy 241.692938 -402.20646)
			(xy 241.682874 -402.206896) (xy 241.664292 -402.214633) (xy 241.65687 -402.221446) (xy 240.415826 -403.46249)
			(xy 275.581108 -403.46249) (xy 275.585179 -403.406868) (xy 275.597305 -403.352431) (xy 275.617228 -403.30034)
			(xy 275.644524 -403.251705) (xy 275.67861 -403.207562) (xy 275.718759 -403.168853) (xy 275.764117 -403.136402)
			(xy 275.813717 -403.110901) (xy 275.866501 -403.092894) (xy 275.921344 -403.082764) (xy 275.977078 -403.080727)
			(xy 276.032515 -403.086827) (xy 276.086472 -403.100933) (xy 276.137801 -403.122745) (xy 276.185407 -403.151799)
			(xy 276.228275 -403.187474) (xy 276.265492 -403.229011) (xy 276.296265 -403.275524) (xy 276.319937 -403.326021)
			(xy 276.336005 -403.379428) (xy 276.344125 -403.434604) (xy 276.344634 -403.46249) (xy 276.344125 -403.490376)
			(xy 276.343819 -403.492458) (xy 276.521908 -403.492458) (xy 276.521908 -403.432522) (xy 276.529731 -403.3731)
			(xy 276.545244 -403.315207) (xy 276.56818 -403.259834) (xy 276.598147 -403.207928) (xy 276.634634 -403.160378)
			(xy 276.677014 -403.117998) (xy 276.724564 -403.081511) (xy 276.77647 -403.051544) (xy 276.831843 -403.028608)
			(xy 276.889736 -403.013095) (xy 276.949158 -403.005272) (xy 277.009094 -403.005272) (xy 277.068516 -403.013095)
			(xy 277.126409 -403.028608) (xy 277.181782 -403.051544) (xy 277.233688 -403.081511) (xy 277.281238 -403.117998)
			(xy 277.323618 -403.160378) (xy 277.360105 -403.207928) (xy 277.390072 -403.259834) (xy 277.413008 -403.315207)
			(xy 277.428521 -403.3731) (xy 277.436344 -403.432522) (xy 277.436834 -403.46249) (xy 277.436344 -403.492458)
			(xy 277.428521 -403.55188) (xy 277.413008 -403.609773) (xy 277.390072 -403.665146) (xy 277.360105 -403.717052)
			(xy 277.323618 -403.764602) (xy 277.281238 -403.806982) (xy 277.233688 -403.843469) (xy 277.181782 -403.873436)
			(xy 277.126409 -403.896372) (xy 277.068516 -403.911885) (xy 277.009094 -403.919708) (xy 276.949158 -403.919708)
			(xy 276.889736 -403.911885) (xy 276.831843 -403.896372) (xy 276.77647 -403.873436) (xy 276.724564 -403.843469)
			(xy 276.677014 -403.806982) (xy 276.634634 -403.764602) (xy 276.598147 -403.717052) (xy 276.56818 -403.665146)
			(xy 276.545244 -403.609773) (xy 276.529731 -403.55188) (xy 276.521908 -403.492458) (xy 276.343819 -403.492458)
			(xy 276.336005 -403.545552) (xy 276.319937 -403.598959) (xy 276.296265 -403.649456) (xy 276.265492 -403.695969)
			(xy 276.228275 -403.737506) (xy 276.185407 -403.773181) (xy 276.137801 -403.802235) (xy 276.086472 -403.824047)
			(xy 276.032515 -403.838153) (xy 275.977078 -403.844253) (xy 275.921344 -403.842216) (xy 275.866501 -403.832086)
			(xy 275.813717 -403.814079) (xy 275.764117 -403.788578) (xy 275.718759 -403.756127) (xy 275.67861 -403.717418)
			(xy 275.644524 -403.673275) (xy 275.617228 -403.62464) (xy 275.597305 -403.572549) (xy 275.585179 -403.518112)
			(xy 275.581108 -403.46249) (xy 240.415826 -403.46249) (xy 239.907826 -403.97049) (xy 278.636984 -403.97049)
			(xy 278.637574 -403.941574) (xy 278.64629 -403.884403) (xy 278.663537 -403.829203) (xy 278.688918 -403.777239)
			(xy 278.721853 -403.729701) (xy 278.761586 -403.68768) (xy 278.807207 -403.652138) (xy 278.85767 -403.62389)
			(xy 278.911819 -403.603583) (xy 278.940006 -403.59711) (xy 278.950674 -403.594824) (xy 278.967438 -403.58314)
			(xy 279.017222 -403.50186) (xy 279.020016 -403.48154) (xy 279.017222 -403.471126) (xy 279.009857 -403.441897)
			(xy 279.001956 -403.382139) (xy 279.001474 -403.352) (xy 279.001964 -403.322032) (xy 279.009787 -403.26261)
			(xy 279.0253 -403.204717) (xy 279.048236 -403.149344) (xy 279.078203 -403.097438) (xy 279.11469 -403.049888)
			(xy 279.15707 -403.007508) (xy 279.20462 -402.971021) (xy 279.256526 -402.941054) (xy 279.311899 -402.918118)
			(xy 279.369792 -402.902605) (xy 279.429214 -402.894782) (xy 279.48915 -402.894782) (xy 279.548572 -402.902605)
			(xy 279.606465 -402.918118) (xy 279.661838 -402.941054) (xy 279.713744 -402.971021) (xy 279.761294 -403.007508)
			(xy 279.803674 -403.049888) (xy 279.840161 -403.097438) (xy 279.870128 -403.149344) (xy 279.893064 -403.204717)
			(xy 279.908577 -403.26261) (xy 279.9164 -403.322032) (xy 279.916819 -403.347682) (xy 280.093164 -403.347682)
			(xy 280.097235 -403.29206) (xy 280.109361 -403.237623) (xy 280.129284 -403.185532) (xy 280.15658 -403.136897)
			(xy 280.190666 -403.092754) (xy 280.230815 -403.054045) (xy 280.276173 -403.021594) (xy 280.325773 -402.996093)
			(xy 280.378557 -402.978086) (xy 280.4334 -402.967956) (xy 280.489134 -402.965919) (xy 280.544571 -402.972019)
			(xy 280.598528 -402.986125) (xy 280.649857 -403.007937) (xy 280.697463 -403.036991) (xy 280.740331 -403.072666)
			(xy 280.777548 -403.114203) (xy 280.808321 -403.160716) (xy 280.831993 -403.211213) (xy 280.848061 -403.26462)
			(xy 280.856181 -403.319796) (xy 280.85669 -403.347682) (xy 280.856181 -403.375568) (xy 280.848061 -403.430744)
			(xy 280.831993 -403.484151) (xy 280.808321 -403.534648) (xy 280.777548 -403.581161) (xy 280.740331 -403.622698)
			(xy 280.697463 -403.658373) (xy 280.649857 -403.687427) (xy 280.598528 -403.709239) (xy 280.544571 -403.723345)
			(xy 280.489134 -403.729445) (xy 280.4334 -403.727408) (xy 280.378557 -403.717278) (xy 280.325773 -403.699271)
			(xy 280.276173 -403.67377) (xy 280.230815 -403.641319) (xy 280.190666 -403.60261) (xy 280.15658 -403.558467)
			(xy 280.129284 -403.509832) (xy 280.109361 -403.457741) (xy 280.097235 -403.403304) (xy 280.093164 -403.347682)
			(xy 279.916819 -403.347682) (xy 279.91689 -403.352) (xy 279.916349 -403.383263) (xy 279.907851 -403.445208)
			(xy 279.890998 -403.50542) (xy 279.866106 -403.562776) (xy 279.833636 -403.61621) (xy 279.794195 -403.664726)
			(xy 279.748515 -403.707421) (xy 279.697449 -403.7435) (xy 279.641947 -403.772291) (xy 279.583041 -403.793258)
			(xy 279.52183 -403.80601) (xy 279.490678 -403.808692) (xy 279.48001 -403.809454) (xy 279.461722 -403.818852)
			(xy 279.40127 -403.892258) (xy 279.395682 -403.91207) (xy 279.396952 -403.922738) (xy 279.398378 -403.934624)
			(xy 279.399902 -403.958519) (xy 279.4 -403.97049) (xy 279.399514 -403.997741) (xy 279.391758 -404.051689)
			(xy 279.376403 -404.103984) (xy 279.353761 -404.153561) (xy 279.324295 -404.199411) (xy 279.288604 -404.240602)
			(xy 279.247413 -404.276293) (xy 279.201563 -404.305759) (xy 279.151986 -404.328401) (xy 279.099691 -404.343756)
			(xy 279.045743 -404.351512) (xy 278.991241 -404.351512) (xy 278.937293 -404.343756) (xy 278.884998 -404.328401)
			(xy 278.835421 -404.305759) (xy 278.789571 -404.276293) (xy 278.74838 -404.240602) (xy 278.712689 -404.199411)
			(xy 278.683223 -404.153561) (xy 278.660581 -404.103984) (xy 278.645226 -404.051689) (xy 278.63747 -403.997741)
			(xy 278.636984 -403.97049) (xy 239.907826 -403.97049) (xy 239.88395 -403.994366) (xy 239.877108 -404.001766)
			(xy 239.86939 -404.020364) (xy 239.868964 -404.030434) (xy 239.868964 -404.704292) (xy 274.853382 -404.704292)
			(xy 274.853382 -404.644356) (xy 274.861205 -404.584934) (xy 274.876718 -404.527041) (xy 274.899654 -404.471668)
			(xy 274.929621 -404.419762) (xy 274.966108 -404.372212) (xy 275.008488 -404.329832) (xy 275.056038 -404.293345)
			(xy 275.107944 -404.263378) (xy 275.163317 -404.240442) (xy 275.22121 -404.224929) (xy 275.280632 -404.217106)
			(xy 275.340568 -404.217106) (xy 275.39999 -404.224929) (xy 275.457883 -404.240442) (xy 275.513256 -404.263378)
			(xy 275.565162 -404.293345) (xy 275.612712 -404.329832) (xy 275.655092 -404.372212) (xy 275.691579 -404.419762)
			(xy 275.721546 -404.471668) (xy 275.744482 -404.527041) (xy 275.759995 -404.584934) (xy 275.767818 -404.644356)
			(xy 275.768308 -404.674324) (xy 275.767818 -404.704292) (xy 275.759995 -404.763714) (xy 275.744482 -404.821607)
			(xy 275.721546 -404.87698) (xy 275.691579 -404.928886) (xy 275.655092 -404.976436) (xy 275.612712 -405.018816)
			(xy 275.565162 -405.055303) (xy 275.513256 -405.08527) (xy 275.457883 -405.108206) (xy 275.39999 -405.123719)
			(xy 275.340568 -405.131542) (xy 275.280632 -405.131542) (xy 275.22121 -405.123719) (xy 275.163317 -405.108206)
			(xy 275.107944 -405.08527) (xy 275.056038 -405.055303) (xy 275.008488 -405.018816) (xy 274.966108 -404.976436)
			(xy 274.929621 -404.928886) (xy 274.899654 -404.87698) (xy 274.876718 -404.821607) (xy 274.861205 -404.763714)
			(xy 274.853382 -404.704292) (xy 239.868964 -404.704292) (xy 239.868964 -406.551892) (xy 274.490686 -406.551892)
			(xy 274.494757 -406.49627) (xy 274.506883 -406.441833) (xy 274.526806 -406.389742) (xy 274.554102 -406.341107)
			(xy 274.588188 -406.296964) (xy 274.628337 -406.258255) (xy 274.673695 -406.225804) (xy 274.723295 -406.200303)
			(xy 274.776079 -406.182296) (xy 274.830922 -406.172166) (xy 274.886656 -406.170129) (xy 274.942093 -406.176229)
			(xy 274.944981 -406.176984) (xy 275.616398 -406.176984) (xy 275.616398 -406.117048) (xy 275.624221 -406.057626)
			(xy 275.639734 -405.999733) (xy 275.66267 -405.94436) (xy 275.692637 -405.892454) (xy 275.729124 -405.844904)
			(xy 275.771504 -405.802524) (xy 275.819054 -405.766037) (xy 275.87096 -405.73607) (xy 275.926333 -405.713134)
			(xy 275.984226 -405.697621) (xy 276.043648 -405.689798) (xy 276.103584 -405.689798) (xy 276.163006 -405.697621)
			(xy 276.220899 -405.713134) (xy 276.276272 -405.73607) (xy 276.328178 -405.766037) (xy 276.375728 -405.802524)
			(xy 276.418108 -405.844904) (xy 276.454595 -405.892454) (xy 276.484562 -405.94436) (xy 276.507498 -405.999733)
			(xy 276.523011 -406.057626) (xy 276.530834 -406.117048) (xy 276.531324 -406.147016) (xy 276.530834 -406.176984)
			(xy 276.529759 -406.185151) (xy 276.708593 -406.185151) (xy 276.708593 -406.130649) (xy 276.71635 -406.076702)
			(xy 276.731705 -406.024408) (xy 276.754347 -405.974832) (xy 276.783813 -405.928983) (xy 276.819505 -405.887794)
			(xy 276.860695 -405.852104) (xy 276.906546 -405.822639) (xy 276.956123 -405.8) (xy 277.008418 -405.784646)
			(xy 277.062365 -405.776892) (xy 277.089616 -405.77643) (xy 277.118199 -405.776937) (xy 277.174724 -405.785474)
			(xy 277.229342 -405.802354) (xy 277.280827 -405.827199) (xy 277.328026 -405.859452) (xy 277.36988 -405.89839)
			(xy 277.388066 -405.920448) (xy 277.394416 -405.928322) (xy 277.412196 -405.938228) (xy 277.504144 -405.948134)
			(xy 277.523702 -405.942546) (xy 277.531576 -405.936196) (xy 277.556126 -405.91698) (xy 277.609428 -405.884642)
			(xy 277.666631 -405.859853) (xy 277.726673 -405.843071) (xy 277.78844 -405.83461) (xy 277.819612 -405.834088)
			(xy 277.849579 -405.834587) (xy 277.909 -405.842411) (xy 277.966891 -405.857924) (xy 278.022262 -405.880861)
			(xy 278.074166 -405.910829) (xy 278.121714 -405.947315) (xy 278.164093 -405.989695) (xy 278.200578 -406.037244)
			(xy 278.230544 -406.089149) (xy 278.253479 -406.14452) (xy 278.268991 -406.202412) (xy 278.276814 -406.261833)
			(xy 278.276814 -406.321767) (xy 278.268991 -406.381188) (xy 278.253479 -406.43908) (xy 278.230544 -406.494451)
			(xy 278.200578 -406.546356) (xy 278.164093 -406.593905) (xy 278.121714 -406.636285) (xy 278.074166 -406.672771)
			(xy 278.022262 -406.702739) (xy 277.966891 -406.725676) (xy 277.909 -406.741189) (xy 277.849579 -406.749013)
			(xy 277.819612 -406.749504) (xy 277.789756 -406.749023) (xy 277.730553 -406.741248) (xy 277.672864 -406.725842)
			(xy 277.617666 -406.703067) (xy 277.565899 -406.673309) (xy 277.518439 -406.637073) (xy 277.476094 -406.594974)
			(xy 277.439581 -406.547728) (xy 277.424134 -406.522174) (xy 277.419054 -406.513284) (xy 277.402798 -406.501092)
			(xy 277.313136 -406.477978) (xy 277.293324 -406.480772) (xy 277.284434 -406.485852) (xy 277.262241 -406.498563)
			(xy 277.21518 -406.518585) (xy 277.165868 -406.53215) (xy 277.115187 -406.539016) (xy 277.089616 -406.539446)
			(xy 277.062365 -406.538908) (xy 277.008418 -406.531154) (xy 276.956123 -406.5158) (xy 276.906546 -406.493161)
			(xy 276.860695 -406.463696) (xy 276.819505 -406.428006) (xy 276.783813 -406.386817) (xy 276.754347 -406.340968)
			(xy 276.731705 -406.291392) (xy 276.71635 -406.239098) (xy 276.708593 -406.185151) (xy 276.529759 -406.185151)
			(xy 276.523011 -406.236406) (xy 276.507498 -406.294299) (xy 276.484562 -406.349672) (xy 276.454595 -406.401578)
			(xy 276.418108 -406.449128) (xy 276.375728 -406.491508) (xy 276.328178 -406.527995) (xy 276.276272 -406.557962)
			(xy 276.220899 -406.580898) (xy 276.163006 -406.596411) (xy 276.103584 -406.604234) (xy 276.043648 -406.604234)
			(xy 275.984226 -406.596411) (xy 275.926333 -406.580898) (xy 275.87096 -406.557962) (xy 275.819054 -406.527995)
			(xy 275.771504 -406.491508) (xy 275.729124 -406.449128) (xy 275.692637 -406.401578) (xy 275.66267 -406.349672)
			(xy 275.639734 -406.294299) (xy 275.624221 -406.236406) (xy 275.616398 -406.176984) (xy 274.944981 -406.176984)
			(xy 274.99605 -406.190335) (xy 275.047379 -406.212147) (xy 275.094985 -406.241201) (xy 275.137853 -406.276876)
			(xy 275.17507 -406.318413) (xy 275.205843 -406.364926) (xy 275.229515 -406.415423) (xy 275.245583 -406.46883)
			(xy 275.253703 -406.524006) (xy 275.254212 -406.551892) (xy 275.253703 -406.579778) (xy 275.245583 -406.634954)
			(xy 275.229515 -406.688361) (xy 275.205843 -406.738858) (xy 275.17507 -406.785371) (xy 275.137853 -406.826908)
			(xy 275.094985 -406.862583) (xy 275.047379 -406.891637) (xy 274.99605 -406.913449) (xy 274.942093 -406.927555)
			(xy 274.886656 -406.933655) (xy 274.830922 -406.931618) (xy 274.776079 -406.921488) (xy 274.723295 -406.903481)
			(xy 274.673695 -406.87798) (xy 274.628337 -406.845529) (xy 274.588188 -406.80682) (xy 274.554102 -406.762677)
			(xy 274.526806 -406.714042) (xy 274.506883 -406.661951) (xy 274.494757 -406.607514) (xy 274.490686 -406.551892)
			(xy 239.868964 -406.551892) (xy 239.868964 -406.97302) (xy 278.664398 -406.97302) (xy 278.664398 -406.913084)
			(xy 278.672221 -406.853662) (xy 278.687734 -406.795769) (xy 278.71067 -406.740396) (xy 278.740637 -406.68849)
			(xy 278.777124 -406.64094) (xy 278.819504 -406.59856) (xy 278.867054 -406.562073) (xy 278.91896 -406.532106)
			(xy 278.974333 -406.50917) (xy 279.032226 -406.493657) (xy 279.091648 -406.485834) (xy 279.151584 -406.485834)
			(xy 279.211006 -406.493657) (xy 279.268899 -406.50917) (xy 279.324272 -406.532106) (xy 279.376178 -406.562073)
			(xy 279.423728 -406.59856) (xy 279.466108 -406.64094) (xy 279.502595 -406.68849) (xy 279.532562 -406.740396)
			(xy 279.555498 -406.795769) (xy 279.571011 -406.853662) (xy 279.578834 -406.913084) (xy 279.579324 -406.943052)
			(xy 279.578834 -406.97302) (xy 279.571011 -407.032442) (xy 279.555498 -407.090335) (xy 279.532562 -407.145708)
			(xy 279.502595 -407.197614) (xy 279.466108 -407.245164) (xy 279.423728 -407.287544) (xy 279.388067 -407.314908)
			(xy 280.953462 -407.314908) (xy 280.957533 -407.259286) (xy 280.969659 -407.204849) (xy 280.989582 -407.152758)
			(xy 281.016878 -407.104123) (xy 281.050964 -407.05998) (xy 281.091113 -407.021271) (xy 281.136471 -406.98882)
			(xy 281.186071 -406.963319) (xy 281.238855 -406.945312) (xy 281.293698 -406.935182) (xy 281.349432 -406.933145)
			(xy 281.404869 -406.939245) (xy 281.458826 -406.953351) (xy 281.510155 -406.975163) (xy 281.557761 -407.004217)
			(xy 281.600629 -407.039892) (xy 281.637846 -407.081429) (xy 281.668619 -407.127942) (xy 281.692291 -407.178439)
			(xy 281.708359 -407.231846) (xy 281.716479 -407.287022) (xy 281.716988 -407.314908) (xy 281.716479 -407.342794)
			(xy 281.708359 -407.39797) (xy 281.692291 -407.451377) (xy 281.668619 -407.501874) (xy 281.637846 -407.548387)
			(xy 281.600629 -407.589924) (xy 281.557761 -407.625599) (xy 281.510155 -407.654653) (xy 281.458826 -407.676465)
			(xy 281.404869 -407.690571) (xy 281.349432 -407.696671) (xy 281.293698 -407.694634) (xy 281.238855 -407.684504)
			(xy 281.186071 -407.666497) (xy 281.136471 -407.640996) (xy 281.091113 -407.608545) (xy 281.050964 -407.569836)
			(xy 281.016878 -407.525693) (xy 280.989582 -407.477058) (xy 280.969659 -407.424967) (xy 280.957533 -407.37053)
			(xy 280.953462 -407.314908) (xy 279.388067 -407.314908) (xy 279.376178 -407.324031) (xy 279.324272 -407.353998)
			(xy 279.268899 -407.376934) (xy 279.211006 -407.392447) (xy 279.151584 -407.40027) (xy 279.091648 -407.40027)
			(xy 279.032226 -407.392447) (xy 278.974333 -407.376934) (xy 278.91896 -407.353998) (xy 278.867054 -407.324031)
			(xy 278.819504 -407.287544) (xy 278.777124 -407.245164) (xy 278.740637 -407.197614) (xy 278.71067 -407.145708)
			(xy 278.687734 -407.090335) (xy 278.672221 -407.032442) (xy 278.664398 -406.97302) (xy 239.868964 -406.97302)
			(xy 239.868964 -408.195014) (xy 275.900116 -408.195014) (xy 275.900116 -408.135078) (xy 275.907939 -408.075656)
			(xy 275.923452 -408.017763) (xy 275.946388 -407.96239) (xy 275.976355 -407.910484) (xy 276.012842 -407.862934)
			(xy 276.055222 -407.820554) (xy 276.102772 -407.784067) (xy 276.154678 -407.7541) (xy 276.210051 -407.731164)
			(xy 276.267944 -407.715651) (xy 276.327366 -407.707828) (xy 276.387302 -407.707828) (xy 276.446724 -407.715651)
			(xy 276.504617 -407.731164) (xy 276.55999 -407.7541) (xy 276.611896 -407.784067) (xy 276.659446 -407.820554)
			(xy 276.701826 -407.862934) (xy 276.738313 -407.910484) (xy 276.76828 -407.96239) (xy 276.791216 -408.017763)
			(xy 276.806729 -408.075656) (xy 276.814552 -408.135078) (xy 276.815042 -408.165046) (xy 276.814552 -408.195014)
			(xy 276.806729 -408.254436) (xy 276.791216 -408.312329) (xy 276.76828 -408.367702) (xy 276.738313 -408.419608)
			(xy 276.701826 -408.467158) (xy 276.659446 -408.509538) (xy 276.611896 -408.546025) (xy 276.55999 -408.575992)
			(xy 276.504617 -408.598928) (xy 276.446724 -408.614441) (xy 276.387302 -408.622264) (xy 276.327366 -408.622264)
			(xy 276.267944 -408.614441) (xy 276.210051 -408.598928) (xy 276.154678 -408.575992) (xy 276.102772 -408.546025)
			(xy 276.055222 -408.509538) (xy 276.012842 -408.467158) (xy 275.976355 -408.419608) (xy 275.946388 -408.367702)
			(xy 275.923452 -408.312329) (xy 275.907939 -408.254436) (xy 275.900116 -408.195014) (xy 239.868964 -408.195014)
			(xy 239.868964 -410.166054) (xy 279.437066 -410.166054) (xy 279.437066 -410.106118) (xy 279.444889 -410.046696)
			(xy 279.460402 -409.988803) (xy 279.483338 -409.93343) (xy 279.513305 -409.881524) (xy 279.549792 -409.833974)
			(xy 279.592172 -409.791594) (xy 279.639722 -409.755107) (xy 279.691628 -409.72514) (xy 279.747001 -409.702204)
			(xy 279.804894 -409.686691) (xy 279.864316 -409.678868) (xy 279.924252 -409.678868) (xy 279.983674 -409.686691)
			(xy 280.041567 -409.702204) (xy 280.09694 -409.72514) (xy 280.148846 -409.755107) (xy 280.196396 -409.791594)
			(xy 280.238776 -409.833974) (xy 280.275263 -409.881524) (xy 280.30523 -409.93343) (xy 280.328166 -409.988803)
			(xy 280.343679 -410.046696) (xy 280.351502 -410.106118) (xy 280.351992 -410.136086) (xy 280.351502 -410.166054)
			(xy 280.343679 -410.225476) (xy 280.328166 -410.283369) (xy 280.30523 -410.338742) (xy 280.275263 -410.390648)
			(xy 280.238776 -410.438198) (xy 280.196396 -410.480578) (xy 280.148846 -410.517065) (xy 280.09694 -410.547032)
			(xy 280.041567 -410.569968) (xy 279.983674 -410.585481) (xy 279.924252 -410.593304) (xy 279.864316 -410.593304)
			(xy 279.804894 -410.585481) (xy 279.747001 -410.569968) (xy 279.691628 -410.547032) (xy 279.639722 -410.517065)
			(xy 279.592172 -410.480578) (xy 279.549792 -410.438198) (xy 279.513305 -410.390648) (xy 279.483338 -410.338742)
			(xy 279.460402 -410.283369) (xy 279.444889 -410.225476) (xy 279.437066 -410.166054) (xy 239.868964 -410.166054)
			(xy 239.868964 -413.69361) (xy 239.869391 -413.703678) (xy 239.877115 -413.722274) (xy 239.88395 -413.729678)
			(xy 239.927384 -413.773112) (xy 275.328378 -413.773112) (xy 275.332449 -413.71749) (xy 275.344575 -413.663053)
			(xy 275.364498 -413.610962) (xy 275.391794 -413.562327) (xy 275.42588 -413.518184) (xy 275.466029 -413.479475)
			(xy 275.511387 -413.447024) (xy 275.560987 -413.421523) (xy 275.613771 -413.403516) (xy 275.668614 -413.393386)
			(xy 275.724348 -413.391349) (xy 275.779785 -413.397449) (xy 275.833742 -413.411555) (xy 275.885071 -413.433367)
			(xy 275.932677 -413.462421) (xy 275.975545 -413.498096) (xy 276.012762 -413.539633) (xy 276.043535 -413.586146)
			(xy 276.058189 -413.617406) (xy 276.426404 -413.617406) (xy 276.426404 -413.55747) (xy 276.434227 -413.498048)
			(xy 276.44974 -413.440155) (xy 276.472676 -413.384782) (xy 276.502643 -413.332876) (xy 276.53913 -413.285326)
			(xy 276.58151 -413.242946) (xy 276.62906 -413.206459) (xy 276.680966 -413.176492) (xy 276.736339 -413.153556)
			(xy 276.794232 -413.138043) (xy 276.853654 -413.13022) (xy 276.91359 -413.13022) (xy 276.973012 -413.138043)
			(xy 277.030905 -413.153556) (xy 277.086278 -413.176492) (xy 277.138184 -413.206459) (xy 277.185734 -413.242946)
			(xy 277.228114 -413.285326) (xy 277.264601 -413.332876) (xy 277.294568 -413.384782) (xy 277.317504 -413.440155)
			(xy 277.333017 -413.498048) (xy 277.335622 -413.517838) (xy 278.165796 -413.517838) (xy 278.165796 -413.457902)
			(xy 278.173619 -413.39848) (xy 278.189132 -413.340587) (xy 278.212068 -413.285214) (xy 278.242035 -413.233308)
			(xy 278.278522 -413.185758) (xy 278.320902 -413.143378) (xy 278.368452 -413.106891) (xy 278.420358 -413.076924)
			(xy 278.475731 -413.053988) (xy 278.533624 -413.038475) (xy 278.593046 -413.030652) (xy 278.652982 -413.030652)
			(xy 278.712404 -413.038475) (xy 278.770297 -413.053988) (xy 278.82567 -413.076924) (xy 278.877576 -413.106891)
			(xy 278.925126 -413.143378) (xy 278.967506 -413.185758) (xy 279.003993 -413.233308) (xy 279.03396 -413.285214)
			(xy 279.056896 -413.340587) (xy 279.072409 -413.39848) (xy 279.080232 -413.457902) (xy 279.080722 -413.48787)
			(xy 279.080232 -413.517838) (xy 279.072409 -413.57726) (xy 279.056896 -413.635153) (xy 279.03396 -413.690526)
			(xy 279.003993 -413.742432) (xy 278.967506 -413.789982) (xy 278.925126 -413.832362) (xy 278.877576 -413.868849)
			(xy 278.82567 -413.898816) (xy 278.798022 -413.910268) (xy 280.333178 -413.910268) (xy 280.333178 -413.850332)
			(xy 280.341001 -413.79091) (xy 280.356514 -413.733017) (xy 280.37945 -413.677644) (xy 280.409417 -413.625738)
			(xy 280.445904 -413.578188) (xy 280.488284 -413.535808) (xy 280.535834 -413.499321) (xy 280.58774 -413.469354)
			(xy 280.643113 -413.446418) (xy 280.701006 -413.430905) (xy 280.760428 -413.423082) (xy 280.820364 -413.423082)
			(xy 280.879786 -413.430905) (xy 280.937679 -413.446418) (xy 280.993052 -413.469354) (xy 281.044958 -413.499321)
			(xy 281.092508 -413.535808) (xy 281.134888 -413.578188) (xy 281.171375 -413.625738) (xy 281.201342 -413.677644)
			(xy 281.224278 -413.733017) (xy 281.239791 -413.79091) (xy 281.247614 -413.850332) (xy 281.248104 -413.8803)
			(xy 281.247614 -413.910268) (xy 281.239791 -413.96969) (xy 281.224278 -414.027583) (xy 281.201342 -414.082956)
			(xy 281.171375 -414.134862) (xy 281.134888 -414.182412) (xy 281.092508 -414.224792) (xy 281.044958 -414.261279)
			(xy 280.993052 -414.291246) (xy 280.937679 -414.314182) (xy 280.879786 -414.329695) (xy 280.820364 -414.337518)
			(xy 280.760428 -414.337518) (xy 280.701006 -414.329695) (xy 280.643113 -414.314182) (xy 280.58774 -414.291246)
			(xy 280.535834 -414.261279) (xy 280.488284 -414.224792) (xy 280.445904 -414.182412) (xy 280.409417 -414.134862)
			(xy 280.37945 -414.082956) (xy 280.356514 -414.027583) (xy 280.341001 -413.96969) (xy 280.333178 -413.910268)
			(xy 278.798022 -413.910268) (xy 278.770297 -413.921752) (xy 278.712404 -413.937265) (xy 278.652982 -413.945088)
			(xy 278.593046 -413.945088) (xy 278.533624 -413.937265) (xy 278.475731 -413.921752) (xy 278.420358 -413.898816)
			(xy 278.368452 -413.868849) (xy 278.320902 -413.832362) (xy 278.278522 -413.789982) (xy 278.242035 -413.742432)
			(xy 278.212068 -413.690526) (xy 278.189132 -413.635153) (xy 278.173619 -413.57726) (xy 278.165796 -413.517838)
			(xy 277.335622 -413.517838) (xy 277.34084 -413.55747) (xy 277.34133 -413.587438) (xy 277.34084 -413.617406)
			(xy 277.333017 -413.676828) (xy 277.317504 -413.734721) (xy 277.294568 -413.790094) (xy 277.264601 -413.842)
			(xy 277.228114 -413.88955) (xy 277.185734 -413.93193) (xy 277.138184 -413.968417) (xy 277.086278 -413.998384)
			(xy 277.030905 -414.02132) (xy 276.973012 -414.036833) (xy 276.91359 -414.044656) (xy 276.853654 -414.044656)
			(xy 276.794232 -414.036833) (xy 276.736339 -414.02132) (xy 276.680966 -413.998384) (xy 276.62906 -413.968417)
			(xy 276.58151 -413.93193) (xy 276.53913 -413.88955) (xy 276.502643 -413.842) (xy 276.472676 -413.790094)
			(xy 276.44974 -413.734721) (xy 276.434227 -413.676828) (xy 276.426404 -413.617406) (xy 276.058189 -413.617406)
			(xy 276.067207 -413.636643) (xy 276.083275 -413.69005) (xy 276.091395 -413.745226) (xy 276.091904 -413.773112)
			(xy 276.091395 -413.800998) (xy 276.083275 -413.856174) (xy 276.067207 -413.909581) (xy 276.043535 -413.960078)
			(xy 276.012762 -414.006591) (xy 275.975545 -414.048128) (xy 275.932677 -414.083803) (xy 275.885071 -414.112857)
			(xy 275.833742 -414.134669) (xy 275.779785 -414.148775) (xy 275.724348 -414.154875) (xy 275.668614 -414.152838)
			(xy 275.613771 -414.142708) (xy 275.560987 -414.124701) (xy 275.511387 -414.0992) (xy 275.466029 -414.066749)
			(xy 275.42588 -414.02804) (xy 275.391794 -413.983897) (xy 275.364498 -413.935262) (xy 275.344575 -413.883171)
			(xy 275.332449 -413.828734) (xy 275.328378 -413.773112) (xy 239.927384 -413.773112) (xy 240.789714 -414.635442)
			(xy 240.79711 -414.642293) (xy 240.815709 -414.650031) (xy 240.825782 -414.650428) (xy 263.550146 -414.650428)
			(xy 263.560213 -414.649997) (xy 263.578808 -414.642274) (xy 263.586214 -414.635442) (xy 272.808954 -414.635442)
			(xy 272.819019 -414.635876) (xy 272.837605 -414.643609) (xy 272.845022 -414.650428) (xy 274.330664 -416.13607)
			(xy 276.269178 -416.13607) (xy 276.269178 -416.076134) (xy 276.277001 -416.016712) (xy 276.292514 -415.958819)
			(xy 276.31545 -415.903446) (xy 276.345417 -415.85154) (xy 276.381904 -415.80399) (xy 276.424284 -415.76161)
			(xy 276.471834 -415.725123) (xy 276.52374 -415.695156) (xy 276.579113 -415.67222) (xy 276.637006 -415.656707)
			(xy 276.696428 -415.648884) (xy 276.756364 -415.648884) (xy 276.815786 -415.656707) (xy 276.873679 -415.67222)
			(xy 276.929052 -415.695156) (xy 276.980958 -415.725123) (xy 277.028508 -415.76161) (xy 277.070888 -415.80399)
			(xy 277.107375 -415.85154) (xy 277.137342 -415.903446) (xy 277.160278 -415.958819) (xy 277.175791 -416.016712)
			(xy 277.183614 -416.076134) (xy 277.184104 -416.106102) (xy 277.360378 -416.106102) (xy 277.364449 -416.05048)
			(xy 277.376575 -415.996043) (xy 277.396498 -415.943952) (xy 277.423794 -415.895317) (xy 277.45788 -415.851174)
			(xy 277.498029 -415.812465) (xy 277.543387 -415.780014) (xy 277.592987 -415.754513) (xy 277.645771 -415.736506)
			(xy 277.700614 -415.726376) (xy 277.756348 -415.724339) (xy 277.811785 -415.730439) (xy 277.865742 -415.744545)
			(xy 277.917071 -415.766357) (xy 277.964677 -415.795411) (xy 278.007545 -415.831086) (xy 278.044762 -415.872623)
			(xy 278.075535 -415.919136) (xy 278.099207 -415.969633) (xy 278.114129 -416.01923) (xy 278.301178 -416.01923)
			(xy 278.301178 -415.959294) (xy 278.309001 -415.899872) (xy 278.324514 -415.841979) (xy 278.34745 -415.786606)
			(xy 278.377417 -415.7347) (xy 278.413904 -415.68715) (xy 278.456284 -415.64477) (xy 278.503834 -415.608283)
			(xy 278.55574 -415.578316) (xy 278.611113 -415.55538) (xy 278.669006 -415.539867) (xy 278.728428 -415.532044)
			(xy 278.788364 -415.532044) (xy 278.847786 -415.539867) (xy 278.905679 -415.55538) (xy 278.961052 -415.578316)
			(xy 279.012958 -415.608283) (xy 279.060508 -415.64477) (xy 279.102888 -415.68715) (xy 279.139375 -415.7347)
			(xy 279.169342 -415.786606) (xy 279.192278 -415.841979) (xy 279.207791 -415.899872) (xy 279.215614 -415.959294)
			(xy 279.216104 -415.989262) (xy 279.215826 -416.00628) (xy 279.392378 -416.00628) (xy 279.396449 -415.950658)
			(xy 279.408575 -415.896221) (xy 279.428498 -415.84413) (xy 279.455794 -415.795495) (xy 279.48988 -415.751352)
			(xy 279.530029 -415.712643) (xy 279.575387 -415.680192) (xy 279.624987 -415.654691) (xy 279.677771 -415.636684)
			(xy 279.732614 -415.626554) (xy 279.788348 -415.624517) (xy 279.843785 -415.630617) (xy 279.897742 -415.644723)
			(xy 279.949071 -415.666535) (xy 279.996677 -415.695589) (xy 280.039545 -415.731264) (xy 280.076762 -415.772801)
			(xy 280.107535 -415.819314) (xy 280.131207 -415.869811) (xy 280.147275 -415.923218) (xy 280.155395 -415.978394)
			(xy 280.155904 -416.00628) (xy 280.155395 -416.034166) (xy 280.147275 -416.089342) (xy 280.131207 -416.142749)
			(xy 280.108976 -416.190172) (xy 280.333178 -416.190172) (xy 280.333178 -416.130236) (xy 280.341001 -416.070814)
			(xy 280.356514 -416.012921) (xy 280.37945 -415.957548) (xy 280.409417 -415.905642) (xy 280.445904 -415.858092)
			(xy 280.488284 -415.815712) (xy 280.535834 -415.779225) (xy 280.58774 -415.749258) (xy 280.643113 -415.726322)
			(xy 280.701006 -415.710809) (xy 280.760428 -415.702986) (xy 280.820364 -415.702986) (xy 280.879786 -415.710809)
			(xy 280.937679 -415.726322) (xy 280.993052 -415.749258) (xy 281.044958 -415.779225) (xy 281.092508 -415.815712)
			(xy 281.134888 -415.858092) (xy 281.171375 -415.905642) (xy 281.201342 -415.957548) (xy 281.224278 -416.012921)
			(xy 281.239791 -416.070814) (xy 281.247614 -416.130236) (xy 281.248104 -416.160204) (xy 281.247614 -416.190172)
			(xy 281.239791 -416.249594) (xy 281.224278 -416.307487) (xy 281.201342 -416.36286) (xy 281.171375 -416.414766)
			(xy 281.134888 -416.462316) (xy 281.092508 -416.504696) (xy 281.044958 -416.541183) (xy 280.993052 -416.57115)
			(xy 280.937679 -416.594086) (xy 280.879786 -416.609599) (xy 280.820364 -416.617422) (xy 280.760428 -416.617422)
			(xy 280.701006 -416.609599) (xy 280.643113 -416.594086) (xy 280.58774 -416.57115) (xy 280.535834 -416.541183)
			(xy 280.488284 -416.504696) (xy 280.445904 -416.462316) (xy 280.409417 -416.414766) (xy 280.37945 -416.36286)
			(xy 280.356514 -416.307487) (xy 280.341001 -416.249594) (xy 280.333178 -416.190172) (xy 280.108976 -416.190172)
			(xy 280.107535 -416.193246) (xy 280.076762 -416.239759) (xy 280.039545 -416.281296) (xy 279.996677 -416.316971)
			(xy 279.949071 -416.346025) (xy 279.897742 -416.367837) (xy 279.843785 -416.381943) (xy 279.788348 -416.388043)
			(xy 279.732614 -416.386006) (xy 279.677771 -416.375876) (xy 279.624987 -416.357869) (xy 279.575387 -416.332368)
			(xy 279.530029 -416.299917) (xy 279.48988 -416.261208) (xy 279.455794 -416.217065) (xy 279.428498 -416.16843)
			(xy 279.408575 -416.116339) (xy 279.396449 -416.061902) (xy 279.392378 -416.00628) (xy 279.215826 -416.00628)
			(xy 279.215614 -416.01923) (xy 279.207791 -416.078652) (xy 279.192278 -416.136545) (xy 279.169342 -416.191918)
			(xy 279.139375 -416.243824) (xy 279.102888 -416.291374) (xy 279.060508 -416.333754) (xy 279.012958 -416.370241)
			(xy 278.961052 -416.400208) (xy 278.905679 -416.423144) (xy 278.847786 -416.438657) (xy 278.788364 -416.44648)
			(xy 278.728428 -416.44648) (xy 278.669006 -416.438657) (xy 278.611113 -416.423144) (xy 278.55574 -416.400208)
			(xy 278.503834 -416.370241) (xy 278.456284 -416.333754) (xy 278.413904 -416.291374) (xy 278.377417 -416.243824)
			(xy 278.34745 -416.191918) (xy 278.324514 -416.136545) (xy 278.309001 -416.078652) (xy 278.301178 -416.01923)
			(xy 278.114129 -416.01923) (xy 278.115275 -416.02304) (xy 278.123395 -416.078216) (xy 278.123904 -416.106102)
			(xy 278.123395 -416.133988) (xy 278.115275 -416.189164) (xy 278.099207 -416.242571) (xy 278.075535 -416.293068)
			(xy 278.044762 -416.339581) (xy 278.007545 -416.381118) (xy 277.964677 -416.416793) (xy 277.917071 -416.445847)
			(xy 277.865742 -416.467659) (xy 277.811785 -416.481765) (xy 277.756348 -416.487865) (xy 277.700614 -416.485828)
			(xy 277.645771 -416.475698) (xy 277.592987 -416.457691) (xy 277.543387 -416.43219) (xy 277.498029 -416.399739)
			(xy 277.45788 -416.36103) (xy 277.423794 -416.316887) (xy 277.396498 -416.268252) (xy 277.376575 -416.216161)
			(xy 277.364449 -416.161724) (xy 277.360378 -416.106102) (xy 277.184104 -416.106102) (xy 277.183614 -416.13607)
			(xy 277.175791 -416.195492) (xy 277.160278 -416.253385) (xy 277.137342 -416.308758) (xy 277.107375 -416.360664)
			(xy 277.070888 -416.408214) (xy 277.028508 -416.450594) (xy 276.980958 -416.487081) (xy 276.929052 -416.517048)
			(xy 276.873679 -416.539984) (xy 276.815786 -416.555497) (xy 276.756364 -416.56332) (xy 276.696428 -416.56332)
			(xy 276.637006 -416.555497) (xy 276.579113 -416.539984) (xy 276.52374 -416.517048) (xy 276.471834 -416.487081)
			(xy 276.424284 -416.450594) (xy 276.381904 -416.408214) (xy 276.345417 -416.360664) (xy 276.31545 -416.308758)
			(xy 276.292514 -416.253385) (xy 276.277001 -416.195492) (xy 276.269178 -416.13607) (xy 274.330664 -416.13607)
			(xy 274.940014 -416.74542) (xy 274.947409 -416.752273) (xy 274.966008 -416.760015) (xy 274.976082 -416.760406)
		)
		(stroke
			(width 0)
			(type solid)
		)
		(fill yes)
		(layer "B.Cu")
		(net "GND")
	)
	(gr_poly
		(pts
			(xy 355.630734 -230.995728) (xy 355.643061 -230.995136) (xy 355.664896 -230.983689) (xy 355.67239 -230.973884)
			(xy 355.727254 -230.895398) (xy 355.730302 -230.87076) (xy 355.725984 -230.859076) (xy 355.717024 -230.833625)
			(xy 355.704458 -230.78115) (xy 355.698162 -230.72756) (xy 355.69779 -230.70058) (xy 355.69828 -230.670612)
			(xy 355.706103 -230.61119) (xy 355.721616 -230.553297) (xy 355.744552 -230.497924) (xy 355.774519 -230.446018)
			(xy 355.811006 -230.398468) (xy 355.853386 -230.356088) (xy 355.900936 -230.319601) (xy 355.952842 -230.289634)
			(xy 356.008215 -230.266698) (xy 356.066108 -230.251185) (xy 356.12553 -230.243362) (xy 356.185466 -230.243362)
			(xy 356.244888 -230.251185) (xy 356.302781 -230.266698) (xy 356.358154 -230.289634) (xy 356.41006 -230.319601)
			(xy 356.45761 -230.356088) (xy 356.49999 -230.398468) (xy 356.536477 -230.446018) (xy 356.566444 -230.497924)
			(xy 356.58938 -230.553297) (xy 356.604893 -230.61119) (xy 356.612716 -230.670612) (xy 356.613206 -230.70058)
			(xy 356.612681 -230.731116) (xy 356.604522 -230.791642) (xy 356.59695 -230.82123) (xy 356.593394 -230.83393)
			(xy 356.59949 -230.859076) (xy 356.675944 -230.942134) (xy 356.700328 -230.950262) (xy 356.713536 -230.947722)
			(xy 356.732737 -230.944467) (xy 356.771532 -230.941035) (xy 356.791006 -230.940864) (xy 356.816872 -230.941224)
			(xy 356.868228 -230.947441) (xy 356.918457 -230.959819) (xy 356.966821 -230.978178) (xy 356.989888 -230.989886)
			(xy 356.995419 -230.992582) (xy 357.00736 -230.995536) (xy 357.01351 -230.995728) (xy 360.606086 -230.995728)
			(xy 360.624882 -230.988108) (xy 360.631994 -230.980742) (xy 360.97337 -230.639366) (xy 360.980214 -230.631967)
			(xy 360.987941 -230.613369) (xy 360.988356 -230.603298) (xy 360.988356 -228.852476) (xy 360.988785 -228.842409)
			(xy 360.996512 -228.823816) (xy 361.003342 -228.816408) (xy 361.671362 -228.148388) (xy 361.678211 -228.140991)
			(xy 361.685947 -228.122392) (xy 361.686348 -228.11232) (xy 361.686348 -216.65565) (xy 361.685914 -216.645585)
			(xy 361.678181 -216.626999) (xy 361.671362 -216.619582) (xy 360.962448 -215.910668) (xy 360.955336 -215.903302)
			(xy 360.93654 -215.895682) (xy 354.618798 -215.895682) (xy 354.608728 -215.896105) (xy 354.590122 -215.903818)
			(xy 354.58273 -215.910668) (xy 354.085398 -216.408) (xy 358.646982 -216.408) (xy 358.651053 -216.352378)
			(xy 358.663179 -216.297941) (xy 358.683102 -216.24585) (xy 358.710398 -216.197215) (xy 358.744484 -216.153072)
			(xy 358.784633 -216.114363) (xy 358.829991 -216.081912) (xy 358.879591 -216.056411) (xy 358.932375 -216.038404)
			(xy 358.987218 -216.028274) (xy 359.042952 -216.026237) (xy 359.098389 -216.032337) (xy 359.152346 -216.046443)
			(xy 359.203675 -216.068255) (xy 359.251281 -216.097309) (xy 359.294149 -216.132984) (xy 359.331366 -216.174521)
			(xy 359.362139 -216.221034) (xy 359.385811 -216.271531) (xy 359.401879 -216.324938) (xy 359.409999 -216.380114)
			(xy 359.410508 -216.408) (xy 359.409999 -216.435886) (xy 359.401879 -216.491062) (xy 359.385811 -216.544469)
			(xy 359.362139 -216.594966) (xy 359.331366 -216.641479) (xy 359.294149 -216.683016) (xy 359.251281 -216.718691)
			(xy 359.203675 -216.747745) (xy 359.152346 -216.769557) (xy 359.098389 -216.783663) (xy 359.042952 -216.789763)
			(xy 358.987218 -216.787726) (xy 358.932375 -216.777596) (xy 358.879591 -216.759589) (xy 358.829991 -216.734088)
			(xy 358.784633 -216.701637) (xy 358.744484 -216.662928) (xy 358.710398 -216.618785) (xy 358.683102 -216.57015)
			(xy 358.663179 -216.518059) (xy 358.651053 -216.463622) (xy 358.646982 -216.408) (xy 354.085398 -216.408)
			(xy 354.0379 -216.455498) (xy 354.030534 -216.46261) (xy 354.022914 -216.481406) (xy 354.022914 -217.424)
			(xy 358.646982 -217.424) (xy 358.651053 -217.368378) (xy 358.663179 -217.313941) (xy 358.683102 -217.26185)
			(xy 358.710398 -217.213215) (xy 358.744484 -217.169072) (xy 358.784633 -217.130363) (xy 358.829991 -217.097912)
			(xy 358.879591 -217.072411) (xy 358.932375 -217.054404) (xy 358.987218 -217.044274) (xy 359.042952 -217.042237)
			(xy 359.098389 -217.048337) (xy 359.152346 -217.062443) (xy 359.203675 -217.084255) (xy 359.251281 -217.113309)
			(xy 359.294149 -217.148984) (xy 359.331366 -217.190521) (xy 359.362139 -217.237034) (xy 359.385811 -217.287531)
			(xy 359.401879 -217.340938) (xy 359.409999 -217.396114) (xy 359.410508 -217.424) (xy 359.409999 -217.451886)
			(xy 359.401879 -217.507062) (xy 359.385811 -217.560469) (xy 359.362139 -217.610966) (xy 359.331366 -217.657479)
			(xy 359.294149 -217.699016) (xy 359.251281 -217.734691) (xy 359.203675 -217.763745) (xy 359.152346 -217.785557)
			(xy 359.098389 -217.799663) (xy 359.042952 -217.805763) (xy 358.987218 -217.803726) (xy 358.932375 -217.793596)
			(xy 358.879591 -217.775589) (xy 358.829991 -217.750088) (xy 358.784633 -217.717637) (xy 358.744484 -217.678928)
			(xy 358.710398 -217.634785) (xy 358.683102 -217.58615) (xy 358.663179 -217.534059) (xy 358.651053 -217.479622)
			(xy 358.646982 -217.424) (xy 354.022914 -217.424) (xy 354.022914 -218.28887) (xy 354.02335 -218.298934)
			(xy 354.031084 -218.317519) (xy 354.0379 -218.324938) (xy 354.062538 -218.349576) (xy 354.069937 -218.356419)
			(xy 354.088536 -218.364144) (xy 354.098606 -218.364562) (xy 354.904802 -218.364562) (xy 354.914871 -218.364987)
			(xy 354.933469 -218.372709) (xy 354.94087 -218.379548) (xy 355.03129 -218.469968) (xy 356.539782 -218.469968)
			(xy 356.539782 -218.410032) (xy 356.547605 -218.35061) (xy 356.563118 -218.292717) (xy 356.586054 -218.237344)
			(xy 356.616021 -218.185438) (xy 356.652508 -218.137888) (xy 356.694888 -218.095508) (xy 356.742438 -218.059021)
			(xy 356.794344 -218.029054) (xy 356.849717 -218.006118) (xy 356.90761 -217.990605) (xy 356.967032 -217.982782)
			(xy 357.026968 -217.982782) (xy 357.08639 -217.990605) (xy 357.144283 -218.006118) (xy 357.199656 -218.029054)
			(xy 357.251562 -218.059021) (xy 357.299112 -218.095508) (xy 357.341492 -218.137888) (xy 357.377979 -218.185438)
			(xy 357.407946 -218.237344) (xy 357.430882 -218.292717) (xy 357.446395 -218.35061) (xy 357.454218 -218.410032)
			(xy 357.454708 -218.44) (xy 358.646982 -218.44) (xy 358.651053 -218.384378) (xy 358.663179 -218.329941)
			(xy 358.683102 -218.27785) (xy 358.710398 -218.229215) (xy 358.744484 -218.185072) (xy 358.784633 -218.146363)
			(xy 358.829991 -218.113912) (xy 358.879591 -218.088411) (xy 358.932375 -218.070404) (xy 358.987218 -218.060274)
			(xy 359.042952 -218.058237) (xy 359.098389 -218.064337) (xy 359.152346 -218.078443) (xy 359.203675 -218.100255)
			(xy 359.251281 -218.129309) (xy 359.294149 -218.164984) (xy 359.331366 -218.206521) (xy 359.362139 -218.253034)
			(xy 359.385811 -218.303531) (xy 359.401879 -218.356938) (xy 359.409999 -218.412114) (xy 359.410508 -218.44)
			(xy 359.409999 -218.467886) (xy 359.401879 -218.523062) (xy 359.385811 -218.576469) (xy 359.362139 -218.626966)
			(xy 359.331366 -218.673479) (xy 359.294149 -218.715016) (xy 359.251281 -218.750691) (xy 359.203675 -218.779745)
			(xy 359.152346 -218.801557) (xy 359.098389 -218.815663) (xy 359.042952 -218.821763) (xy 358.987218 -218.819726)
			(xy 358.932375 -218.809596) (xy 358.879591 -218.791589) (xy 358.829991 -218.766088) (xy 358.784633 -218.733637)
			(xy 358.744484 -218.694928) (xy 358.710398 -218.650785) (xy 358.683102 -218.60215) (xy 358.663179 -218.550059)
			(xy 358.651053 -218.495622) (xy 358.646982 -218.44) (xy 357.454708 -218.44) (xy 357.454218 -218.469968)
			(xy 357.446395 -218.52939) (xy 357.430882 -218.587283) (xy 357.407946 -218.642656) (xy 357.377979 -218.694562)
			(xy 357.341492 -218.742112) (xy 357.299112 -218.784492) (xy 357.251562 -218.820979) (xy 357.199656 -218.850946)
			(xy 357.144283 -218.873882) (xy 357.08639 -218.889395) (xy 357.026968 -218.897218) (xy 356.967032 -218.897218)
			(xy 356.90761 -218.889395) (xy 356.849717 -218.873882) (xy 356.794344 -218.850946) (xy 356.742438 -218.820979)
			(xy 356.694888 -218.784492) (xy 356.652508 -218.742112) (xy 356.616021 -218.694562) (xy 356.586054 -218.642656)
			(xy 356.563118 -218.587283) (xy 356.547605 -218.52939) (xy 356.539782 -218.469968) (xy 355.03129 -218.469968)
			(xy 355.266752 -218.70543) (xy 355.273599 -218.712828) (xy 355.28133 -218.731426) (xy 355.281738 -218.741498)
			(xy 355.281738 -219.02801) (xy 355.283516 -219.034614) (xy 355.291093 -219.065041) (xy 355.299246 -219.127214)
			(xy 355.299772 -219.158566) (xy 355.299259 -219.189919) (xy 355.291109 -219.252094) (xy 355.283516 -219.282518)
			(xy 355.281738 -219.289122) (xy 355.281738 -219.485968) (xy 355.650782 -219.485968) (xy 355.650782 -219.426032)
			(xy 355.658605 -219.36661) (xy 355.674118 -219.308717) (xy 355.697054 -219.253344) (xy 355.727021 -219.201438)
			(xy 355.763508 -219.153888) (xy 355.805888 -219.111508) (xy 355.853438 -219.075021) (xy 355.905344 -219.045054)
			(xy 355.960717 -219.022118) (xy 356.01861 -219.006605) (xy 356.078032 -218.998782) (xy 356.137968 -218.998782)
			(xy 356.19739 -219.006605) (xy 356.255283 -219.022118) (xy 356.310656 -219.045054) (xy 356.362562 -219.075021)
			(xy 356.410112 -219.111508) (xy 356.452492 -219.153888) (xy 356.488979 -219.201438) (xy 356.518946 -219.253344)
			(xy 356.541882 -219.308717) (xy 356.557395 -219.36661) (xy 356.565218 -219.426032) (xy 356.565708 -219.456)
			(xy 358.646982 -219.456) (xy 358.651053 -219.400378) (xy 358.663179 -219.345941) (xy 358.683102 -219.29385)
			(xy 358.710398 -219.245215) (xy 358.744484 -219.201072) (xy 358.784633 -219.162363) (xy 358.829991 -219.129912)
			(xy 358.879591 -219.104411) (xy 358.932375 -219.086404) (xy 358.987218 -219.076274) (xy 359.042952 -219.074237)
			(xy 359.098389 -219.080337) (xy 359.152346 -219.094443) (xy 359.203675 -219.116255) (xy 359.251281 -219.145309)
			(xy 359.294149 -219.180984) (xy 359.331366 -219.222521) (xy 359.362139 -219.269034) (xy 359.385811 -219.319531)
			(xy 359.401879 -219.372938) (xy 359.409999 -219.428114) (xy 359.410508 -219.456) (xy 359.409999 -219.483886)
			(xy 359.401879 -219.539062) (xy 359.385811 -219.592469) (xy 359.362139 -219.642966) (xy 359.331366 -219.689479)
			(xy 359.294149 -219.731016) (xy 359.251281 -219.766691) (xy 359.203675 -219.795745) (xy 359.152346 -219.817557)
			(xy 359.098389 -219.831663) (xy 359.042952 -219.837763) (xy 358.987218 -219.835726) (xy 358.932375 -219.825596)
			(xy 358.879591 -219.807589) (xy 358.829991 -219.782088) (xy 358.784633 -219.749637) (xy 358.744484 -219.710928)
			(xy 358.710398 -219.666785) (xy 358.683102 -219.61815) (xy 358.663179 -219.566059) (xy 358.651053 -219.511622)
			(xy 358.646982 -219.456) (xy 356.565708 -219.456) (xy 356.565218 -219.485968) (xy 356.557395 -219.54539)
			(xy 356.541882 -219.603283) (xy 356.518946 -219.658656) (xy 356.488979 -219.710562) (xy 356.452492 -219.758112)
			(xy 356.410112 -219.800492) (xy 356.362562 -219.836979) (xy 356.310656 -219.866946) (xy 356.255283 -219.889882)
			(xy 356.19739 -219.905395) (xy 356.137968 -219.913218) (xy 356.078032 -219.913218) (xy 356.01861 -219.905395)
			(xy 355.960717 -219.889882) (xy 355.905344 -219.866946) (xy 355.853438 -219.836979) (xy 355.805888 -219.800492)
			(xy 355.763508 -219.758112) (xy 355.727021 -219.710562) (xy 355.697054 -219.658656) (xy 355.674118 -219.603283)
			(xy 355.658605 -219.54539) (xy 355.650782 -219.485968) (xy 355.281738 -219.485968) (xy 355.281738 -220.501968)
			(xy 356.539782 -220.501968) (xy 356.539782 -220.442032) (xy 356.547605 -220.38261) (xy 356.563118 -220.324717)
			(xy 356.586054 -220.269344) (xy 356.616021 -220.217438) (xy 356.652508 -220.169888) (xy 356.694888 -220.127508)
			(xy 356.742438 -220.091021) (xy 356.794344 -220.061054) (xy 356.849717 -220.038118) (xy 356.90761 -220.022605)
			(xy 356.967032 -220.014782) (xy 357.026968 -220.014782) (xy 357.08639 -220.022605) (xy 357.144283 -220.038118)
			(xy 357.199656 -220.061054) (xy 357.251562 -220.091021) (xy 357.299112 -220.127508) (xy 357.341492 -220.169888)
			(xy 357.377979 -220.217438) (xy 357.407946 -220.269344) (xy 357.430882 -220.324717) (xy 357.446395 -220.38261)
			(xy 357.454218 -220.442032) (xy 357.454708 -220.472) (xy 358.646982 -220.472) (xy 358.651053 -220.416378)
			(xy 358.663179 -220.361941) (xy 358.683102 -220.30985) (xy 358.710398 -220.261215) (xy 358.744484 -220.217072)
			(xy 358.784633 -220.178363) (xy 358.829991 -220.145912) (xy 358.879591 -220.120411) (xy 358.932375 -220.102404)
			(xy 358.987218 -220.092274) (xy 359.042952 -220.090237) (xy 359.098389 -220.096337) (xy 359.152346 -220.110443)
			(xy 359.203675 -220.132255) (xy 359.251281 -220.161309) (xy 359.294149 -220.196984) (xy 359.331366 -220.238521)
			(xy 359.362139 -220.285034) (xy 359.385811 -220.335531) (xy 359.401879 -220.388938) (xy 359.409999 -220.444114)
			(xy 359.410508 -220.472) (xy 359.409999 -220.499886) (xy 359.401879 -220.555062) (xy 359.385811 -220.608469)
			(xy 359.362139 -220.658966) (xy 359.331366 -220.705479) (xy 359.294149 -220.747016) (xy 359.251281 -220.782691)
			(xy 359.203675 -220.811745) (xy 359.152346 -220.833557) (xy 359.098389 -220.847663) (xy 359.042952 -220.853763)
			(xy 358.987218 -220.851726) (xy 358.932375 -220.841596) (xy 358.879591 -220.823589) (xy 358.829991 -220.798088)
			(xy 358.784633 -220.765637) (xy 358.744484 -220.726928) (xy 358.710398 -220.682785) (xy 358.683102 -220.63415)
			(xy 358.663179 -220.582059) (xy 358.651053 -220.527622) (xy 358.646982 -220.472) (xy 357.454708 -220.472)
			(xy 357.454218 -220.501968) (xy 357.446395 -220.56139) (xy 357.430882 -220.619283) (xy 357.407946 -220.674656)
			(xy 357.377979 -220.726562) (xy 357.341492 -220.774112) (xy 357.299112 -220.816492) (xy 357.251562 -220.852979)
			(xy 357.199656 -220.882946) (xy 357.144283 -220.905882) (xy 357.08639 -220.921395) (xy 357.026968 -220.929218)
			(xy 356.967032 -220.929218) (xy 356.90761 -220.921395) (xy 356.849717 -220.905882) (xy 356.794344 -220.882946)
			(xy 356.742438 -220.852979) (xy 356.694888 -220.816492) (xy 356.652508 -220.774112) (xy 356.616021 -220.726562)
			(xy 356.586054 -220.674656) (xy 356.563118 -220.619283) (xy 356.547605 -220.56139) (xy 356.539782 -220.501968)
			(xy 355.281738 -220.501968) (xy 355.281738 -221.488) (xy 358.646982 -221.488) (xy 358.651053 -221.432378)
			(xy 358.663179 -221.377941) (xy 358.683102 -221.32585) (xy 358.710398 -221.277215) (xy 358.744484 -221.233072)
			(xy 358.784633 -221.194363) (xy 358.829991 -221.161912) (xy 358.879591 -221.136411) (xy 358.932375 -221.118404)
			(xy 358.987218 -221.108274) (xy 359.042952 -221.106237) (xy 359.098389 -221.112337) (xy 359.152346 -221.126443)
			(xy 359.203675 -221.148255) (xy 359.251281 -221.177309) (xy 359.294149 -221.212984) (xy 359.331366 -221.254521)
			(xy 359.362139 -221.301034) (xy 359.385811 -221.351531) (xy 359.401879 -221.404938) (xy 359.409999 -221.460114)
			(xy 359.410508 -221.488) (xy 359.409999 -221.515886) (xy 359.401879 -221.571062) (xy 359.385811 -221.624469)
			(xy 359.362139 -221.674966) (xy 359.331366 -221.721479) (xy 359.294149 -221.763016) (xy 359.251281 -221.798691)
			(xy 359.203675 -221.827745) (xy 359.152346 -221.849557) (xy 359.098389 -221.863663) (xy 359.042952 -221.869763)
			(xy 358.987218 -221.867726) (xy 358.932375 -221.857596) (xy 358.879591 -221.839589) (xy 358.829991 -221.814088)
			(xy 358.784633 -221.781637) (xy 358.744484 -221.742928) (xy 358.710398 -221.698785) (xy 358.683102 -221.65015)
			(xy 358.663179 -221.598059) (xy 358.651053 -221.543622) (xy 358.646982 -221.488) (xy 355.281738 -221.488)
			(xy 355.281738 -222.533968) (xy 355.650782 -222.533968) (xy 355.650782 -222.474032) (xy 355.658605 -222.41461)
			(xy 355.674118 -222.356717) (xy 355.697054 -222.301344) (xy 355.727021 -222.249438) (xy 355.763508 -222.201888)
			(xy 355.805888 -222.159508) (xy 355.853438 -222.123021) (xy 355.905344 -222.093054) (xy 355.960717 -222.070118)
			(xy 356.01861 -222.054605) (xy 356.078032 -222.046782) (xy 356.137968 -222.046782) (xy 356.19739 -222.054605)
			(xy 356.255283 -222.070118) (xy 356.310656 -222.093054) (xy 356.362562 -222.123021) (xy 356.410112 -222.159508)
			(xy 356.452492 -222.201888) (xy 356.488979 -222.249438) (xy 356.518946 -222.301344) (xy 356.541882 -222.356717)
			(xy 356.557395 -222.41461) (xy 356.565218 -222.474032) (xy 356.565708 -222.504) (xy 356.565218 -222.533968)
			(xy 358.571782 -222.533968) (xy 358.571782 -222.474032) (xy 358.579605 -222.41461) (xy 358.595118 -222.356717)
			(xy 358.618054 -222.301344) (xy 358.648021 -222.249438) (xy 358.684508 -222.201888) (xy 358.726888 -222.159508)
			(xy 358.774438 -222.123021) (xy 358.826344 -222.093054) (xy 358.881717 -222.070118) (xy 358.93961 -222.054605)
			(xy 358.999032 -222.046782) (xy 359.058968 -222.046782) (xy 359.11839 -222.054605) (xy 359.176283 -222.070118)
			(xy 359.231656 -222.093054) (xy 359.283562 -222.123021) (xy 359.331112 -222.159508) (xy 359.373492 -222.201888)
			(xy 359.409979 -222.249438) (xy 359.439946 -222.301344) (xy 359.462882 -222.356717) (xy 359.478395 -222.41461)
			(xy 359.486218 -222.474032) (xy 359.486708 -222.504) (xy 359.486218 -222.533968) (xy 359.478395 -222.59339)
			(xy 359.462882 -222.651283) (xy 359.439946 -222.706656) (xy 359.409979 -222.758562) (xy 359.373492 -222.806112)
			(xy 359.331112 -222.848492) (xy 359.283562 -222.884979) (xy 359.231656 -222.914946) (xy 359.176283 -222.937882)
			(xy 359.11839 -222.953395) (xy 359.058968 -222.961218) (xy 358.999032 -222.961218) (xy 358.93961 -222.953395)
			(xy 358.881717 -222.937882) (xy 358.826344 -222.914946) (xy 358.774438 -222.884979) (xy 358.726888 -222.848492)
			(xy 358.684508 -222.806112) (xy 358.648021 -222.758562) (xy 358.618054 -222.706656) (xy 358.595118 -222.651283)
			(xy 358.579605 -222.59339) (xy 358.571782 -222.533968) (xy 356.565218 -222.533968) (xy 356.557395 -222.59339)
			(xy 356.541882 -222.651283) (xy 356.518946 -222.706656) (xy 356.488979 -222.758562) (xy 356.452492 -222.806112)
			(xy 356.410112 -222.848492) (xy 356.362562 -222.884979) (xy 356.310656 -222.914946) (xy 356.255283 -222.937882)
			(xy 356.19739 -222.953395) (xy 356.137968 -222.961218) (xy 356.078032 -222.961218) (xy 356.01861 -222.953395)
			(xy 355.960717 -222.937882) (xy 355.905344 -222.914946) (xy 355.853438 -222.884979) (xy 355.805888 -222.848492)
			(xy 355.763508 -222.806112) (xy 355.727021 -222.758562) (xy 355.697054 -222.706656) (xy 355.674118 -222.651283)
			(xy 355.658605 -222.59339) (xy 355.650782 -222.533968) (xy 355.281738 -222.533968) (xy 355.281738 -222.668084)
			(xy 355.281298 -222.678146) (xy 355.273555 -222.696722) (xy 355.266752 -222.704152) (xy 354.83165 -223.139254)
			(xy 354.824251 -223.146098) (xy 354.805652 -223.153821) (xy 354.795582 -223.15424) (xy 354.071174 -223.15424)
			(xy 354.061107 -223.154669) (xy 354.042513 -223.162395) (xy 354.035106 -223.169226) (xy 353.736656 -223.467676)
			(xy 353.72929 -223.474788) (xy 353.72167 -223.493584) (xy 353.72167 -223.549968) (xy 356.539782 -223.549968)
			(xy 356.539782 -223.490032) (xy 356.547605 -223.43061) (xy 356.563118 -223.372717) (xy 356.586054 -223.317344)
			(xy 356.616021 -223.265438) (xy 356.652508 -223.217888) (xy 356.694888 -223.175508) (xy 356.742438 -223.139021)
			(xy 356.794344 -223.109054) (xy 356.849717 -223.086118) (xy 356.90761 -223.070605) (xy 356.967032 -223.062782)
			(xy 357.026968 -223.062782) (xy 357.08639 -223.070605) (xy 357.144283 -223.086118) (xy 357.199656 -223.109054)
			(xy 357.251562 -223.139021) (xy 357.299112 -223.175508) (xy 357.341492 -223.217888) (xy 357.377979 -223.265438)
			(xy 357.407946 -223.317344) (xy 357.430882 -223.372717) (xy 357.444415 -223.423222) (xy 359.66322 -223.423222)
			(xy 359.66322 -223.363286) (xy 359.671043 -223.303864) (xy 359.686556 -223.245971) (xy 359.709492 -223.190598)
			(xy 359.739459 -223.138692) (xy 359.775946 -223.091142) (xy 359.818326 -223.048762) (xy 359.865876 -223.012275)
			(xy 359.917782 -222.982308) (xy 359.973155 -222.959372) (xy 360.031048 -222.943859) (xy 360.09047 -222.936036)
			(xy 360.150406 -222.936036) (xy 360.209828 -222.943859) (xy 360.267721 -222.959372) (xy 360.323094 -222.982308)
			(xy 360.375 -223.012275) (xy 360.42255 -223.048762) (xy 360.46493 -223.091142) (xy 360.501417 -223.138692)
			(xy 360.531384 -223.190598) (xy 360.55432 -223.245971) (xy 360.569833 -223.303864) (xy 360.577656 -223.363286)
			(xy 360.578146 -223.393254) (xy 360.577656 -223.423222) (xy 360.569833 -223.482644) (xy 360.55432 -223.540537)
			(xy 360.531384 -223.59591) (xy 360.501417 -223.647816) (xy 360.46493 -223.695366) (xy 360.42255 -223.737746)
			(xy 360.375 -223.774233) (xy 360.323094 -223.8042) (xy 360.267721 -223.827136) (xy 360.209828 -223.842649)
			(xy 360.150406 -223.850472) (xy 360.09047 -223.850472) (xy 360.031048 -223.842649) (xy 359.973155 -223.827136)
			(xy 359.917782 -223.8042) (xy 359.865876 -223.774233) (xy 359.818326 -223.737746) (xy 359.775946 -223.695366)
			(xy 359.739459 -223.647816) (xy 359.709492 -223.59591) (xy 359.686556 -223.540537) (xy 359.671043 -223.482644)
			(xy 359.66322 -223.423222) (xy 357.444415 -223.423222) (xy 357.446395 -223.43061) (xy 357.454218 -223.490032)
			(xy 357.454708 -223.52) (xy 357.454218 -223.549968) (xy 357.446395 -223.60939) (xy 357.430882 -223.667283)
			(xy 357.407946 -223.722656) (xy 357.377979 -223.774562) (xy 357.341492 -223.822112) (xy 357.299112 -223.864492)
			(xy 357.251562 -223.900979) (xy 357.199656 -223.930946) (xy 357.144283 -223.953882) (xy 357.08639 -223.969395)
			(xy 357.026968 -223.977218) (xy 356.967032 -223.977218) (xy 356.90761 -223.969395) (xy 356.849717 -223.953882)
			(xy 356.794344 -223.930946) (xy 356.742438 -223.900979) (xy 356.694888 -223.864492) (xy 356.652508 -223.822112)
			(xy 356.616021 -223.774562) (xy 356.586054 -223.722656) (xy 356.563118 -223.667283) (xy 356.547605 -223.60939)
			(xy 356.539782 -223.549968) (xy 353.72167 -223.549968) (xy 353.72167 -224.36455) (xy 353.722101 -224.374617)
			(xy 353.729825 -224.393211) (xy 353.736656 -224.400618) (xy 353.902006 -224.565968) (xy 355.650782 -224.565968)
			(xy 355.650782 -224.506032) (xy 355.658605 -224.44661) (xy 355.674118 -224.388717) (xy 355.697054 -224.333344)
			(xy 355.727021 -224.281438) (xy 355.763508 -224.233888) (xy 355.805888 -224.191508) (xy 355.853438 -224.155021)
			(xy 355.905344 -224.125054) (xy 355.960717 -224.102118) (xy 356.01861 -224.086605) (xy 356.078032 -224.078782)
			(xy 356.137968 -224.078782) (xy 356.19739 -224.086605) (xy 356.255283 -224.102118) (xy 356.310656 -224.125054)
			(xy 356.362562 -224.155021) (xy 356.410112 -224.191508) (xy 356.452492 -224.233888) (xy 356.488979 -224.281438)
			(xy 356.518946 -224.333344) (xy 356.541882 -224.388717) (xy 356.557395 -224.44661) (xy 356.565218 -224.506032)
			(xy 356.565708 -224.536) (xy 356.565218 -224.565968) (xy 358.571782 -224.565968) (xy 358.571782 -224.506032)
			(xy 358.579605 -224.44661) (xy 358.595118 -224.388717) (xy 358.618054 -224.333344) (xy 358.648021 -224.281438)
			(xy 358.684508 -224.233888) (xy 358.726888 -224.191508) (xy 358.774438 -224.155021) (xy 358.826344 -224.125054)
			(xy 358.881717 -224.102118) (xy 358.93961 -224.086605) (xy 358.999032 -224.078782) (xy 359.058968 -224.078782)
			(xy 359.11839 -224.086605) (xy 359.176283 -224.102118) (xy 359.231656 -224.125054) (xy 359.283562 -224.155021)
			(xy 359.331112 -224.191508) (xy 359.373492 -224.233888) (xy 359.409979 -224.281438) (xy 359.439946 -224.333344)
			(xy 359.462882 -224.388717) (xy 359.478395 -224.44661) (xy 359.486218 -224.506032) (xy 359.486708 -224.536)
			(xy 359.486218 -224.565968) (xy 359.478395 -224.62539) (xy 359.462882 -224.683283) (xy 359.439946 -224.738656)
			(xy 359.409979 -224.790562) (xy 359.373492 -224.838112) (xy 359.331112 -224.880492) (xy 359.283562 -224.916979)
			(xy 359.231656 -224.946946) (xy 359.176283 -224.969882) (xy 359.11839 -224.985395) (xy 359.058968 -224.993218)
			(xy 358.999032 -224.993218) (xy 358.93961 -224.985395) (xy 358.881717 -224.969882) (xy 358.826344 -224.946946)
			(xy 358.774438 -224.916979) (xy 358.726888 -224.880492) (xy 358.684508 -224.838112) (xy 358.648021 -224.790562)
			(xy 358.618054 -224.738656) (xy 358.595118 -224.683283) (xy 358.579605 -224.62539) (xy 358.571782 -224.565968)
			(xy 356.565218 -224.565968) (xy 356.557395 -224.62539) (xy 356.541882 -224.683283) (xy 356.518946 -224.738656)
			(xy 356.488979 -224.790562) (xy 356.452492 -224.838112) (xy 356.410112 -224.880492) (xy 356.362562 -224.916979)
			(xy 356.310656 -224.946946) (xy 356.255283 -224.969882) (xy 356.19739 -224.985395) (xy 356.137968 -224.993218)
			(xy 356.078032 -224.993218) (xy 356.01861 -224.985395) (xy 355.960717 -224.969882) (xy 355.905344 -224.946946)
			(xy 355.853438 -224.916979) (xy 355.805888 -224.880492) (xy 355.763508 -224.838112) (xy 355.727021 -224.790562)
			(xy 355.697054 -224.738656) (xy 355.674118 -224.683283) (xy 355.658605 -224.62539) (xy 355.650782 -224.565968)
			(xy 353.902006 -224.565968) (xy 354.007928 -224.67189) (xy 354.015328 -224.678733) (xy 354.033926 -224.686459)
			(xy 354.043996 -224.686876) (xy 355.178614 -224.686876) (xy 355.188684 -224.687301) (xy 355.207287 -224.695016)
			(xy 355.214682 -224.701862) (xy 355.759512 -225.246692) (xy 355.766369 -225.254086) (xy 355.77412 -225.272685)
			(xy 355.774498 -225.28276) (xy 355.774498 -225.581968) (xy 356.539782 -225.581968) (xy 356.539782 -225.522032)
			(xy 356.547605 -225.46261) (xy 356.563118 -225.404717) (xy 356.586054 -225.349344) (xy 356.616021 -225.297438)
			(xy 356.652508 -225.249888) (xy 356.694888 -225.207508) (xy 356.742438 -225.171021) (xy 356.794344 -225.141054)
			(xy 356.849717 -225.118118) (xy 356.90761 -225.102605) (xy 356.967032 -225.094782) (xy 357.026968 -225.094782)
			(xy 357.08639 -225.102605) (xy 357.144283 -225.118118) (xy 357.199656 -225.141054) (xy 357.251562 -225.171021)
			(xy 357.299112 -225.207508) (xy 357.341492 -225.249888) (xy 357.377979 -225.297438) (xy 357.407946 -225.349344)
			(xy 357.430882 -225.404717) (xy 357.446395 -225.46261) (xy 357.454218 -225.522032) (xy 357.454708 -225.552)
			(xy 358.646982 -225.552) (xy 358.651053 -225.496378) (xy 358.663179 -225.441941) (xy 358.683102 -225.38985)
			(xy 358.710398 -225.341215) (xy 358.744484 -225.297072) (xy 358.784633 -225.258363) (xy 358.829991 -225.225912)
			(xy 358.879591 -225.200411) (xy 358.932375 -225.182404) (xy 358.987218 -225.172274) (xy 359.042952 -225.170237)
			(xy 359.098389 -225.176337) (xy 359.152346 -225.190443) (xy 359.203675 -225.212255) (xy 359.251281 -225.241309)
			(xy 359.294149 -225.276984) (xy 359.331366 -225.318521) (xy 359.362139 -225.365034) (xy 359.385811 -225.415531)
			(xy 359.401879 -225.468938) (xy 359.409999 -225.524114) (xy 359.410508 -225.552) (xy 359.409999 -225.579886)
			(xy 359.401879 -225.635062) (xy 359.385811 -225.688469) (xy 359.362139 -225.738966) (xy 359.331366 -225.785479)
			(xy 359.294149 -225.827016) (xy 359.251281 -225.862691) (xy 359.203675 -225.891745) (xy 359.152346 -225.913557)
			(xy 359.098389 -225.927663) (xy 359.042952 -225.933763) (xy 358.987218 -225.931726) (xy 358.932375 -225.921596)
			(xy 358.879591 -225.903589) (xy 358.829991 -225.878088) (xy 358.784633 -225.845637) (xy 358.744484 -225.806928)
			(xy 358.710398 -225.762785) (xy 358.683102 -225.71415) (xy 358.663179 -225.662059) (xy 358.651053 -225.607622)
			(xy 358.646982 -225.552) (xy 357.454708 -225.552) (xy 357.454218 -225.581968) (xy 357.446395 -225.64139)
			(xy 357.430882 -225.699283) (xy 357.407946 -225.754656) (xy 357.377979 -225.806562) (xy 357.341492 -225.854112)
			(xy 357.299112 -225.896492) (xy 357.251562 -225.932979) (xy 357.199656 -225.962946) (xy 357.144283 -225.985882)
			(xy 357.08639 -226.001395) (xy 357.026968 -226.009218) (xy 356.967032 -226.009218) (xy 356.90761 -226.001395)
			(xy 356.849717 -225.985882) (xy 356.794344 -225.962946) (xy 356.742438 -225.932979) (xy 356.694888 -225.896492)
			(xy 356.652508 -225.854112) (xy 356.616021 -225.806562) (xy 356.586054 -225.754656) (xy 356.563118 -225.699283)
			(xy 356.547605 -225.64139) (xy 356.539782 -225.581968) (xy 355.774498 -225.581968) (xy 355.774498 -226.071938)
			(xy 355.786944 -226.094544) (xy 355.797866 -226.101656) (xy 355.869748 -226.147884) (xy 355.877052 -226.152199)
			(xy 355.893527 -226.156212) (xy 355.91041 -226.154652) (xy 355.918262 -226.15144) (xy 355.948189 -226.138447)
			(xy 356.0108 -226.120111) (xy 356.07538 -226.11085) (xy 356.108 -226.110292) (xy 356.137968 -226.110782)
			(xy 356.19739 -226.118605) (xy 356.255283 -226.134118) (xy 356.310656 -226.157054) (xy 356.362562 -226.187021)
			(xy 356.410112 -226.223508) (xy 356.452492 -226.265888) (xy 356.488979 -226.313438) (xy 356.518946 -226.365344)
			(xy 356.541882 -226.420717) (xy 356.557395 -226.47861) (xy 356.565218 -226.538032) (xy 356.565218 -226.597968)
			(xy 358.571782 -226.597968) (xy 358.571782 -226.538032) (xy 358.579605 -226.47861) (xy 358.595118 -226.420717)
			(xy 358.618054 -226.365344) (xy 358.648021 -226.313438) (xy 358.684508 -226.265888) (xy 358.726888 -226.223508)
			(xy 358.774438 -226.187021) (xy 358.826344 -226.157054) (xy 358.881717 -226.134118) (xy 358.93961 -226.118605)
			(xy 358.999032 -226.110782) (xy 359.058968 -226.110782) (xy 359.11839 -226.118605) (xy 359.176283 -226.134118)
			(xy 359.231656 -226.157054) (xy 359.283562 -226.187021) (xy 359.331112 -226.223508) (xy 359.373492 -226.265888)
			(xy 359.409979 -226.313438) (xy 359.439946 -226.365344) (xy 359.462882 -226.420717) (xy 359.478395 -226.47861)
			(xy 359.486218 -226.538032) (xy 359.486708 -226.568) (xy 359.486218 -226.597968) (xy 359.478395 -226.65739)
			(xy 359.462882 -226.715283) (xy 359.439946 -226.770656) (xy 359.409979 -226.822562) (xy 359.373492 -226.870112)
			(xy 359.331112 -226.912492) (xy 359.283562 -226.948979) (xy 359.231656 -226.978946) (xy 359.176283 -227.001882)
			(xy 359.11839 -227.017395) (xy 359.058968 -227.025218) (xy 358.999032 -227.025218) (xy 358.93961 -227.017395)
			(xy 358.881717 -227.001882) (xy 358.826344 -226.978946) (xy 358.774438 -226.948979) (xy 358.726888 -226.912492)
			(xy 358.684508 -226.870112) (xy 358.648021 -226.822562) (xy 358.618054 -226.770656) (xy 358.595118 -226.715283)
			(xy 358.579605 -226.65739) (xy 358.571782 -226.597968) (xy 356.565218 -226.597968) (xy 356.557395 -226.65739)
			(xy 356.541882 -226.715283) (xy 356.518946 -226.770656) (xy 356.488979 -226.822562) (xy 356.452492 -226.870112)
			(xy 356.410112 -226.912492) (xy 356.362562 -226.948979) (xy 356.310656 -226.978946) (xy 356.255283 -227.001882)
			(xy 356.19739 -227.017395) (xy 356.137968 -227.025218) (xy 356.108 -227.025708) (xy 356.092506 -227.025708)
			(xy 356.062462 -227.024229) (xy 356.003123 -227.014369) (xy 355.945585 -226.996827) (xy 355.918008 -226.984814)
			(xy 355.91016 -226.981576) (xy 355.893268 -226.979981) (xy 355.876792 -226.984031) (xy 355.869494 -226.98837)
			(xy 355.797866 -227.034344) (xy 355.790909 -227.0392) (xy 355.780425 -227.052526) (xy 355.774849 -227.068539)
			(xy 355.774498 -227.077016) (xy 355.774498 -227.613968) (xy 356.539782 -227.613968) (xy 356.539782 -227.554032)
			(xy 356.547605 -227.49461) (xy 356.563118 -227.436717) (xy 356.586054 -227.381344) (xy 356.616021 -227.329438)
			(xy 356.652508 -227.281888) (xy 356.694888 -227.239508) (xy 356.742438 -227.203021) (xy 356.794344 -227.173054)
			(xy 356.849717 -227.150118) (xy 356.90761 -227.134605) (xy 356.967032 -227.126782) (xy 357.026968 -227.126782)
			(xy 357.08639 -227.134605) (xy 357.144283 -227.150118) (xy 357.199656 -227.173054) (xy 357.251562 -227.203021)
			(xy 357.299112 -227.239508) (xy 357.341492 -227.281888) (xy 357.377979 -227.329438) (xy 357.407946 -227.381344)
			(xy 357.430882 -227.436717) (xy 357.446395 -227.49461) (xy 357.454218 -227.554032) (xy 357.454708 -227.584)
			(xy 357.454218 -227.613968) (xy 359.481356 -227.613968) (xy 359.481356 -227.554032) (xy 359.489179 -227.49461)
			(xy 359.504692 -227.436717) (xy 359.527628 -227.381344) (xy 359.557595 -227.329438) (xy 359.594082 -227.281888)
			(xy 359.636462 -227.239508) (xy 359.684012 -227.203021) (xy 359.735918 -227.173054) (xy 359.791291 -227.150118)
			(xy 359.849184 -227.134605) (xy 359.908606 -227.126782) (xy 359.968542 -227.126782) (xy 360.027964 -227.134605)
			(xy 360.085857 -227.150118) (xy 360.14123 -227.173054) (xy 360.193136 -227.203021) (xy 360.240686 -227.239508)
			(xy 360.283066 -227.281888) (xy 360.319553 -227.329438) (xy 360.34952 -227.381344) (xy 360.372456 -227.436717)
			(xy 360.387969 -227.49461) (xy 360.395792 -227.554032) (xy 360.396282 -227.584) (xy 360.395792 -227.613968)
			(xy 360.387969 -227.67339) (xy 360.372456 -227.731283) (xy 360.34952 -227.786656) (xy 360.319553 -227.838562)
			(xy 360.283066 -227.886112) (xy 360.240686 -227.928492) (xy 360.193136 -227.964979) (xy 360.14123 -227.994946)
			(xy 360.085857 -228.017882) (xy 360.027964 -228.033395) (xy 359.968542 -228.041218) (xy 359.908606 -228.041218)
			(xy 359.849184 -228.033395) (xy 359.791291 -228.017882) (xy 359.735918 -227.994946) (xy 359.684012 -227.964979)
			(xy 359.636462 -227.928492) (xy 359.594082 -227.886112) (xy 359.557595 -227.838562) (xy 359.527628 -227.786656)
			(xy 359.504692 -227.731283) (xy 359.489179 -227.67339) (xy 359.481356 -227.613968) (xy 357.454218 -227.613968)
			(xy 357.446395 -227.67339) (xy 357.430882 -227.731283) (xy 357.407946 -227.786656) (xy 357.377979 -227.838562)
			(xy 357.341492 -227.886112) (xy 357.299112 -227.928492) (xy 357.251562 -227.964979) (xy 357.199656 -227.994946)
			(xy 357.144283 -228.017882) (xy 357.08639 -228.033395) (xy 357.026968 -228.041218) (xy 356.967032 -228.041218)
			(xy 356.90761 -228.033395) (xy 356.849717 -228.017882) (xy 356.794344 -227.994946) (xy 356.742438 -227.964979)
			(xy 356.694888 -227.928492) (xy 356.652508 -227.886112) (xy 356.616021 -227.838562) (xy 356.586054 -227.786656)
			(xy 356.563118 -227.731283) (xy 356.547605 -227.67339) (xy 356.539782 -227.613968) (xy 355.774498 -227.613968)
			(xy 355.774498 -228.103938) (xy 355.786944 -228.126544) (xy 355.797866 -228.133656) (xy 355.869748 -228.179884)
			(xy 355.877052 -228.184199) (xy 355.893527 -228.188212) (xy 355.91041 -228.186652) (xy 355.918262 -228.18344)
			(xy 355.948189 -228.170447) (xy 356.0108 -228.152111) (xy 356.07538 -228.14285) (xy 356.108 -228.142292)
			(xy 356.137968 -228.142782) (xy 356.19739 -228.150605) (xy 356.255283 -228.166118) (xy 356.310656 -228.189054)
			(xy 356.362562 -228.219021) (xy 356.410112 -228.255508) (xy 356.452492 -228.297888) (xy 356.488979 -228.345438)
			(xy 356.518946 -228.397344) (xy 356.541882 -228.452717) (xy 356.557395 -228.51061) (xy 356.565218 -228.570032)
			(xy 356.565218 -228.6) (xy 358.646982 -228.6) (xy 358.651053 -228.544378) (xy 358.663179 -228.489941)
			(xy 358.683102 -228.43785) (xy 358.710398 -228.389215) (xy 358.744484 -228.345072) (xy 358.784633 -228.306363)
			(xy 358.829991 -228.273912) (xy 358.879591 -228.248411) (xy 358.932375 -228.230404) (xy 358.987218 -228.220274)
			(xy 359.042952 -228.218237) (xy 359.098389 -228.224337) (xy 359.152346 -228.238443) (xy 359.203675 -228.260255)
			(xy 359.251281 -228.289309) (xy 359.294149 -228.324984) (xy 359.331366 -228.366521) (xy 359.362139 -228.413034)
			(xy 359.385811 -228.463531) (xy 359.401879 -228.516938) (xy 359.409999 -228.572114) (xy 359.410508 -228.6)
			(xy 359.409999 -228.627886) (xy 359.401879 -228.683062) (xy 359.385811 -228.736469) (xy 359.362139 -228.786966)
			(xy 359.331366 -228.833479) (xy 359.294149 -228.875016) (xy 359.251281 -228.910691) (xy 359.203675 -228.939745)
			(xy 359.152346 -228.961557) (xy 359.098389 -228.975663) (xy 359.042952 -228.981763) (xy 358.987218 -228.979726)
			(xy 358.932375 -228.969596) (xy 358.879591 -228.951589) (xy 358.829991 -228.926088) (xy 358.784633 -228.893637)
			(xy 358.744484 -228.854928) (xy 358.710398 -228.810785) (xy 358.683102 -228.76215) (xy 358.663179 -228.710059)
			(xy 358.651053 -228.655622) (xy 358.646982 -228.6) (xy 356.565218 -228.6) (xy 356.565218 -228.629968)
			(xy 356.557395 -228.68939) (xy 356.541882 -228.747283) (xy 356.518946 -228.802656) (xy 356.488979 -228.854562)
			(xy 356.452492 -228.902112) (xy 356.410112 -228.944492) (xy 356.362562 -228.980979) (xy 356.310656 -229.010946)
			(xy 356.255283 -229.033882) (xy 356.19739 -229.049395) (xy 356.137968 -229.057218) (xy 356.108 -229.057708)
			(xy 356.078043 -229.057219) (xy 356.018641 -229.049401) (xy 355.960767 -229.033899) (xy 355.90541 -229.010979)
			(xy 355.853518 -228.981032) (xy 355.805976 -228.944569) (xy 355.763599 -228.902215) (xy 355.72711 -228.854694)
			(xy 355.697133 -228.802818) (xy 355.674182 -228.747474) (xy 355.658649 -228.689608) (xy 355.650798 -228.630211)
			(xy 355.650292 -228.600254) (xy 355.650292 -228.599746) (xy 355.6508 -228.575616) (xy 355.651308 -228.564948)
			(xy 355.643688 -228.544882) (xy 355.636068 -228.537262) (xy 355.628621 -228.530574) (xy 355.610125 -228.522978)
			(xy 355.590129 -228.522978) (xy 355.571633 -228.530574) (xy 355.564186 -228.537262) (xy 355.543104 -228.558344)
			(xy 355.535708 -228.565197) (xy 355.51711 -228.572942) (xy 355.507036 -228.57333) (xy 354.509324 -228.57333)
			(xy 354.499261 -228.573768) (xy 354.480679 -228.581505) (xy 354.473256 -228.588316) (xy 354.229416 -228.832156)
			(xy 354.22205 -228.839268) (xy 354.21443 -228.858064) (xy 354.21443 -229.645968) (xy 356.539782 -229.645968)
			(xy 356.539782 -229.586032) (xy 356.547605 -229.52661) (xy 356.563118 -229.468717) (xy 356.586054 -229.413344)
			(xy 356.616021 -229.361438) (xy 356.652508 -229.313888) (xy 356.694888 -229.271508) (xy 356.742438 -229.235021)
			(xy 356.794344 -229.205054) (xy 356.849717 -229.182118) (xy 356.90761 -229.166605) (xy 356.967032 -229.158782)
			(xy 357.026968 -229.158782) (xy 357.08639 -229.166605) (xy 357.144283 -229.182118) (xy 357.199656 -229.205054)
			(xy 357.251562 -229.235021) (xy 357.299112 -229.271508) (xy 357.341492 -229.313888) (xy 357.377979 -229.361438)
			(xy 357.407946 -229.413344) (xy 357.430882 -229.468717) (xy 357.446395 -229.52661) (xy 357.454218 -229.586032)
			(xy 357.454708 -229.616) (xy 358.646982 -229.616) (xy 358.651053 -229.560378) (xy 358.663179 -229.505941)
			(xy 358.683102 -229.45385) (xy 358.710398 -229.405215) (xy 358.744484 -229.361072) (xy 358.784633 -229.322363)
			(xy 358.829991 -229.289912) (xy 358.879591 -229.264411) (xy 358.932375 -229.246404) (xy 358.987218 -229.236274)
			(xy 359.042952 -229.234237) (xy 359.098389 -229.240337) (xy 359.152346 -229.254443) (xy 359.203675 -229.276255)
			(xy 359.251281 -229.305309) (xy 359.294149 -229.340984) (xy 359.331366 -229.382521) (xy 359.362139 -229.429034)
			(xy 359.385811 -229.479531) (xy 359.401879 -229.532938) (xy 359.409999 -229.588114) (xy 359.410508 -229.616)
			(xy 359.409999 -229.643886) (xy 359.401879 -229.699062) (xy 359.385811 -229.752469) (xy 359.362139 -229.802966)
			(xy 359.331366 -229.849479) (xy 359.294149 -229.891016) (xy 359.251281 -229.926691) (xy 359.203675 -229.955745)
			(xy 359.152346 -229.977557) (xy 359.098389 -229.991663) (xy 359.042952 -229.997763) (xy 358.987218 -229.995726)
			(xy 358.932375 -229.985596) (xy 358.879591 -229.967589) (xy 358.829991 -229.942088) (xy 358.784633 -229.909637)
			(xy 358.744484 -229.870928) (xy 358.710398 -229.826785) (xy 358.683102 -229.77815) (xy 358.663179 -229.726059)
			(xy 358.651053 -229.671622) (xy 358.646982 -229.616) (xy 357.454708 -229.616) (xy 357.454218 -229.645968)
			(xy 357.446395 -229.70539) (xy 357.430882 -229.763283) (xy 357.407946 -229.818656) (xy 357.377979 -229.870562)
			(xy 357.341492 -229.918112) (xy 357.299112 -229.960492) (xy 357.251562 -229.996979) (xy 357.199656 -230.026946)
			(xy 357.144283 -230.049882) (xy 357.08639 -230.065395) (xy 357.026968 -230.073218) (xy 356.967032 -230.073218)
			(xy 356.90761 -230.065395) (xy 356.849717 -230.049882) (xy 356.794344 -230.026946) (xy 356.742438 -229.996979)
			(xy 356.694888 -229.960492) (xy 356.652508 -229.918112) (xy 356.616021 -229.870562) (xy 356.586054 -229.818656)
			(xy 356.563118 -229.763283) (xy 356.547605 -229.70539) (xy 356.539782 -229.645968) (xy 354.21443 -229.645968)
			(xy 354.21443 -230.627428) (xy 354.22205 -230.646224) (xy 354.229416 -230.653336) (xy 354.556822 -230.980742)
			(xy 354.564219 -230.987591) (xy 354.582818 -230.995327) (xy 354.59289 -230.995728)
		)
		(stroke
			(width 0)
			(type solid)
		)
		(fill yes)
		(layer "B.Cu")
		(net "P3V3_AUX")
	)
	(gr_poly
		(pts
			(xy 16.13916 -319.15608) (xy 16.149225 -319.155645) (xy 16.167812 -319.147913) (xy 16.175228 -319.141094)
			(xy 17.037304 -318.279018) (xy 17.044137 -318.271615) (xy 17.051841 -318.253017) (xy 17.05229 -318.24295)
			(xy 17.05229 -310.925464) (xy 17.051796 -310.915462) (xy 17.044129 -310.896984) (xy 17.029977 -310.882845)
			(xy 17.011493 -310.875195) (xy 17.00149 -310.874664) (xy 16.53794 -310.874664) (xy 16.525748 -310.877712)
			(xy 16.519906 -310.881014) (xy 16.50263 -310.890302) (xy 16.465669 -310.903418) (xy 16.426996 -310.909942)
			(xy 16.407384 -310.910224) (xy 16.108172 -310.910224) (xy 16.085857 -310.909861) (xy 16.042038 -310.901421)
			(xy 16.000722 -310.884558) (xy 15.963513 -310.859925) (xy 15.931852 -310.828478) (xy 15.906967 -310.791437)
			(xy 15.889823 -310.750237) (xy 15.881085 -310.706476) (xy 15.880588 -310.684164) (xy 15.880588 -310.467248)
			(xy 15.880999 -310.457219) (xy 15.88866 -310.438684) (xy 15.902834 -310.424494) (xy 15.92136 -310.416811)
			(xy 15.931388 -310.416448) (xy 15.940532 -310.416448) (xy 15.940532 -309.942484) (xy 15.940042 -309.932476)
			(xy 15.93238 -309.913984) (xy 15.918229 -309.899829) (xy 15.89974 -309.892161) (xy 15.889732 -309.891684)
			(xy 15.880588 -309.891684) (xy 15.880588 -309.623968) (xy 15.881173 -309.599379) (xy 15.891717 -309.551347)
			(xy 15.912386 -309.506725) (xy 15.926816 -309.486808) (xy 15.93166 -309.480058) (xy 15.937106 -309.464374)
			(xy 15.937484 -309.456074) (xy 15.937484 -309.033164) (xy 15.93699 -309.023162) (xy 15.929323 -309.004686)
			(xy 15.915171 -308.990548) (xy 15.896686 -308.9829) (xy 15.886684 -308.982364) (xy 14.063218 -308.982364)
			(xy 14.035532 -309.00497) (xy 14.031722 -309.02275) (xy 14.024807 -309.053223) (xy 14.003815 -309.112079)
			(xy 13.97501 -309.16753) (xy 13.938927 -309.218546) (xy 13.896237 -309.264178) (xy 13.847735 -309.303576)
			(xy 13.794324 -309.336007) (xy 13.736996 -309.36087) (xy 13.676818 -309.3777) (xy 13.61491 -309.386184)
			(xy 13.583666 -309.386732) (xy 13.553699 -309.38624) (xy 13.494279 -309.378413) (xy 13.436388 -309.362898)
			(xy 13.381018 -309.33996) (xy 13.329115 -309.309992) (xy 13.281567 -309.273505) (xy 13.239188 -309.231125)
			(xy 13.202703 -309.183577) (xy 13.172735 -309.131673) (xy 13.149799 -309.076302) (xy 13.134285 -309.018411)
			(xy 13.12646 -308.958991) (xy 13.125958 -308.929024) (xy 13.126426 -308.89968) (xy 13.133924 -308.841472)
			(xy 13.148801 -308.784701) (xy 13.170813 -308.730296) (xy 13.199597 -308.679152) (xy 13.234683 -308.632106)
			(xy 13.275494 -308.58993) (xy 13.321361 -308.553317) (xy 13.371532 -308.522867) (xy 13.425184 -308.499079)
			(xy 13.481435 -308.482345) (xy 13.539365 -308.472937) (xy 13.56868 -308.47157) (xy 13.578586 -308.471316)
			(xy 13.595858 -308.463696) (xy 13.624306 -308.435248) (xy 13.642434 -308.417756) (xy 13.683168 -308.388119)
			(xy 13.728037 -308.365223) (xy 13.775937 -308.34963) (xy 13.825687 -308.341727) (xy 13.850874 -308.341268)
			(xy 14.872716 -308.341268) (xy 14.883087 -308.34078) (xy 14.902147 -308.332596) (xy 14.916437 -308.317561)
			(xy 14.920468 -308.307994) (xy 14.929358 -308.283864) (xy 14.932293 -308.274444) (xy 14.931502 -308.254749)
			(xy 14.923288 -308.236831) (xy 14.916404 -308.229762) (xy 14.907768 -308.221126) (xy 14.619478 -307.932836)
			(xy 14.599962 -307.912852) (xy 14.564959 -307.869317) (xy 14.549628 -307.845968) (xy 14.54404 -307.836824)
			(xy 14.52626 -307.82514) (xy 14.43101 -307.808376) (xy 14.410182 -307.813456) (xy 14.4018 -307.82006)
			(xy 14.377646 -307.838189) (xy 14.325474 -307.868612) (xy 14.269752 -307.891904) (xy 14.21145 -307.90766)
			(xy 14.151581 -307.915606) (xy 14.121384 -307.916072) (xy 14.091415 -307.915603) (xy 14.031988 -307.90778)
			(xy 13.974092 -307.892267) (xy 13.918715 -307.86933) (xy 13.866806 -307.839361) (xy 13.819254 -307.802872)
			(xy 13.77687 -307.760489) (xy 13.740382 -307.712937) (xy 13.710412 -307.661028) (xy 13.687474 -307.605652)
			(xy 13.671961 -307.547756) (xy 13.664137 -307.488329) (xy 13.664137 -307.428391) (xy 13.671961 -307.368964)
			(xy 13.687474 -307.311068) (xy 13.710412 -307.255692) (xy 13.740382 -307.203783) (xy 13.77687 -307.156231)
			(xy 13.819254 -307.113848) (xy 13.866806 -307.077359) (xy 13.918715 -307.04739) (xy 13.974092 -307.024453)
			(xy 14.031988 -307.00894) (xy 14.091415 -307.001117) (xy 14.121384 -307.000656) (xy 14.156396 -307.001301)
			(xy 14.225606 -307.011936) (xy 14.292383 -307.033006) (xy 14.324076 -307.0479) (xy 14.33576 -307.053742)
			(xy 14.361922 -307.052472) (xy 14.446504 -306.999894) (xy 14.453609 -306.995025) (xy 14.464337 -306.981563)
			(xy 14.470037 -306.96532) (xy 14.47038 -306.956714) (xy 14.47038 -306.550822) (xy 14.470037 -306.541247)
			(xy 14.463127 -306.523392) (xy 14.450151 -306.509316) (xy 14.441678 -306.504848) (xy 14.345666 -306.459128)
			(xy 14.31671 -306.46243) (xy 14.305026 -306.471828) (xy 14.280514 -306.490922) (xy 14.227308 -306.523015)
			(xy 14.170249 -306.547612) (xy 14.110385 -306.564258) (xy 14.04882 -306.572648) (xy 14.017752 -306.573174)
			(xy 13.987783 -306.572705) (xy 13.928358 -306.564882) (xy 13.870463 -306.549369) (xy 13.815088 -306.526432)
			(xy 13.76318 -306.496463) (xy 13.715628 -306.459976) (xy 13.673246 -306.417593) (xy 13.636758 -306.370042)
			(xy 13.606789 -306.318134) (xy 13.583852 -306.262759) (xy 13.568339 -306.204864) (xy 13.560515 -306.145439)
			(xy 13.560515 -306.085501) (xy 13.568339 -306.026076) (xy 13.583852 -305.968181) (xy 13.606789 -305.912806)
			(xy 13.636758 -305.860898) (xy 13.673246 -305.813347) (xy 13.715628 -305.770964) (xy 13.76318 -305.734477)
			(xy 13.815088 -305.704508) (xy 13.870463 -305.681571) (xy 13.928358 -305.666058) (xy 13.987783 -305.658235)
			(xy 14.017752 -305.657758) (xy 14.048818 -305.65828) (xy 14.11038 -305.666688) (xy 14.170239 -305.683343)
			(xy 14.227297 -305.707938) (xy 14.280505 -305.740021) (xy 14.305026 -305.759104) (xy 14.31671 -305.768502)
			(xy 14.345666 -305.771804) (xy 14.441678 -305.726084) (xy 14.45011 -305.721556) (xy 14.463079 -305.7075)
			(xy 14.470009 -305.689674) (xy 14.47038 -305.68011) (xy 14.47038 -305.651154) (xy 14.469943 -305.641122)
			(xy 14.462368 -305.622546) (xy 14.455648 -305.615086) (xy 13.266166 -304.425604) (xy 13.25874 -304.418831)
			(xy 13.240143 -304.41125) (xy 13.230098 -304.410872) (xy 8.820912 -304.410872) (xy 8.810882 -304.411316)
			(xy 8.792313 -304.418896) (xy 8.784844 -304.425604) (xy 8.393684 -304.816764) (xy 8.369784 -304.839928)
			(xy 8.316978 -304.880446) (xy 8.259334 -304.913722) (xy 8.197839 -304.939186) (xy 8.133545 -304.956403)
			(xy 8.067554 -304.965077) (xy 8.034274 -304.965608) (xy 8.003559 -304.965161) (xy 7.942578 -304.957753)
			(xy 7.882934 -304.943049) (xy 7.825498 -304.921262) (xy 7.771107 -304.892711) (xy 7.720554 -304.857812)
			(xy 7.674576 -304.817073) (xy 7.633844 -304.77109) (xy 7.598952 -304.720532) (xy 7.570408 -304.666136)
			(xy 7.54863 -304.608697) (xy 7.533934 -304.549051) (xy 7.526534 -304.488069) (xy 7.52602 -304.457354)
			(xy 7.526566 -304.424077) (xy 7.535256 -304.358091) (xy 7.55248 -304.293804) (xy 7.577945 -304.232313)
			(xy 7.611214 -304.17467) (xy 7.65172 -304.121861) (xy 7.674864 -304.097944) (xy 8.229854 -303.542954)
			(xy 8.253768 -303.519795) (xy 8.306567 -303.479249) (xy 8.364204 -303.445936) (xy 8.425693 -303.420426)
			(xy 8.489984 -303.403153) (xy 8.555979 -303.394414) (xy 8.589264 -303.393856) (xy 13.461746 -303.393856)
			(xy 13.495036 -303.394387) (xy 13.561043 -303.403099) (xy 13.625348 -303.420356) (xy 13.686849 -303.445861)
			(xy 13.744493 -303.479179) (xy 13.797293 -303.519738) (xy 13.821156 -303.542954) (xy 14.698218 -304.420016)
			(xy 14.704755 -304.425964) (xy 14.720761 -304.433428) (xy 14.738345 -304.435073) (xy 14.746986 -304.433224)
			(xy 14.84503 -304.40757) (xy 14.86408 -304.388774) (xy 14.86789 -304.37582) (xy 14.876406 -304.347409)
			(xy 14.899773 -304.292893) (xy 14.929985 -304.241851) (xy 14.966536 -304.195139) (xy 15.008815 -304.15354)
			(xy 15.056112 -304.117749) (xy 15.107636 -304.088368) (xy 15.162524 -304.065888) (xy 15.219855 -304.050685)
			(xy 15.27867 -304.043014) (xy 15.308326 -304.042572) (xy 15.338293 -304.043064) (xy 15.397714 -304.05089)
			(xy 15.455605 -304.066404) (xy 15.510976 -304.089341) (xy 15.56288 -304.11931) (xy 15.610428 -304.155796)
			(xy 15.652808 -304.198176) (xy 15.689294 -304.245725) (xy 15.719261 -304.297629) (xy 15.742198 -304.353)
			(xy 15.757712 -304.410892) (xy 15.765537 -304.470313) (xy 15.766034 -304.50028) (xy 15.76554 -304.530997)
			(xy 15.757325 -304.591881) (xy 15.741041 -304.651118) (xy 15.716979 -304.707645) (xy 15.685573 -304.760445)
			(xy 15.647387 -304.80857) (xy 15.603107 -304.851156) (xy 15.553528 -304.887435) (xy 15.499543 -304.916757)
			(xy 15.44212 -304.938595) (xy 15.382293 -304.952556) (xy 15.35176 -304.955956) (xy 15.343124 -304.956718)
			(xy 15.327122 -304.964338) (xy 15.320772 -304.970434) (xy 15.313929 -304.977801) (xy 15.306181 -304.996337)
			(xy 15.306174 -305.016428) (xy 15.313909 -305.03497) (xy 15.320772 -305.042316) (xy 15.338298 -305.060096)
			(xy 15.361453 -305.084012) (xy 15.40199 -305.136813) (xy 15.435295 -305.194451) (xy 15.460798 -305.25594)
			(xy 15.478063 -305.32023) (xy 15.486796 -305.386222) (xy 15.487396 -305.419506) (xy 15.487396 -306.38242)
			(xy 15.487841 -306.392908) (xy 15.496123 -306.412173) (xy 15.511449 -306.426486) (xy 15.521178 -306.430426)
			(xy 15.627096 -306.467256) (xy 15.658084 -306.458366) (xy 15.668244 -306.445666) (xy 15.686926 -306.423056)
			(xy 15.729106 -306.382303) (xy 15.776144 -306.347266) (xy 15.827268 -306.318521) (xy 15.881643 -306.296535)
			(xy 15.93838 -306.28167) (xy 15.99655 -306.274168) (xy 16.025876 -306.273708) (xy 16.055845 -306.274176)
			(xy 16.115271 -306.281996) (xy 16.173167 -306.297507) (xy 16.228543 -306.320442) (xy 16.280452 -306.350409)
			(xy 16.328005 -306.386895) (xy 16.370389 -306.429277) (xy 16.406878 -306.476828) (xy 16.436848 -306.528735)
			(xy 16.459786 -306.58411) (xy 16.475299 -306.642006) (xy 16.483123 -306.701431) (xy 16.483123 -306.761369)
			(xy 16.475299 -306.820794) (xy 16.459786 -306.87869) (xy 16.436848 -306.934065) (xy 16.406878 -306.985972)
			(xy 16.370389 -307.033523) (xy 16.328005 -307.075905) (xy 16.280452 -307.112391) (xy 16.228543 -307.142358)
			(xy 16.173167 -307.165293) (xy 16.115271 -307.180804) (xy 16.055845 -307.188624) (xy 16.025876 -307.189124)
			(xy 15.996548 -307.188661) (xy 15.938371 -307.181179) (xy 15.881626 -307.166327) (xy 15.827243 -307.144349)
			(xy 15.776112 -307.115606) (xy 15.729072 -307.080567) (xy 15.686892 -307.039806) (xy 15.668244 -307.017166)
			(xy 15.658084 -307.004466) (xy 15.627096 -306.995576) (xy 15.521178 -307.032406) (xy 15.511497 -307.036415)
			(xy 15.496228 -307.050736) (xy 15.487911 -307.069945) (xy 15.487396 -307.080412) (xy 15.487396 -307.302408)
			(xy 15.487754 -307.312452) (xy 15.495367 -307.331035) (xy 15.509568 -307.345235) (xy 15.528152 -307.352847)
			(xy 15.538196 -307.353208) (xy 16.251174 -307.353208) (xy 16.281902 -307.353652) (xy 16.342911 -307.361059)
			(xy 16.402582 -307.375768) (xy 16.460044 -307.397564) (xy 16.514458 -307.42613) (xy 16.565031 -307.461048)
			(xy 16.611025 -307.501809) (xy 16.651769 -307.547818) (xy 16.686669 -307.598405) (xy 16.715214 -307.65283)
			(xy 16.736989 -307.7103) (xy 16.751675 -307.769976) (xy 16.759059 -307.830987) (xy 16.759428 -307.861716)
			(xy 16.758969 -307.892653) (xy 16.751458 -307.954071) (xy 16.736549 -308.014122) (xy 16.714463 -308.071921)
			(xy 16.685525 -308.126612) (xy 16.650164 -308.177387) (xy 16.608903 -308.223495) (xy 16.585946 -308.24424)
			(xy 16.578028 -308.251791) (xy 16.568932 -308.271666) (xy 16.56842 -308.282594) (xy 16.56842 -308.473348)
			(xy 16.568917 -308.483348) (xy 16.576585 -308.50182) (xy 16.590737 -308.515953) (xy 16.60922 -308.523597)
			(xy 16.61922 -308.524148) (xy 16.628364 -308.524148) (xy 16.628364 -308.791864) (xy 16.62781 -308.814924)
			(xy 16.61849 -308.860094) (xy 16.600248 -308.902454) (xy 16.58747 -308.921658) (xy 16.582898 -308.928008)
			(xy 16.578072 -308.942994) (xy 16.578072 -309.456074) (xy 16.57848 -309.464368) (xy 16.583916 -309.480049)
			(xy 16.58874 -309.486808) (xy 16.603131 -309.506748) (xy 16.623778 -309.551368) (xy 16.634342 -309.599385)
			(xy 16.634968 -309.623968) (xy 16.634968 -309.840884) (xy 16.634551 -309.850905) (xy 16.626882 -309.869422)
			(xy 16.612708 -309.883591) (xy 16.594189 -309.891254) (xy 16.584168 -309.891684) (xy 16.575024 -309.891684)
			(xy 16.575024 -310.182768) (xy 16.575439 -310.192792) (xy 16.583104 -310.211315) (xy 16.597278 -310.225492)
			(xy 16.6158 -310.23316) (xy 16.625824 -310.233568) (xy 16.85671 -310.233568) (xy 16.866676 -310.233091)
			(xy 16.885112 -310.225514) (xy 16.892524 -310.218836) (xy 17.037304 -310.074056) (xy 17.044143 -310.066655)
			(xy 17.051861 -310.048057) (xy 17.05229 -310.037988) (xy 17.05229 -308.137814) (xy 17.05191 -308.128982)
			(xy 17.045933 -308.112358) (xy 17.040606 -308.105302) (xy 17.024074 -308.084673) (xy 16.996258 -308.039717)
			(xy 16.974915 -307.991352) (xy 16.960455 -307.940503) (xy 16.953154 -307.888145) (xy 16.953153 -307.83528)
			(xy 16.96045 -307.782921) (xy 16.974907 -307.732071) (xy 16.996246 -307.683704) (xy 17.024059 -307.638747)
			(xy 17.040606 -307.61813) (xy 17.046013 -307.611119) (xy 17.051998 -307.594467) (xy 17.05229 -307.585618)
			(xy 17.05229 -302.769524) (xy 17.052194 -302.764364) (xy 17.050143 -302.75425) (xy 17.048226 -302.749458)
			(xy 17.014596 -302.670219) (xy 16.954475 -302.508901) (xy 16.90265 -302.34473) (xy 16.859256 -302.178132)
			(xy 16.824406 -302.00954) (xy 16.79819 -301.839391) (xy 16.780676 -301.668128) (xy 16.77191 -301.496194)
			(xy 16.771366 -301.410116) (xy 16.77192 -301.324039) (xy 16.780705 -301.152108) (xy 16.79823 -300.980847)
			(xy 16.824453 -300.810701) (xy 16.859303 -300.64211) (xy 16.902692 -300.475513) (xy 16.954506 -300.31134)
			(xy 17.014611 -300.150018) (xy 17.048226 -300.070774) (xy 17.050112 -300.065973) (xy 17.052152 -300.055864)
			(xy 17.05229 -300.050708) (xy 17.05229 -294.86733) (xy 17.052725 -294.857265) (xy 17.060457 -294.838678)
			(xy 17.067276 -294.831262) (xy 18.150332 -293.748206) (xy 18.157187 -293.740811) (xy 18.164934 -293.722212)
			(xy 18.165318 -293.712138) (xy 18.165318 -273.618198) (xy 18.164915 -273.609001) (xy 18.158423 -273.59179)
			(xy 18.146303 -273.577953) (xy 18.138394 -273.57324) (xy 18.046954 -273.524472) (xy 18.019014 -273.525742)
			(xy 18.00733 -273.533616) (xy 17.983648 -273.548865) (xy 17.932749 -273.572983) (xy 17.878859 -273.589363)
			(xy 17.823148 -273.597649) (xy 17.794986 -273.598132) (xy 17.767734 -273.597645) (xy 17.713784 -273.589887)
			(xy 17.661488 -273.574529) (xy 17.611909 -273.551886) (xy 17.566058 -273.522417) (xy 17.524866 -273.486724)
			(xy 17.489174 -273.445531) (xy 17.459707 -273.399679) (xy 17.437066 -273.350099) (xy 17.42171 -273.297802)
			(xy 17.413954 -273.243852) (xy 17.413954 -273.189348) (xy 17.42171 -273.135398) (xy 17.437066 -273.083101)
			(xy 17.459707 -273.033521) (xy 17.489174 -272.987669) (xy 17.524866 -272.946476) (xy 17.566058 -272.910783)
			(xy 17.611909 -272.881314) (xy 17.661488 -272.858671) (xy 17.713784 -272.843313) (xy 17.767734 -272.835555)
			(xy 17.794986 -272.835116) (xy 17.823148 -272.835619) (xy 17.87886 -272.843894) (xy 17.93275 -272.860266)
			(xy 17.98365 -272.884381) (xy 18.00733 -272.899632) (xy 18.019014 -272.907506) (xy 18.046954 -272.908776)
			(xy 18.138394 -272.860008) (xy 18.146355 -272.855353) (xy 18.158531 -272.841521) (xy 18.164995 -272.824265)
			(xy 18.165318 -272.81505) (xy 18.165318 -271.620996) (xy 18.164991 -271.61245) (xy 18.159365 -271.59631)
			(xy 18.14874 -271.58292) (xy 18.141696 -271.57807) (xy 18.057876 -271.525238) (xy 18.032222 -271.523714)
			(xy 18.020284 -271.529302) (xy 17.994598 -271.540926) (xy 17.940661 -271.557337) (xy 17.884897 -271.56564)
			(xy 17.856708 -271.566132) (xy 17.829456 -271.565647) (xy 17.775506 -271.557891) (xy 17.723209 -271.542537)
			(xy 17.673629 -271.519897) (xy 17.627776 -271.490431) (xy 17.586583 -271.45474) (xy 17.550888 -271.41355)
			(xy 17.521419 -271.367699) (xy 17.498774 -271.318121) (xy 17.483415 -271.265825) (xy 17.475656 -271.211876)
			(xy 17.4752 -271.184624) (xy 17.475675 -271.157499) (xy 17.483357 -271.103795) (xy 17.498569 -271.051721)
			(xy 17.521005 -271.002327) (xy 17.550212 -270.956609) (xy 17.585601 -270.915491) (xy 17.626458 -270.8798)
			(xy 17.671959 -270.850257) (xy 17.721186 -270.827458) (xy 17.773147 -270.811862) (xy 17.826793 -270.803785)
			(xy 17.853914 -270.803116) (xy 17.869408 -270.803116) (xy 17.894554 -270.785844) (xy 17.935956 -270.685006)
			(xy 17.939306 -270.675557) (xy 17.939244 -270.65553) (xy 17.931527 -270.63705) (xy 17.92478 -270.629634)
			(xy 17.765776 -270.47063) (xy 17.739106 -270.463772) (xy 17.725644 -270.467582) (xy 17.699962 -270.474445)
			(xy 17.647321 -270.481833) (xy 17.620742 -270.482314) (xy 17.592408 -270.481799) (xy 17.536364 -270.473419)
			(xy 17.482178 -270.456837) (xy 17.431042 -270.432418) (xy 17.384082 -270.400701) (xy 17.342334 -270.362383)
			(xy 17.306717 -270.318308) (xy 17.278014 -270.269448) (xy 17.256859 -270.216878) (xy 17.243716 -270.161756)
			(xy 17.240758 -270.133572) (xy 17.23898 -270.11376) (xy 17.210024 -270.08709) (xy 13.141198 -270.08709)
			(xy 13.131128 -270.087513) (xy 13.112523 -270.095227) (xy 13.10513 -270.102076) (xy 12.901676 -270.30553)
			(xy 12.894826 -270.312926) (xy 12.88709 -270.331525) (xy 12.88669 -270.341598) (xy 12.88669 -270.635222)
			(xy 12.645136 -270.876776) (xy 12.638444 -270.884183) (xy 12.630848 -270.902619) (xy 12.630404 -270.91259)
			(xy 12.630404 -270.913098) (xy 12.084304 -271.458944) (xy 12.076893 -271.465624) (xy 12.058457 -271.473201)
			(xy 12.04849 -271.473676) (xy 12.048236 -271.473676) (xy 11.258296 -272.263616) (xy 11.250901 -272.270471)
			(xy 11.232302 -272.278217) (xy 11.222228 -272.278602) (xy 10.922254 -272.278602) (xy 10.912188 -272.279034)
			(xy 10.893595 -272.28676) (xy 10.886186 -272.293588) (xy 10.803894 -272.37588) (xy 11.560538 -272.37588)
			(xy 11.560538 -272.315944) (xy 11.568361 -272.256522) (xy 11.583874 -272.198629) (xy 11.60681 -272.143256)
			(xy 11.636777 -272.09135) (xy 11.673264 -272.0438) (xy 11.715644 -272.00142) (xy 11.763194 -271.964933)
			(xy 11.8151 -271.934966) (xy 11.870473 -271.91203) (xy 11.928366 -271.896517) (xy 11.987788 -271.888694)
			(xy 12.047724 -271.888694) (xy 12.107146 -271.896517) (xy 12.165039 -271.91203) (xy 12.220412 -271.934966)
			(xy 12.272318 -271.964933) (xy 12.319868 -272.00142) (xy 12.362248 -272.0438) (xy 12.398735 -272.09135)
			(xy 12.428702 -272.143256) (xy 12.451638 -272.198629) (xy 12.467151 -272.256522) (xy 12.474974 -272.315944)
			(xy 12.475464 -272.345912) (xy 12.474974 -272.37588) (xy 12.467151 -272.435302) (xy 12.451638 -272.493195)
			(xy 12.444154 -272.511262) (xy 13.690328 -272.511262) (xy 13.690328 -272.451326) (xy 13.698151 -272.391904)
			(xy 13.713664 -272.334011) (xy 13.7366 -272.278638) (xy 13.766567 -272.226732) (xy 13.803054 -272.179182)
			(xy 13.845434 -272.136802) (xy 13.892984 -272.100315) (xy 13.94489 -272.070348) (xy 14.000263 -272.047412)
			(xy 14.058156 -272.031899) (xy 14.117578 -272.024076) (xy 14.177514 -272.024076) (xy 14.236936 -272.031899)
			(xy 14.294829 -272.047412) (xy 14.350202 -272.070348) (xy 14.402108 -272.100315) (xy 14.449658 -272.136802)
			(xy 14.492038 -272.179182) (xy 14.528525 -272.226732) (xy 14.558492 -272.278638) (xy 14.581428 -272.334011)
			(xy 14.596941 -272.391904) (xy 14.604764 -272.451326) (xy 14.605254 -272.481294) (xy 14.604764 -272.511262)
			(xy 14.596941 -272.570684) (xy 14.581428 -272.628577) (xy 14.558492 -272.68395) (xy 14.528525 -272.735856)
			(xy 14.492038 -272.783406) (xy 14.449658 -272.825786) (xy 14.402108 -272.862273) (xy 14.350202 -272.89224)
			(xy 14.294829 -272.915176) (xy 14.236936 -272.930689) (xy 14.177514 -272.938512) (xy 14.117578 -272.938512)
			(xy 14.058156 -272.930689) (xy 14.000263 -272.915176) (xy 13.94489 -272.89224) (xy 13.892984 -272.862273)
			(xy 13.845434 -272.825786) (xy 13.803054 -272.783406) (xy 13.766567 -272.735856) (xy 13.7366 -272.68395)
			(xy 13.713664 -272.628577) (xy 13.698151 -272.570684) (xy 13.690328 -272.511262) (xy 12.444154 -272.511262)
			(xy 12.428702 -272.548568) (xy 12.398735 -272.600474) (xy 12.362248 -272.648024) (xy 12.319868 -272.690404)
			(xy 12.272318 -272.726891) (xy 12.220412 -272.756858) (xy 12.165039 -272.779794) (xy 12.107146 -272.795307)
			(xy 12.047724 -272.80313) (xy 11.987788 -272.80313) (xy 11.928366 -272.795307) (xy 11.870473 -272.779794)
			(xy 11.8151 -272.756858) (xy 11.763194 -272.726891) (xy 11.715644 -272.690404) (xy 11.673264 -272.648024)
			(xy 11.636777 -272.600474) (xy 11.60681 -272.548568) (xy 11.583874 -272.493195) (xy 11.568361 -272.435302)
			(xy 11.560538 -272.37588) (xy 10.803894 -272.37588) (xy 10.787634 -272.39214) (xy 10.780826 -272.399486)
			(xy 10.773103 -272.417949) (xy 10.772648 -272.427954) (xy 10.772648 -272.752566) (xy 10.77216 -272.762527)
			(xy 10.764567 -272.780947) (xy 10.757916 -272.78838) (xy 10.598154 -272.948142) (xy 15.186134 -272.948142)
			(xy 15.186134 -272.888206) (xy 15.193957 -272.828784) (xy 15.20947 -272.770891) (xy 15.232406 -272.715518)
			(xy 15.262373 -272.663612) (xy 15.29886 -272.616062) (xy 15.34124 -272.573682) (xy 15.38879 -272.537195)
			(xy 15.440696 -272.507228) (xy 15.496069 -272.484292) (xy 15.553962 -272.468779) (xy 15.613384 -272.460956)
			(xy 15.67332 -272.460956) (xy 15.732742 -272.468779) (xy 15.790635 -272.484292) (xy 15.846008 -272.507228)
			(xy 15.897914 -272.537195) (xy 15.945464 -272.573682) (xy 15.987844 -272.616062) (xy 16.024331 -272.663612)
			(xy 16.054298 -272.715518) (xy 16.077234 -272.770891) (xy 16.092747 -272.828784) (xy 16.10057 -272.888206)
			(xy 16.10106 -272.918174) (xy 16.10057 -272.948142) (xy 16.092747 -273.007564) (xy 16.077234 -273.065457)
			(xy 16.054298 -273.12083) (xy 16.024331 -273.172736) (xy 15.987844 -273.220286) (xy 15.945464 -273.262666)
			(xy 15.897914 -273.299153) (xy 15.846008 -273.32912) (xy 15.790635 -273.352056) (xy 15.732742 -273.367569)
			(xy 15.67332 -273.375392) (xy 15.613384 -273.375392) (xy 15.553962 -273.367569) (xy 15.496069 -273.352056)
			(xy 15.440696 -273.32912) (xy 15.38879 -273.299153) (xy 15.34124 -273.262666) (xy 15.29886 -273.220286)
			(xy 15.262373 -273.172736) (xy 15.232406 -273.12083) (xy 15.20947 -273.065457) (xy 15.193957 -273.007564)
			(xy 15.186134 -272.948142) (xy 10.598154 -272.948142) (xy 10.59561 -272.950686) (xy 10.588266 -272.9575)
			(xy 10.569804 -272.965238) (xy 10.559796 -272.965672) (xy 10.556494 -272.965672) (xy 9.409715 -274.112224)
			(xy 10.00047 -274.112224) (xy 10.00047 -274.052288) (xy 10.008293 -273.992866) (xy 10.023806 -273.934973)
			(xy 10.046742 -273.8796) (xy 10.076709 -273.827694) (xy 10.113196 -273.780144) (xy 10.155576 -273.737764)
			(xy 10.203126 -273.701277) (xy 10.255032 -273.67131) (xy 10.310405 -273.648374) (xy 10.368298 -273.632861)
			(xy 10.42772 -273.625038) (xy 10.487656 -273.625038) (xy 10.547078 -273.632861) (xy 10.604971 -273.648374)
			(xy 10.660344 -273.67131) (xy 10.71225 -273.701277) (xy 10.7598 -273.737764) (xy 10.80218 -273.780144)
			(xy 10.838667 -273.827694) (xy 10.868634 -273.8796) (xy 10.89157 -273.934973) (xy 10.907083 -273.992866)
			(xy 10.914906 -274.052288) (xy 10.915396 -274.082256) (xy 10.914906 -274.112224) (xy 10.907083 -274.171646)
			(xy 10.89157 -274.229539) (xy 10.877879 -274.262592) (xy 15.318468 -274.262592) (xy 15.318468 -274.202656)
			(xy 15.326291 -274.143234) (xy 15.341804 -274.085341) (xy 15.36474 -274.029968) (xy 15.394707 -273.978062)
			(xy 15.431194 -273.930512) (xy 15.473574 -273.888132) (xy 15.521124 -273.851645) (xy 15.57303 -273.821678)
			(xy 15.628403 -273.798742) (xy 15.686296 -273.783229) (xy 15.745718 -273.775406) (xy 15.805654 -273.775406)
			(xy 15.865076 -273.783229) (xy 15.922969 -273.798742) (xy 15.978342 -273.821678) (xy 16.030248 -273.851645)
			(xy 16.077798 -273.888132) (xy 16.120178 -273.930512) (xy 16.156665 -273.978062) (xy 16.186632 -274.029968)
			(xy 16.209568 -274.085341) (xy 16.225081 -274.143234) (xy 16.232904 -274.202656) (xy 16.233394 -274.232624)
			(xy 16.232904 -274.262592) (xy 16.225081 -274.322014) (xy 16.209568 -274.379907) (xy 16.186632 -274.43528)
			(xy 16.156665 -274.487186) (xy 16.120178 -274.534736) (xy 16.077798 -274.577116) (xy 16.030248 -274.613603)
			(xy 15.978342 -274.64357) (xy 15.922969 -274.666506) (xy 15.865076 -274.682019) (xy 15.805654 -274.689842)
			(xy 15.745718 -274.689842) (xy 15.686296 -274.682019) (xy 15.628403 -274.666506) (xy 15.57303 -274.64357)
			(xy 15.521124 -274.613603) (xy 15.473574 -274.577116) (xy 15.431194 -274.534736) (xy 15.394707 -274.487186)
			(xy 15.36474 -274.43528) (xy 15.341804 -274.379907) (xy 15.326291 -274.322014) (xy 15.318468 -274.262592)
			(xy 10.877879 -274.262592) (xy 10.868634 -274.284912) (xy 10.838667 -274.336818) (xy 10.80218 -274.384368)
			(xy 10.7598 -274.426748) (xy 10.71225 -274.463235) (xy 10.660344 -274.493202) (xy 10.604971 -274.516138)
			(xy 10.547078 -274.531651) (xy 10.487656 -274.539474) (xy 10.42772 -274.539474) (xy 10.368298 -274.531651)
			(xy 10.310405 -274.516138) (xy 10.255032 -274.493202) (xy 10.203126 -274.463235) (xy 10.155576 -274.426748)
			(xy 10.113196 -274.384368) (xy 10.076709 -274.336818) (xy 10.046742 -274.284912) (xy 10.023806 -274.229539)
			(xy 10.008293 -274.171646) (xy 10.00047 -274.112224) (xy 9.409715 -274.112224) (xy 9.275064 -274.246848)
			(xy 9.268218 -274.254246) (xy 9.260491 -274.272845) (xy 9.260078 -274.282916) (xy 9.260078 -275.502624)
			(xy 15.317978 -275.502624) (xy 15.318468 -275.472656) (xy 15.326291 -275.413234) (xy 15.341804 -275.355341)
			(xy 15.36474 -275.299968) (xy 15.394707 -275.248062) (xy 15.431194 -275.200512) (xy 15.473574 -275.158132)
			(xy 15.521124 -275.121645) (xy 15.57303 -275.091678) (xy 15.628403 -275.068742) (xy 15.686296 -275.053229)
			(xy 15.745718 -275.045406) (xy 15.805654 -275.045406) (xy 15.865076 -275.053229) (xy 15.922969 -275.068742)
			(xy 15.978342 -275.091678) (xy 16.030248 -275.121645) (xy 16.077798 -275.158132) (xy 16.120178 -275.200512)
			(xy 16.156665 -275.248062) (xy 16.186632 -275.299968) (xy 16.209568 -275.355341) (xy 16.225081 -275.413234)
			(xy 16.232904 -275.472656) (xy 16.233394 -275.502624) (xy 16.232933 -275.531586) (xy 16.225618 -275.589047)
			(xy 16.211108 -275.645125) (xy 16.189635 -275.698922) (xy 16.161543 -275.749579) (xy 16.127281 -275.796284)
			(xy 16.087398 -275.838291) (xy 16.065246 -275.856954) (xy 16.057118 -275.863812) (xy 16.047466 -275.882354)
			(xy 16.040862 -275.97735) (xy 16.047974 -275.997162) (xy 16.055086 -276.004782) (xy 16.07418 -276.026077)
			(xy 16.106433 -276.073309) (xy 16.131277 -276.124826) (xy 16.148154 -276.179473) (xy 16.156686 -276.236027)
			(xy 16.157194 -276.264624) (xy 16.156708 -276.291875) (xy 16.148952 -276.345823) (xy 16.133597 -276.398118)
			(xy 16.110955 -276.447695) (xy 16.081489 -276.493545) (xy 16.045798 -276.534736) (xy 16.004607 -276.570427)
			(xy 15.958757 -276.599893) (xy 15.90918 -276.622535) (xy 15.856885 -276.63789) (xy 15.802937 -276.645646)
			(xy 15.748435 -276.645646) (xy 15.694487 -276.63789) (xy 15.642192 -276.622535) (xy 15.592615 -276.599893)
			(xy 15.546765 -276.570427) (xy 15.505574 -276.534736) (xy 15.469883 -276.493545) (xy 15.440417 -276.447695)
			(xy 15.417775 -276.398118) (xy 15.40242 -276.345823) (xy 15.394664 -276.291875) (xy 15.394178 -276.264624)
			(xy 15.394707 -276.236029) (xy 15.403246 -276.179479) (xy 15.420122 -276.124834) (xy 15.444957 -276.073317)
			(xy 15.477197 -276.026079) (xy 15.496286 -276.004782) (xy 15.503398 -275.997162) (xy 15.51051 -275.97735)
			(xy 15.503906 -275.882354) (xy 15.494254 -275.863812) (xy 15.486126 -275.856954) (xy 15.464001 -275.838259)
			(xy 15.424107 -275.796263) (xy 15.389836 -275.749566) (xy 15.361736 -275.698915) (xy 15.340257 -275.645121)
			(xy 15.325743 -275.589045) (xy 15.318426 -275.531586) (xy 15.317978 -275.502624) (xy 9.260078 -275.502624)
			(xy 9.260078 -276.507702) (xy 9.259654 -276.517772) (xy 9.251937 -276.536373) (xy 9.245092 -276.54377)
			(xy 8.998712 -276.79015) (xy 8.992019 -276.797557) (xy 8.984417 -276.815993) (xy 8.98398 -276.825964)
			(xy 8.98398 -277.310592) (xy 15.318468 -277.310592) (xy 15.318468 -277.250656) (xy 15.326291 -277.191234)
			(xy 15.341804 -277.133341) (xy 15.36474 -277.077968) (xy 15.394707 -277.026062) (xy 15.431194 -276.978512)
			(xy 15.473574 -276.936132) (xy 15.521124 -276.899645) (xy 15.57303 -276.869678) (xy 15.628403 -276.846742)
			(xy 15.686296 -276.831229) (xy 15.745718 -276.823406) (xy 15.805654 -276.823406) (xy 15.865076 -276.831229)
			(xy 15.922969 -276.846742) (xy 15.978342 -276.869678) (xy 16.030248 -276.899645) (xy 16.077798 -276.936132)
			(xy 16.120178 -276.978512) (xy 16.156665 -277.026062) (xy 16.186632 -277.077968) (xy 16.209568 -277.133341)
			(xy 16.225081 -277.191234) (xy 16.232904 -277.250656) (xy 16.233394 -277.280624) (xy 16.232904 -277.310592)
			(xy 16.225081 -277.370014) (xy 16.209568 -277.427907) (xy 16.186632 -277.48328) (xy 16.156665 -277.535186)
			(xy 16.120178 -277.582736) (xy 16.077798 -277.625116) (xy 16.030248 -277.661603) (xy 15.978342 -277.69157)
			(xy 15.922969 -277.714506) (xy 15.865076 -277.730019) (xy 15.805654 -277.737842) (xy 15.745718 -277.737842)
			(xy 15.686296 -277.730019) (xy 15.628403 -277.714506) (xy 15.57303 -277.69157) (xy 15.521124 -277.661603)
			(xy 15.473574 -277.625116) (xy 15.431194 -277.582736) (xy 15.394707 -277.535186) (xy 15.36474 -277.48328)
			(xy 15.341804 -277.427907) (xy 15.326291 -277.370014) (xy 15.318468 -277.310592) (xy 8.98398 -277.310592)
			(xy 8.98398 -278.012144) (xy 8.984461 -278.022108) (xy 8.992041 -278.04054) (xy 8.998712 -278.047958)
			(xy 9.033256 -278.082502) (xy 9.040658 -278.089339) (xy 9.059256 -278.097053) (xy 9.069324 -278.097488)
			(xy 9.543796 -278.097488) (xy 9.544558 -278.09825) (xy 11.27887 -278.09825) (xy 11.291377 -278.097605)
			(xy 11.313476 -278.085884) (xy 11.321034 -278.075898) (xy 11.375136 -277.995126) (xy 11.377676 -277.970234)
			(xy 11.37285 -277.958296) (xy 11.36391 -277.935351) (xy 11.351346 -277.887737) (xy 11.345026 -277.8389)
			(xy 11.344656 -277.814278) (xy 11.345142 -277.787027) (xy 11.352898 -277.733079) (xy 11.368253 -277.680784)
			(xy 11.390895 -277.631207) (xy 11.420361 -277.585357) (xy 11.456052 -277.544166) (xy 11.497243 -277.508475)
			(xy 11.543093 -277.479009) (xy 11.59267 -277.456367) (xy 11.644965 -277.441012) (xy 11.698913 -277.433256)
			(xy 11.753415 -277.433256) (xy 11.807363 -277.441012) (xy 11.859658 -277.456367) (xy 11.909235 -277.479009)
			(xy 11.955085 -277.508475) (xy 11.996276 -277.544166) (xy 12.031967 -277.585357) (xy 12.061433 -277.631207)
			(xy 12.084075 -277.680784) (xy 12.09943 -277.733079) (xy 12.107186 -277.787027) (xy 12.107672 -277.814278)
			(xy 12.107284 -277.838899) (xy 12.100953 -277.887732) (xy 12.088405 -277.935348) (xy 12.079478 -277.958296)
			(xy 12.074652 -277.970234) (xy 12.077192 -277.995126) (xy 12.131294 -278.075898) (xy 12.138816 -278.085931)
			(xy 12.160934 -278.097678) (xy 12.173458 -278.09825) (xy 13.261594 -278.09825) (xy 13.271664 -278.098673)
			(xy 13.290265 -278.106392) (xy 13.297662 -278.113236) (xy 13.647928 -278.463502) (xy 13.654782 -278.470897)
			(xy 13.662527 -278.489496) (xy 13.662914 -278.49957) (xy 13.662914 -278.548338) (xy 13.662152 -278.5491)
			(xy 13.662152 -291.287708) (xy 13.661726 -291.297776) (xy 13.654004 -291.316374) (xy 13.647166 -291.323776)
			(xy 13.289534 -291.681408) (xy 13.282132 -291.688243) (xy 13.263533 -291.695952) (xy 13.253466 -291.696394)
			(xy 5.19938 -291.696394) (xy 5.189312 -291.695967) (xy 5.170713 -291.688247) (xy 5.163312 -291.681408)
			(xy 4.522724 -291.04082) (xy 4.515888 -291.033418) (xy 4.508178 -291.01482) (xy 4.507738 -291.004752)
			(xy 4.507738 -282.165806) (xy 4.507314 -282.155737) (xy 4.499595 -282.137136) (xy 4.492752 -282.129738)
			(xy 4.33451 -281.971496) (xy 4.327112 -281.964648) (xy 4.308514 -281.956911) (xy 4.298442 -281.95651)
			(xy 1.39827 -281.95651) (xy 1.388267 -281.957003) (xy 1.369787 -281.964669) (xy 1.355646 -281.978821)
			(xy 1.347996 -281.997307) (xy 1.34747 -282.00731) (xy 1.34747 -292.921182) (xy 1.347976 -292.931232)
			(xy 1.355697 -292.949793) (xy 1.362456 -292.95725) (xy 2.959354 -294.554148) (xy 2.966198 -294.561547)
			(xy 2.973922 -294.580146) (xy 2.97434 -294.590216) (xy 2.97434 -305.189632) (xy 12.502624 -305.189632)
			(xy 12.502624 -305.129696) (xy 12.510447 -305.070274) (xy 12.52596 -305.012381) (xy 12.548896 -304.957008)
			(xy 12.578863 -304.905102) (xy 12.61535 -304.857552) (xy 12.65773 -304.815172) (xy 12.70528 -304.778685)
			(xy 12.757186 -304.748718) (xy 12.812559 -304.725782) (xy 12.870452 -304.710269) (xy 12.929874 -304.702446)
			(xy 12.98981 -304.702446) (xy 13.049232 -304.710269) (xy 13.107125 -304.725782) (xy 13.162498 -304.748718)
			(xy 13.214404 -304.778685) (xy 13.261954 -304.815172) (xy 13.304334 -304.857552) (xy 13.340821 -304.905102)
			(xy 13.370788 -304.957008) (xy 13.393724 -305.012381) (xy 13.409237 -305.070274) (xy 13.41706 -305.129696)
			(xy 13.41755 -305.159664) (xy 13.41706 -305.189632) (xy 13.409237 -305.249054) (xy 13.393724 -305.306947)
			(xy 13.370788 -305.36232) (xy 13.340821 -305.414226) (xy 13.304334 -305.461776) (xy 13.261954 -305.504156)
			(xy 13.214404 -305.540643) (xy 13.162498 -305.57061) (xy 13.107125 -305.593546) (xy 13.049232 -305.609059)
			(xy 12.98981 -305.616882) (xy 12.929874 -305.616882) (xy 12.870452 -305.609059) (xy 12.812559 -305.593546)
			(xy 12.757186 -305.57061) (xy 12.70528 -305.540643) (xy 12.65773 -305.504156) (xy 12.61535 -305.461776)
			(xy 12.578863 -305.414226) (xy 12.548896 -305.36232) (xy 12.52596 -305.306947) (xy 12.510447 -305.249054)
			(xy 12.502624 -305.189632) (xy 2.97434 -305.189632) (xy 2.97434 -307.651654) (xy 11.94865 -307.651654)
			(xy 11.94865 -307.591718) (xy 11.956473 -307.532296) (xy 11.971986 -307.474403) (xy 11.994922 -307.41903)
			(xy 12.024889 -307.367124) (xy 12.061376 -307.319574) (xy 12.103756 -307.277194) (xy 12.151306 -307.240707)
			(xy 12.203212 -307.21074) (xy 12.258585 -307.187804) (xy 12.316478 -307.172291) (xy 12.3759 -307.164468)
			(xy 12.435836 -307.164468) (xy 12.495258 -307.172291) (xy 12.553151 -307.187804) (xy 12.608524 -307.21074)
			(xy 12.66043 -307.240707) (xy 12.70798 -307.277194) (xy 12.75036 -307.319574) (xy 12.786847 -307.367124)
			(xy 12.816814 -307.41903) (xy 12.83975 -307.474403) (xy 12.855263 -307.532296) (xy 12.863086 -307.591718)
			(xy 12.863576 -307.621686) (xy 12.863086 -307.651654) (xy 12.855263 -307.711076) (xy 12.83975 -307.768969)
			(xy 12.816814 -307.824342) (xy 12.786847 -307.876248) (xy 12.75036 -307.923798) (xy 12.70798 -307.966178)
			(xy 12.66043 -308.002665) (xy 12.608524 -308.032632) (xy 12.553151 -308.055568) (xy 12.495258 -308.071081)
			(xy 12.435836 -308.078904) (xy 12.3759 -308.078904) (xy 12.316478 -308.071081) (xy 12.258585 -308.055568)
			(xy 12.203212 -308.032632) (xy 12.151306 -308.002665) (xy 12.103756 -307.966178) (xy 12.061376 -307.923798)
			(xy 12.024889 -307.876248) (xy 11.994922 -307.824342) (xy 11.971986 -307.768969) (xy 11.956473 -307.711076)
			(xy 11.94865 -307.651654) (xy 2.97434 -307.651654) (xy 2.97434 -318.52997) (xy 10.590784 -318.52997)
			(xy 10.591212 -318.502598) (xy 10.599036 -318.448417) (xy 10.614533 -318.395912) (xy 10.637383 -318.346166)
			(xy 10.667118 -318.300202) (xy 10.684764 -318.279272) (xy 10.69086 -318.27216) (xy 10.69721 -318.255142)
			(xy 10.69721 -318.169798) (xy 10.69086 -318.15278) (xy 10.684764 -318.145668) (xy 10.667138 -318.124726)
			(xy 10.637425 -318.078755) (xy 10.614587 -318.02901) (xy 10.599093 -317.976512) (xy 10.591261 -317.922338)
			(xy 10.590784 -317.89497) (xy 10.59125 -317.867718) (xy 10.59901 -317.81377) (xy 10.614369 -317.761476)
			(xy 10.637013 -317.711899) (xy 10.666482 -317.666049) (xy 10.702175 -317.624859) (xy 10.743367 -317.589168)
			(xy 10.789218 -317.559702) (xy 10.838796 -317.537061) (xy 10.891092 -317.521706) (xy 10.94504 -317.513948)
			(xy 10.972292 -317.513462) (xy 10.999663 -317.513918) (xy 11.053843 -317.521736) (xy 11.106347 -317.537226)
			(xy 11.156093 -317.560071) (xy 11.202059 -317.589799) (xy 11.22299 -317.607442) (xy 11.230102 -317.613538)
			(xy 11.24712 -317.619888) (xy 11.332464 -317.619888) (xy 11.349482 -317.613538) (xy 11.356594 -317.607442)
			(xy 11.377527 -317.589801) (xy 11.423495 -317.560077) (xy 11.473241 -317.537231) (xy 11.525743 -317.521735)
			(xy 11.579921 -317.513906) (xy 11.634663 -317.513906) (xy 11.688841 -317.521735) (xy 11.741343 -317.537231)
			(xy 11.791089 -317.560077) (xy 11.837057 -317.589801) (xy 11.85799 -317.607442) (xy 11.865102 -317.613538)
			(xy 11.88212 -317.619888) (xy 11.967464 -317.619888) (xy 11.984482 -317.613538) (xy 11.991594 -317.607442)
			(xy 12.012523 -317.589799) (xy 12.058496 -317.560086) (xy 12.108244 -317.53725) (xy 12.160746 -317.52176)
			(xy 12.214922 -317.513934) (xy 12.242292 -317.513462) (xy 12.269542 -317.513985) (xy 12.323487 -317.52174)
			(xy 12.375779 -317.537092) (xy 12.425354 -317.55973) (xy 12.471203 -317.589193) (xy 12.512393 -317.624881)
			(xy 12.548084 -317.666067) (xy 12.577551 -317.711913) (xy 12.600194 -317.761486) (xy 12.615552 -317.813776)
			(xy 12.623312 -317.86772) (xy 12.6238 -317.89497) (xy 12.623316 -317.92234) (xy 12.615503 -317.976518)
			(xy 12.600018 -318.029021) (xy 12.57718 -318.078768) (xy 12.547459 -318.124736) (xy 12.52982 -318.145668)
			(xy 12.523724 -318.15278) (xy 12.517374 -318.169798) (xy 12.517374 -318.255142) (xy 12.523724 -318.27216)
			(xy 12.52982 -318.279272) (xy 12.547463 -318.300201) (xy 12.577173 -318.346175) (xy 12.600008 -318.395923)
			(xy 12.615498 -318.448425) (xy 12.623326 -318.502601) (xy 12.6238 -318.52997) (xy 12.623317 -318.557222)
			(xy 12.615564 -318.611173) (xy 12.600211 -318.663471) (xy 12.577571 -318.713052) (xy 12.548106 -318.758905)
			(xy 12.512414 -318.800099) (xy 12.471223 -318.835793) (xy 12.425371 -318.865261) (xy 12.375792 -318.887903)
			(xy 12.323495 -318.903259) (xy 12.269544 -318.911015) (xy 12.242292 -318.911478) (xy 12.214921 -318.911022)
			(xy 12.160742 -318.903203) (xy 12.108238 -318.887711) (xy 12.058491 -318.864867) (xy 12.012525 -318.83514)
			(xy 11.991594 -318.817498) (xy 11.984482 -318.811402) (xy 11.967464 -318.805052) (xy 11.88212 -318.805052)
			(xy 11.865102 -318.811402) (xy 11.85799 -318.817498) (xy 11.837057 -318.835139) (xy 11.791089 -318.864863)
			(xy 11.741343 -318.887709) (xy 11.688841 -318.903205) (xy 11.634663 -318.911034) (xy 11.579921 -318.911034)
			(xy 11.525743 -318.903205) (xy 11.473241 -318.887709) (xy 11.423495 -318.864863) (xy 11.377527 -318.835139)
			(xy 11.356594 -318.817498) (xy 11.349482 -318.811402) (xy 11.332464 -318.805052) (xy 11.24712 -318.805052)
			(xy 11.230102 -318.811402) (xy 11.22299 -318.817498) (xy 11.202072 -318.835155) (xy 11.156096 -318.864864)
			(xy 11.106344 -318.887697) (xy 11.053841 -318.903184) (xy 10.999662 -318.911007) (xy 10.972292 -318.911478)
			(xy 10.945038 -318.911052) (xy 10.891084 -318.903293) (xy 10.838783 -318.887935) (xy 10.789201 -318.865289)
			(xy 10.743347 -318.835817) (xy 10.702153 -318.80012) (xy 10.66646 -318.758923) (xy 10.636993 -318.713065)
			(xy 10.614352 -318.663481) (xy 10.598999 -318.611179) (xy 10.591245 -318.557224) (xy 10.590784 -318.52997)
			(xy 2.97434 -318.52997) (xy 2.97434 -318.835786) (xy 2.974811 -318.845659) (xy 2.982265 -318.863945)
			(xy 2.988818 -318.871346) (xy 2.989072 -318.8716) (xy 3.258566 -319.141094) (xy 3.259074 -319.141602)
			(xy 3.266454 -319.148187) (xy 3.284754 -319.155637) (xy 3.294634 -319.15608)
		)
		(stroke
			(width 0)
			(type solid)
		)
		(fill yes)
		(layer "B.Cu")
		(net "GND")
	)
	(gr_poly
		(pts
			(xy 331.705204 -122.654822) (xy 331.715624 -122.65431) (xy 331.734756 -122.64604) (xy 331.742288 -122.63882)
			(xy 331.8002 -122.577352) (xy 331.807312 -122.558048) (xy 331.806804 -122.54738) (xy 331.806042 -122.525028)
			(xy 331.806528 -122.497777) (xy 331.814284 -122.443829) (xy 331.829639 -122.391534) (xy 331.852281 -122.341957)
			(xy 331.881747 -122.296107) (xy 331.917438 -122.254916) (xy 331.958629 -122.219225) (xy 332.004479 -122.189759)
			(xy 332.054056 -122.167117) (xy 332.106351 -122.151762) (xy 332.160299 -122.144006) (xy 332.214801 -122.144006)
			(xy 332.268749 -122.151762) (xy 332.321044 -122.167117) (xy 332.370621 -122.189759) (xy 332.416471 -122.219225)
			(xy 332.457662 -122.254916) (xy 332.493353 -122.296107) (xy 332.522819 -122.341957) (xy 332.545461 -122.391534)
			(xy 332.560816 -122.443829) (xy 332.568572 -122.497777) (xy 332.569058 -122.525028) (xy 332.568296 -122.54738)
			(xy 332.567788 -122.558048) (xy 332.5749 -122.577352) (xy 332.632812 -122.63882) (xy 332.640312 -122.646086)
			(xy 332.659464 -122.654349) (xy 332.669896 -122.654822) (xy 334.331818 -122.654822) (xy 334.341887 -122.654396)
			(xy 334.360489 -122.64668) (xy 334.367886 -122.639836) (xy 336.013044 -120.994678) (xy 336.019893 -120.987281)
			(xy 336.027628 -120.968682) (xy 336.02803 -120.95861) (xy 336.02803 -117.84838) (xy 336.027604 -117.838311)
			(xy 336.019888 -117.819709) (xy 336.013044 -117.812312) (xy 335.622392 -117.42166) (xy 335.615715 -117.414248)
			(xy 335.608149 -117.395812) (xy 335.60766 -117.385846) (xy 335.60766 -114.64798) (xy 335.607118 -114.637995)
			(xy 335.599395 -114.619572) (xy 335.592674 -114.612166) (xy 335.472278 -114.49177) (xy 335.464882 -114.48492)
			(xy 335.446283 -114.477182) (xy 335.43621 -114.476784) (xy 333.050388 -114.476784) (xy 333.041493 -114.477111)
			(xy 333.024772 -114.483186) (xy 333.011151 -114.494629) (xy 333.006446 -114.502184) (xy 332.991571 -114.526751)
			(xy 332.955609 -114.571526) (xy 332.934818 -114.591338) (xy 332.92738 -114.598833) (xy 332.918862 -114.618129)
			(xy 332.918308 -114.628676) (xy 332.918308 -114.703352) (xy 332.91889 -114.713889) (xy 332.927413 -114.733172)
			(xy 332.934818 -114.74069) (xy 332.953881 -114.758839) (xy 332.98734 -114.79947) (xy 333.014901 -114.844311)
			(xy 333.036042 -114.892513) (xy 333.050362 -114.943161) (xy 333.057589 -114.995297) (xy 333.058008 -115.021614)
			(xy 333.057585 -115.047932) (xy 333.05038 -115.100072) (xy 333.03607 -115.150724) (xy 333.014925 -115.198925)
			(xy 332.987348 -115.243757) (xy 332.953863 -115.284369) (xy 332.934818 -115.302538) (xy 332.92738 -115.310033)
			(xy 332.918862 -115.329329) (xy 332.918308 -115.339876) (xy 332.918308 -115.414552) (xy 332.91889 -115.425089)
			(xy 332.927413 -115.444372) (xy 332.934818 -115.45189) (xy 332.953881 -115.470039) (xy 332.98734 -115.51067)
			(xy 333.014901 -115.555511) (xy 333.036042 -115.603713) (xy 333.050362 -115.654361) (xy 333.057589 -115.706497)
			(xy 333.058008 -115.732814) (xy 333.057522 -115.760065) (xy 333.049766 -115.814013) (xy 333.034411 -115.866308)
			(xy 333.011769 -115.915885) (xy 332.982303 -115.961735) (xy 332.946612 -116.002926) (xy 332.905421 -116.038617)
			(xy 332.859571 -116.068083) (xy 332.809994 -116.090725) (xy 332.757699 -116.10608) (xy 332.703751 -116.113836)
			(xy 332.649249 -116.113836) (xy 332.595301 -116.10608) (xy 332.543006 -116.090725) (xy 332.493429 -116.068083)
			(xy 332.447579 -116.038617) (xy 332.406388 -116.002926) (xy 332.370697 -115.961735) (xy 332.341231 -115.915885)
			(xy 332.318589 -115.866308) (xy 332.303234 -115.814013) (xy 332.295478 -115.760065) (xy 332.294992 -115.732814)
			(xy 332.295414 -115.706495) (xy 332.302614 -115.654354) (xy 332.316922 -115.603699) (xy 332.338065 -115.555495)
			(xy 332.36564 -115.51066) (xy 332.399123 -115.470046) (xy 332.418182 -115.45189) (xy 332.425625 -115.444396)
			(xy 332.434153 -115.425101) (xy 332.434692 -115.414552) (xy 332.434692 -115.339876) (xy 332.434116 -115.329336)
			(xy 332.4256 -115.310046) (xy 332.418182 -115.302538) (xy 332.399123 -115.284387) (xy 332.365672 -115.243755)
			(xy 332.338119 -115.198913) (xy 332.316987 -115.150711) (xy 332.302676 -115.100063) (xy 332.295459 -115.047929)
			(xy 332.294992 -115.021614) (xy 332.295414 -114.995295) (xy 332.302614 -114.943154) (xy 332.316922 -114.892499)
			(xy 332.338065 -114.844295) (xy 332.36564 -114.79946) (xy 332.399123 -114.758846) (xy 332.418182 -114.74069)
			(xy 332.425625 -114.733196) (xy 332.434153 -114.713901) (xy 332.434692 -114.703352) (xy 332.434692 -114.628676)
			(xy 332.434116 -114.618136) (xy 332.4256 -114.598846) (xy 332.418182 -114.591338) (xy 332.397396 -114.571521)
			(xy 332.361429 -114.526751) (xy 332.346554 -114.502184) (xy 332.341774 -114.494692) (xy 332.328169 -114.483281)
			(xy 332.31149 -114.477191) (xy 332.302612 -114.476784) (xy 330.512166 -114.476784) (xy 330.503272 -114.477114)
			(xy 330.486558 -114.483194) (xy 330.472943 -114.494639) (xy 330.468224 -114.502184) (xy 330.453348 -114.52675)
			(xy 330.417384 -114.571524) (xy 330.396596 -114.591338) (xy 330.38916 -114.598835) (xy 330.380647 -114.61813)
			(xy 330.380086 -114.628676) (xy 330.380086 -114.703352) (xy 330.380667 -114.71389) (xy 330.389188 -114.733174)
			(xy 330.396596 -114.74069) (xy 330.41566 -114.758839) (xy 330.449121 -114.799469) (xy 330.476683 -114.844309)
			(xy 330.497826 -114.892511) (xy 330.512147 -114.94316) (xy 330.519375 -114.995297) (xy 330.519786 -115.021614)
			(xy 330.519363 -115.047932) (xy 330.51216 -115.100074) (xy 330.497851 -115.150728) (xy 330.476709 -115.198931)
			(xy 330.449136 -115.243768) (xy 330.415656 -115.284384) (xy 330.396596 -115.302538) (xy 330.38916 -115.310035)
			(xy 330.380647 -115.32933) (xy 330.380086 -115.339876) (xy 330.380086 -115.414552) (xy 330.380667 -115.42509)
			(xy 330.389188 -115.444374) (xy 330.396596 -115.45189) (xy 330.41566 -115.470039) (xy 330.449121 -115.510669)
			(xy 330.476683 -115.555509) (xy 330.497826 -115.603711) (xy 330.512147 -115.65436) (xy 330.519375 -115.706497)
			(xy 330.519786 -115.732814) (xy 330.5193 -115.760065) (xy 330.511544 -115.814013) (xy 330.496189 -115.866308)
			(xy 330.473547 -115.915885) (xy 330.444081 -115.961735) (xy 330.40839 -116.002926) (xy 330.367199 -116.038617)
			(xy 330.321349 -116.068083) (xy 330.271772 -116.090725) (xy 330.219477 -116.10608) (xy 330.165529 -116.113836)
			(xy 330.111027 -116.113836) (xy 330.057079 -116.10608) (xy 330.004784 -116.090725) (xy 329.955207 -116.068083)
			(xy 329.909357 -116.038617) (xy 329.868166 -116.002926) (xy 329.832475 -115.961735) (xy 329.803009 -115.915885)
			(xy 329.780367 -115.866308) (xy 329.765012 -115.814013) (xy 329.757256 -115.760065) (xy 329.75677 -115.732814)
			(xy 329.757191 -115.706495) (xy 329.764392 -115.654353) (xy 329.778699 -115.603698) (xy 329.799841 -115.555493)
			(xy 329.827415 -115.510657) (xy 329.860897 -115.470041) (xy 329.87996 -115.45189) (xy 329.887405 -115.444397)
			(xy 329.895937 -115.425101) (xy 329.89647 -115.414552) (xy 329.89647 -115.339876) (xy 329.895893 -115.329337)
			(xy 329.887374 -115.310049) (xy 329.87996 -115.302538) (xy 329.860902 -115.284387) (xy 329.827452 -115.243754)
			(xy 329.799901 -115.198911) (xy 329.778771 -115.150709) (xy 329.764461 -115.100062) (xy 329.757244 -115.047929)
			(xy 329.75677 -115.021614) (xy 329.757191 -114.995295) (xy 329.764392 -114.943153) (xy 329.778699 -114.892498)
			(xy 329.799841 -114.844293) (xy 329.827415 -114.799457) (xy 329.860897 -114.758841) (xy 329.87996 -114.74069)
			(xy 329.887405 -114.733197) (xy 329.895937 -114.713901) (xy 329.89647 -114.703352) (xy 329.89647 -114.628676)
			(xy 329.895893 -114.618137) (xy 329.887374 -114.598849) (xy 329.87996 -114.591338) (xy 329.859175 -114.57152)
			(xy 329.823209 -114.526749) (xy 329.808332 -114.502184) (xy 329.803551 -114.494695) (xy 329.789945 -114.483289)
			(xy 329.773266 -114.477206) (xy 329.76439 -114.476784) (xy 325.279258 -114.476784) (xy 325.270075 -114.477126)
			(xy 325.252857 -114.483511) (xy 325.238995 -114.495555) (xy 325.2343 -114.503454) (xy 325.220921 -114.527409)
			(xy 325.188339 -114.571556) (xy 325.149766 -114.610575) (xy 325.105997 -114.643663) (xy 325.057937 -114.670134)
			(xy 325.006579 -114.689443) (xy 324.952984 -114.70119) (xy 324.898258 -114.705133) (xy 324.843532 -114.70119)
			(xy 324.789937 -114.689443) (xy 324.738579 -114.670134) (xy 324.690519 -114.643663) (xy 324.64675 -114.610575)
			(xy 324.608177 -114.571556) (xy 324.575595 -114.527409) (xy 324.562216 -114.503454) (xy 324.557512 -114.495561)
			(xy 324.543654 -114.483516) (xy 324.52644 -114.477127) (xy 324.517258 -114.476784) (xy 324.466458 -114.476784)
			(xy 324.457275 -114.477126) (xy 324.440057 -114.483511) (xy 324.426195 -114.495555) (xy 324.4215 -114.503454)
			(xy 324.408121 -114.527409) (xy 324.375539 -114.571556) (xy 324.336966 -114.610575) (xy 324.293197 -114.643663)
			(xy 324.245137 -114.670134) (xy 324.193779 -114.689443) (xy 324.140184 -114.70119) (xy 324.085458 -114.705133)
			(xy 324.030732 -114.70119) (xy 323.977137 -114.689443) (xy 323.925779 -114.670134) (xy 323.877719 -114.643663)
			(xy 323.83395 -114.610575) (xy 323.795377 -114.571556) (xy 323.762795 -114.527409) (xy 323.749416 -114.503454)
			(xy 323.742558 -114.491008) (xy 323.718682 -114.476784) (xy 323.690234 -114.476784) (xy 323.666358 -114.491008)
			(xy 323.6595 -114.503454) (xy 323.646121 -114.527409) (xy 323.613539 -114.571556) (xy 323.574966 -114.610575)
			(xy 323.531197 -114.643663) (xy 323.483137 -114.670134) (xy 323.431779 -114.689443) (xy 323.378184 -114.70119)
			(xy 323.323458 -114.705133) (xy 323.268732 -114.70119) (xy 323.215137 -114.689443) (xy 323.163779 -114.670134)
			(xy 323.115719 -114.643663) (xy 323.07195 -114.610575) (xy 323.033377 -114.571556) (xy 323.000795 -114.527409)
			(xy 322.987416 -114.503454) (xy 322.982712 -114.495561) (xy 322.968854 -114.483516) (xy 322.95164 -114.477127)
			(xy 322.942458 -114.476784) (xy 322.213986 -114.476784) (xy 322.204842 -114.480594) (xy 322.177062 -114.491522)
			(xy 322.119382 -114.506903) (xy 322.060192 -114.51466) (xy 322.000496 -114.51466) (xy 321.941306 -114.506903)
			(xy 321.883626 -114.491522) (xy 321.855846 -114.480594) (xy 321.846702 -114.476784) (xy 308.037738 -114.476784)
			(xy 308.027673 -114.476349) (xy 308.009087 -114.468617) (xy 308.00167 -114.461798) (xy 307.97881 -114.438938)
			(xy 307.964332 -114.431826) (xy 307.955696 -114.430556) (xy 307.922163 -114.425438) (xy 307.85688 -114.407017)
			(xy 307.79482 -114.379634) (xy 307.765704 -114.36223) (xy 307.759608 -114.35842) (xy 307.745892 -114.354356)
			(xy 307.733192 -114.354356) (xy 307.70322 -114.324892) (xy 307.70322 -114.316764) (xy 307.687472 -114.301778)
			(xy 307.664253 -114.278898) (xy 307.623558 -114.227975) (xy 307.590085 -114.172038) (xy 307.564444 -114.112106)
			(xy 307.547102 -114.049269) (xy 307.542184 -114.017044) (xy 307.540914 -114.008408) (xy 307.533802 -113.99393)
			(xy 306.773834 -113.233962) (xy 306.766435 -113.227119) (xy 306.747836 -113.219399) (xy 306.737766 -113.218976)
			(xy 305.758342 -113.218976) (xy 305.748276 -113.219409) (xy 305.729684 -113.227136) (xy 305.722274 -113.233962)
			(xy 305.654202 -113.302034) (xy 305.647361 -113.309434) (xy 305.639638 -113.328032) (xy 305.639216 -113.338102)
			(xy 305.639216 -113.766854) (xy 305.638784 -113.77692) (xy 305.631057 -113.795512) (xy 305.62423 -113.802922)
			(xy 305.570382 -113.85677) (xy 305.563538 -113.864168) (xy 305.555816 -113.882768) (xy 305.555396 -113.892838)
			(xy 305.555396 -115.400836) (xy 319.460624 -115.400836) (xy 319.464695 -115.345214) (xy 319.476821 -115.290777)
			(xy 319.496744 -115.238686) (xy 319.52404 -115.190051) (xy 319.558126 -115.145908) (xy 319.598275 -115.107199)
			(xy 319.643633 -115.074748) (xy 319.693233 -115.049247) (xy 319.746017 -115.03124) (xy 319.80086 -115.02111)
			(xy 319.856594 -115.019073) (xy 319.912031 -115.025173) (xy 319.965988 -115.039279) (xy 320.017317 -115.061091)
			(xy 320.064923 -115.090145) (xy 320.107791 -115.12582) (xy 320.145008 -115.167357) (xy 320.175781 -115.21387)
			(xy 320.199453 -115.264367) (xy 320.215521 -115.317774) (xy 320.223641 -115.37295) (xy 320.224141 -115.400324)
			(xy 321.486004 -115.400324) (xy 321.486004 -115.340388) (xy 321.493827 -115.280966) (xy 321.50934 -115.223073)
			(xy 321.532276 -115.1677) (xy 321.562243 -115.115794) (xy 321.59873 -115.068244) (xy 321.64111 -115.025864)
			(xy 321.68866 -114.989377) (xy 321.740566 -114.95941) (xy 321.795939 -114.936474) (xy 321.853832 -114.920961)
			(xy 321.913254 -114.913138) (xy 321.97319 -114.913138) (xy 322.032612 -114.920961) (xy 322.090505 -114.936474)
			(xy 322.145878 -114.95941) (xy 322.197784 -114.989377) (xy 322.245334 -115.025864) (xy 322.287714 -115.068244)
			(xy 322.324201 -115.115794) (xy 322.354168 -115.1677) (xy 322.377104 -115.223073) (xy 322.392617 -115.280966)
			(xy 322.40044 -115.340388) (xy 322.40093 -115.370356) (xy 322.40044 -115.400324) (xy 322.392617 -115.459746)
			(xy 322.377104 -115.517639) (xy 322.354168 -115.573012) (xy 322.324201 -115.624918) (xy 322.287714 -115.672468)
			(xy 322.245334 -115.714848) (xy 322.197784 -115.751335) (xy 322.145878 -115.781302) (xy 322.090505 -115.804238)
			(xy 322.032612 -115.819751) (xy 321.97319 -115.827574) (xy 321.913254 -115.827574) (xy 321.853832 -115.819751)
			(xy 321.795939 -115.804238) (xy 321.740566 -115.781302) (xy 321.68866 -115.751335) (xy 321.64111 -115.714848)
			(xy 321.59873 -115.672468) (xy 321.562243 -115.624918) (xy 321.532276 -115.573012) (xy 321.50934 -115.517639)
			(xy 321.493827 -115.459746) (xy 321.486004 -115.400324) (xy 320.224141 -115.400324) (xy 320.22415 -115.400836)
			(xy 320.223641 -115.428722) (xy 320.215521 -115.483898) (xy 320.199453 -115.537305) (xy 320.175781 -115.587802)
			(xy 320.145008 -115.634315) (xy 320.107791 -115.675852) (xy 320.064923 -115.711527) (xy 320.017317 -115.740581)
			(xy 319.965988 -115.762393) (xy 319.912031 -115.776499) (xy 319.856594 -115.782599) (xy 319.80086 -115.780562)
			(xy 319.746017 -115.770432) (xy 319.693233 -115.752425) (xy 319.643633 -115.726924) (xy 319.598275 -115.694473)
			(xy 319.558126 -115.655764) (xy 319.52404 -115.611621) (xy 319.496744 -115.562986) (xy 319.476821 -115.510895)
			(xy 319.464695 -115.456458) (xy 319.460624 -115.400836) (xy 305.555396 -115.400836) (xy 305.555396 -115.832636)
			(xy 325.10349 -115.832636) (xy 325.104004 -115.800435) (xy 325.11304 -115.736669) (xy 325.130925 -115.674799)
			(xy 325.157306 -115.616047) (xy 325.191661 -115.561572) (xy 325.233313 -115.512451) (xy 325.281438 -115.469653)
			(xy 325.30796 -115.451382) (xy 325.31812 -115.444524) (xy 325.329804 -115.424204) (xy 325.335646 -115.318286)
			(xy 325.326248 -115.296696) (xy 325.316596 -115.288822) (xy 325.295562 -115.27059) (xy 325.258489 -115.22907)
			(xy 325.227841 -115.182604) (xy 325.204269 -115.132179) (xy 325.188272 -115.078864) (xy 325.180191 -115.023791)
			(xy 325.17969 -114.99596) (xy 325.180176 -114.968709) (xy 325.187932 -114.914761) (xy 325.203287 -114.862466)
			(xy 325.225929 -114.812889) (xy 325.255395 -114.767039) (xy 325.291086 -114.725848) (xy 325.332277 -114.690157)
			(xy 325.378127 -114.660691) (xy 325.427704 -114.638049) (xy 325.479999 -114.622694) (xy 325.533947 -114.614938)
			(xy 325.588449 -114.614938) (xy 325.642397 -114.622694) (xy 325.694692 -114.638049) (xy 325.744269 -114.660691)
			(xy 325.790119 -114.690157) (xy 325.83131 -114.725848) (xy 325.867001 -114.767039) (xy 325.896467 -114.812889)
			(xy 325.919109 -114.862466) (xy 325.934464 -114.914761) (xy 325.94222 -114.968709) (xy 325.942706 -114.99596)
			(xy 325.942167 -115.023789) (xy 325.934079 -115.078855) (xy 325.918082 -115.132165) (xy 325.894516 -115.182587)
			(xy 325.86388 -115.229054) (xy 325.826823 -115.270582) (xy 325.8058 -115.288822) (xy 325.796148 -115.296696)
			(xy 325.78675 -115.318286) (xy 325.790953 -115.394486) (xy 327.34707 -115.394486) (xy 327.351141 -115.338864)
			(xy 327.363267 -115.284427) (xy 327.38319 -115.232336) (xy 327.410486 -115.183701) (xy 327.444572 -115.139558)
			(xy 327.484721 -115.100849) (xy 327.530079 -115.068398) (xy 327.579679 -115.042897) (xy 327.632463 -115.02489)
			(xy 327.687306 -115.01476) (xy 327.74304 -115.012723) (xy 327.798477 -115.018823) (xy 327.852434 -115.032929)
			(xy 327.903763 -115.054741) (xy 327.951369 -115.083795) (xy 327.994237 -115.11947) (xy 328.031454 -115.161007)
			(xy 328.062227 -115.20752) (xy 328.085899 -115.258017) (xy 328.101967 -115.311424) (xy 328.110087 -115.3666)
			(xy 328.110596 -115.394486) (xy 328.110087 -115.422372) (xy 328.101967 -115.477548) (xy 328.085899 -115.530955)
			(xy 328.062227 -115.581452) (xy 328.031454 -115.627965) (xy 327.994237 -115.669502) (xy 327.951369 -115.705177)
			(xy 327.903763 -115.734231) (xy 327.852434 -115.756043) (xy 327.798477 -115.770149) (xy 327.74304 -115.776249)
			(xy 327.687306 -115.774212) (xy 327.632463 -115.764082) (xy 327.579679 -115.746075) (xy 327.530079 -115.720574)
			(xy 327.484721 -115.688123) (xy 327.444572 -115.649414) (xy 327.410486 -115.605271) (xy 327.38319 -115.556636)
			(xy 327.363267 -115.504545) (xy 327.351141 -115.450108) (xy 327.34707 -115.394486) (xy 325.790953 -115.394486)
			(xy 325.792592 -115.424204) (xy 325.804276 -115.444524) (xy 325.814436 -115.451382) (xy 325.840957 -115.469653)
			(xy 325.889083 -115.512449) (xy 325.930733 -115.561569) (xy 325.965085 -115.616044) (xy 325.991459 -115.674798)
			(xy 326.009335 -115.736669) (xy 326.01836 -115.800435) (xy 326.018906 -115.832636) (xy 326.018416 -115.862604)
			(xy 326.010593 -115.922026) (xy 325.99508 -115.979919) (xy 325.972144 -116.035292) (xy 325.942177 -116.087198)
			(xy 325.90569 -116.134748) (xy 325.86331 -116.177128) (xy 325.81576 -116.213615) (xy 325.763854 -116.243582)
			(xy 325.708481 -116.266518) (xy 325.650588 -116.282031) (xy 325.591166 -116.289854) (xy 325.53123 -116.289854)
			(xy 325.471808 -116.282031) (xy 325.413915 -116.266518) (xy 325.358542 -116.243582) (xy 325.306636 -116.213615)
			(xy 325.259086 -116.177128) (xy 325.216706 -116.134748) (xy 325.180219 -116.087198) (xy 325.150252 -116.035292)
			(xy 325.127316 -115.979919) (xy 325.111803 -115.922026) (xy 325.10398 -115.862604) (xy 325.10349 -115.832636)
			(xy 305.555396 -115.832636) (xy 305.555396 -115.903502) (xy 305.55582 -115.913572) (xy 305.563534 -115.932176)
			(xy 305.570382 -115.93957) (xy 305.61407 -115.983258) (xy 305.62147 -115.990098) (xy 305.640069 -115.997814)
			(xy 305.650138 -115.998244) (xy 307.389276 -115.998244) (xy 307.399339 -115.998682) (xy 307.417919 -116.006421)
			(xy 307.425344 -116.01323) (xy 307.82895 -116.416836) (xy 319.460624 -116.416836) (xy 319.464695 -116.361214)
			(xy 319.476821 -116.306777) (xy 319.496744 -116.254686) (xy 319.52404 -116.206051) (xy 319.558126 -116.161908)
			(xy 319.598275 -116.123199) (xy 319.643633 -116.090748) (xy 319.693233 -116.065247) (xy 319.746017 -116.04724)
			(xy 319.80086 -116.03711) (xy 319.856594 -116.035073) (xy 319.912031 -116.041173) (xy 319.965988 -116.055279)
			(xy 320.017317 -116.077091) (xy 320.064923 -116.106145) (xy 320.107791 -116.14182) (xy 320.145008 -116.183357)
			(xy 320.175781 -116.22987) (xy 320.199453 -116.280367) (xy 320.215521 -116.333774) (xy 320.223641 -116.38895)
			(xy 320.22415 -116.416836) (xy 320.223641 -116.444722) (xy 320.215521 -116.499898) (xy 320.199453 -116.553305)
			(xy 320.175781 -116.603802) (xy 320.145008 -116.650315) (xy 320.107791 -116.691852) (xy 320.098255 -116.699788)
			(xy 321.497942 -116.699788) (xy 321.497942 -116.639852) (xy 321.505765 -116.58043) (xy 321.521278 -116.522537)
			(xy 321.544214 -116.467164) (xy 321.574181 -116.415258) (xy 321.610668 -116.367708) (xy 321.653048 -116.325328)
			(xy 321.700598 -116.288841) (xy 321.752504 -116.258874) (xy 321.807877 -116.235938) (xy 321.86577 -116.220425)
			(xy 321.925192 -116.212602) (xy 321.985128 -116.212602) (xy 322.04455 -116.220425) (xy 322.102443 -116.235938)
			(xy 322.157816 -116.258874) (xy 322.209722 -116.288841) (xy 322.257272 -116.325328) (xy 322.299652 -116.367708)
			(xy 322.332477 -116.410486) (xy 327.34707 -116.410486) (xy 327.351141 -116.354864) (xy 327.363267 -116.300427)
			(xy 327.38319 -116.248336) (xy 327.410486 -116.199701) (xy 327.444572 -116.155558) (xy 327.484721 -116.116849)
			(xy 327.530079 -116.084398) (xy 327.579679 -116.058897) (xy 327.632463 -116.04089) (xy 327.687306 -116.03076)
			(xy 327.74304 -116.028723) (xy 327.798477 -116.034823) (xy 327.852434 -116.048929) (xy 327.903763 -116.070741)
			(xy 327.951369 -116.099795) (xy 327.994237 -116.13547) (xy 328.031454 -116.177007) (xy 328.062227 -116.22352)
			(xy 328.085899 -116.274017) (xy 328.101967 -116.327424) (xy 328.110087 -116.3826) (xy 328.110596 -116.410486)
			(xy 328.110087 -116.438372) (xy 328.101967 -116.493548) (xy 328.085899 -116.546955) (xy 328.062227 -116.597452)
			(xy 328.031454 -116.643965) (xy 327.994237 -116.685502) (xy 327.951369 -116.721177) (xy 327.903763 -116.750231)
			(xy 327.852434 -116.772043) (xy 327.798477 -116.786149) (xy 327.74304 -116.792249) (xy 327.687306 -116.790212)
			(xy 327.632463 -116.780082) (xy 327.579679 -116.762075) (xy 327.530079 -116.736574) (xy 327.484721 -116.704123)
			(xy 327.444572 -116.665414) (xy 327.410486 -116.621271) (xy 327.38319 -116.572636) (xy 327.363267 -116.520545)
			(xy 327.351141 -116.466108) (xy 327.34707 -116.410486) (xy 322.332477 -116.410486) (xy 322.336139 -116.415258)
			(xy 322.366106 -116.467164) (xy 322.389042 -116.522537) (xy 322.404555 -116.58043) (xy 322.412378 -116.639852)
			(xy 322.412868 -116.66982) (xy 322.412378 -116.699788) (xy 322.404555 -116.75921) (xy 322.389042 -116.817103)
			(xy 322.366106 -116.872476) (xy 322.336139 -116.924382) (xy 322.299652 -116.971932) (xy 322.257272 -117.014312)
			(xy 322.209722 -117.050799) (xy 322.157816 -117.080766) (xy 322.102443 -117.103702) (xy 322.04455 -117.119215)
			(xy 321.985128 -117.127038) (xy 321.925192 -117.127038) (xy 321.86577 -117.119215) (xy 321.807877 -117.103702)
			(xy 321.752504 -117.080766) (xy 321.700598 -117.050799) (xy 321.653048 -117.014312) (xy 321.610668 -116.971932)
			(xy 321.574181 -116.924382) (xy 321.544214 -116.872476) (xy 321.521278 -116.817103) (xy 321.505765 -116.75921)
			(xy 321.497942 -116.699788) (xy 320.098255 -116.699788) (xy 320.064923 -116.727527) (xy 320.017317 -116.756581)
			(xy 319.965988 -116.778393) (xy 319.912031 -116.792499) (xy 319.856594 -116.798599) (xy 319.80086 -116.796562)
			(xy 319.746017 -116.786432) (xy 319.693233 -116.768425) (xy 319.643633 -116.742924) (xy 319.598275 -116.710473)
			(xy 319.558126 -116.671764) (xy 319.52404 -116.627621) (xy 319.496744 -116.578986) (xy 319.476821 -116.526895)
			(xy 319.464695 -116.472458) (xy 319.460624 -116.416836) (xy 307.82895 -116.416836) (xy 308.544718 -117.132604)
			(xy 325.10398 -117.132604) (xy 325.10398 -117.072668) (xy 325.111803 -117.013246) (xy 325.127316 -116.955353)
			(xy 325.150252 -116.89998) (xy 325.180219 -116.848074) (xy 325.216706 -116.800524) (xy 325.259086 -116.758144)
			(xy 325.306636 -116.721657) (xy 325.358542 -116.69169) (xy 325.413915 -116.668754) (xy 325.471808 -116.653241)
			(xy 325.53123 -116.645418) (xy 325.591166 -116.645418) (xy 325.650588 -116.653241) (xy 325.708481 -116.668754)
			(xy 325.763854 -116.69169) (xy 325.81576 -116.721657) (xy 325.86331 -116.758144) (xy 325.90569 -116.800524)
			(xy 325.942177 -116.848074) (xy 325.972144 -116.89998) (xy 325.99508 -116.955353) (xy 326.010593 -117.013246)
			(xy 326.018416 -117.072668) (xy 326.018906 -117.102636) (xy 326.018416 -117.132604) (xy 326.010593 -117.192026)
			(xy 325.99508 -117.249919) (xy 325.972144 -117.305292) (xy 325.942177 -117.357198) (xy 325.90569 -117.404748)
			(xy 325.883952 -117.426486) (xy 327.34707 -117.426486) (xy 327.351141 -117.370864) (xy 327.363267 -117.316427)
			(xy 327.38319 -117.264336) (xy 327.410486 -117.215701) (xy 327.444572 -117.171558) (xy 327.484721 -117.132849)
			(xy 327.530079 -117.100398) (xy 327.579679 -117.074897) (xy 327.632463 -117.05689) (xy 327.687306 -117.04676)
			(xy 327.74304 -117.044723) (xy 327.798477 -117.050823) (xy 327.852434 -117.064929) (xy 327.903763 -117.086741)
			(xy 327.951369 -117.115795) (xy 327.994237 -117.15147) (xy 328.031454 -117.193007) (xy 328.062227 -117.23952)
			(xy 328.085899 -117.290017) (xy 328.101967 -117.343424) (xy 328.110087 -117.3986) (xy 328.110596 -117.426486)
			(xy 328.110087 -117.454372) (xy 328.101967 -117.509548) (xy 328.085899 -117.562955) (xy 328.062227 -117.613452)
			(xy 328.031454 -117.659965) (xy 327.994237 -117.701502) (xy 327.951369 -117.737177) (xy 327.903763 -117.766231)
			(xy 327.852434 -117.788043) (xy 327.798477 -117.802149) (xy 327.74304 -117.808249) (xy 327.687306 -117.806212)
			(xy 327.632463 -117.796082) (xy 327.579679 -117.778075) (xy 327.530079 -117.752574) (xy 327.484721 -117.720123)
			(xy 327.444572 -117.681414) (xy 327.410486 -117.637271) (xy 327.38319 -117.588636) (xy 327.363267 -117.536545)
			(xy 327.351141 -117.482108) (xy 327.34707 -117.426486) (xy 325.883952 -117.426486) (xy 325.86331 -117.447128)
			(xy 325.81576 -117.483615) (xy 325.763854 -117.513582) (xy 325.708481 -117.536518) (xy 325.650588 -117.552031)
			(xy 325.591166 -117.559854) (xy 325.53123 -117.559854) (xy 325.471808 -117.552031) (xy 325.413915 -117.536518)
			(xy 325.358542 -117.513582) (xy 325.306636 -117.483615) (xy 325.259086 -117.447128) (xy 325.216706 -117.404748)
			(xy 325.180219 -117.357198) (xy 325.150252 -117.305292) (xy 325.127316 -117.249919) (xy 325.111803 -117.192026)
			(xy 325.10398 -117.132604) (xy 308.544718 -117.132604) (xy 309.072026 -117.659912) (xy 309.079422 -117.666764)
			(xy 309.098021 -117.674503) (xy 309.108094 -117.674898) (xy 315.1124 -117.674898) (xy 315.12247 -117.675321)
			(xy 315.141075 -117.683035) (xy 315.148468 -117.689884) (xy 316.352936 -118.894352) (xy 325.616062 -118.894352)
			(xy 325.616515 -118.868036) (xy 325.623737 -118.815903) (xy 325.638051 -118.765255) (xy 325.659185 -118.717053)
			(xy 325.68674 -118.672211) (xy 325.720193 -118.631579) (xy 325.739252 -118.613428) (xy 325.746636 -118.605891)
			(xy 325.755172 -118.586623) (xy 325.755762 -118.57609) (xy 325.755762 -118.501414) (xy 325.75525 -118.490862)
			(xy 325.746704 -118.471566) (xy 325.739252 -118.464076) (xy 325.720171 -118.445943) (xy 325.686691 -118.405323)
			(xy 325.659119 -118.360483) (xy 325.637981 -118.312275) (xy 325.623677 -118.261617) (xy 325.616481 -118.209472)
			(xy 325.616062 -118.183152) (xy 325.616548 -118.155901) (xy 325.624304 -118.101953) (xy 325.639659 -118.049658)
			(xy 325.662301 -118.000081) (xy 325.691767 -117.954231) (xy 325.727458 -117.91304) (xy 325.768649 -117.877349)
			(xy 325.814499 -117.847883) (xy 325.864076 -117.825241) (xy 325.916371 -117.809886) (xy 325.970319 -117.80213)
			(xy 326.024821 -117.80213) (xy 326.078769 -117.809886) (xy 326.131064 -117.825241) (xy 326.180641 -117.847883)
			(xy 326.226491 -117.877349) (xy 326.267682 -117.91304) (xy 326.303373 -117.954231) (xy 326.332839 -118.000081)
			(xy 326.355481 -118.049658) (xy 326.370836 -118.101953) (xy 326.378592 -118.155901) (xy 326.379078 -118.183152)
			(xy 326.378646 -118.209469) (xy 326.371423 -118.261604) (xy 326.357106 -118.312253) (xy 326.335968 -118.360455)
			(xy 326.308408 -118.405296) (xy 326.27495 -118.445927) (xy 326.255888 -118.464076) (xy 326.248493 -118.471603)
			(xy 326.239965 -118.490879) (xy 326.239576 -118.497854) (xy 329.607146 -118.497854) (xy 329.607146 -118.437918)
			(xy 329.614969 -118.378496) (xy 329.630482 -118.320603) (xy 329.653418 -118.26523) (xy 329.683385 -118.213324)
			(xy 329.719872 -118.165774) (xy 329.762252 -118.123394) (xy 329.809802 -118.086907) (xy 329.861708 -118.05694)
			(xy 329.917081 -118.034004) (xy 329.974974 -118.018491) (xy 330.034396 -118.010668) (xy 330.094332 -118.010668)
			(xy 330.153754 -118.018491) (xy 330.211647 -118.034004) (xy 330.26702 -118.05694) (xy 330.318926 -118.086907)
			(xy 330.366476 -118.123394) (xy 330.408856 -118.165774) (xy 330.445343 -118.213324) (xy 330.47531 -118.26523)
			(xy 330.498246 -118.320603) (xy 330.513759 -118.378496) (xy 330.521582 -118.437918) (xy 330.522072 -118.467886)
			(xy 331.852522 -118.467886) (xy 331.856593 -118.412264) (xy 331.868719 -118.357827) (xy 331.888642 -118.305736)
			(xy 331.915938 -118.257101) (xy 331.950024 -118.212958) (xy 331.990173 -118.174249) (xy 332.035531 -118.141798)
			(xy 332.085131 -118.116297) (xy 332.137915 -118.09829) (xy 332.192758 -118.08816) (xy 332.248492 -118.086123)
			(xy 332.303929 -118.092223) (xy 332.357886 -118.106329) (xy 332.409215 -118.128141) (xy 332.456821 -118.157195)
			(xy 332.499689 -118.19287) (xy 332.536906 -118.234407) (xy 332.567679 -118.28092) (xy 332.591351 -118.331417)
			(xy 332.607419 -118.384824) (xy 332.615539 -118.44) (xy 332.616048 -118.467886) (xy 332.615539 -118.495772)
			(xy 332.607419 -118.550948) (xy 332.591351 -118.604355) (xy 332.567679 -118.654852) (xy 332.536906 -118.701365)
			(xy 332.499689 -118.742902) (xy 332.456821 -118.778577) (xy 332.437763 -118.790208) (xy 334.689178 -118.790208)
			(xy 334.689178 -118.730272) (xy 334.697001 -118.67085) (xy 334.712514 -118.612957) (xy 334.73545 -118.557584)
			(xy 334.765417 -118.505678) (xy 334.801904 -118.458128) (xy 334.844284 -118.415748) (xy 334.891834 -118.379261)
			(xy 334.94374 -118.349294) (xy 334.999113 -118.326358) (xy 335.057006 -118.310845) (xy 335.116428 -118.303022)
			(xy 335.176364 -118.303022) (xy 335.235786 -118.310845) (xy 335.293679 -118.326358) (xy 335.349052 -118.349294)
			(xy 335.400958 -118.379261) (xy 335.448508 -118.415748) (xy 335.490888 -118.458128) (xy 335.527375 -118.505678)
			(xy 335.557342 -118.557584) (xy 335.580278 -118.612957) (xy 335.595791 -118.67085) (xy 335.603614 -118.730272)
			(xy 335.604104 -118.76024) (xy 335.603614 -118.790208) (xy 335.595791 -118.84963) (xy 335.580278 -118.907523)
			(xy 335.557342 -118.962896) (xy 335.527375 -119.014802) (xy 335.490888 -119.062352) (xy 335.448508 -119.104732)
			(xy 335.400958 -119.141219) (xy 335.349052 -119.171186) (xy 335.293679 -119.194122) (xy 335.235786 -119.209635)
			(xy 335.176364 -119.217458) (xy 335.116428 -119.217458) (xy 335.057006 -119.209635) (xy 334.999113 -119.194122)
			(xy 334.94374 -119.171186) (xy 334.891834 -119.141219) (xy 334.844284 -119.104732) (xy 334.801904 -119.062352)
			(xy 334.765417 -119.014802) (xy 334.73545 -118.962896) (xy 334.712514 -118.907523) (xy 334.697001 -118.84963)
			(xy 334.689178 -118.790208) (xy 332.437763 -118.790208) (xy 332.409215 -118.807631) (xy 332.357886 -118.829443)
			(xy 332.303929 -118.843549) (xy 332.248492 -118.849649) (xy 332.192758 -118.847612) (xy 332.137915 -118.837482)
			(xy 332.085131 -118.819475) (xy 332.035531 -118.793974) (xy 331.990173 -118.761523) (xy 331.950024 -118.722814)
			(xy 331.915938 -118.678671) (xy 331.888642 -118.630036) (xy 331.868719 -118.577945) (xy 331.856593 -118.523508)
			(xy 331.852522 -118.467886) (xy 330.522072 -118.467886) (xy 330.521582 -118.497854) (xy 330.513759 -118.557276)
			(xy 330.498246 -118.615169) (xy 330.47531 -118.670542) (xy 330.445343 -118.722448) (xy 330.408856 -118.769998)
			(xy 330.366476 -118.812378) (xy 330.318926 -118.848865) (xy 330.26702 -118.878832) (xy 330.211647 -118.901768)
			(xy 330.153754 -118.917281) (xy 330.094332 -118.925104) (xy 330.034396 -118.925104) (xy 329.974974 -118.917281)
			(xy 329.917081 -118.901768) (xy 329.861708 -118.878832) (xy 329.809802 -118.848865) (xy 329.762252 -118.812378)
			(xy 329.719872 -118.769998) (xy 329.683385 -118.722448) (xy 329.653418 -118.670542) (xy 329.630482 -118.615169)
			(xy 329.614969 -118.557276) (xy 329.607146 -118.497854) (xy 326.239576 -118.497854) (xy 326.239378 -118.501414)
			(xy 326.239378 -118.57609) (xy 326.239905 -118.58664) (xy 326.248442 -118.605935) (xy 326.255888 -118.613428)
			(xy 326.274979 -118.631551) (xy 326.308456 -118.672174) (xy 326.336025 -118.717017) (xy 326.357162 -118.765227)
			(xy 326.371464 -118.815886) (xy 326.378659 -118.868032) (xy 326.379078 -118.894352) (xy 326.378592 -118.921603)
			(xy 326.370836 -118.975551) (xy 326.355481 -119.027846) (xy 326.332839 -119.077423) (xy 326.303373 -119.123273)
			(xy 326.267682 -119.164464) (xy 326.226491 -119.200155) (xy 326.180641 -119.229621) (xy 326.131064 -119.252263)
			(xy 326.078769 -119.267618) (xy 326.024821 -119.275374) (xy 325.970319 -119.275374) (xy 325.916371 -119.267618)
			(xy 325.864076 -119.252263) (xy 325.814499 -119.229621) (xy 325.768649 -119.200155) (xy 325.727458 -119.164464)
			(xy 325.691767 -119.123273) (xy 325.662301 -119.077423) (xy 325.639659 -119.027846) (xy 325.624304 -118.975551)
			(xy 325.616548 -118.921603) (xy 325.616062 -118.894352) (xy 316.352936 -118.894352) (xy 316.866141 -119.407557)
			(xy 326.699509 -119.407557) (xy 326.699509 -119.353043) (xy 326.707268 -119.299083) (xy 326.722627 -119.246777)
			(xy 326.745274 -119.197189) (xy 326.774748 -119.151329) (xy 326.810449 -119.11013) (xy 326.85165 -119.074432)
			(xy 326.897512 -119.044962) (xy 326.947101 -119.022318) (xy 326.999408 -119.006962) (xy 327.053369 -118.999207)
			(xy 327.080626 -118.998746) (xy 327.107997 -118.999186) (xy 327.162178 -119.007008) (xy 327.214682 -119.022503)
			(xy 327.264428 -119.045351) (xy 327.310394 -119.075082) (xy 327.331324 -119.092726) (xy 327.338436 -119.098822)
			(xy 327.355454 -119.105172) (xy 327.440798 -119.105172) (xy 327.457816 -119.098822) (xy 327.464928 -119.092726)
			(xy 327.48588 -119.075111) (xy 327.531847 -119.045395) (xy 327.581589 -119.022554) (xy 327.634086 -119.007057)
			(xy 327.688258 -118.999223) (xy 327.715626 -118.998746) (xy 327.742873 -118.999326) (xy 327.796811 -119.007085)
			(xy 327.849096 -119.02244) (xy 327.898664 -119.04508) (xy 327.944506 -119.074543) (xy 327.985688 -119.11023)
			(xy 328.021372 -119.151415) (xy 328.050833 -119.197259) (xy 328.073469 -119.246828) (xy 328.088821 -119.299114)
			(xy 328.096576 -119.353053) (xy 328.096576 -119.407547) (xy 328.088821 -119.461486) (xy 328.073469 -119.513772)
			(xy 328.050833 -119.563341) (xy 328.021372 -119.609185) (xy 327.985688 -119.65037) (xy 327.944506 -119.686057)
			(xy 327.898664 -119.71552) (xy 327.849096 -119.73816) (xy 327.796811 -119.753515) (xy 327.742873 -119.761274)
			(xy 327.715626 -119.761762) (xy 327.688256 -119.76129) (xy 327.634077 -119.753475) (xy 327.581573 -119.737988)
			(xy 327.531826 -119.715147) (xy 327.48586 -119.685423) (xy 327.464928 -119.667782) (xy 327.457816 -119.661686)
			(xy 327.440798 -119.655336) (xy 327.355454 -119.655336) (xy 327.338436 -119.661686) (xy 327.331324 -119.667782)
			(xy 327.310391 -119.685421) (xy 327.264419 -119.715133) (xy 327.214672 -119.737969) (xy 327.162171 -119.753461)
			(xy 327.107995 -119.761288) (xy 327.080626 -119.761762) (xy 327.053369 -119.761393) (xy 326.999408 -119.753638)
			(xy 326.947101 -119.738282) (xy 326.897512 -119.715638) (xy 326.85165 -119.686168) (xy 326.810449 -119.65047)
			(xy 326.774748 -119.609271) (xy 326.745274 -119.563411) (xy 326.722627 -119.513823) (xy 326.707268 -119.461517)
			(xy 326.699509 -119.407557) (xy 316.866141 -119.407557) (xy 317.39459 -119.936006) (xy 324.894446 -119.936006)
			(xy 324.898517 -119.880384) (xy 324.910643 -119.825947) (xy 324.930566 -119.773856) (xy 324.957862 -119.725221)
			(xy 324.991948 -119.681078) (xy 325.032097 -119.642369) (xy 325.077455 -119.609918) (xy 325.127055 -119.584417)
			(xy 325.179839 -119.56641) (xy 325.234682 -119.55628) (xy 325.290416 -119.554243) (xy 325.345853 -119.560343)
			(xy 325.39981 -119.574449) (xy 325.451139 -119.596261) (xy 325.498745 -119.625315) (xy 325.541613 -119.66099)
			(xy 325.57883 -119.702527) (xy 325.609603 -119.74904) (xy 325.633275 -119.799537) (xy 325.649343 -119.852944)
			(xy 325.657463 -119.90812) (xy 325.657735 -119.923048) (xy 329.69376 -119.923048) (xy 329.69376 -119.863112)
			(xy 329.701583 -119.80369) (xy 329.717096 -119.745797) (xy 329.740032 -119.690424) (xy 329.769999 -119.638518)
			(xy 329.806486 -119.590968) (xy 329.848866 -119.548588) (xy 329.896416 -119.512101) (xy 329.948322 -119.482134)
			(xy 330.003695 -119.459198) (xy 330.061588 -119.443685) (xy 330.12101 -119.435862) (xy 330.180946 -119.435862)
			(xy 330.240368 -119.443685) (xy 330.298261 -119.459198) (xy 330.353634 -119.482134) (xy 330.40554 -119.512101)
			(xy 330.45309 -119.548588) (xy 330.49547 -119.590968) (xy 330.531957 -119.638518) (xy 330.561924 -119.690424)
			(xy 330.58486 -119.745797) (xy 330.593018 -119.77624) (xy 332.735934 -119.77624) (xy 332.740005 -119.720618)
			(xy 332.752131 -119.666181) (xy 332.772054 -119.61409) (xy 332.79935 -119.565455) (xy 332.833436 -119.521312)
			(xy 332.873585 -119.482603) (xy 332.918943 -119.450152) (xy 332.968543 -119.424651) (xy 333.021327 -119.406644)
			(xy 333.07617 -119.396514) (xy 333.131904 -119.394477) (xy 333.187341 -119.400577) (xy 333.241298 -119.414683)
			(xy 333.292627 -119.436495) (xy 333.340233 -119.465549) (xy 333.383101 -119.501224) (xy 333.420318 -119.542761)
			(xy 333.451091 -119.589274) (xy 333.474763 -119.639771) (xy 333.490831 -119.693178) (xy 333.498951 -119.748354)
			(xy 333.49946 -119.77624) (xy 333.498951 -119.804126) (xy 333.490831 -119.859302) (xy 333.474763 -119.912709)
			(xy 333.451091 -119.963206) (xy 333.420318 -120.009719) (xy 333.383101 -120.051256) (xy 333.340233 -120.086931)
			(xy 333.292627 -120.115985) (xy 333.241298 -120.137797) (xy 333.187341 -120.151903) (xy 333.131904 -120.158003)
			(xy 333.07617 -120.155966) (xy 333.021327 -120.145836) (xy 332.968543 -120.127829) (xy 332.918943 -120.102328)
			(xy 332.873585 -120.069877) (xy 332.833436 -120.031168) (xy 332.79935 -119.987025) (xy 332.772054 -119.93839)
			(xy 332.752131 -119.886299) (xy 332.740005 -119.831862) (xy 332.735934 -119.77624) (xy 330.593018 -119.77624)
			(xy 330.600373 -119.80369) (xy 330.608196 -119.863112) (xy 330.608686 -119.89308) (xy 330.608196 -119.923048)
			(xy 330.600373 -119.98247) (xy 330.58486 -120.040363) (xy 330.561924 -120.095736) (xy 330.531957 -120.147642)
			(xy 330.49547 -120.195192) (xy 330.45309 -120.237572) (xy 330.40554 -120.274059) (xy 330.353634 -120.304026)
			(xy 330.298261 -120.326962) (xy 330.240368 -120.342475) (xy 330.180946 -120.350298) (xy 330.12101 -120.350298)
			(xy 330.061588 -120.342475) (xy 330.003695 -120.326962) (xy 329.948322 -120.304026) (xy 329.896416 -120.274059)
			(xy 329.848866 -120.237572) (xy 329.806486 -120.195192) (xy 329.769999 -120.147642) (xy 329.740032 -120.095736)
			(xy 329.717096 -120.040363) (xy 329.701583 -119.98247) (xy 329.69376 -119.923048) (xy 325.657735 -119.923048)
			(xy 325.657972 -119.936006) (xy 325.657463 -119.963892) (xy 325.649343 -120.019068) (xy 325.633275 -120.072475)
			(xy 325.609603 -120.122972) (xy 325.57883 -120.169485) (xy 325.541613 -120.211022) (xy 325.498745 -120.246697)
			(xy 325.451139 -120.275751) (xy 325.39981 -120.297563) (xy 325.345853 -120.311669) (xy 325.290416 -120.317769)
			(xy 325.234682 -120.315732) (xy 325.179839 -120.305602) (xy 325.127055 -120.287595) (xy 325.077455 -120.262094)
			(xy 325.032097 -120.229643) (xy 324.991948 -120.190934) (xy 324.957862 -120.146791) (xy 324.930566 -120.098156)
			(xy 324.910643 -120.046065) (xy 324.898517 -119.991628) (xy 324.894446 -119.936006) (xy 317.39459 -119.936006)
			(xy 317.98158 -120.522996) (xy 331.728808 -120.522996) (xy 331.728808 -120.46306) (xy 331.736631 -120.403638)
			(xy 331.752144 -120.345745) (xy 331.77508 -120.290372) (xy 331.805047 -120.238466) (xy 331.841534 -120.190916)
			(xy 331.883914 -120.148536) (xy 331.931464 -120.112049) (xy 331.98337 -120.082082) (xy 332.038743 -120.059146)
			(xy 332.096636 -120.043633) (xy 332.156058 -120.03581) (xy 332.215994 -120.03581) (xy 332.275416 -120.043633)
			(xy 332.333309 -120.059146) (xy 332.388682 -120.082082) (xy 332.440588 -120.112049) (xy 332.488138 -120.148536)
			(xy 332.530518 -120.190916) (xy 332.567005 -120.238466) (xy 332.596972 -120.290372) (xy 332.619908 -120.345745)
			(xy 332.635421 -120.403638) (xy 332.643244 -120.46306) (xy 332.643734 -120.493028) (xy 332.643244 -120.522996)
			(xy 332.635421 -120.582418) (xy 332.619908 -120.640311) (xy 332.596972 -120.695684) (xy 332.567005 -120.74759)
			(xy 332.530518 -120.79514) (xy 332.50345 -120.822208) (xy 334.816178 -120.822208) (xy 334.816178 -120.762272)
			(xy 334.824001 -120.70285) (xy 334.839514 -120.644957) (xy 334.86245 -120.589584) (xy 334.892417 -120.537678)
			(xy 334.928904 -120.490128) (xy 334.971284 -120.447748) (xy 335.018834 -120.411261) (xy 335.07074 -120.381294)
			(xy 335.126113 -120.358358) (xy 335.184006 -120.342845) (xy 335.243428 -120.335022) (xy 335.303364 -120.335022)
			(xy 335.362786 -120.342845) (xy 335.420679 -120.358358) (xy 335.476052 -120.381294) (xy 335.527958 -120.411261)
			(xy 335.575508 -120.447748) (xy 335.617888 -120.490128) (xy 335.654375 -120.537678) (xy 335.684342 -120.589584)
			(xy 335.707278 -120.644957) (xy 335.722791 -120.70285) (xy 335.730614 -120.762272) (xy 335.731104 -120.79224)
			(xy 335.730614 -120.822208) (xy 335.722791 -120.88163) (xy 335.707278 -120.939523) (xy 335.684342 -120.994896)
			(xy 335.654375 -121.046802) (xy 335.617888 -121.094352) (xy 335.575508 -121.136732) (xy 335.527958 -121.173219)
			(xy 335.476052 -121.203186) (xy 335.420679 -121.226122) (xy 335.362786 -121.241635) (xy 335.303364 -121.249458)
			(xy 335.243428 -121.249458) (xy 335.184006 -121.241635) (xy 335.126113 -121.226122) (xy 335.07074 -121.203186)
			(xy 335.018834 -121.173219) (xy 334.971284 -121.136732) (xy 334.928904 -121.094352) (xy 334.892417 -121.046802)
			(xy 334.86245 -120.994896) (xy 334.839514 -120.939523) (xy 334.824001 -120.88163) (xy 334.816178 -120.822208)
			(xy 332.50345 -120.822208) (xy 332.488138 -120.83752) (xy 332.440588 -120.874007) (xy 332.388682 -120.903974)
			(xy 332.333309 -120.92691) (xy 332.275416 -120.942423) (xy 332.215994 -120.950246) (xy 332.156058 -120.950246)
			(xy 332.096636 -120.942423) (xy 332.038743 -120.92691) (xy 331.98337 -120.903974) (xy 331.931464 -120.874007)
			(xy 331.883914 -120.83752) (xy 331.841534 -120.79514) (xy 331.805047 -120.74759) (xy 331.77508 -120.695684)
			(xy 331.752144 -120.640311) (xy 331.736631 -120.582418) (xy 331.728808 -120.522996) (xy 317.98158 -120.522996)
			(xy 318.727324 -121.26874) (xy 329.709 -121.26874) (xy 329.709 -121.208804) (xy 329.716823 -121.149382)
			(xy 329.732336 -121.091489) (xy 329.755272 -121.036116) (xy 329.785239 -120.98421) (xy 329.821726 -120.93666)
			(xy 329.864106 -120.89428) (xy 329.911656 -120.857793) (xy 329.963562 -120.827826) (xy 330.018935 -120.80489)
			(xy 330.076828 -120.789377) (xy 330.13625 -120.781554) (xy 330.196186 -120.781554) (xy 330.255608 -120.789377)
			(xy 330.313501 -120.80489) (xy 330.368874 -120.827826) (xy 330.42078 -120.857793) (xy 330.46833 -120.89428)
			(xy 330.51071 -120.93666) (xy 330.547197 -120.98421) (xy 330.577164 -121.036116) (xy 330.6001 -121.091489)
			(xy 330.615613 -121.149382) (xy 330.623436 -121.208804) (xy 330.623926 -121.238772) (xy 330.623436 -121.26874)
			(xy 330.615613 -121.328162) (xy 330.6001 -121.386055) (xy 330.577164 -121.441428) (xy 330.547197 -121.493334)
			(xy 330.535154 -121.509028) (xy 331.829408 -121.509028) (xy 331.833479 -121.453406) (xy 331.845605 -121.398969)
			(xy 331.865528 -121.346878) (xy 331.892824 -121.298243) (xy 331.92691 -121.2541) (xy 331.967059 -121.215391)
			(xy 332.012417 -121.18294) (xy 332.062017 -121.157439) (xy 332.114801 -121.139432) (xy 332.169644 -121.129302)
			(xy 332.225378 -121.127265) (xy 332.280815 -121.133365) (xy 332.334772 -121.147471) (xy 332.386101 -121.169283)
			(xy 332.433707 -121.198337) (xy 332.476575 -121.234012) (xy 332.513792 -121.275549) (xy 332.544565 -121.322062)
			(xy 332.568237 -121.372559) (xy 332.584305 -121.425966) (xy 332.592425 -121.481142) (xy 332.592934 -121.509028)
			(xy 332.592425 -121.536914) (xy 332.584305 -121.59209) (xy 332.568237 -121.645497) (xy 332.544565 -121.695994)
			(xy 332.513792 -121.742507) (xy 332.476575 -121.784044) (xy 332.4475 -121.80824) (xy 332.735934 -121.80824)
			(xy 332.740005 -121.752618) (xy 332.752131 -121.698181) (xy 332.772054 -121.64609) (xy 332.79935 -121.597455)
			(xy 332.833436 -121.553312) (xy 332.873585 -121.514603) (xy 332.918943 -121.482152) (xy 332.968543 -121.456651)
			(xy 333.021327 -121.438644) (xy 333.07617 -121.428514) (xy 333.131904 -121.426477) (xy 333.187341 -121.432577)
			(xy 333.241298 -121.446683) (xy 333.292627 -121.468495) (xy 333.340233 -121.497549) (xy 333.383101 -121.533224)
			(xy 333.420318 -121.574761) (xy 333.451091 -121.621274) (xy 333.474763 -121.671771) (xy 333.490831 -121.725178)
			(xy 333.498951 -121.780354) (xy 333.49946 -121.80824) (xy 333.498951 -121.836126) (xy 333.490831 -121.891302)
			(xy 333.474763 -121.944709) (xy 333.451091 -121.995206) (xy 333.420318 -122.041719) (xy 333.383101 -122.083256)
			(xy 333.340233 -122.118931) (xy 333.292627 -122.147985) (xy 333.241298 -122.169797) (xy 333.187341 -122.183903)
			(xy 333.131904 -122.190003) (xy 333.07617 -122.187966) (xy 333.021327 -122.177836) (xy 332.968543 -122.159829)
			(xy 332.918943 -122.134328) (xy 332.873585 -122.101877) (xy 332.833436 -122.063168) (xy 332.79935 -122.019025)
			(xy 332.772054 -121.97039) (xy 332.752131 -121.918299) (xy 332.740005 -121.863862) (xy 332.735934 -121.80824)
			(xy 332.4475 -121.80824) (xy 332.433707 -121.819719) (xy 332.386101 -121.848773) (xy 332.334772 -121.870585)
			(xy 332.280815 -121.884691) (xy 332.225378 -121.890791) (xy 332.169644 -121.888754) (xy 332.114801 -121.878624)
			(xy 332.062017 -121.860617) (xy 332.012417 -121.835116) (xy 331.967059 -121.802665) (xy 331.92691 -121.763956)
			(xy 331.892824 -121.719813) (xy 331.865528 -121.671178) (xy 331.845605 -121.619087) (xy 331.833479 -121.56465)
			(xy 331.829408 -121.509028) (xy 330.535154 -121.509028) (xy 330.51071 -121.540884) (xy 330.46833 -121.583264)
			(xy 330.42078 -121.619751) (xy 330.368874 -121.649718) (xy 330.313501 -121.672654) (xy 330.255608 -121.688167)
			(xy 330.196186 -121.69599) (xy 330.13625 -121.69599) (xy 330.076828 -121.688167) (xy 330.018935 -121.672654)
			(xy 329.963562 -121.649718) (xy 329.911656 -121.619751) (xy 329.864106 -121.583264) (xy 329.821726 -121.540884)
			(xy 329.785239 -121.493334) (xy 329.755272 -121.441428) (xy 329.732336 -121.386055) (xy 329.716823 -121.328162)
			(xy 329.709 -121.26874) (xy 318.727324 -121.26874) (xy 320.09842 -122.639836) (xy 320.105817 -122.646686)
			(xy 320.124415 -122.654423) (xy 320.134488 -122.654822)
		)
		(stroke
			(width 0)
			(type solid)
		)
		(fill yes)
		(layer "B.Cu")
		(net "P3V3_NIC5")
	)
	(gr_poly
		(pts
			(xy 161.222182 -296.620438) (xy 161.232055 -296.619968) (xy 161.25034 -296.612512) (xy 161.257742 -296.60596)
			(xy 161.257996 -296.605706) (xy 161.387282 -296.47642) (xy 161.38779 -296.475912) (xy 161.394363 -296.468527)
			(xy 161.401795 -296.450229) (xy 161.402268 -296.440352) (xy 161.402268 -291.76726) (xy 161.402698 -291.757192)
			(xy 161.410419 -291.738595) (xy 161.417254 -291.731192) (xy 161.68751 -291.460936) (xy 161.690812 -291.455602)
			(xy 161.705301 -291.432318) (xy 161.740742 -291.390472) (xy 161.782599 -291.355044) (xy 161.805874 -291.34054)
			(xy 161.811208 -291.337238) (xy 161.975546 -291.1729) (xy 161.981935 -291.166066) (xy 161.989586 -291.149008)
			(xy 161.99055 -291.130337) (xy 161.987992 -291.121338) (xy 161.955988 -291.02177) (xy 161.934652 -291.003482)
			(xy 161.920428 -291.000942) (xy 161.895042 -290.996184) (xy 161.846051 -290.979836) (xy 161.800196 -290.956072)
			(xy 161.758591 -290.92547) (xy 161.722248 -290.888774) (xy 161.69205 -290.846875) (xy 161.668731 -290.800793)
			(xy 161.652857 -290.751646) (xy 161.644813 -290.700629) (xy 161.64433 -290.674806) (xy 161.644819 -290.649081)
			(xy 161.652787 -290.598252) (xy 161.668531 -290.549271) (xy 161.691671 -290.503319) (xy 161.72165 -290.461506)
			(xy 161.757742 -290.42484) (xy 161.799078 -290.394207) (xy 161.84466 -290.370346) (xy 161.868866 -290.361624)
			(xy 161.88436 -290.35629) (xy 161.90341 -290.329874) (xy 161.90341 -290.069778) (xy 161.88436 -290.043362)
			(xy 161.868866 -290.038028) (xy 161.844663 -290.029303) (xy 161.799088 -290.005435) (xy 161.757759 -289.974798)
			(xy 161.721672 -289.938132) (xy 161.691697 -289.89632) (xy 161.668558 -289.850371) (xy 161.652812 -289.801394)
			(xy 161.644839 -289.750569) (xy 161.64433 -289.724846) (xy 161.64484 -289.698859) (xy 161.65297 -289.647524)
			(xy 161.669031 -289.598094) (xy 161.692627 -289.551784) (xy 161.723177 -289.509736) (xy 161.759928 -289.472985)
			(xy 161.801976 -289.442435) (xy 161.848286 -289.418839) (xy 161.897716 -289.402778) (xy 161.949051 -289.394648)
			(xy 162.001025 -289.394648) (xy 162.05236 -289.402778) (xy 162.10179 -289.418839) (xy 162.1481 -289.442435)
			(xy 162.190148 -289.472985) (xy 162.226899 -289.509736) (xy 162.257449 -289.551784) (xy 162.281045 -289.598094)
			(xy 162.297106 -289.647524) (xy 162.305236 -289.698859) (xy 162.305746 -289.724846) (xy 162.305607 -289.740239)
			(xy 162.302808 -289.770896) (xy 162.300158 -289.78606) (xy 162.298772 -289.795321) (xy 162.302152 -289.813725)
			(xy 162.306762 -289.821874) (xy 162.342068 -289.879786) (xy 162.34468 -289.883866) (xy 162.351209 -289.891021)
			(xy 162.355022 -289.89401) (xy 162.362388 -289.899598) (xy 162.371278 -289.902392) (xy 162.386891 -289.907467)
			(xy 162.415027 -289.924361) (xy 162.437935 -289.947863) (xy 162.454104 -289.976422) (xy 162.462469 -290.008157)
			(xy 162.462972 -290.024566) (xy 162.462972 -290.40582) (xy 162.462669 -290.418073) (xy 162.457945 -290.442121)
			(xy 162.453574 -290.453572) (xy 162.451559 -290.458989) (xy 162.449772 -290.470404) (xy 162.450018 -290.476178)
			(xy 162.450272 -290.484306) (xy 162.450272 -290.865306) (xy 162.449782 -290.880323) (xy 162.442008 -290.909334)
			(xy 162.426991 -290.935345) (xy 162.405754 -290.956584) (xy 162.379745 -290.971603) (xy 162.350735 -290.97938)
			(xy 162.335718 -290.97986) (xy 162.273996 -290.97986) (xy 162.261443 -290.980505) (xy 162.239318 -290.992368)
			(xy 162.231832 -291.002466) (xy 162.22472 -291.01288) (xy 162.22218 -291.037772) (xy 162.229038 -291.05479)
			(xy 162.233222 -291.063967) (xy 162.24738 -291.078309) (xy 162.265953 -291.086131) (xy 162.276028 -291.08654)
			(xy 162.80257 -291.08654) (xy 162.812585 -291.086058) (xy 162.831094 -291.078405) (xy 162.845266 -291.064252)
			(xy 162.852944 -291.045754) (xy 162.85337 -291.03574) (xy 162.85337 -291.00526) (xy 162.853624 -291.005006)
			(xy 162.853624 -290.974526) (xy 162.854116 -290.957835) (xy 162.86275 -290.925588) (xy 162.879435 -290.896674)
			(xy 162.903036 -290.873065) (xy 162.931943 -290.856368) (xy 162.964187 -290.847722) (xy 162.980878 -290.847272)
			(xy 163.176204 -290.847272) (xy 163.186223 -290.846851) (xy 163.204733 -290.83918) (xy 163.218897 -290.825006)
			(xy 163.226557 -290.806491) (xy 163.227004 -290.796472) (xy 163.227004 -290.078922) (xy 163.227004 -290.076382)
			(xy 163.22578 -290.06477) (xy 163.214396 -290.044412) (xy 163.20516 -290.037266) (xy 163.201858 -290.03498)
			(xy 163.126674 -289.991292) (xy 163.099242 -289.991292) (xy 163.087304 -289.998404) (xy 163.062544 -290.012332)
			(xy 163.009305 -290.03214) (xy 162.9534 -290.042203) (xy 162.924998 -290.042854) (xy 162.900005 -290.042363)
			(xy 162.850635 -290.034544) (xy 162.803097 -290.019097) (xy 162.758559 -289.996404) (xy 162.71812 -289.967023)
			(xy 162.682776 -289.931678) (xy 162.653395 -289.891239) (xy 162.630702 -289.846702) (xy 162.615256 -289.799163)
			(xy 162.607436 -289.749793) (xy 162.607436 -289.699807) (xy 162.615256 -289.650437) (xy 162.630702 -289.602898)
			(xy 162.653395 -289.558361) (xy 162.682776 -289.517922) (xy 162.71812 -289.482577) (xy 162.758559 -289.453196)
			(xy 162.803097 -289.430503) (xy 162.850635 -289.415056) (xy 162.900005 -289.407237) (xy 162.924998 -289.406838)
			(xy 162.953406 -289.407433) (xy 163.009326 -289.417475) (xy 163.062566 -289.437311) (xy 163.087304 -289.451288)
			(xy 163.099242 -289.4584) (xy 163.126674 -289.4584) (xy 163.201858 -289.414712) (xy 163.20516 -289.412426)
			(xy 163.21444 -289.405321) (xy 163.225826 -289.384938) (xy 163.227004 -289.37331) (xy 163.227004 -289.128962)
			(xy 163.227004 -289.126422) (xy 163.225788 -289.114806) (xy 163.214413 -289.094434) (xy 163.20516 -289.087306)
			(xy 163.201858 -289.08502) (xy 163.126674 -289.041332) (xy 163.099242 -289.041332) (xy 163.087304 -289.048444)
			(xy 163.062545 -289.062375) (xy 163.009307 -289.082186) (xy 162.9534 -289.092251) (xy 162.924998 -289.092894)
			(xy 162.900007 -289.092429) (xy 162.850641 -289.08461) (xy 162.803106 -289.069164) (xy 162.758573 -289.046472)
			(xy 162.718138 -289.017093) (xy 162.682796 -288.98175) (xy 162.653419 -288.941313) (xy 162.63073 -288.896779)
			(xy 162.615286 -288.849243) (xy 162.607469 -288.799877) (xy 162.60699 -288.774886) (xy 162.607556 -288.747586)
			(xy 162.616884 -288.693787) (xy 162.635263 -288.642373) (xy 162.662153 -288.594852) (xy 162.696764 -288.552623)
			(xy 162.738079 -288.516925) (xy 162.761168 -288.502344) (xy 162.768482 -288.497502) (xy 162.779568 -288.483926)
			(xy 162.785462 -288.467419) (xy 162.785806 -288.458656) (xy 162.785806 -288.141156) (xy 162.785494 -288.132381)
			(xy 162.779642 -288.115842) (xy 162.768513 -288.10228) (xy 162.761168 -288.097468) (xy 162.738059 -288.082919)
			(xy 162.696748 -288.047211) (xy 162.662142 -288.004974) (xy 162.635255 -287.957448) (xy 162.616878 -287.906029)
			(xy 162.607551 -287.852228) (xy 162.60699 -287.824926) (xy 162.607452 -287.799933) (xy 162.615268 -287.750563)
			(xy 162.630711 -287.703023) (xy 162.653401 -287.658485) (xy 162.68278 -287.618045) (xy 162.718123 -287.582698)
			(xy 162.758561 -287.553316) (xy 162.803097 -287.530622) (xy 162.850636 -287.515175) (xy 162.900005 -287.507355)
			(xy 162.924998 -287.506918) (xy 162.953406 -287.507513) (xy 163.009327 -287.517554) (xy 163.062567 -287.537389)
			(xy 163.087304 -287.551368) (xy 163.099242 -287.55848) (xy 163.126674 -287.55848) (xy 163.201858 -287.514792)
			(xy 163.20516 -287.512506) (xy 163.214437 -287.505399) (xy 163.225815 -287.485016) (xy 163.227004 -287.47339)
			(xy 163.227004 -287.229042) (xy 163.227004 -287.226502) (xy 163.225784 -287.214888) (xy 163.214404 -287.194523)
			(xy 163.20516 -287.187386) (xy 163.201858 -287.1851) (xy 163.126674 -287.141412) (xy 163.099242 -287.141412)
			(xy 163.087304 -287.148524) (xy 163.062545 -287.162456) (xy 163.009307 -287.182268) (xy 162.953401 -287.192334)
			(xy 162.924998 -287.192974) (xy 162.900012 -287.192484) (xy 162.850654 -287.184666) (xy 162.803127 -287.169223)
			(xy 162.758601 -287.146536) (xy 162.718172 -287.117162) (xy 162.682836 -287.081826) (xy 162.653463 -287.041397)
			(xy 162.630776 -286.996871) (xy 162.615334 -286.949344) (xy 162.607516 -286.899986) (xy 162.607516 -286.850014)
			(xy 162.615334 -286.800656) (xy 162.630776 -286.753129) (xy 162.653463 -286.708603) (xy 162.682836 -286.668174)
			(xy 162.718172 -286.632838) (xy 162.758601 -286.603464) (xy 162.803127 -286.580777) (xy 162.850654 -286.565334)
			(xy 162.900012 -286.557516) (xy 162.924998 -286.556958) (xy 162.953406 -286.557553) (xy 163.009326 -286.567596)
			(xy 163.062565 -286.587433) (xy 163.087304 -286.601408) (xy 163.099242 -286.60852) (xy 163.126674 -286.60852)
			(xy 163.201858 -286.564832) (xy 163.20516 -286.562546) (xy 163.214428 -286.555435) (xy 163.225782 -286.53505)
			(xy 163.227004 -286.52343) (xy 163.227004 -286.278828) (xy 163.227004 -286.276288) (xy 163.225781 -286.264676)
			(xy 163.214399 -286.244315) (xy 163.20516 -286.237172) (xy 163.201858 -286.234886) (xy 163.126674 -286.191198)
			(xy 163.099242 -286.191198) (xy 163.087304 -286.19831) (xy 163.062544 -286.212238) (xy 163.009305 -286.232046)
			(xy 162.9534 -286.242108) (xy 162.924998 -286.24276) (xy 162.900013 -286.24227) (xy 162.850657 -286.234452)
			(xy 162.803132 -286.21901) (xy 162.758608 -286.196324) (xy 162.718181 -286.166952) (xy 162.682847 -286.131617)
			(xy 162.653475 -286.09119) (xy 162.630789 -286.046666) (xy 162.615347 -285.999141) (xy 162.60753 -285.949785)
			(xy 162.60753 -285.899815) (xy 162.615347 -285.850459) (xy 162.630789 -285.802934) (xy 162.653475 -285.75841)
			(xy 162.682847 -285.717983) (xy 162.718181 -285.682648) (xy 162.758608 -285.653276) (xy 162.803132 -285.63059)
			(xy 162.850657 -285.615148) (xy 162.900013 -285.60733) (xy 162.924998 -285.606744) (xy 162.953406 -285.607339)
			(xy 163.009326 -285.617381) (xy 163.062565 -285.637217) (xy 163.087304 -285.651194) (xy 163.099242 -285.658306)
			(xy 163.126674 -285.658306) (xy 163.201858 -285.614618) (xy 163.20516 -285.612332) (xy 163.214441 -285.605227)
			(xy 163.225829 -285.584845) (xy 163.227004 -285.573216) (xy 163.227004 -285.378398) (xy 163.227428 -285.368328)
			(xy 163.235143 -285.349725) (xy 163.24199 -285.34233) (xy 163.270692 -285.313628) (xy 163.277528 -285.306226)
			(xy 163.285237 -285.287628) (xy 163.285678 -285.27756) (xy 163.285678 -285.17469) (xy 163.285256 -285.164672)
			(xy 163.277584 -285.146162) (xy 163.263411 -285.131998) (xy 163.244897 -285.124338) (xy 163.234878 -285.12389)
			(xy 163.221924 -285.12389) (xy 163.199318 -285.136336) (xy 163.192206 -285.147258) (xy 163.177419 -285.169203)
			(xy 163.141764 -285.208299) (xy 163.100127 -285.240953) (xy 163.053658 -285.266261) (xy 163.003641 -285.283526)
			(xy 162.951455 -285.29227) (xy 162.924998 -285.2928) (xy 162.90001 -285.29231) (xy 162.850648 -285.284491)
			(xy 162.803117 -285.269047) (xy 162.758588 -285.246358) (xy 162.718155 -285.216982) (xy 162.682817 -285.181643)
			(xy 162.653441 -285.141211) (xy 162.630752 -285.096681) (xy 162.615308 -285.04915) (xy 162.60749 -284.999788)
			(xy 162.60749 -284.949812) (xy 162.615308 -284.90045) (xy 162.630752 -284.852919) (xy 162.653441 -284.808389)
			(xy 162.682817 -284.767957) (xy 162.718155 -284.732618) (xy 162.758588 -284.703242) (xy 162.803117 -284.680553)
			(xy 162.850648 -284.665109) (xy 162.90001 -284.65729) (xy 162.924998 -284.656784) (xy 162.951466 -284.657309)
			(xy 163.003673 -284.666069) (xy 163.053711 -284.683347) (xy 163.1002 -284.708667) (xy 163.12134 -284.724602)
			(xy 163.133024 -284.733746) (xy 163.161726 -284.736794) (xy 163.256976 -284.690312) (xy 163.265342 -284.685836)
			(xy 163.278252 -284.671948) (xy 163.285248 -284.654324) (xy 163.285678 -284.644846) (xy 163.285678 -284.354778)
			(xy 163.285249 -284.345295) (xy 163.278275 -284.327653) (xy 163.265364 -284.313755) (xy 163.256976 -284.309312)
			(xy 163.161726 -284.26283) (xy 163.133024 -284.265878) (xy 163.12134 -284.275022) (xy 163.100193 -284.290949)
			(xy 163.053712 -284.316283) (xy 163.003675 -284.333565) (xy 162.951467 -284.342319) (xy 162.924998 -284.34284)
			(xy 162.900006 -284.342349) (xy 162.850639 -284.33453) (xy 162.803102 -284.319084) (xy 162.758567 -284.296392)
			(xy 162.71813 -284.267013) (xy 162.682786 -284.231669) (xy 162.653407 -284.191232) (xy 162.630715 -284.146696)
			(xy 162.615269 -284.099159) (xy 162.60745 -284.049792) (xy 162.60745 -283.999808) (xy 162.615269 -283.950441)
			(xy 162.630715 -283.902904) (xy 162.653407 -283.858368) (xy 162.682786 -283.817931) (xy 162.71813 -283.782587)
			(xy 162.758567 -283.753208) (xy 162.803102 -283.730516) (xy 162.850639 -283.71507) (xy 162.900006 -283.707251)
			(xy 162.924998 -283.706824) (xy 162.951454 -283.707349) (xy 163.003637 -283.716105) (xy 163.053652 -283.733375)
			(xy 163.10012 -283.758683) (xy 163.141759 -283.791332) (xy 163.177421 -283.830421) (xy 163.192206 -283.852366)
			(xy 163.199318 -283.863288) (xy 163.221924 -283.875734) (xy 163.234878 -283.875734) (xy 163.244891 -283.87525)
			(xy 163.263396 -283.867596) (xy 163.277564 -283.853443) (xy 163.285239 -283.834947) (xy 163.285678 -283.824934)
			(xy 163.285678 -283.758132) (xy 163.285242 -283.748068) (xy 163.277508 -283.729483) (xy 163.270692 -283.722064)
			(xy 162.949382 -283.400754) (xy 162.931094 -283.39288) (xy 162.921188 -283.39288) (xy 162.895118 -283.392044)
			(xy 162.843766 -283.382919) (xy 162.794591 -283.36554) (xy 162.748909 -283.340372) (xy 162.707945 -283.308088)
			(xy 162.672796 -283.269555) (xy 162.644404 -283.225804) (xy 162.623529 -283.178007) (xy 162.616642 -283.15285)
			(xy 162.612324 -283.135832) (xy 162.584892 -283.114496) (xy 162.315144 -283.114496) (xy 162.287712 -283.135832)
			(xy 162.283394 -283.15285) (xy 162.276864 -283.176746) (xy 162.257421 -283.222307) (xy 162.23115 -283.264303)
			(xy 162.198685 -283.301718) (xy 162.160813 -283.333648) (xy 162.118448 -283.35932) (xy 162.072616 -283.378114)
			(xy 162.024424 -283.389575) (xy 161.975038 -283.393427) (xy 161.925652 -283.389575) (xy 161.87746 -283.378114)
			(xy 161.831628 -283.35932) (xy 161.789263 -283.333648) (xy 161.751391 -283.301718) (xy 161.718926 -283.264303)
			(xy 161.692655 -283.222307) (xy 161.673212 -283.176746) (xy 161.666682 -283.15285) (xy 161.662364 -283.135832)
			(xy 161.634932 -283.114496) (xy 161.365184 -283.114496) (xy 161.337752 -283.135832) (xy 161.333434 -283.15285)
			(xy 161.326904 -283.176746) (xy 161.307461 -283.222307) (xy 161.28119 -283.264303) (xy 161.248725 -283.301718)
			(xy 161.210853 -283.333648) (xy 161.168488 -283.35932) (xy 161.122656 -283.378114) (xy 161.074464 -283.389575)
			(xy 161.025078 -283.393427) (xy 160.975692 -283.389575) (xy 160.9275 -283.378114) (xy 160.881668 -283.35932)
			(xy 160.839303 -283.333648) (xy 160.801431 -283.301718) (xy 160.768966 -283.264303) (xy 160.742695 -283.222307)
			(xy 160.723252 -283.176746) (xy 160.716722 -283.15285) (xy 160.712404 -283.135832) (xy 160.684972 -283.114496)
			(xy 160.41497 -283.114496) (xy 160.387538 -283.135832) (xy 160.38322 -283.15285) (xy 160.37669 -283.176746)
			(xy 160.357247 -283.222307) (xy 160.330976 -283.264303) (xy 160.298511 -283.301718) (xy 160.260639 -283.333648)
			(xy 160.218274 -283.35932) (xy 160.172442 -283.378114) (xy 160.12425 -283.389575) (xy 160.074864 -283.393427)
			(xy 160.025478 -283.389575) (xy 159.977286 -283.378114) (xy 159.931454 -283.35932) (xy 159.889089 -283.333648)
			(xy 159.851217 -283.301718) (xy 159.818752 -283.264303) (xy 159.792481 -283.222307) (xy 159.773038 -283.176746)
			(xy 159.766508 -283.15285) (xy 159.76219 -283.135832) (xy 159.734758 -283.114496) (xy 159.46501 -283.114496)
			(xy 159.437578 -283.135832) (xy 159.43326 -283.15285) (xy 159.42631 -283.178238) (xy 159.405179 -283.226445)
			(xy 159.376399 -283.270515) (xy 159.340754 -283.309243) (xy 159.299218 -283.341573) (xy 159.252926 -283.366621)
			(xy 159.20314 -283.383705) (xy 159.151222 -283.392357) (xy 159.124904 -283.39288) (xy 159.099174 -283.392376)
			(xy 159.048386 -283.384074) (xy 158.999599 -283.367702) (xy 158.954085 -283.343687) (xy 158.913032 -283.312656)
			(xy 158.877512 -283.275419) (xy 158.848452 -283.232948) (xy 158.82661 -283.186352) (xy 158.819088 -283.16174)
			(xy 158.814262 -283.145484) (xy 158.787084 -283.12491) (xy 158.512764 -283.12491) (xy 158.485586 -283.145484)
			(xy 158.48076 -283.16174) (xy 158.473268 -283.186368) (xy 158.451443 -283.232987) (xy 158.422391 -283.275481)
			(xy 158.386871 -283.312737) (xy 158.345811 -283.343782) (xy 158.300286 -283.367805) (xy 158.251484 -283.384179)
			(xy 158.200682 -283.392473) (xy 158.149206 -283.392473) (xy 158.098404 -283.384179) (xy 158.049602 -283.367805)
			(xy 158.004077 -283.343782) (xy 157.963017 -283.312737) (xy 157.927497 -283.275481) (xy 157.898445 -283.232987)
			(xy 157.87662 -283.186368) (xy 157.869128 -283.16174) (xy 157.864302 -283.145484) (xy 157.837124 -283.12491)
			(xy 157.562804 -283.12491) (xy 157.535626 -283.145484) (xy 157.5308 -283.16174) (xy 157.523315 -283.18637)
			(xy 157.5015 -283.232993) (xy 157.472453 -283.275488) (xy 157.436932 -283.312742) (xy 157.395868 -283.34378)
			(xy 157.350336 -283.36779) (xy 157.301528 -283.384142) (xy 157.250721 -283.392408) (xy 157.224984 -283.39288)
			(xy 157.198532 -283.392362) (xy 157.146354 -283.383623) (xy 157.096342 -283.366371) (xy 157.049873 -283.341083)
			(xy 157.008229 -283.308455) (xy 156.990034 -283.289248) (xy 156.989272 -283.288232) (xy 156.98851 -283.28747)
			(xy 156.981076 -283.280754) (xy 156.962576 -283.273118) (xy 156.942562 -283.273118) (xy 156.924062 -283.280754)
			(xy 156.916628 -283.28747) (xy 156.882084 -283.322014) (xy 156.875231 -283.329409) (xy 156.867488 -283.348008)
			(xy 156.867098 -283.358082) (xy 156.867098 -284.049821) (xy 158.807386 -284.049821) (xy 158.807386 -283.999843)
			(xy 158.815205 -283.95048) (xy 158.830649 -283.902948) (xy 158.853339 -283.858416) (xy 158.882715 -283.817983)
			(xy 158.918055 -283.782643) (xy 158.958488 -283.753267) (xy 159.00302 -283.730577) (xy 159.050552 -283.715133)
			(xy 159.099915 -283.707314) (xy 159.149893 -283.707314) (xy 159.199256 -283.715133) (xy 159.246788 -283.730577)
			(xy 159.29132 -283.753267) (xy 159.331753 -283.782643) (xy 159.367093 -283.817983) (xy 159.396469 -283.858416)
			(xy 159.419159 -283.902948) (xy 159.434603 -283.95048) (xy 159.442422 -283.999843) (xy 159.442912 -284.024832)
			(xy 159.442422 -284.049821) (xy 159.757346 -284.049821) (xy 159.757346 -283.999843) (xy 159.765165 -283.95048)
			(xy 159.780609 -283.902948) (xy 159.803299 -283.858416) (xy 159.832675 -283.817983) (xy 159.868015 -283.782643)
			(xy 159.908448 -283.753267) (xy 159.95298 -283.730577) (xy 160.000512 -283.715133) (xy 160.049875 -283.707314)
			(xy 160.099853 -283.707314) (xy 160.149216 -283.715133) (xy 160.196748 -283.730577) (xy 160.24128 -283.753267)
			(xy 160.281713 -283.782643) (xy 160.317053 -283.817983) (xy 160.346429 -283.858416) (xy 160.369119 -283.902948)
			(xy 160.384563 -283.95048) (xy 160.392382 -283.999843) (xy 160.392872 -284.024832) (xy 160.392382 -284.049821)
			(xy 160.70756 -284.049821) (xy 160.70756 -283.999843) (xy 160.715379 -283.95048) (xy 160.730823 -283.902948)
			(xy 160.753513 -283.858416) (xy 160.782889 -283.817983) (xy 160.818229 -283.782643) (xy 160.858662 -283.753267)
			(xy 160.903194 -283.730577) (xy 160.950726 -283.715133) (xy 161.000089 -283.707314) (xy 161.050067 -283.707314)
			(xy 161.09943 -283.715133) (xy 161.146962 -283.730577) (xy 161.191494 -283.753267) (xy 161.231927 -283.782643)
			(xy 161.267267 -283.817983) (xy 161.296643 -283.858416) (xy 161.319333 -283.902948) (xy 161.334777 -283.95048)
			(xy 161.342596 -283.999843) (xy 161.343086 -284.024832) (xy 161.342596 -284.049821) (xy 161.65752 -284.049821)
			(xy 161.65752 -283.999843) (xy 161.665339 -283.95048) (xy 161.680783 -283.902948) (xy 161.703473 -283.858416)
			(xy 161.732849 -283.817983) (xy 161.768189 -283.782643) (xy 161.808622 -283.753267) (xy 161.853154 -283.730577)
			(xy 161.900686 -283.715133) (xy 161.950049 -283.707314) (xy 162.000027 -283.707314) (xy 162.04939 -283.715133)
			(xy 162.096922 -283.730577) (xy 162.141454 -283.753267) (xy 162.181887 -283.782643) (xy 162.217227 -283.817983)
			(xy 162.246603 -283.858416) (xy 162.269293 -283.902948) (xy 162.284737 -283.95048) (xy 162.292556 -283.999843)
			(xy 162.293046 -284.024832) (xy 162.292556 -284.049821) (xy 162.284737 -284.099184) (xy 162.269293 -284.146716)
			(xy 162.246603 -284.191248) (xy 162.217227 -284.231681) (xy 162.181887 -284.267021) (xy 162.141454 -284.296397)
			(xy 162.096922 -284.319087) (xy 162.04939 -284.334531) (xy 162.000027 -284.34235) (xy 161.950049 -284.34235)
			(xy 161.900686 -284.334531) (xy 161.853154 -284.319087) (xy 161.808622 -284.296397) (xy 161.768189 -284.267021)
			(xy 161.732849 -284.231681) (xy 161.703473 -284.191248) (xy 161.680783 -284.146716) (xy 161.665339 -284.099184)
			(xy 161.65752 -284.049821) (xy 161.342596 -284.049821) (xy 161.334777 -284.099184) (xy 161.319333 -284.146716)
			(xy 161.296643 -284.191248) (xy 161.267267 -284.231681) (xy 161.231927 -284.267021) (xy 161.191494 -284.296397)
			(xy 161.146962 -284.319087) (xy 161.09943 -284.334531) (xy 161.050067 -284.34235) (xy 161.000089 -284.34235)
			(xy 160.950726 -284.334531) (xy 160.903194 -284.319087) (xy 160.858662 -284.296397) (xy 160.818229 -284.267021)
			(xy 160.782889 -284.231681) (xy 160.753513 -284.191248) (xy 160.730823 -284.146716) (xy 160.715379 -284.099184)
			(xy 160.70756 -284.049821) (xy 160.392382 -284.049821) (xy 160.384563 -284.099184) (xy 160.369119 -284.146716)
			(xy 160.346429 -284.191248) (xy 160.317053 -284.231681) (xy 160.281713 -284.267021) (xy 160.24128 -284.296397)
			(xy 160.196748 -284.319087) (xy 160.149216 -284.334531) (xy 160.099853 -284.34235) (xy 160.049875 -284.34235)
			(xy 160.000512 -284.334531) (xy 159.95298 -284.319087) (xy 159.908448 -284.296397) (xy 159.868015 -284.267021)
			(xy 159.832675 -284.231681) (xy 159.803299 -284.191248) (xy 159.780609 -284.146716) (xy 159.765165 -284.099184)
			(xy 159.757346 -284.049821) (xy 159.442422 -284.049821) (xy 159.434603 -284.099184) (xy 159.419159 -284.146716)
			(xy 159.396469 -284.191248) (xy 159.367093 -284.231681) (xy 159.331753 -284.267021) (xy 159.29132 -284.296397)
			(xy 159.246788 -284.319087) (xy 159.199256 -284.334531) (xy 159.149893 -284.34235) (xy 159.099915 -284.34235)
			(xy 159.050552 -284.334531) (xy 159.00302 -284.319087) (xy 158.958488 -284.296397) (xy 158.918055 -284.267021)
			(xy 158.882715 -284.231681) (xy 158.853339 -284.191248) (xy 158.830649 -284.146716) (xy 158.815205 -284.099184)
			(xy 158.807386 -284.049821) (xy 156.867098 -284.049821) (xy 156.867098 -285.0769) (xy 156.867521 -285.08697)
			(xy 156.875235 -285.105575) (xy 156.882084 -285.112968) (xy 156.991304 -285.222188) (xy 156.998702 -285.229035)
			(xy 157.0173 -285.23677) (xy 157.027372 -285.237174) (xy 158.7373 -285.237174) (xy 158.749855 -285.236532)
			(xy 158.771987 -285.224674) (xy 158.779464 -285.214568) (xy 158.833566 -285.133542) (xy 158.836106 -285.10865)
			(xy 158.83128 -285.096712) (xy 158.819916 -285.067522) (xy 158.807635 -285.006107) (xy 158.806896 -284.974792)
			(xy 158.807386 -284.949803) (xy 158.815205 -284.90044) (xy 158.830649 -284.852908) (xy 158.853339 -284.808376)
			(xy 158.882715 -284.767943) (xy 158.918055 -284.732603) (xy 158.958488 -284.703227) (xy 159.00302 -284.680537)
			(xy 159.050552 -284.665093) (xy 159.099915 -284.657274) (xy 159.149893 -284.657274) (xy 159.199256 -284.665093)
			(xy 159.246788 -284.680537) (xy 159.29132 -284.703227) (xy 159.331753 -284.732603) (xy 159.367093 -284.767943)
			(xy 159.396469 -284.808376) (xy 159.419159 -284.852908) (xy 159.434603 -284.90044) (xy 159.442422 -284.949803)
			(xy 159.442912 -284.974792) (xy 159.442489 -284.999196) (xy 159.442399 -284.999781) (xy 160.70756 -284.999781)
			(xy 160.70756 -284.949803) (xy 160.715379 -284.90044) (xy 160.730823 -284.852908) (xy 160.753513 -284.808376)
			(xy 160.782889 -284.767943) (xy 160.818229 -284.732603) (xy 160.858662 -284.703227) (xy 160.903194 -284.680537)
			(xy 160.950726 -284.665093) (xy 161.000089 -284.657274) (xy 161.050067 -284.657274) (xy 161.09943 -284.665093)
			(xy 161.146962 -284.680537) (xy 161.191494 -284.703227) (xy 161.231927 -284.732603) (xy 161.267267 -284.767943)
			(xy 161.296643 -284.808376) (xy 161.319333 -284.852908) (xy 161.334777 -284.90044) (xy 161.342596 -284.949803)
			(xy 161.343086 -284.974792) (xy 161.342596 -284.999781) (xy 161.65752 -284.999781) (xy 161.65752 -284.949803)
			(xy 161.665339 -284.90044) (xy 161.680783 -284.852908) (xy 161.703473 -284.808376) (xy 161.732849 -284.767943)
			(xy 161.768189 -284.732603) (xy 161.808622 -284.703227) (xy 161.853154 -284.680537) (xy 161.900686 -284.665093)
			(xy 161.950049 -284.657274) (xy 162.000027 -284.657274) (xy 162.04939 -284.665093) (xy 162.096922 -284.680537)
			(xy 162.141454 -284.703227) (xy 162.181887 -284.732603) (xy 162.217227 -284.767943) (xy 162.246603 -284.808376)
			(xy 162.269293 -284.852908) (xy 162.284737 -284.90044) (xy 162.292556 -284.949803) (xy 162.293046 -284.974792)
			(xy 162.292556 -284.999781) (xy 162.284737 -285.049144) (xy 162.269293 -285.096676) (xy 162.246603 -285.141208)
			(xy 162.217227 -285.181641) (xy 162.181887 -285.216981) (xy 162.141454 -285.246357) (xy 162.096922 -285.269047)
			(xy 162.04939 -285.284491) (xy 162.000027 -285.29231) (xy 161.950049 -285.29231) (xy 161.900686 -285.284491)
			(xy 161.853154 -285.269047) (xy 161.808622 -285.246357) (xy 161.768189 -285.216981) (xy 161.732849 -285.181641)
			(xy 161.703473 -285.141208) (xy 161.680783 -285.096676) (xy 161.665339 -285.049144) (xy 161.65752 -284.999781)
			(xy 161.342596 -284.999781) (xy 161.334777 -285.049144) (xy 161.319333 -285.096676) (xy 161.296643 -285.141208)
			(xy 161.267267 -285.181641) (xy 161.231927 -285.216981) (xy 161.191494 -285.246357) (xy 161.146962 -285.269047)
			(xy 161.09943 -285.284491) (xy 161.050067 -285.29231) (xy 161.000089 -285.29231) (xy 160.950726 -285.284491)
			(xy 160.903194 -285.269047) (xy 160.858662 -285.246357) (xy 160.818229 -285.216981) (xy 160.782889 -285.181641)
			(xy 160.753513 -285.141208) (xy 160.730823 -285.096676) (xy 160.715379 -285.049144) (xy 160.70756 -284.999781)
			(xy 159.442399 -284.999781) (xy 159.435072 -285.047437) (xy 159.420364 -285.093976) (xy 159.398711 -285.137719)
			(xy 159.370624 -285.177635) (xy 159.354012 -285.195518) (xy 159.3469 -285.20263) (xy 159.339534 -285.220918)
			(xy 159.340296 -285.302198) (xy 159.34086 -285.312125) (xy 159.348556 -285.330437) (xy 159.355282 -285.337758)
			(xy 159.377888 -285.360364) (xy 159.384725 -285.367766) (xy 159.392438 -285.386364) (xy 159.392874 -285.396432)
			(xy 159.392874 -285.949741) (xy 160.70756 -285.949741) (xy 160.70756 -285.899763) (xy 160.715379 -285.8504)
			(xy 160.730823 -285.802868) (xy 160.753513 -285.758336) (xy 160.782889 -285.717903) (xy 160.818229 -285.682563)
			(xy 160.858662 -285.653187) (xy 160.903194 -285.630497) (xy 160.950726 -285.615053) (xy 161.000089 -285.607234)
			(xy 161.050067 -285.607234) (xy 161.09943 -285.615053) (xy 161.146962 -285.630497) (xy 161.191494 -285.653187)
			(xy 161.231927 -285.682563) (xy 161.267267 -285.717903) (xy 161.296643 -285.758336) (xy 161.319333 -285.802868)
			(xy 161.334777 -285.8504) (xy 161.342596 -285.899763) (xy 161.343086 -285.924752) (xy 161.342596 -285.949741)
			(xy 161.65752 -285.949741) (xy 161.65752 -285.899763) (xy 161.665339 -285.8504) (xy 161.680783 -285.802868)
			(xy 161.703473 -285.758336) (xy 161.732849 -285.717903) (xy 161.768189 -285.682563) (xy 161.808622 -285.653187)
			(xy 161.853154 -285.630497) (xy 161.900686 -285.615053) (xy 161.950049 -285.607234) (xy 162.000027 -285.607234)
			(xy 162.04939 -285.615053) (xy 162.096922 -285.630497) (xy 162.141454 -285.653187) (xy 162.181887 -285.682563)
			(xy 162.217227 -285.717903) (xy 162.246603 -285.758336) (xy 162.269293 -285.802868) (xy 162.284737 -285.8504)
			(xy 162.292556 -285.899763) (xy 162.293046 -285.924752) (xy 162.292556 -285.949741) (xy 162.284737 -285.999104)
			(xy 162.269293 -286.046636) (xy 162.246603 -286.091168) (xy 162.217227 -286.131601) (xy 162.181887 -286.166941)
			(xy 162.141454 -286.196317) (xy 162.096922 -286.219007) (xy 162.04939 -286.234451) (xy 162.000027 -286.24227)
			(xy 161.950049 -286.24227) (xy 161.900686 -286.234451) (xy 161.853154 -286.219007) (xy 161.808622 -286.196317)
			(xy 161.768189 -286.166941) (xy 161.732849 -286.131601) (xy 161.703473 -286.091168) (xy 161.680783 -286.046636)
			(xy 161.665339 -285.999104) (xy 161.65752 -285.949741) (xy 161.342596 -285.949741) (xy 161.334777 -285.999104)
			(xy 161.319333 -286.046636) (xy 161.296643 -286.091168) (xy 161.267267 -286.131601) (xy 161.231927 -286.166941)
			(xy 161.191494 -286.196317) (xy 161.146962 -286.219007) (xy 161.09943 -286.234451) (xy 161.050067 -286.24227)
			(xy 161.000089 -286.24227) (xy 160.950726 -286.234451) (xy 160.903194 -286.219007) (xy 160.858662 -286.196317)
			(xy 160.818229 -286.166941) (xy 160.782889 -286.131601) (xy 160.753513 -286.091168) (xy 160.730823 -286.046636)
			(xy 160.715379 -285.999104) (xy 160.70756 -285.949741) (xy 159.392874 -285.949741) (xy 159.392874 -286.69615)
			(xy 159.39643 -286.70885) (xy 159.399732 -286.714692) (xy 159.411415 -286.735623) (xy 159.429042 -286.780198)
			(xy 159.43978 -286.826913) (xy 159.443386 -286.87471) (xy 159.441499 -286.899701) (xy 159.757346 -286.899701)
			(xy 159.757346 -286.849723) (xy 159.765165 -286.80036) (xy 159.780609 -286.752828) (xy 159.803299 -286.708296)
			(xy 159.832675 -286.667863) (xy 159.868015 -286.632523) (xy 159.908448 -286.603147) (xy 159.95298 -286.580457)
			(xy 160.000512 -286.565013) (xy 160.049875 -286.557194) (xy 160.099853 -286.557194) (xy 160.149216 -286.565013)
			(xy 160.196748 -286.580457) (xy 160.24128 -286.603147) (xy 160.281713 -286.632523) (xy 160.317053 -286.667863)
			(xy 160.346429 -286.708296) (xy 160.369119 -286.752828) (xy 160.384563 -286.80036) (xy 160.392382 -286.849723)
			(xy 160.392872 -286.874712) (xy 160.392382 -286.899701) (xy 160.392342 -286.899955) (xy 160.70756 -286.899955)
			(xy 160.70756 -286.849977) (xy 160.715379 -286.800614) (xy 160.730823 -286.753082) (xy 160.753513 -286.70855)
			(xy 160.782889 -286.668117) (xy 160.818229 -286.632777) (xy 160.858662 -286.603401) (xy 160.903194 -286.580711)
			(xy 160.950726 -286.565267) (xy 161.000089 -286.557448) (xy 161.050067 -286.557448) (xy 161.09943 -286.565267)
			(xy 161.146962 -286.580711) (xy 161.191494 -286.603401) (xy 161.231927 -286.632777) (xy 161.267267 -286.668117)
			(xy 161.296643 -286.70855) (xy 161.319333 -286.753082) (xy 161.334777 -286.800614) (xy 161.342596 -286.849977)
			(xy 161.343086 -286.874966) (xy 161.342596 -286.899955) (xy 161.65752 -286.899955) (xy 161.65752 -286.849977)
			(xy 161.665339 -286.800614) (xy 161.680783 -286.753082) (xy 161.703473 -286.70855) (xy 161.732849 -286.668117)
			(xy 161.768189 -286.632777) (xy 161.808622 -286.603401) (xy 161.853154 -286.580711) (xy 161.900686 -286.565267)
			(xy 161.950049 -286.557448) (xy 162.000027 -286.557448) (xy 162.04939 -286.565267) (xy 162.096922 -286.580711)
			(xy 162.141454 -286.603401) (xy 162.181887 -286.632777) (xy 162.217227 -286.668117) (xy 162.246603 -286.70855)
			(xy 162.269293 -286.753082) (xy 162.284737 -286.800614) (xy 162.292556 -286.849977) (xy 162.293046 -286.874966)
			(xy 162.292556 -286.899955) (xy 162.284737 -286.949318) (xy 162.269293 -286.99685) (xy 162.246603 -287.041382)
			(xy 162.217227 -287.081815) (xy 162.181887 -287.117155) (xy 162.141454 -287.146531) (xy 162.096922 -287.169221)
			(xy 162.04939 -287.184665) (xy 162.000027 -287.192484) (xy 161.950049 -287.192484) (xy 161.900686 -287.184665)
			(xy 161.853154 -287.169221) (xy 161.808622 -287.146531) (xy 161.768189 -287.117155) (xy 161.732849 -287.081815)
			(xy 161.703473 -287.041382) (xy 161.680783 -286.99685) (xy 161.665339 -286.949318) (xy 161.65752 -286.899955)
			(xy 161.342596 -286.899955) (xy 161.334777 -286.949318) (xy 161.319333 -286.99685) (xy 161.296643 -287.041382)
			(xy 161.267267 -287.081815) (xy 161.231927 -287.117155) (xy 161.191494 -287.146531) (xy 161.146962 -287.169221)
			(xy 161.09943 -287.184665) (xy 161.050067 -287.192484) (xy 161.000089 -287.192484) (xy 160.950726 -287.184665)
			(xy 160.903194 -287.169221) (xy 160.858662 -287.146531) (xy 160.818229 -287.117155) (xy 160.782889 -287.081815)
			(xy 160.753513 -287.041382) (xy 160.730823 -286.99685) (xy 160.715379 -286.949318) (xy 160.70756 -286.899955)
			(xy 160.392342 -286.899955) (xy 160.384563 -286.949064) (xy 160.369119 -286.996596) (xy 160.346429 -287.041128)
			(xy 160.317053 -287.081561) (xy 160.281713 -287.116901) (xy 160.24128 -287.146277) (xy 160.196748 -287.168967)
			(xy 160.149216 -287.184411) (xy 160.099853 -287.19223) (xy 160.049875 -287.19223) (xy 160.000512 -287.184411)
			(xy 159.95298 -287.168967) (xy 159.908448 -287.146277) (xy 159.868015 -287.116901) (xy 159.832675 -287.081561)
			(xy 159.803299 -287.041128) (xy 159.780609 -286.996596) (xy 159.765165 -286.949064) (xy 159.757346 -286.899701)
			(xy 159.441499 -286.899701) (xy 159.439777 -286.922508) (xy 159.429036 -286.969222) (xy 159.411406 -287.013796)
			(xy 159.399732 -287.034732) (xy 159.39643 -287.040574) (xy 159.392874 -287.053274) (xy 159.392874 -287.5534)
			(xy 159.39245 -287.56347) (xy 159.384733 -287.582072) (xy 159.377888 -287.589468) (xy 159.23768 -287.729676)
			(xy 159.230282 -287.736522) (xy 159.211683 -287.744253) (xy 159.201612 -287.744662) (xy 157.845252 -287.744662)
			(xy 157.835187 -287.745096) (xy 157.816601 -287.752829) (xy 157.809184 -287.759648) (xy 157.718917 -287.849915)
			(xy 160.70756 -287.849915) (xy 160.70756 -287.799937) (xy 160.715379 -287.750574) (xy 160.730823 -287.703042)
			(xy 160.753513 -287.65851) (xy 160.782889 -287.618077) (xy 160.818229 -287.582737) (xy 160.858662 -287.553361)
			(xy 160.903194 -287.530671) (xy 160.950726 -287.515227) (xy 161.000089 -287.507408) (xy 161.050067 -287.507408)
			(xy 161.09943 -287.515227) (xy 161.146962 -287.530671) (xy 161.191494 -287.553361) (xy 161.231927 -287.582737)
			(xy 161.267267 -287.618077) (xy 161.296643 -287.65851) (xy 161.319333 -287.703042) (xy 161.334777 -287.750574)
			(xy 161.342596 -287.799937) (xy 161.343086 -287.824926) (xy 161.342596 -287.849915) (xy 161.65752 -287.849915)
			(xy 161.65752 -287.799937) (xy 161.665339 -287.750574) (xy 161.680783 -287.703042) (xy 161.703473 -287.65851)
			(xy 161.732849 -287.618077) (xy 161.768189 -287.582737) (xy 161.808622 -287.553361) (xy 161.853154 -287.530671)
			(xy 161.900686 -287.515227) (xy 161.950049 -287.507408) (xy 162.000027 -287.507408) (xy 162.04939 -287.515227)
			(xy 162.096922 -287.530671) (xy 162.141454 -287.553361) (xy 162.181887 -287.582737) (xy 162.217227 -287.618077)
			(xy 162.246603 -287.65851) (xy 162.269293 -287.703042) (xy 162.284737 -287.750574) (xy 162.292556 -287.799937)
			(xy 162.293046 -287.824926) (xy 162.292556 -287.849915) (xy 162.284737 -287.899278) (xy 162.269293 -287.94681)
			(xy 162.246603 -287.991342) (xy 162.217227 -288.031775) (xy 162.181887 -288.067115) (xy 162.141454 -288.096491)
			(xy 162.096922 -288.119181) (xy 162.04939 -288.134625) (xy 162.000027 -288.142444) (xy 161.950049 -288.142444)
			(xy 161.900686 -288.134625) (xy 161.853154 -288.119181) (xy 161.808622 -288.096491) (xy 161.768189 -288.067115)
			(xy 161.732849 -288.031775) (xy 161.703473 -287.991342) (xy 161.680783 -287.94681) (xy 161.665339 -287.899278)
			(xy 161.65752 -287.849915) (xy 161.342596 -287.849915) (xy 161.334777 -287.899278) (xy 161.319333 -287.94681)
			(xy 161.296643 -287.991342) (xy 161.267267 -288.031775) (xy 161.231927 -288.067115) (xy 161.191494 -288.096491)
			(xy 161.146962 -288.119181) (xy 161.09943 -288.134625) (xy 161.050067 -288.142444) (xy 161.000089 -288.142444)
			(xy 160.950726 -288.134625) (xy 160.903194 -288.119181) (xy 160.858662 -288.096491) (xy 160.818229 -288.067115)
			(xy 160.782889 -288.031775) (xy 160.753513 -287.991342) (xy 160.730823 -287.94681) (xy 160.715379 -287.899278)
			(xy 160.70756 -287.849915) (xy 157.718917 -287.849915) (xy 157.448758 -288.120074) (xy 157.441917 -288.127474)
			(xy 157.4342 -288.146073) (xy 157.433772 -288.156142) (xy 157.433772 -288.583878) (xy 157.434277 -288.593929)
			(xy 157.441998 -288.61249) (xy 157.448758 -288.619946) (xy 157.599126 -288.770314) (xy 157.606468 -288.77713)
			(xy 157.624932 -288.784866) (xy 157.63494 -288.7853) (xy 158.004764 -288.7853) (xy 158.77794 -288.7853)
			(xy 158.806642 -288.759646) (xy 158.808928 -288.740088) (xy 158.812229 -288.714464) (xy 158.826063 -288.664688)
			(xy 158.84777 -288.617808) (xy 158.876778 -288.575058) (xy 158.912321 -288.537566) (xy 158.953463 -288.50632)
			(xy 158.999119 -288.482144) (xy 159.048086 -288.465675) (xy 159.099073 -288.457348) (xy 159.124904 -288.456878)
			(xy 159.149893 -288.457369) (xy 159.199257 -288.465187) (xy 159.246789 -288.480632) (xy 159.291321 -288.503321)
			(xy 159.331755 -288.532698) (xy 159.367096 -288.568038) (xy 159.396473 -288.608471) (xy 159.419164 -288.653001)
			(xy 159.43461 -288.700533) (xy 159.442431 -288.749897) (xy 159.442912 -288.774886) (xy 159.44244 -288.799875)
			(xy 159.757346 -288.799875) (xy 159.757346 -288.749897) (xy 159.765165 -288.700534) (xy 159.780609 -288.653002)
			(xy 159.803299 -288.60847) (xy 159.832675 -288.568037) (xy 159.868015 -288.532697) (xy 159.908448 -288.503321)
			(xy 159.95298 -288.480631) (xy 160.000512 -288.465187) (xy 160.049875 -288.457368) (xy 160.099853 -288.457368)
			(xy 160.149216 -288.465187) (xy 160.196748 -288.480631) (xy 160.24128 -288.503321) (xy 160.281713 -288.532697)
			(xy 160.317053 -288.568037) (xy 160.346429 -288.60847) (xy 160.369119 -288.653002) (xy 160.384563 -288.700534)
			(xy 160.392382 -288.749897) (xy 160.392872 -288.774886) (xy 160.392382 -288.799875) (xy 160.70756 -288.799875)
			(xy 160.70756 -288.749897) (xy 160.715379 -288.700534) (xy 160.730823 -288.653002) (xy 160.753513 -288.60847)
			(xy 160.782889 -288.568037) (xy 160.818229 -288.532697) (xy 160.858662 -288.503321) (xy 160.903194 -288.480631)
			(xy 160.950726 -288.465187) (xy 161.000089 -288.457368) (xy 161.050067 -288.457368) (xy 161.09943 -288.465187)
			(xy 161.146962 -288.480631) (xy 161.191494 -288.503321) (xy 161.231927 -288.532697) (xy 161.267267 -288.568037)
			(xy 161.296643 -288.60847) (xy 161.319333 -288.653002) (xy 161.334777 -288.700534) (xy 161.342596 -288.749897)
			(xy 161.343086 -288.774886) (xy 161.342596 -288.799875) (xy 161.65752 -288.799875) (xy 161.65752 -288.749897)
			(xy 161.665339 -288.700534) (xy 161.680783 -288.653002) (xy 161.703473 -288.60847) (xy 161.732849 -288.568037)
			(xy 161.768189 -288.532697) (xy 161.808622 -288.503321) (xy 161.853154 -288.480631) (xy 161.900686 -288.465187)
			(xy 161.950049 -288.457368) (xy 162.000027 -288.457368) (xy 162.04939 -288.465187) (xy 162.096922 -288.480631)
			(xy 162.141454 -288.503321) (xy 162.181887 -288.532697) (xy 162.217227 -288.568037) (xy 162.246603 -288.60847)
			(xy 162.269293 -288.653002) (xy 162.284737 -288.700534) (xy 162.292556 -288.749897) (xy 162.293046 -288.774886)
			(xy 162.292556 -288.799875) (xy 162.284737 -288.849238) (xy 162.269293 -288.89677) (xy 162.246603 -288.941302)
			(xy 162.217227 -288.981735) (xy 162.181887 -289.017075) (xy 162.141454 -289.046451) (xy 162.096922 -289.069141)
			(xy 162.04939 -289.084585) (xy 162.000027 -289.092404) (xy 161.950049 -289.092404) (xy 161.900686 -289.084585)
			(xy 161.853154 -289.069141) (xy 161.808622 -289.046451) (xy 161.768189 -289.017075) (xy 161.732849 -288.981735)
			(xy 161.703473 -288.941302) (xy 161.680783 -288.89677) (xy 161.665339 -288.849238) (xy 161.65752 -288.799875)
			(xy 161.342596 -288.799875) (xy 161.334777 -288.849238) (xy 161.319333 -288.89677) (xy 161.296643 -288.941302)
			(xy 161.267267 -288.981735) (xy 161.231927 -289.017075) (xy 161.191494 -289.046451) (xy 161.146962 -289.069141)
			(xy 161.09943 -289.084585) (xy 161.050067 -289.092404) (xy 161.000089 -289.092404) (xy 160.950726 -289.084585)
			(xy 160.903194 -289.069141) (xy 160.858662 -289.046451) (xy 160.818229 -289.017075) (xy 160.782889 -288.981735)
			(xy 160.753513 -288.941302) (xy 160.730823 -288.89677) (xy 160.715379 -288.849238) (xy 160.70756 -288.799875)
			(xy 160.392382 -288.799875) (xy 160.384563 -288.849238) (xy 160.369119 -288.89677) (xy 160.346429 -288.941302)
			(xy 160.317053 -288.981735) (xy 160.281713 -289.017075) (xy 160.24128 -289.046451) (xy 160.196748 -289.069141)
			(xy 160.149216 -289.084585) (xy 160.099853 -289.092404) (xy 160.049875 -289.092404) (xy 160.000512 -289.084585)
			(xy 159.95298 -289.069141) (xy 159.908448 -289.046451) (xy 159.868015 -289.017075) (xy 159.832675 -288.981735)
			(xy 159.803299 -288.941302) (xy 159.780609 -288.89677) (xy 159.765165 -288.849238) (xy 159.757346 -288.799875)
			(xy 159.44244 -288.799875) (xy 159.442437 -288.800037) (xy 159.434525 -288.849714) (xy 159.418896 -288.897527)
			(xy 159.395939 -288.942286) (xy 159.381444 -288.962846) (xy 159.370268 -288.978086) (xy 159.373062 -289.015424)
			(xy 159.377888 -289.02025) (xy 159.384728 -289.027651) (xy 159.392446 -289.046249) (xy 159.392874 -289.056318)
			(xy 159.392874 -289.515296) (xy 159.393128 -289.522708) (xy 159.397389 -289.536907) (xy 159.401256 -289.543236)
			(xy 159.415903 -289.566499) (xy 159.438092 -289.61679) (xy 159.451652 -289.670059) (xy 159.45621 -289.724838)
			(xy 159.454124 -289.749835) (xy 159.757346 -289.749835) (xy 159.757346 -289.699857) (xy 159.765165 -289.650494)
			(xy 159.780609 -289.602962) (xy 159.803299 -289.55843) (xy 159.832675 -289.517997) (xy 159.868015 -289.482657)
			(xy 159.908448 -289.453281) (xy 159.95298 -289.430591) (xy 160.000512 -289.415147) (xy 160.049875 -289.407328)
			(xy 160.099853 -289.407328) (xy 160.149216 -289.415147) (xy 160.196748 -289.430591) (xy 160.24128 -289.453281)
			(xy 160.281713 -289.482657) (xy 160.317053 -289.517997) (xy 160.346429 -289.55843) (xy 160.369119 -289.602962)
			(xy 160.384563 -289.650494) (xy 160.392382 -289.699857) (xy 160.392872 -289.724846) (xy 160.392382 -289.749835)
			(xy 160.70756 -289.749835) (xy 160.70756 -289.699857) (xy 160.715379 -289.650494) (xy 160.730823 -289.602962)
			(xy 160.753513 -289.55843) (xy 160.782889 -289.517997) (xy 160.818229 -289.482657) (xy 160.858662 -289.453281)
			(xy 160.903194 -289.430591) (xy 160.950726 -289.415147) (xy 161.000089 -289.407328) (xy 161.050067 -289.407328)
			(xy 161.09943 -289.415147) (xy 161.146962 -289.430591) (xy 161.191494 -289.453281) (xy 161.231927 -289.482657)
			(xy 161.267267 -289.517997) (xy 161.296643 -289.55843) (xy 161.319333 -289.602962) (xy 161.334777 -289.650494)
			(xy 161.342596 -289.699857) (xy 161.343086 -289.724846) (xy 161.342596 -289.749835) (xy 161.334777 -289.799198)
			(xy 161.319333 -289.84673) (xy 161.296643 -289.891262) (xy 161.267267 -289.931695) (xy 161.231927 -289.967035)
			(xy 161.191494 -289.996411) (xy 161.146962 -290.019101) (xy 161.09943 -290.034545) (xy 161.050067 -290.042364)
			(xy 161.000089 -290.042364) (xy 160.950726 -290.034545) (xy 160.903194 -290.019101) (xy 160.858662 -289.996411)
			(xy 160.818229 -289.967035) (xy 160.782889 -289.931695) (xy 160.753513 -289.891262) (xy 160.730823 -289.84673)
			(xy 160.715379 -289.799198) (xy 160.70756 -289.749835) (xy 160.392382 -289.749835) (xy 160.384563 -289.799198)
			(xy 160.369119 -289.84673) (xy 160.346429 -289.891262) (xy 160.317053 -289.931695) (xy 160.281713 -289.967035)
			(xy 160.24128 -289.996411) (xy 160.196748 -290.019101) (xy 160.149216 -290.034545) (xy 160.099853 -290.042364)
			(xy 160.049875 -290.042364) (xy 160.000512 -290.034545) (xy 159.95298 -290.019101) (xy 159.908448 -289.996411)
			(xy 159.868015 -289.967035) (xy 159.832675 -289.931695) (xy 159.803299 -289.891262) (xy 159.780609 -289.84673)
			(xy 159.765165 -289.799198) (xy 159.757346 -289.749835) (xy 159.454124 -289.749835) (xy 159.451639 -289.779617)
			(xy 159.438067 -289.832883) (xy 159.415866 -289.883169) (xy 159.401256 -289.906456) (xy 159.397398 -289.912788)
			(xy 159.393152 -289.926986) (xy 159.392874 -289.934396) (xy 159.392874 -290.465256) (xy 159.393123 -290.47267)
			(xy 159.397375 -290.486875) (xy 159.401256 -290.493196) (xy 159.415906 -290.516459) (xy 159.438102 -290.566751)
			(xy 159.451668 -290.620023) (xy 159.456232 -290.674805) (xy 159.45415 -290.699795) (xy 159.757346 -290.699795)
			(xy 159.757346 -290.649817) (xy 159.765165 -290.600454) (xy 159.780609 -290.552922) (xy 159.803299 -290.50839)
			(xy 159.832675 -290.467957) (xy 159.868015 -290.432617) (xy 159.908448 -290.403241) (xy 159.95298 -290.380551)
			(xy 160.000512 -290.365107) (xy 160.049875 -290.357288) (xy 160.099853 -290.357288) (xy 160.149216 -290.365107)
			(xy 160.196748 -290.380551) (xy 160.24128 -290.403241) (xy 160.281713 -290.432617) (xy 160.317053 -290.467957)
			(xy 160.346429 -290.50839) (xy 160.369119 -290.552922) (xy 160.384563 -290.600454) (xy 160.392382 -290.649817)
			(xy 160.392872 -290.674806) (xy 160.392382 -290.699795) (xy 160.384563 -290.749158) (xy 160.369119 -290.79669)
			(xy 160.346429 -290.841222) (xy 160.317053 -290.881655) (xy 160.281713 -290.916995) (xy 160.24128 -290.946371)
			(xy 160.196748 -290.969061) (xy 160.149216 -290.984505) (xy 160.099853 -290.992324) (xy 160.049875 -290.992324)
			(xy 160.000512 -290.984505) (xy 159.95298 -290.969061) (xy 159.908448 -290.946371) (xy 159.868015 -290.916995)
			(xy 159.832675 -290.881655) (xy 159.803299 -290.841222) (xy 159.780609 -290.79669) (xy 159.765165 -290.749158)
			(xy 159.757346 -290.699795) (xy 159.45415 -290.699795) (xy 159.451667 -290.729587) (xy 159.438099 -290.782859)
			(xy 159.415902 -290.83315) (xy 159.401256 -290.856416) (xy 159.396938 -290.862766) (xy 159.392874 -290.876736)
			(xy 159.392874 -290.907978) (xy 159.393344 -290.917851) (xy 159.4008 -290.936137) (xy 159.407352 -290.943538)
			(xy 159.407606 -290.943792) (xy 159.698182 -291.234368) (xy 159.69869 -291.234876) (xy 159.706074 -291.24145)
			(xy 159.724373 -291.248884) (xy 159.73425 -291.249354) (xy 159.748982 -291.249354) (xy 159.74949 -291.249354)
			(xy 159.750506 -291.249354) (xy 159.756602 -291.2491) (xy 160.302194 -291.2491) (xy 160.30829 -291.249354)
			(xy 160.309306 -291.249354) (xy 160.309814 -291.249354) (xy 160.45561 -291.249354) (xy 160.465678 -291.24978)
			(xy 160.484275 -291.257503) (xy 160.491678 -291.26434) (xy 160.649412 -291.422074) (xy 160.656256 -291.429472)
			(xy 160.663978 -291.448072) (xy 160.664398 -291.458142) (xy 160.664398 -296.548556) (xy 160.664865 -296.55843)
			(xy 160.672318 -296.576719) (xy 160.678876 -296.584116) (xy 160.67913 -296.58437) (xy 160.700212 -296.605452)
			(xy 160.70072 -296.60596) (xy 160.7081 -296.612547) (xy 160.726399 -296.620008) (xy 160.73628 -296.620438)
		)
		(stroke
			(width 0)
			(type solid)
		)
		(fill yes)
		(layer "B.Cu")
		(net "P1V8_PEX")
	)
	(gr_poly
		(pts
			(xy 45.130466 -296.619676) (xy 45.138073 -296.618165) (xy 45.151911 -296.611182) (xy 45.157644 -296.60596)
			(xy 45.287184 -296.47642) (xy 45.29402 -296.469018) (xy 45.301727 -296.450419) (xy 45.30217 -296.440352)
			(xy 45.30217 -291.472112) (xy 45.30259 -291.46204) (xy 45.310298 -291.44343) (xy 45.317156 -291.436044)
			(xy 45.552614 -291.200586) (xy 45.560009 -291.193732) (xy 45.578608 -291.18599) (xy 45.588682 -291.1856)
			(xy 46.943518 -291.1856) (xy 46.953395 -291.18514) (xy 46.971694 -291.177697) (xy 46.979078 -291.171122)
			(xy 46.979332 -291.170868) (xy 47.11192 -291.03828) (xy 47.112428 -291.037772) (xy 47.119017 -291.030393)
			(xy 47.12648 -291.012094) (xy 47.126906 -291.002212) (xy 47.126906 -290.078922) (xy 47.126568 -290.070033)
			(xy 47.120478 -290.05333) (xy 47.109029 -290.039729) (xy 47.101506 -290.03498) (xy 47.026322 -289.991292)
			(xy 46.999144 -289.991292) (xy 46.987206 -289.998404) (xy 46.962484 -290.012314) (xy 46.90933 -290.032107)
			(xy 46.853513 -290.042185) (xy 46.825154 -290.042854) (xy 46.8249 -290.042854) (xy 46.799907 -290.042364)
			(xy 46.750537 -290.034544) (xy 46.702998 -290.019098) (xy 46.65846 -289.996405) (xy 46.618021 -289.967024)
			(xy 46.582676 -289.931679) (xy 46.553295 -289.89124) (xy 46.530602 -289.846702) (xy 46.515156 -289.799163)
			(xy 46.507336 -289.749793) (xy 46.507336 -289.699807) (xy 46.515156 -289.650437) (xy 46.530602 -289.602898)
			(xy 46.553295 -289.55836) (xy 46.582676 -289.517921) (xy 46.618021 -289.482576) (xy 46.65846 -289.453195)
			(xy 46.702998 -289.430502) (xy 46.750537 -289.415056) (xy 46.799907 -289.407236) (xy 46.8249 -289.406838)
			(xy 46.825154 -289.406838) (xy 46.853519 -289.407452) (xy 46.909351 -289.417509) (xy 46.962506 -289.43733)
			(xy 46.987206 -289.451288) (xy 46.999144 -289.4584) (xy 47.026322 -289.4584) (xy 47.101506 -289.414966)
			(xy 47.107298 -289.411337) (xy 47.116832 -289.401551) (xy 47.120302 -289.395662) (xy 47.120556 -289.395408)
			(xy 47.123513 -289.389684) (xy 47.126725 -289.377211) (xy 47.126906 -289.37077) (xy 47.126906 -289.128962)
			(xy 47.126575 -289.120069) (xy 47.120494 -289.103356) (xy 47.109047 -289.089744) (xy 47.101506 -289.08502)
			(xy 47.026322 -289.041332) (xy 46.999144 -289.041332) (xy 46.987206 -289.048444) (xy 46.962485 -289.062357)
			(xy 46.909331 -289.082153) (xy 46.853514 -289.092233) (xy 46.825154 -289.092894) (xy 46.8249 -289.092894)
			(xy 46.799909 -289.09243) (xy 46.750543 -289.084611) (xy 46.703008 -289.069165) (xy 46.658474 -289.046473)
			(xy 46.618039 -289.017094) (xy 46.582697 -288.981751) (xy 46.55332 -288.941314) (xy 46.53063 -288.896779)
			(xy 46.515186 -288.849243) (xy 46.507369 -288.799877) (xy 46.506892 -288.774886) (xy 46.507458 -288.747586)
			(xy 46.516786 -288.693787) (xy 46.535165 -288.642373) (xy 46.562055 -288.594853) (xy 46.596667 -288.552623)
			(xy 46.637982 -288.516926) (xy 46.66107 -288.502344) (xy 46.668351 -288.49753) (xy 46.679407 -288.484038)
			(xy 46.685326 -288.46763) (xy 46.685708 -288.45891) (xy 46.685708 -288.140902) (xy 46.685359 -288.132171)
			(xy 46.67948 -288.115731) (xy 46.668382 -288.102252) (xy 46.66107 -288.097468) (xy 46.63796 -288.082919)
			(xy 46.59665 -288.047211) (xy 46.562043 -288.004974) (xy 46.535156 -287.957448) (xy 46.516779 -287.906029)
			(xy 46.507452 -287.852228) (xy 46.506892 -287.824926) (xy 46.507354 -287.799933) (xy 46.51517 -287.750563)
			(xy 46.530613 -287.703024) (xy 46.553304 -287.658485) (xy 46.582682 -287.618045) (xy 46.618025 -287.582699)
			(xy 46.658463 -287.553317) (xy 46.703 -287.530623) (xy 46.750538 -287.515176) (xy 46.799907 -287.507357)
			(xy 46.8249 -287.506918) (xy 46.825154 -287.506918) (xy 46.853519 -287.507532) (xy 46.909351 -287.517589)
			(xy 46.962506 -287.537408) (xy 46.987206 -287.551368) (xy 46.999144 -287.55848) (xy 47.026322 -287.55848)
			(xy 47.101506 -287.515046) (xy 47.107297 -287.511416) (xy 47.116828 -287.501628) (xy 47.120302 -287.495742)
			(xy 47.120556 -287.495488) (xy 47.123511 -287.489763) (xy 47.126718 -287.47729) (xy 47.126906 -287.47085)
			(xy 47.126906 -287.229042) (xy 47.126572 -287.220151) (xy 47.120486 -287.203443) (xy 47.109038 -287.189837)
			(xy 47.101506 -287.1851) (xy 47.026322 -287.141412) (xy 46.999144 -287.141412) (xy 46.987206 -287.148524)
			(xy 46.962485 -287.162437) (xy 46.909332 -287.182235) (xy 46.853514 -287.192316) (xy 46.825154 -287.192974)
			(xy 46.8249 -287.192974) (xy 46.799913 -287.192484) (xy 46.750556 -287.184666) (xy 46.703029 -287.169224)
			(xy 46.658502 -287.146536) (xy 46.618073 -287.117163) (xy 46.582737 -287.081827) (xy 46.553364 -287.041398)
			(xy 46.530676 -286.996871) (xy 46.515234 -286.949344) (xy 46.507416 -286.899987) (xy 46.507416 -286.850013)
			(xy 46.515234 -286.800656) (xy 46.530676 -286.753129) (xy 46.553364 -286.708602) (xy 46.582737 -286.668173)
			(xy 46.618073 -286.632837) (xy 46.658502 -286.603464) (xy 46.703029 -286.580776) (xy 46.750556 -286.565334)
			(xy 46.799913 -286.557516) (xy 46.8249 -286.556958) (xy 46.825154 -286.556958) (xy 46.853519 -286.557572)
			(xy 46.90935 -286.56763) (xy 46.962505 -286.587452) (xy 46.987206 -286.601408) (xy 46.999144 -286.60852)
			(xy 47.026322 -286.60852) (xy 47.101506 -286.565086) (xy 47.1073 -286.561458) (xy 47.116837 -286.551674)
			(xy 47.120302 -286.545782) (xy 47.120556 -286.545528) (xy 47.123515 -286.539804) (xy 47.126733 -286.527331)
			(xy 47.126906 -286.52089) (xy 47.126906 -286.278828) (xy 47.126569 -286.269938) (xy 47.120481 -286.253234)
			(xy 47.109032 -286.239632) (xy 47.101506 -286.234886) (xy 47.026322 -286.191198) (xy 46.999144 -286.191198)
			(xy 46.987206 -286.19831) (xy 46.962484 -286.21222) (xy 46.90933 -286.232013) (xy 46.853513 -286.24209)
			(xy 46.825154 -286.24276) (xy 46.8249 -286.24276) (xy 46.799915 -286.24227) (xy 46.750559 -286.234453)
			(xy 46.703034 -286.219011) (xy 46.65851 -286.196325) (xy 46.618082 -286.166952) (xy 46.582748 -286.131618)
			(xy 46.553375 -286.09119) (xy 46.530689 -286.046666) (xy 46.515247 -285.999141) (xy 46.50743 -285.949785)
			(xy 46.50743 -285.899815) (xy 46.515247 -285.850459) (xy 46.530689 -285.802934) (xy 46.553375 -285.75841)
			(xy 46.582748 -285.717982) (xy 46.618082 -285.682648) (xy 46.65851 -285.653275) (xy 46.703034 -285.630589)
			(xy 46.750559 -285.615147) (xy 46.799915 -285.60733) (xy 46.8249 -285.606744) (xy 46.825154 -285.606744)
			(xy 46.853519 -285.607358) (xy 46.909351 -285.617416) (xy 46.962505 -285.637237) (xy 46.987206 -285.651194)
			(xy 46.999144 -285.658306) (xy 47.026322 -285.658306) (xy 47.101506 -285.614872) (xy 47.107299 -285.611244)
			(xy 47.116834 -285.601458) (xy 47.120302 -285.595568) (xy 47.120556 -285.595314) (xy 47.123514 -285.58959)
			(xy 47.126727 -285.577117) (xy 47.126906 -285.570676) (xy 47.126906 -285.378398) (xy 47.12733 -285.368328)
			(xy 47.135045 -285.349725) (xy 47.141892 -285.34233) (xy 47.170594 -285.313628) (xy 47.171102 -285.31312)
			(xy 47.177686 -285.30574) (xy 47.185134 -285.28744) (xy 47.18558 -285.27756) (xy 47.18558 -285.17469)
			(xy 47.185065 -285.163769) (xy 47.176031 -285.143883) (xy 47.159583 -285.129511) (xy 47.149258 -285.125922)
			(xy 47.133002 -285.121096) (xy 47.101506 -285.13278) (xy 47.092108 -285.147258) (xy 47.077321 -285.169203)
			(xy 47.041666 -285.2083) (xy 47.000029 -285.240953) (xy 46.953561 -285.266262) (xy 46.903543 -285.283527)
			(xy 46.851357 -285.292272) (xy 46.8249 -285.2928) (xy 46.799911 -285.29231) (xy 46.75055 -285.284492)
			(xy 46.703019 -285.269048) (xy 46.658489 -285.246359) (xy 46.618056 -285.216983) (xy 46.582717 -285.181644)
			(xy 46.553341 -285.141211) (xy 46.530652 -285.096681) (xy 46.515208 -285.04915) (xy 46.50739 -284.999789)
			(xy 46.50739 -284.949811) (xy 46.515208 -284.90045) (xy 46.530652 -284.852919) (xy 46.553341 -284.808389)
			(xy 46.582717 -284.767956) (xy 46.618056 -284.732617) (xy 46.658489 -284.703241) (xy 46.703019 -284.680552)
			(xy 46.75055 -284.665108) (xy 46.799911 -284.65729) (xy 46.8249 -284.656784) (xy 46.851368 -284.657309)
			(xy 46.903575 -284.666069) (xy 46.953613 -284.683348) (xy 47.000101 -284.708668) (xy 47.021242 -284.724602)
			(xy 47.028969 -284.730154) (xy 47.047184 -284.735607) (xy 47.066133 -284.734035) (xy 47.074836 -284.73019)
			(xy 47.157132 -284.690312) (xy 47.165505 -284.6858) (xy 47.178378 -284.671817) (xy 47.185251 -284.654097)
			(xy 47.18558 -284.644592) (xy 47.18558 -284.355032) (xy 47.185187 -284.345541) (xy 47.178297 -284.327853)
			(xy 47.165474 -284.313855) (xy 47.157132 -284.309312) (xy 47.074836 -284.269434) (xy 47.066131 -284.265597)
			(xy 47.047185 -284.264025) (xy 47.028974 -284.269479) (xy 47.021242 -284.275022) (xy 47.000095 -284.290949)
			(xy 46.953614 -284.316283) (xy 46.903577 -284.333566) (xy 46.851369 -284.34232) (xy 46.8249 -284.34284)
			(xy 46.799908 -284.34235) (xy 46.75054 -284.33453) (xy 46.703003 -284.319085) (xy 46.658468 -284.296393)
			(xy 46.61803 -284.267013) (xy 46.582687 -284.23167) (xy 46.553307 -284.191232) (xy 46.530615 -284.146697)
			(xy 46.51517 -284.09916) (xy 46.50735 -284.049792) (xy 46.50735 -283.999808) (xy 46.51517 -283.95044)
			(xy 46.530615 -283.902903) (xy 46.553307 -283.858368) (xy 46.582687 -283.81793) (xy 46.61803 -283.782587)
			(xy 46.658468 -283.753207) (xy 46.703003 -283.730515) (xy 46.75054 -283.71507) (xy 46.799908 -283.70725)
			(xy 46.8249 -283.706824) (xy 46.851356 -283.707349) (xy 46.903539 -283.716105) (xy 46.953554 -283.733375)
			(xy 47.000021 -283.758684) (xy 47.04166 -283.791333) (xy 47.077321 -283.830422) (xy 47.092108 -283.852366)
			(xy 47.092362 -283.85262) (xy 47.098716 -283.861487) (xy 47.11708 -283.873222) (xy 47.138657 -283.876278)
			(xy 47.149258 -283.873702) (xy 47.165514 -283.868622) (xy 47.18558 -283.841952) (xy 47.18558 -283.758132)
			(xy 47.185144 -283.748068) (xy 47.17741 -283.729483) (xy 47.170594 -283.722064) (xy 46.849284 -283.400754)
			(xy 46.830996 -283.39288) (xy 46.82109 -283.39288) (xy 46.79502 -283.392044) (xy 46.743668 -283.38292)
			(xy 46.694492 -283.365541) (xy 46.64881 -283.340372) (xy 46.607846 -283.308089) (xy 46.572696 -283.269556)
			(xy 46.544304 -283.225805) (xy 46.523429 -283.178008) (xy 46.516544 -283.15285) (xy 46.513208 -283.14208)
			(xy 46.498894 -283.124698) (xy 46.478527 -283.115094) (xy 46.467268 -283.114496) (xy 46.232572 -283.114496)
			(xy 46.221312 -283.115092) (xy 46.200946 -283.124702) (xy 46.186618 -283.142077) (xy 46.183296 -283.15285)
			(xy 46.176766 -283.176746) (xy 46.157323 -283.222307) (xy 46.131052 -283.264303) (xy 46.098587 -283.301718)
			(xy 46.060715 -283.333648) (xy 46.01835 -283.35932) (xy 45.972518 -283.378114) (xy 45.924326 -283.389575)
			(xy 45.87494 -283.393427) (xy 45.825554 -283.389575) (xy 45.777362 -283.378114) (xy 45.73153 -283.35932)
			(xy 45.689165 -283.333648) (xy 45.651293 -283.301718) (xy 45.618828 -283.264303) (xy 45.592557 -283.222307)
			(xy 45.573114 -283.176746) (xy 45.566584 -283.15285) (xy 45.563246 -283.142087) (xy 45.548928 -283.124721)
			(xy 45.528563 -283.115139) (xy 45.517308 -283.114496) (xy 45.282612 -283.114496) (xy 45.271347 -283.115085)
			(xy 45.250966 -283.124687) (xy 45.236625 -283.142063) (xy 45.233336 -283.15285) (xy 45.226806 -283.176746)
			(xy 45.207363 -283.222307) (xy 45.181092 -283.264303) (xy 45.148627 -283.301718) (xy 45.110755 -283.333648)
			(xy 45.06839 -283.35932) (xy 45.022558 -283.378114) (xy 44.974366 -283.389575) (xy 44.92498 -283.393427)
			(xy 44.875594 -283.389575) (xy 44.827402 -283.378114) (xy 44.78157 -283.35932) (xy 44.739205 -283.333648)
			(xy 44.701333 -283.301718) (xy 44.668868 -283.264303) (xy 44.642597 -283.222307) (xy 44.623154 -283.176746)
			(xy 44.616624 -283.15285) (xy 44.613288 -283.142082) (xy 44.598972 -283.124705) (xy 44.578606 -283.115109)
			(xy 44.567348 -283.114496) (xy 43.380152 -283.114496) (xy 43.375199 -283.114619) (xy 43.365481 -283.116547)
			(xy 43.360848 -283.118306) (xy 43.354244 -283.1211) (xy 43.349617 -283.122876) (xy 43.339895 -283.124803)
			(xy 43.33494 -283.12491) (xy 42.429684 -283.12491) (xy 42.421404 -283.12523) (xy 42.405721 -283.130546)
			(xy 42.39895 -283.135324) (xy 42.392092 -283.140404) (xy 42.382948 -283.153866) (xy 42.380662 -283.161994)
			(xy 42.373155 -283.186607) (xy 42.351307 -283.233195) (xy 42.322241 -283.275655) (xy 42.286716 -283.31288)
			(xy 42.24566 -283.343899) (xy 42.200145 -283.3679) (xy 42.151358 -283.384257) (xy 42.100574 -283.392544)
			(xy 42.049118 -283.392544) (xy 41.998334 -283.384257) (xy 41.949547 -283.3679) (xy 41.904032 -283.343899)
			(xy 41.862976 -283.31288) (xy 41.827451 -283.275655) (xy 41.798385 -283.233195) (xy 41.776537 -283.186607)
			(xy 41.76903 -283.161994) (xy 41.766744 -283.153866) (xy 41.7576 -283.140404) (xy 41.750742 -283.135324)
			(xy 41.743959 -283.130572) (xy 41.728282 -283.125262) (xy 41.720008 -283.12491) (xy 41.479724 -283.12491)
			(xy 41.471441 -283.125224) (xy 41.455751 -283.13053) (xy 41.44899 -283.135324) (xy 41.442132 -283.140404)
			(xy 41.432988 -283.153866) (xy 41.430702 -283.161994) (xy 41.423176 -283.186592) (xy 41.401301 -283.233145)
			(xy 41.37222 -283.275572) (xy 41.336691 -283.312767) (xy 41.29564 -283.34376) (xy 41.250138 -283.367744)
			(xy 41.201369 -283.384094) (xy 41.150604 -283.392385) (xy 41.124886 -283.39288) (xy 41.098434 -283.392362)
			(xy 41.046256 -283.383623) (xy 40.996244 -283.366372) (xy 40.949774 -283.341084) (xy 40.90813 -283.308456)
			(xy 40.889936 -283.289248) (xy 40.889174 -283.288232) (xy 40.888412 -283.28747) (xy 40.880965 -283.280782)
			(xy 40.862469 -283.273186) (xy 40.842473 -283.273186) (xy 40.823977 -283.280782) (xy 40.81653 -283.28747)
			(xy 40.781986 -283.322014) (xy 40.77462 -283.329126) (xy 40.767 -283.347922) (xy 40.767 -284.049821)
			(xy 44.607462 -284.049821) (xy 44.607462 -283.999843) (xy 44.615281 -283.95048) (xy 44.630725 -283.902948)
			(xy 44.653415 -283.858416) (xy 44.682791 -283.817983) (xy 44.718131 -283.782643) (xy 44.758564 -283.753267)
			(xy 44.803096 -283.730577) (xy 44.850628 -283.715133) (xy 44.899991 -283.707314) (xy 44.949969 -283.707314)
			(xy 44.999332 -283.715133) (xy 45.046864 -283.730577) (xy 45.091396 -283.753267) (xy 45.131829 -283.782643)
			(xy 45.167169 -283.817983) (xy 45.196545 -283.858416) (xy 45.219235 -283.902948) (xy 45.234679 -283.95048)
			(xy 45.242498 -283.999843) (xy 45.242988 -284.024832) (xy 45.242498 -284.049821) (xy 45.557422 -284.049821)
			(xy 45.557422 -283.999843) (xy 45.565241 -283.95048) (xy 45.580685 -283.902948) (xy 45.603375 -283.858416)
			(xy 45.632751 -283.817983) (xy 45.668091 -283.782643) (xy 45.708524 -283.753267) (xy 45.753056 -283.730577)
			(xy 45.800588 -283.715133) (xy 45.849951 -283.707314) (xy 45.899929 -283.707314) (xy 45.949292 -283.715133)
			(xy 45.996824 -283.730577) (xy 46.041356 -283.753267) (xy 46.081789 -283.782643) (xy 46.117129 -283.817983)
			(xy 46.146505 -283.858416) (xy 46.169195 -283.902948) (xy 46.184639 -283.95048) (xy 46.192458 -283.999843)
			(xy 46.192948 -284.024832) (xy 46.192458 -284.049821) (xy 46.184639 -284.099184) (xy 46.169195 -284.146716)
			(xy 46.146505 -284.191248) (xy 46.117129 -284.231681) (xy 46.081789 -284.267021) (xy 46.041356 -284.296397)
			(xy 45.996824 -284.319087) (xy 45.949292 -284.334531) (xy 45.899929 -284.34235) (xy 45.849951 -284.34235)
			(xy 45.800588 -284.334531) (xy 45.753056 -284.319087) (xy 45.708524 -284.296397) (xy 45.668091 -284.267021)
			(xy 45.632751 -284.231681) (xy 45.603375 -284.191248) (xy 45.580685 -284.146716) (xy 45.565241 -284.099184)
			(xy 45.557422 -284.049821) (xy 45.242498 -284.049821) (xy 45.234679 -284.099184) (xy 45.219235 -284.146716)
			(xy 45.196545 -284.191248) (xy 45.167169 -284.231681) (xy 45.131829 -284.267021) (xy 45.091396 -284.296397)
			(xy 45.046864 -284.319087) (xy 44.999332 -284.334531) (xy 44.949969 -284.34235) (xy 44.899991 -284.34235)
			(xy 44.850628 -284.334531) (xy 44.803096 -284.319087) (xy 44.758564 -284.296397) (xy 44.718131 -284.267021)
			(xy 44.682791 -284.231681) (xy 44.653415 -284.191248) (xy 44.630725 -284.146716) (xy 44.615281 -284.099184)
			(xy 44.607462 -284.049821) (xy 40.767 -284.049821) (xy 40.767 -285.0769) (xy 40.767457 -285.086778)
			(xy 40.774896 -285.105082) (xy 40.781478 -285.11246) (xy 40.781732 -285.112714) (xy 40.884856 -285.215838)
			(xy 40.893118 -285.223355) (xy 40.914079 -285.230991) (xy 40.925242 -285.23057) (xy 40.926004 -285.23057)
			(xy 40.956484 -285.228792) (xy 42.578782 -285.228792) (xy 42.595106 -285.229045) (xy 42.627562 -285.232609)
			(xy 42.643552 -285.235904) (xy 42.64914 -285.237174) (xy 42.667682 -285.237174) (xy 42.674794 -285.244286)
			(xy 42.685208 -285.24835) (xy 42.694098 -285.251906) (xy 42.70444 -285.255525) (xy 42.72631 -285.254582)
			(xy 42.745827 -285.24467) (xy 42.753026 -285.236412) (xy 42.764964 -285.221426) (xy 42.771347 -285.212457)
			(xy 42.776542 -285.191089) (xy 42.772415 -285.169488) (xy 42.766488 -285.160212) (xy 42.752425 -285.139827)
			(xy 42.730122 -285.095614) (xy 42.714952 -285.048475) (xy 42.707282 -284.999552) (xy 42.706798 -284.974792)
			(xy 42.707289 -284.949804) (xy 42.715108 -284.900442) (xy 42.730553 -284.852911) (xy 42.753243 -284.808382)
			(xy 42.782619 -284.767951) (xy 42.817959 -284.732612) (xy 42.858392 -284.703237) (xy 42.902922 -284.680549)
			(xy 42.950453 -284.665106) (xy 42.999815 -284.657288) (xy 43.049792 -284.657289) (xy 43.099153 -284.665107)
			(xy 43.146684 -284.680551) (xy 43.191214 -284.703241) (xy 43.231646 -284.732616) (xy 43.266985 -284.767956)
			(xy 43.296361 -284.808388) (xy 43.31905 -284.852918) (xy 43.334493 -284.900449) (xy 43.342312 -284.94981)
			(xy 43.342312 -284.999781) (xy 44.607462 -284.999781) (xy 44.607462 -284.949803) (xy 44.615281 -284.90044)
			(xy 44.630725 -284.852908) (xy 44.653415 -284.808376) (xy 44.682791 -284.767943) (xy 44.718131 -284.732603)
			(xy 44.758564 -284.703227) (xy 44.803096 -284.680537) (xy 44.850628 -284.665093) (xy 44.899991 -284.657274)
			(xy 44.949969 -284.657274) (xy 44.999332 -284.665093) (xy 45.046864 -284.680537) (xy 45.091396 -284.703227)
			(xy 45.131829 -284.732603) (xy 45.167169 -284.767943) (xy 45.196545 -284.808376) (xy 45.219235 -284.852908)
			(xy 45.234679 -284.90044) (xy 45.242498 -284.949803) (xy 45.242988 -284.974792) (xy 45.242498 -284.999781)
			(xy 45.557422 -284.999781) (xy 45.557422 -284.949803) (xy 45.565241 -284.90044) (xy 45.580685 -284.852908)
			(xy 45.603375 -284.808376) (xy 45.632751 -284.767943) (xy 45.668091 -284.732603) (xy 45.708524 -284.703227)
			(xy 45.753056 -284.680537) (xy 45.800588 -284.665093) (xy 45.849951 -284.657274) (xy 45.899929 -284.657274)
			(xy 45.949292 -284.665093) (xy 45.996824 -284.680537) (xy 46.041356 -284.703227) (xy 46.081789 -284.732603)
			(xy 46.117129 -284.767943) (xy 46.146505 -284.808376) (xy 46.169195 -284.852908) (xy 46.184639 -284.90044)
			(xy 46.192458 -284.949803) (xy 46.192948 -284.974792) (xy 46.192458 -284.999781) (xy 46.184639 -285.049144)
			(xy 46.169195 -285.096676) (xy 46.146505 -285.141208) (xy 46.117129 -285.181641) (xy 46.081789 -285.216981)
			(xy 46.041356 -285.246357) (xy 45.996824 -285.269047) (xy 45.949292 -285.284491) (xy 45.899929 -285.29231)
			(xy 45.849951 -285.29231) (xy 45.800588 -285.284491) (xy 45.753056 -285.269047) (xy 45.708524 -285.246357)
			(xy 45.668091 -285.216981) (xy 45.632751 -285.181641) (xy 45.603375 -285.141208) (xy 45.580685 -285.096676)
			(xy 45.565241 -285.049144) (xy 45.557422 -284.999781) (xy 45.242498 -284.999781) (xy 45.234679 -285.049144)
			(xy 45.219235 -285.096676) (xy 45.196545 -285.141208) (xy 45.167169 -285.181641) (xy 45.131829 -285.216981)
			(xy 45.091396 -285.246357) (xy 45.046864 -285.269047) (xy 44.999332 -285.284491) (xy 44.949969 -285.29231)
			(xy 44.899991 -285.29231) (xy 44.850628 -285.284491) (xy 44.803096 -285.269047) (xy 44.758564 -285.246357)
			(xy 44.718131 -285.216981) (xy 44.682791 -285.181641) (xy 44.653415 -285.141208) (xy 44.630725 -285.096676)
			(xy 44.615281 -285.049144) (xy 44.607462 -284.999781) (xy 43.342312 -284.999781) (xy 43.342312 -284.999787)
			(xy 43.334494 -285.049149) (xy 43.319051 -285.09668) (xy 43.296362 -285.14121) (xy 43.266987 -285.181642)
			(xy 43.231648 -285.216982) (xy 43.191216 -285.246358) (xy 43.146687 -285.269048) (xy 43.099156 -285.284492)
			(xy 43.049794 -285.292311) (xy 43.024806 -285.2928) (xy 43.013589 -285.292666) (xy 42.991216 -285.291014)
			(xy 42.980102 -285.289498) (xy 42.979594 -285.289498) (xy 42.966132 -285.28772) (xy 42.953686 -285.2928)
			(xy 42.947564 -285.295449) (xy 42.936881 -285.303429) (xy 42.932604 -285.308548) (xy 42.869866 -285.389066)
			(xy 42.866056 -285.41599) (xy 42.87139 -285.42869) (xy 42.874692 -285.437834) (xy 42.874946 -285.438088)
			(xy 42.87901 -285.448502) (xy 42.911522 -285.481014) (xy 42.918375 -285.48841) (xy 42.926116 -285.507008)
			(xy 42.926508 -285.517082) (xy 42.926508 -285.949741) (xy 44.607462 -285.949741) (xy 44.607462 -285.899763)
			(xy 44.615281 -285.8504) (xy 44.630725 -285.802868) (xy 44.653415 -285.758336) (xy 44.682791 -285.717903)
			(xy 44.718131 -285.682563) (xy 44.758564 -285.653187) (xy 44.803096 -285.630497) (xy 44.850628 -285.615053)
			(xy 44.899991 -285.607234) (xy 44.949969 -285.607234) (xy 44.999332 -285.615053) (xy 45.046864 -285.630497)
			(xy 45.091396 -285.653187) (xy 45.131829 -285.682563) (xy 45.167169 -285.717903) (xy 45.196545 -285.758336)
			(xy 45.219235 -285.802868) (xy 45.234679 -285.8504) (xy 45.242498 -285.899763) (xy 45.242988 -285.924752)
			(xy 45.242498 -285.949741) (xy 45.557422 -285.949741) (xy 45.557422 -285.899763) (xy 45.565241 -285.8504)
			(xy 45.580685 -285.802868) (xy 45.603375 -285.758336) (xy 45.632751 -285.717903) (xy 45.668091 -285.682563)
			(xy 45.708524 -285.653187) (xy 45.753056 -285.630497) (xy 45.800588 -285.615053) (xy 45.849951 -285.607234)
			(xy 45.899929 -285.607234) (xy 45.949292 -285.615053) (xy 45.996824 -285.630497) (xy 46.041356 -285.653187)
			(xy 46.081789 -285.682563) (xy 46.117129 -285.717903) (xy 46.146505 -285.758336) (xy 46.169195 -285.802868)
			(xy 46.184639 -285.8504) (xy 46.192458 -285.899763) (xy 46.192948 -285.924752) (xy 46.192458 -285.949741)
			(xy 46.184639 -285.999104) (xy 46.169195 -286.046636) (xy 46.146505 -286.091168) (xy 46.117129 -286.131601)
			(xy 46.081789 -286.166941) (xy 46.041356 -286.196317) (xy 45.996824 -286.219007) (xy 45.949292 -286.234451)
			(xy 45.899929 -286.24227) (xy 45.849951 -286.24227) (xy 45.800588 -286.234451) (xy 45.753056 -286.219007)
			(xy 45.708524 -286.196317) (xy 45.668091 -286.166941) (xy 45.632751 -286.131601) (xy 45.603375 -286.091168)
			(xy 45.580685 -286.046636) (xy 45.565241 -285.999104) (xy 45.557422 -285.949741) (xy 45.242498 -285.949741)
			(xy 45.234679 -285.999104) (xy 45.219235 -286.046636) (xy 45.196545 -286.091168) (xy 45.167169 -286.131601)
			(xy 45.131829 -286.166941) (xy 45.091396 -286.196317) (xy 45.046864 -286.219007) (xy 44.999332 -286.234451)
			(xy 44.949969 -286.24227) (xy 44.899991 -286.24227) (xy 44.850628 -286.234451) (xy 44.803096 -286.219007)
			(xy 44.758564 -286.196317) (xy 44.718131 -286.166941) (xy 44.682791 -286.131601) (xy 44.653415 -286.091168)
			(xy 44.630725 -286.046636) (xy 44.615281 -285.999104) (xy 44.607462 -285.949741) (xy 42.926508 -285.949741)
			(xy 42.926508 -286.442404) (xy 42.926983 -286.452371) (xy 42.934556 -286.470811) (xy 42.94124 -286.478218)
			(xy 42.998898 -286.536384) (xy 43.016932 -286.544004) (xy 43.027346 -286.544004) (xy 43.053202 -286.544703)
			(xy 43.104229 -286.553148) (xy 43.153319 -286.569433) (xy 43.199275 -286.593163) (xy 43.240977 -286.623757)
			(xy 43.277408 -286.66047) (xy 43.307679 -286.702408) (xy 43.331052 -286.748546) (xy 43.346957 -286.797761)
			(xy 43.355007 -286.848851) (xy 43.355514 -286.874712) (xy 43.355082 -286.898757) (xy 43.354944 -286.899701)
			(xy 43.657248 -286.899701) (xy 43.657248 -286.849723) (xy 43.665067 -286.80036) (xy 43.680511 -286.752828)
			(xy 43.703201 -286.708296) (xy 43.732577 -286.667863) (xy 43.767917 -286.632523) (xy 43.80835 -286.603147)
			(xy 43.852882 -286.580457) (xy 43.900414 -286.565013) (xy 43.949777 -286.557194) (xy 43.999755 -286.557194)
			(xy 44.049118 -286.565013) (xy 44.09665 -286.580457) (xy 44.141182 -286.603147) (xy 44.181615 -286.632523)
			(xy 44.216955 -286.667863) (xy 44.246331 -286.708296) (xy 44.269021 -286.752828) (xy 44.284465 -286.80036)
			(xy 44.292284 -286.849723) (xy 44.292774 -286.874712) (xy 44.292284 -286.899701) (xy 44.292244 -286.899955)
			(xy 44.607462 -286.899955) (xy 44.607462 -286.849977) (xy 44.615281 -286.800614) (xy 44.630725 -286.753082)
			(xy 44.653415 -286.70855) (xy 44.682791 -286.668117) (xy 44.718131 -286.632777) (xy 44.758564 -286.603401)
			(xy 44.803096 -286.580711) (xy 44.850628 -286.565267) (xy 44.899991 -286.557448) (xy 44.949969 -286.557448)
			(xy 44.999332 -286.565267) (xy 45.046864 -286.580711) (xy 45.091396 -286.603401) (xy 45.131829 -286.632777)
			(xy 45.167169 -286.668117) (xy 45.196545 -286.70855) (xy 45.219235 -286.753082) (xy 45.234679 -286.800614)
			(xy 45.242498 -286.849977) (xy 45.242988 -286.874966) (xy 45.242498 -286.899955) (xy 45.557422 -286.899955)
			(xy 45.557422 -286.849977) (xy 45.565241 -286.800614) (xy 45.580685 -286.753082) (xy 45.603375 -286.70855)
			(xy 45.632751 -286.668117) (xy 45.668091 -286.632777) (xy 45.708524 -286.603401) (xy 45.753056 -286.580711)
			(xy 45.800588 -286.565267) (xy 45.849951 -286.557448) (xy 45.899929 -286.557448) (xy 45.949292 -286.565267)
			(xy 45.996824 -286.580711) (xy 46.041356 -286.603401) (xy 46.081789 -286.632777) (xy 46.117129 -286.668117)
			(xy 46.146505 -286.70855) (xy 46.169195 -286.753082) (xy 46.184639 -286.800614) (xy 46.192458 -286.849977)
			(xy 46.192948 -286.874966) (xy 46.192458 -286.899955) (xy 46.184639 -286.949318) (xy 46.169195 -286.99685)
			(xy 46.146505 -287.041382) (xy 46.117129 -287.081815) (xy 46.081789 -287.117155) (xy 46.041356 -287.146531)
			(xy 45.996824 -287.169221) (xy 45.949292 -287.184665) (xy 45.899929 -287.192484) (xy 45.849951 -287.192484)
			(xy 45.800588 -287.184665) (xy 45.753056 -287.169221) (xy 45.708524 -287.146531) (xy 45.668091 -287.117155)
			(xy 45.632751 -287.081815) (xy 45.603375 -287.041382) (xy 45.580685 -286.99685) (xy 45.565241 -286.949318)
			(xy 45.557422 -286.899955) (xy 45.242498 -286.899955) (xy 45.234679 -286.949318) (xy 45.219235 -286.99685)
			(xy 45.196545 -287.041382) (xy 45.167169 -287.081815) (xy 45.131829 -287.117155) (xy 45.091396 -287.146531)
			(xy 45.046864 -287.169221) (xy 44.999332 -287.184665) (xy 44.949969 -287.192484) (xy 44.899991 -287.192484)
			(xy 44.850628 -287.184665) (xy 44.803096 -287.169221) (xy 44.758564 -287.146531) (xy 44.718131 -287.117155)
			(xy 44.682791 -287.081815) (xy 44.653415 -287.041382) (xy 44.630725 -286.99685) (xy 44.615281 -286.949318)
			(xy 44.607462 -286.899955) (xy 44.292244 -286.899955) (xy 44.284465 -286.949064) (xy 44.269021 -286.996596)
			(xy 44.246331 -287.041128) (xy 44.216955 -287.081561) (xy 44.181615 -287.116901) (xy 44.141182 -287.146277)
			(xy 44.09665 -287.168967) (xy 44.049118 -287.184411) (xy 43.999755 -287.19223) (xy 43.949777 -287.19223)
			(xy 43.900414 -287.184411) (xy 43.852882 -287.168967) (xy 43.80835 -287.146277) (xy 43.767917 -287.116901)
			(xy 43.732577 -287.081561) (xy 43.703201 -287.041128) (xy 43.680511 -286.996596) (xy 43.665067 -286.949064)
			(xy 43.657248 -286.899701) (xy 43.354944 -286.899701) (xy 43.348115 -286.946339) (xy 43.33433 -286.992411)
			(xy 43.314018 -287.036001) (xy 43.301158 -287.056322) (xy 43.29684 -287.062672) (xy 43.292776 -287.076642)
			(xy 43.292776 -287.177734) (xy 43.292346 -287.187801) (xy 43.28462 -287.206394) (xy 43.27779 -287.213802)
			(xy 43.122342 -287.36925) (xy 43.11415 -287.378545) (xy 43.106828 -287.402172) (xy 43.108372 -287.414462)
			(xy 43.123866 -287.497012) (xy 43.126804 -287.508864) (xy 43.141796 -287.528091) (xy 43.152568 -287.533842)
			(xy 43.153076 -287.534096) (xy 43.176891 -287.545167) (xy 43.220823 -287.573934) (xy 43.259426 -287.609535)
			(xy 43.291651 -287.650998) (xy 43.316618 -287.697196) (xy 43.333649 -287.746871) (xy 43.34228 -287.798669)
			(xy 43.342814 -287.824926) (xy 43.342324 -287.849915) (xy 43.657248 -287.849915) (xy 43.657248 -287.799937)
			(xy 43.665067 -287.750574) (xy 43.680511 -287.703042) (xy 43.703201 -287.65851) (xy 43.732577 -287.618077)
			(xy 43.767917 -287.582737) (xy 43.80835 -287.553361) (xy 43.852882 -287.530671) (xy 43.900414 -287.515227)
			(xy 43.949777 -287.507408) (xy 43.999755 -287.507408) (xy 44.049118 -287.515227) (xy 44.09665 -287.530671)
			(xy 44.141182 -287.553361) (xy 44.181615 -287.582737) (xy 44.216955 -287.618077) (xy 44.246331 -287.65851)
			(xy 44.269021 -287.703042) (xy 44.284465 -287.750574) (xy 44.292284 -287.799937) (xy 44.292774 -287.824926)
			(xy 44.292284 -287.849915) (xy 44.607462 -287.849915) (xy 44.607462 -287.799937) (xy 44.615281 -287.750574)
			(xy 44.630725 -287.703042) (xy 44.653415 -287.65851) (xy 44.682791 -287.618077) (xy 44.718131 -287.582737)
			(xy 44.758564 -287.553361) (xy 44.803096 -287.530671) (xy 44.850628 -287.515227) (xy 44.899991 -287.507408)
			(xy 44.949969 -287.507408) (xy 44.999332 -287.515227) (xy 45.046864 -287.530671) (xy 45.091396 -287.553361)
			(xy 45.131829 -287.582737) (xy 45.167169 -287.618077) (xy 45.196545 -287.65851) (xy 45.219235 -287.703042)
			(xy 45.234679 -287.750574) (xy 45.242498 -287.799937) (xy 45.242988 -287.824926) (xy 45.242498 -287.849915)
			(xy 45.557422 -287.849915) (xy 45.557422 -287.799937) (xy 45.565241 -287.750574) (xy 45.580685 -287.703042)
			(xy 45.603375 -287.65851) (xy 45.632751 -287.618077) (xy 45.668091 -287.582737) (xy 45.708524 -287.553361)
			(xy 45.753056 -287.530671) (xy 45.800588 -287.515227) (xy 45.849951 -287.507408) (xy 45.899929 -287.507408)
			(xy 45.949292 -287.515227) (xy 45.996824 -287.530671) (xy 46.041356 -287.553361) (xy 46.081789 -287.582737)
			(xy 46.117129 -287.618077) (xy 46.146505 -287.65851) (xy 46.169195 -287.703042) (xy 46.184639 -287.750574)
			(xy 46.192458 -287.799937) (xy 46.192948 -287.824926) (xy 46.192458 -287.849915) (xy 46.184639 -287.899278)
			(xy 46.169195 -287.94681) (xy 46.146505 -287.991342) (xy 46.117129 -288.031775) (xy 46.081789 -288.067115)
			(xy 46.041356 -288.096491) (xy 45.996824 -288.119181) (xy 45.949292 -288.134625) (xy 45.899929 -288.142444)
			(xy 45.849951 -288.142444) (xy 45.800588 -288.134625) (xy 45.753056 -288.119181) (xy 45.708524 -288.096491)
			(xy 45.668091 -288.067115) (xy 45.632751 -288.031775) (xy 45.603375 -287.991342) (xy 45.580685 -287.94681)
			(xy 45.565241 -287.899278) (xy 45.557422 -287.849915) (xy 45.242498 -287.849915) (xy 45.234679 -287.899278)
			(xy 45.219235 -287.94681) (xy 45.196545 -287.991342) (xy 45.167169 -288.031775) (xy 45.131829 -288.067115)
			(xy 45.091396 -288.096491) (xy 45.046864 -288.119181) (xy 44.999332 -288.134625) (xy 44.949969 -288.142444)
			(xy 44.899991 -288.142444) (xy 44.850628 -288.134625) (xy 44.803096 -288.119181) (xy 44.758564 -288.096491)
			(xy 44.718131 -288.067115) (xy 44.682791 -288.031775) (xy 44.653415 -287.991342) (xy 44.630725 -287.94681)
			(xy 44.615281 -287.899278) (xy 44.607462 -287.849915) (xy 44.292284 -287.849915) (xy 44.284465 -287.899278)
			(xy 44.269021 -287.94681) (xy 44.246331 -287.991342) (xy 44.216955 -288.031775) (xy 44.181615 -288.067115)
			(xy 44.141182 -288.096491) (xy 44.09665 -288.119181) (xy 44.049118 -288.134625) (xy 43.999755 -288.142444)
			(xy 43.949777 -288.142444) (xy 43.900414 -288.134625) (xy 43.852882 -288.119181) (xy 43.80835 -288.096491)
			(xy 43.767917 -288.067115) (xy 43.732577 -288.031775) (xy 43.703201 -287.991342) (xy 43.680511 -287.94681)
			(xy 43.665067 -287.899278) (xy 43.657248 -287.849915) (xy 43.342324 -287.849915) (xy 43.334505 -287.899278)
			(xy 43.319061 -287.94681) (xy 43.296371 -287.991342) (xy 43.266995 -288.031775) (xy 43.231655 -288.067115)
			(xy 43.191222 -288.096491) (xy 43.14669 -288.119181) (xy 43.099158 -288.134625) (xy 43.049795 -288.142444)
			(xy 42.999817 -288.142444) (xy 42.950454 -288.134625) (xy 42.902922 -288.119181) (xy 42.85839 -288.096491)
			(xy 42.817957 -288.067115) (xy 42.782617 -288.031775) (xy 42.753241 -287.991342) (xy 42.730551 -287.94681)
			(xy 42.715107 -287.899278) (xy 42.707288 -287.849915) (xy 42.706798 -287.824926) (xy 42.707411 -287.796617)
			(xy 42.717417 -287.74089) (xy 42.737119 -287.687811) (xy 42.750994 -287.663128) (xy 42.755247 -287.655257)
			(xy 42.758519 -287.637678) (xy 42.755574 -287.620042) (xy 42.751502 -287.612074) (xy 42.707814 -287.535366)
			(xy 42.703086 -287.527747) (xy 42.68941 -287.516167) (xy 42.672579 -287.510015) (xy 42.663618 -287.509712)
			(xy 42.451274 -287.509712) (xy 42.442427 -287.510106) (xy 42.425793 -287.516138) (xy 42.412183 -287.527447)
			(xy 42.407332 -287.534858) (xy 42.362882 -287.61055) (xy 42.358768 -287.618328) (xy 42.355575 -287.63562)
			(xy 42.358442 -287.652968) (xy 42.362374 -287.660842) (xy 42.362628 -287.66135) (xy 42.362882 -287.661604)
			(xy 42.376365 -287.686601) (xy 42.3955 -287.74007) (xy 42.405217 -287.796023) (xy 42.405808 -287.824418)
			(xy 42.405297 -287.850426) (xy 42.397158 -287.9018) (xy 42.381084 -287.951269) (xy 42.35747 -287.997615)
			(xy 42.326897 -288.039697) (xy 42.290118 -288.076479) (xy 42.248039 -288.107055) (xy 42.201695 -288.130673)
			(xy 42.152227 -288.146752) (xy 42.100853 -288.154895) (xy 42.074846 -288.15538) (xy 41.311576 -288.15538)
			(xy 41.30157 -288.155872) (xy 41.283083 -288.163535) (xy 41.268933 -288.177686) (xy 41.261271 -288.196174)
			(xy 41.260776 -288.20618) (xy 41.260776 -288.55924) (xy 41.261239 -288.569116) (xy 41.268685 -288.587411)
			(xy 41.275254 -288.5948) (xy 41.275508 -288.595054) (xy 41.355772 -288.675318) (xy 41.35628 -288.675826)
			(xy 41.363661 -288.682407) (xy 41.381961 -288.689852) (xy 41.39184 -288.690304) (xy 41.74744 -288.690304)
			(xy 41.773094 -288.672778) (xy 41.778936 -288.658046) (xy 41.788719 -288.634659) (xy 41.814608 -288.591077)
			(xy 41.847078 -288.552149) (xy 41.885308 -288.518862) (xy 41.928332 -288.492056) (xy 41.975062 -288.472409)
			(xy 42.024315 -288.460419) (xy 42.074846 -288.456388) (xy 42.125377 -288.460419) (xy 42.17463 -288.472409)
			(xy 42.22136 -288.492056) (xy 42.264384 -288.518862) (xy 42.302614 -288.552149) (xy 42.335084 -288.591077)
			(xy 42.360973 -288.634659) (xy 42.370756 -288.658046) (xy 42.376598 -288.672778) (xy 42.402252 -288.690304)
			(xy 42.667936 -288.690304) (xy 42.678117 -288.689862) (xy 42.696883 -288.681961) (xy 42.711093 -288.667379)
			(xy 42.71518 -288.658046) (xy 42.715434 -288.657538) (xy 42.715434 -288.657284) (xy 42.724725 -288.63406)
			(xy 42.749284 -288.590485) (xy 42.780115 -288.551098) (xy 42.816516 -288.516793) (xy 42.857662 -288.488351)
			(xy 42.902615 -288.466418) (xy 42.950356 -288.451493) (xy 42.999797 -288.443914) (xy 43.024806 -288.443416)
			(xy 43.974766 -288.443416) (xy 44.000779 -288.443897) (xy 44.052164 -288.452031) (xy 44.101645 -288.468103)
			(xy 44.148001 -288.491719) (xy 44.190092 -288.522296) (xy 44.226882 -288.559082) (xy 44.257463 -288.60117)
			(xy 44.281084 -288.647524) (xy 44.297161 -288.697003) (xy 44.3053 -288.748387) (xy 44.3053 -288.799875)
			(xy 44.607462 -288.799875) (xy 44.607462 -288.749897) (xy 44.615281 -288.700534) (xy 44.630725 -288.653002)
			(xy 44.653415 -288.60847) (xy 44.682791 -288.568037) (xy 44.718131 -288.532697) (xy 44.758564 -288.503321)
			(xy 44.803096 -288.480631) (xy 44.850628 -288.465187) (xy 44.899991 -288.457368) (xy 44.949969 -288.457368)
			(xy 44.999332 -288.465187) (xy 45.046864 -288.480631) (xy 45.091396 -288.503321) (xy 45.131829 -288.532697)
			(xy 45.167169 -288.568037) (xy 45.196545 -288.60847) (xy 45.219235 -288.653002) (xy 45.234679 -288.700534)
			(xy 45.242498 -288.749897) (xy 45.242988 -288.774886) (xy 45.242498 -288.799875) (xy 45.557422 -288.799875)
			(xy 45.557422 -288.749897) (xy 45.565241 -288.700534) (xy 45.580685 -288.653002) (xy 45.603375 -288.60847)
			(xy 45.632751 -288.568037) (xy 45.668091 -288.532697) (xy 45.708524 -288.503321) (xy 45.753056 -288.480631)
			(xy 45.800588 -288.465187) (xy 45.849951 -288.457368) (xy 45.899929 -288.457368) (xy 45.949292 -288.465187)
			(xy 45.996824 -288.480631) (xy 46.041356 -288.503321) (xy 46.081789 -288.532697) (xy 46.117129 -288.568037)
			(xy 46.146505 -288.60847) (xy 46.169195 -288.653002) (xy 46.184639 -288.700534) (xy 46.192458 -288.749897)
			(xy 46.192948 -288.774886) (xy 46.192458 -288.799875) (xy 46.184639 -288.849238) (xy 46.169195 -288.89677)
			(xy 46.146505 -288.941302) (xy 46.117129 -288.981735) (xy 46.081789 -289.017075) (xy 46.041356 -289.046451)
			(xy 45.996824 -289.069141) (xy 45.949292 -289.084585) (xy 45.899929 -289.092404) (xy 45.849951 -289.092404)
			(xy 45.800588 -289.084585) (xy 45.753056 -289.069141) (xy 45.708524 -289.046451) (xy 45.668091 -289.017075)
			(xy 45.632751 -288.981735) (xy 45.603375 -288.941302) (xy 45.580685 -288.89677) (xy 45.565241 -288.849238)
			(xy 45.557422 -288.799875) (xy 45.242498 -288.799875) (xy 45.234679 -288.849238) (xy 45.219235 -288.89677)
			(xy 45.196545 -288.941302) (xy 45.167169 -288.981735) (xy 45.131829 -289.017075) (xy 45.091396 -289.046451)
			(xy 45.046864 -289.069141) (xy 44.999332 -289.084585) (xy 44.949969 -289.092404) (xy 44.899991 -289.092404)
			(xy 44.850628 -289.084585) (xy 44.803096 -289.069141) (xy 44.758564 -289.046451) (xy 44.718131 -289.017075)
			(xy 44.682791 -288.981735) (xy 44.653415 -288.941302) (xy 44.630725 -288.89677) (xy 44.615281 -288.849238)
			(xy 44.607462 -288.799875) (xy 44.3053 -288.799875) (xy 44.3053 -288.800413) (xy 44.297161 -288.851797)
			(xy 44.281084 -288.901276) (xy 44.257463 -288.94763) (xy 44.226882 -288.989718) (xy 44.190092 -289.026504)
			(xy 44.148001 -289.057081) (xy 44.101645 -289.080697) (xy 44.052164 -289.096769) (xy 44.000779 -289.104903)
			(xy 43.974766 -289.10534) (xy 43.343576 -289.10534) (xy 43.333561 -289.105764) (xy 43.315059 -289.11344)
			(xy 43.300904 -289.127613) (xy 43.293252 -289.146124) (xy 43.292776 -289.15614) (xy 43.292776 -289.515296)
			(xy 43.29303 -289.522708) (xy 43.297292 -289.536907) (xy 43.301158 -289.543236) (xy 43.315805 -289.566499)
			(xy 43.337994 -289.61679) (xy 43.351554 -289.670059) (xy 43.356112 -289.724838) (xy 43.354026 -289.749835)
			(xy 43.657248 -289.749835) (xy 43.657248 -289.699857) (xy 43.665067 -289.650494) (xy 43.680511 -289.602962)
			(xy 43.703201 -289.55843) (xy 43.732577 -289.517997) (xy 43.767917 -289.482657) (xy 43.80835 -289.453281)
			(xy 43.852882 -289.430591) (xy 43.900414 -289.415147) (xy 43.949777 -289.407328) (xy 43.999755 -289.407328)
			(xy 44.049118 -289.415147) (xy 44.09665 -289.430591) (xy 44.141182 -289.453281) (xy 44.181615 -289.482657)
			(xy 44.216955 -289.517997) (xy 44.246331 -289.55843) (xy 44.269021 -289.602962) (xy 44.284465 -289.650494)
			(xy 44.292284 -289.699857) (xy 44.292774 -289.724846) (xy 44.292284 -289.749835) (xy 44.607462 -289.749835)
			(xy 44.607462 -289.699857) (xy 44.615281 -289.650494) (xy 44.630725 -289.602962) (xy 44.653415 -289.55843)
			(xy 44.682791 -289.517997) (xy 44.718131 -289.482657) (xy 44.758564 -289.453281) (xy 44.803096 -289.430591)
			(xy 44.850628 -289.415147) (xy 44.899991 -289.407328) (xy 44.949969 -289.407328) (xy 44.999332 -289.415147)
			(xy 45.046864 -289.430591) (xy 45.091396 -289.453281) (xy 45.131829 -289.482657) (xy 45.167169 -289.517997)
			(xy 45.196545 -289.55843) (xy 45.219235 -289.602962) (xy 45.234679 -289.650494) (xy 45.242498 -289.699857)
			(xy 45.242988 -289.724846) (xy 45.242498 -289.749835) (xy 45.557422 -289.749835) (xy 45.557422 -289.699857)
			(xy 45.565241 -289.650494) (xy 45.580685 -289.602962) (xy 45.603375 -289.55843) (xy 45.632751 -289.517997)
			(xy 45.668091 -289.482657) (xy 45.708524 -289.453281) (xy 45.753056 -289.430591) (xy 45.800588 -289.415147)
			(xy 45.849951 -289.407328) (xy 45.899929 -289.407328) (xy 45.949292 -289.415147) (xy 45.996824 -289.430591)
			(xy 46.041356 -289.453281) (xy 46.081789 -289.482657) (xy 46.117129 -289.517997) (xy 46.146505 -289.55843)
			(xy 46.169195 -289.602962) (xy 46.184639 -289.650494) (xy 46.192458 -289.699857) (xy 46.192948 -289.724846)
			(xy 46.192458 -289.749835) (xy 46.184639 -289.799198) (xy 46.169195 -289.84673) (xy 46.146505 -289.891262)
			(xy 46.117129 -289.931695) (xy 46.081789 -289.967035) (xy 46.041356 -289.996411) (xy 45.996824 -290.019101)
			(xy 45.949292 -290.034545) (xy 45.899929 -290.042364) (xy 45.849951 -290.042364) (xy 45.800588 -290.034545)
			(xy 45.753056 -290.019101) (xy 45.708524 -289.996411) (xy 45.668091 -289.967035) (xy 45.632751 -289.931695)
			(xy 45.603375 -289.891262) (xy 45.580685 -289.84673) (xy 45.565241 -289.799198) (xy 45.557422 -289.749835)
			(xy 45.242498 -289.749835) (xy 45.234679 -289.799198) (xy 45.219235 -289.84673) (xy 45.196545 -289.891262)
			(xy 45.167169 -289.931695) (xy 45.131829 -289.967035) (xy 45.091396 -289.996411) (xy 45.046864 -290.019101)
			(xy 44.999332 -290.034545) (xy 44.949969 -290.042364) (xy 44.899991 -290.042364) (xy 44.850628 -290.034545)
			(xy 44.803096 -290.019101) (xy 44.758564 -289.996411) (xy 44.718131 -289.967035) (xy 44.682791 -289.931695)
			(xy 44.653415 -289.891262) (xy 44.630725 -289.84673) (xy 44.615281 -289.799198) (xy 44.607462 -289.749835)
			(xy 44.292284 -289.749835) (xy 44.284465 -289.799198) (xy 44.269021 -289.84673) (xy 44.246331 -289.891262)
			(xy 44.216955 -289.931695) (xy 44.181615 -289.967035) (xy 44.141182 -289.996411) (xy 44.09665 -290.019101)
			(xy 44.049118 -290.034545) (xy 43.999755 -290.042364) (xy 43.949777 -290.042364) (xy 43.900414 -290.034545)
			(xy 43.852882 -290.019101) (xy 43.80835 -289.996411) (xy 43.767917 -289.967035) (xy 43.732577 -289.931695)
			(xy 43.703201 -289.891262) (xy 43.680511 -289.84673) (xy 43.665067 -289.799198) (xy 43.657248 -289.749835)
			(xy 43.354026 -289.749835) (xy 43.351541 -289.779617) (xy 43.337969 -289.832883) (xy 43.315768 -289.883169)
			(xy 43.301158 -289.906456) (xy 43.2973 -289.912788) (xy 43.293053 -289.926986) (xy 43.292776 -289.934396)
			(xy 43.292776 -290.465256) (xy 43.293025 -290.47267) (xy 43.297277 -290.486875) (xy 43.301158 -290.493196)
			(xy 43.315808 -290.516459) (xy 43.338004 -290.566751) (xy 43.35157 -290.620023) (xy 43.356134 -290.674805)
			(xy 43.354051 -290.699795) (xy 43.657248 -290.699795) (xy 43.657248 -290.649817) (xy 43.665067 -290.600454)
			(xy 43.680511 -290.552922) (xy 43.703201 -290.50839) (xy 43.732577 -290.467957) (xy 43.767917 -290.432617)
			(xy 43.80835 -290.403241) (xy 43.852882 -290.380551) (xy 43.900414 -290.365107) (xy 43.949777 -290.357288)
			(xy 43.999755 -290.357288) (xy 44.049118 -290.365107) (xy 44.09665 -290.380551) (xy 44.141182 -290.403241)
			(xy 44.181615 -290.432617) (xy 44.216955 -290.467957) (xy 44.246331 -290.50839) (xy 44.269021 -290.552922)
			(xy 44.284465 -290.600454) (xy 44.292284 -290.649817) (xy 44.292774 -290.674806) (xy 44.292284 -290.699793)
			(xy 45.557363 -290.699793) (xy 45.557363 -290.649807) (xy 45.565183 -290.600437) (xy 45.58063 -290.552899)
			(xy 45.603325 -290.508362) (xy 45.632708 -290.467924) (xy 45.668055 -290.432582) (xy 45.708496 -290.403204)
			(xy 45.753036 -290.380515) (xy 45.800576 -290.365073) (xy 45.849947 -290.357259) (xy 45.87494 -290.356798)
			(xy 45.895961 -290.357164) (xy 45.937627 -290.362775) (xy 45.957998 -290.367974) (xy 45.971206 -290.369752)
			(xy 46.23562 -290.369752) (xy 46.250647 -290.370262) (xy 46.279678 -290.378032) (xy 46.305716 -290.39304)
			(xy 46.326993 -290.414265) (xy 46.342062 -290.440268) (xy 46.349902 -290.469281) (xy 46.350428 -290.484306)
			(xy 46.350428 -290.865306) (xy 46.350013 -290.880331) (xy 46.342233 -290.909357) (xy 46.327205 -290.935379)
			(xy 46.305953 -290.956625) (xy 46.279927 -290.971645) (xy 46.250899 -290.979417) (xy 46.235874 -290.97986)
			(xy 46.23562 -290.97986) (xy 45.964602 -290.97986) (xy 45.957998 -290.981638) (xy 45.937625 -290.986829)
			(xy 45.89596 -290.99244) (xy 45.87494 -290.992814) (xy 45.849947 -290.992341) (xy 45.800576 -290.984527)
			(xy 45.753036 -290.969085) (xy 45.708496 -290.946396) (xy 45.668055 -290.917018) (xy 45.632708 -290.881676)
			(xy 45.603325 -290.841238) (xy 45.58063 -290.796701) (xy 45.565183 -290.749163) (xy 45.557363 -290.699793)
			(xy 44.292284 -290.699793) (xy 44.292284 -290.699795) (xy 44.284465 -290.749158) (xy 44.269021 -290.79669)
			(xy 44.246331 -290.841222) (xy 44.216955 -290.881655) (xy 44.181615 -290.916995) (xy 44.141182 -290.946371)
			(xy 44.09665 -290.969061) (xy 44.049118 -290.984505) (xy 43.999755 -290.992324) (xy 43.949777 -290.992324)
			(xy 43.900414 -290.984505) (xy 43.852882 -290.969061) (xy 43.80835 -290.946371) (xy 43.767917 -290.916995)
			(xy 43.732577 -290.881655) (xy 43.703201 -290.841222) (xy 43.680511 -290.79669) (xy 43.665067 -290.749158)
			(xy 43.657248 -290.699795) (xy 43.354051 -290.699795) (xy 43.351568 -290.729587) (xy 43.338 -290.782859)
			(xy 43.315803 -290.83315) (xy 43.301158 -290.856416) (xy 43.29684 -290.862766) (xy 43.292776 -290.876736)
			(xy 43.292776 -290.907978) (xy 43.293281 -290.918029) (xy 43.301002 -290.93659) (xy 43.307762 -290.944046)
			(xy 43.598084 -291.234368) (xy 43.605485 -291.241205) (xy 43.624084 -291.248914) (xy 43.634152 -291.249354)
			(xy 43.651678 -291.249354) (xy 43.656504 -291.2491) (xy 44.202096 -291.2491) (xy 44.206922 -291.249354)
			(xy 44.355512 -291.249354) (xy 44.36558 -291.249781) (xy 44.384176 -291.257504) (xy 44.39158 -291.26434)
			(xy 44.549314 -291.422074) (xy 44.556158 -291.429472) (xy 44.563879 -291.448072) (xy 44.5643 -291.458142)
			(xy 44.5643 -296.548556) (xy 44.564734 -296.558622) (xy 44.572462 -296.577211) (xy 44.579286 -296.584624)
			(xy 44.600114 -296.605452) (xy 44.607511 -296.612302) (xy 44.626109 -296.620039) (xy 44.636182 -296.620438)
			(xy 45.122084 -296.620438)
		)
		(stroke
			(width 0)
			(type solid)
		)
		(fill yes)
		(layer "B.Cu")
		(net "P1V8_PEX")
	)
	(gr_poly
		(pts
			(xy 217.672666 -130.214624) (xy 217.68254 -130.214156) (xy 217.700828 -130.206703) (xy 217.708226 -130.200146)
			(xy 217.70848 -130.199892) (xy 219.76842 -128.139952) (xy 219.768928 -128.139444) (xy 219.775513 -128.132064)
			(xy 219.782966 -128.113765) (xy 219.783406 -128.103884) (xy 219.783406 -119.02567) (xy 219.782978 -119.015602)
			(xy 219.775256 -118.997005) (xy 219.76842 -118.989602) (xy 219.723716 -118.944898) (xy 219.714318 -118.937532)
			(xy 219.714064 -118.937278) (xy 219.706668 -118.933139) (xy 219.690116 -118.929539) (xy 219.673297 -118.931557)
			(xy 219.66555 -118.934992) (xy 219.564712 -118.984014) (xy 219.549218 -119.012208) (xy 219.550996 -119.028464)
			(xy 219.552198 -119.039537) (xy 219.553466 -119.061776) (xy 219.553536 -119.072914) (xy 219.553049 -119.100165)
			(xy 219.545291 -119.154113) (xy 219.529935 -119.206408) (xy 219.507294 -119.255985) (xy 219.477827 -119.301836)
			(xy 219.442136 -119.343026) (xy 219.400947 -119.378719) (xy 219.355097 -119.408187) (xy 219.305521 -119.43083)
			(xy 219.253227 -119.446188) (xy 219.199279 -119.453948) (xy 219.172028 -119.454422) (xy 219.145213 -119.453963)
			(xy 219.092112 -119.446446) (xy 219.040585 -119.43157) (xy 218.991648 -119.409629) (xy 218.946264 -119.381054)
			(xy 218.905327 -119.346408) (xy 218.869642 -119.306373) (xy 218.839912 -119.261737) (xy 218.816722 -119.213379)
			(xy 218.80053 -119.162252) (xy 218.791653 -119.109361) (xy 218.79052 -119.082566) (xy 218.79052 -119.075708)
			(xy 218.79052 -119.072914) (xy 218.790943 -119.047424) (xy 218.797728 -118.996899) (xy 218.811178 -118.947726)
			(xy 218.831054 -118.900781) (xy 218.857002 -118.8569) (xy 218.888561 -118.816863) (xy 218.906598 -118.798848)
			(xy 218.91371 -118.791736) (xy 218.925902 -118.764558) (xy 218.927934 -118.75966) (xy 218.930113 -118.749285)
			(xy 218.93022 -118.743984) (xy 218.93022 -118.690644) (xy 218.930084 -118.685346) (xy 218.92791 -118.674974)
			(xy 218.925902 -118.67007) (xy 218.91371 -118.642892) (xy 218.906598 -118.63578) (xy 218.888582 -118.617743)
			(xy 218.85701 -118.577718) (xy 218.831052 -118.533843) (xy 218.811171 -118.486901) (xy 218.79772 -118.437729)
			(xy 218.79094 -118.387203) (xy 218.79052 -118.361714) (xy 218.79052 -118.352062) (xy 218.791749 -118.323921)
			(xy 218.801473 -118.26844) (xy 218.819268 -118.214998) (xy 218.844745 -118.164762) (xy 218.860624 -118.141496)
			(xy 218.865431 -118.133977) (xy 218.870072 -118.11676) (xy 218.868548 -118.098994) (xy 218.861044 -118.082818)
			(xy 218.855036 -118.076218) (xy 218.699588 -117.92077) (xy 218.692192 -117.913918) (xy 218.673593 -117.906177)
			(xy 218.66352 -117.905784) (xy 217.468196 -117.905784) (xy 217.458027 -117.90624) (xy 217.439295 -117.914162)
			(xy 217.425127 -117.928754) (xy 217.420952 -117.938042) (xy 217.380566 -118.040404) (xy 217.387932 -118.071392)
			(xy 217.399616 -118.081806) (xy 217.418531 -118.099935) (xy 217.451719 -118.140475) (xy 217.479052 -118.185173)
			(xy 217.500017 -118.233188) (xy 217.51422 -118.283619) (xy 217.521395 -118.335518) (xy 217.52179 -118.361714)
			(xy 217.52179 -118.36654) (xy 217.521282 -118.377462) (xy 217.519547 -118.406434) (xy 217.5084 -118.46339)
			(xy 217.488748 -118.517999) (xy 217.461045 -118.568998) (xy 217.425932 -118.615208) (xy 217.405458 -118.63578)
			(xy 217.398346 -118.642892) (xy 217.386154 -118.67007) (xy 217.384126 -118.674968) (xy 217.381955 -118.685343)
			(xy 217.381836 -118.690644) (xy 217.381836 -118.743984) (xy 217.381975 -118.749282) (xy 217.384152 -118.759651)
			(xy 217.386154 -118.764558) (xy 217.398346 -118.791736) (xy 217.405458 -118.798848) (xy 217.42347 -118.816886)
			(xy 217.455035 -118.856914) (xy 217.480986 -118.90079) (xy 217.500861 -118.947731) (xy 217.514306 -118.996902)
			(xy 217.521081 -119.047426) (xy 217.521536 -119.072914) (xy 217.521536 -119.082566) (xy 217.520326 -119.110645)
			(xy 217.51068 -119.166011) (xy 217.493019 -119.219364) (xy 217.467724 -119.26955) (xy 217.435342 -119.315484)
			(xy 217.396573 -119.356171) (xy 217.352257 -119.390733) (xy 217.303351 -119.418422) (xy 217.250912 -119.438639)
			(xy 217.196076 -119.450947) (xy 217.140028 -119.455079) (xy 217.08398 -119.450947) (xy 217.029144 -119.438639)
			(xy 216.976705 -119.418422) (xy 216.927799 -119.390733) (xy 216.883483 -119.356171) (xy 216.844714 -119.315484)
			(xy 216.812332 -119.26955) (xy 216.787037 -119.219364) (xy 216.769376 -119.166011) (xy 216.75973 -119.110645)
			(xy 216.75852 -119.082566) (xy 216.75852 -119.075708) (xy 216.75852 -119.072914) (xy 216.758943 -119.047424)
			(xy 216.765728 -118.996899) (xy 216.779178 -118.947726) (xy 216.799054 -118.900781) (xy 216.825002 -118.8569)
			(xy 216.856561 -118.816863) (xy 216.874598 -118.798848) (xy 216.88171 -118.791736) (xy 216.893902 -118.764558)
			(xy 216.895934 -118.75966) (xy 216.898113 -118.749285) (xy 216.89822 -118.743984) (xy 216.89822 -118.690644)
			(xy 216.898084 -118.685346) (xy 216.89591 -118.674974) (xy 216.893902 -118.67007) (xy 216.88171 -118.642892)
			(xy 216.874598 -118.63578) (xy 216.855123 -118.61626) (xy 216.821428 -118.572615) (xy 216.794364 -118.524575)
			(xy 216.774495 -118.47314) (xy 216.762234 -118.419382) (xy 216.759536 -118.39194) (xy 216.758266 -118.375176)
			(xy 216.758266 -118.362222) (xy 216.758666 -118.335984) (xy 216.765783 -118.283993) (xy 216.779954 -118.233467)
			(xy 216.800912 -118.185358) (xy 216.828263 -118.140574) (xy 216.86149 -118.099958) (xy 216.88044 -118.081806)
			(xy 216.892124 -118.071392) (xy 216.89949 -118.040404) (xy 216.859104 -117.938042) (xy 216.854964 -117.92874)
			(xy 216.840764 -117.91417) (xy 216.822031 -117.906234) (xy 216.81186 -117.905784) (xy 216.802462 -117.905784)
			(xy 216.793064 -117.90172) (xy 216.788636 -117.899755) (xy 216.780573 -117.894389) (xy 216.777062 -117.891052)
			(xy 216.707466 -117.82171) (xy 216.700055 -117.81503) (xy 216.681619 -117.807459) (xy 216.671652 -117.806978)
			(xy 215.872314 -117.806978) (xy 215.862251 -117.806539) (xy 215.843672 -117.7988) (xy 215.836246 -117.791992)
			(xy 215.099138 -117.054884) (xy 215.092026 -117.047518) (xy 215.07323 -117.039898) (xy 214.555832 -117.039898)
			(xy 214.545296 -117.040483) (xy 214.526017 -117.049008) (xy 214.518494 -117.056408) (xy 214.460582 -117.1194)
			(xy 214.453724 -117.13972) (xy 214.45474 -117.150388) (xy 214.456518 -117.190266) (xy 214.456518 -117.191028)
			(xy 214.456028 -117.220996) (xy 214.448205 -117.280418) (xy 214.432692 -117.338311) (xy 214.409756 -117.393684)
			(xy 214.379789 -117.44559) (xy 214.343302 -117.49314) (xy 214.300922 -117.53552) (xy 214.253372 -117.572007)
			(xy 214.201466 -117.601974) (xy 214.146093 -117.62491) (xy 214.0882 -117.640423) (xy 214.028778 -117.648246)
			(xy 213.968842 -117.648246) (xy 213.90942 -117.640423) (xy 213.851527 -117.62491) (xy 213.796154 -117.601974)
			(xy 213.744248 -117.572007) (xy 213.696698 -117.53552) (xy 213.654318 -117.49314) (xy 213.617831 -117.44559)
			(xy 213.587864 -117.393684) (xy 213.564928 -117.338311) (xy 213.549415 -117.280418) (xy 213.541592 -117.220996)
			(xy 213.541102 -117.191028) (xy 213.541102 -117.190266) (xy 213.54288 -117.150388) (xy 213.543896 -117.13972)
			(xy 213.537038 -117.1194) (xy 213.479126 -117.056408) (xy 213.471631 -117.048854) (xy 213.452167 -117.040298)
			(xy 213.441534 -117.039898) (xy 211.666328 -117.039898) (xy 211.661168 -117.039803) (xy 211.651054 -117.037752)
			(xy 211.646262 -117.035834) (xy 211.638134 -117.032278) (xy 210.251802 -117.032278) (xy 210.242312 -117.032675)
			(xy 210.224628 -117.039569) (xy 210.21063 -117.052388) (xy 210.206082 -117.060726) (xy 210.16595 -117.142514)
			(xy 210.162052 -117.151249) (xy 210.160433 -117.170293) (xy 210.16596 -117.188588) (xy 210.171538 -117.196362)
			(xy 210.186735 -117.216538) (xy 210.212243 -117.260137) (xy 210.231771 -117.306721) (xy 210.244979 -117.355476)
			(xy 210.251634 -117.405548) (xy 210.252056 -117.430804) (xy 210.25157 -117.458055) (xy 210.243814 -117.512003)
			(xy 210.228459 -117.564298) (xy 210.205817 -117.613875) (xy 210.176351 -117.659725) (xy 210.14066 -117.700916)
			(xy 210.099469 -117.736607) (xy 210.053619 -117.766073) (xy 210.004042 -117.788715) (xy 209.951747 -117.80407)
			(xy 209.897799 -117.811826) (xy 209.843297 -117.811826) (xy 209.789349 -117.80407) (xy 209.737054 -117.788715)
			(xy 209.687477 -117.766073) (xy 209.641627 -117.736607) (xy 209.600436 -117.700916) (xy 209.564745 -117.659725)
			(xy 209.535279 -117.613875) (xy 209.512637 -117.564298) (xy 209.497282 -117.512003) (xy 209.489526 -117.458055)
			(xy 209.48904 -117.430804) (xy 209.489448 -117.405547) (xy 209.496111 -117.355475) (xy 209.509321 -117.30672)
			(xy 209.528847 -117.260133) (xy 209.554348 -117.216529) (xy 209.569558 -117.196362) (xy 209.578448 -117.184932)
			(xy 209.58175 -117.155722) (xy 209.535014 -117.060726) (xy 209.530498 -117.052358) (xy 209.516513 -117.039495)
			(xy 209.498796 -117.032628) (xy 209.489294 -117.032278) (xy 208.235042 -117.032278) (xy 208.230216 -117.027706)
			(xy 206.158592 -117.027706) (xy 206.148522 -117.027282) (xy 206.129919 -117.019566) (xy 206.122524 -117.01272)
			(xy 204.36078 -115.250976) (xy 204.353668 -115.24361) (xy 204.334872 -115.23599) (xy 203.90993 -115.23599)
			(xy 203.900024 -115.240562) (xy 203.87557 -115.251134) (xy 203.824445 -115.266115) (xy 203.771732 -115.273834)
			(xy 203.718459 -115.274141) (xy 203.691998 -115.271042) (xy 203.664527 -115.266842) (xy 203.611105 -115.251535)
			(xy 203.585572 -115.240562) (xy 203.575412 -115.23599) (xy 194.68211 -115.23599) (xy 194.672039 -115.235568)
			(xy 194.653433 -115.227855) (xy 194.646042 -115.221004) (xy 193.967608 -114.54257) (xy 193.960496 -114.535204)
			(xy 193.9417 -114.527584) (xy 191.556386 -114.527584) (xy 191.546317 -114.527158) (xy 191.527718 -114.519438)
			(xy 191.520318 -114.512598) (xy 191.333882 -114.326162) (xy 191.32677 -114.318796) (xy 191.307974 -114.311176)
			(xy 189.5983 -114.311176) (xy 189.588229 -114.311598) (xy 189.569623 -114.31931) (xy 189.562232 -114.326162)
			(xy 189.531244 -114.35715) (xy 189.523878 -114.364262) (xy 189.516258 -114.383058) (xy 189.516258 -116.13134)
			(xy 189.516721 -116.141216) (xy 189.524165 -116.159513) (xy 189.530736 -116.1669) (xy 189.53099 -116.167154)
			(xy 189.73292 -116.369084) (xy 189.733428 -116.369592) (xy 189.74081 -116.376174) (xy 189.759108 -116.383628)
			(xy 189.768988 -116.38407) (xy 189.927992 -116.38407) (xy 189.939331 -116.383474) (xy 189.959805 -116.373729)
			(xy 189.974065 -116.3561) (xy 189.977268 -116.345208) (xy 189.984477 -116.317696) (xy 190.00593 -116.265025)
			(xy 190.034964 -116.216122) (xy 190.070935 -116.17207) (xy 190.113045 -116.133845) (xy 190.160363 -116.102293)
			(xy 190.21184 -116.078114) (xy 190.266335 -116.061844) (xy 190.322642 -116.053842) (xy 190.379512 -116.054287)
			(xy 190.435687 -116.063167) (xy 190.489922 -116.080287) (xy 190.541014 -116.105267) (xy 190.587833 -116.137554)
			(xy 190.629341 -116.176433) (xy 190.664619 -116.221041) (xy 190.692885 -116.270392) (xy 190.703708 -116.296694)
			(xy 190.707264 -116.306092) (xy 190.72098 -116.32057) (xy 190.804292 -116.357908) (xy 190.824104 -116.35867)
			(xy 190.833502 -116.355114) (xy 190.865492 -116.343911) (xy 190.931427 -116.328192) (xy 190.998747 -116.32028)
			(xy 191.032638 -116.319808) (xy 191.065558 -116.320234) (xy 191.130975 -116.327689) (xy 191.195115 -116.342554)
			(xy 191.257141 -116.364636) (xy 191.286892 -116.378736) (xy 191.292157 -116.381179) (xy 191.303443 -116.383879)
			(xy 191.309244 -116.38407) (xy 191.609726 -116.38407) (xy 191.619795 -116.384497) (xy 191.638395 -116.392215)
			(xy 191.645794 -116.399056) (xy 191.85636 -116.609622) (xy 191.8716 -116.616988) (xy 191.88049 -116.618004)
			(xy 191.912497 -116.622079) (xy 191.975397 -116.636459) (xy 192.036295 -116.657785) (xy 192.094424 -116.68579)
			(xy 192.149056 -116.720121) (xy 192.199504 -116.760349) (xy 192.222628 -116.78285) (xy 192.775078 -117.3353)
			(xy 192.797564 -117.358438) (xy 192.837785 -117.408889) (xy 192.872116 -117.463519) (xy 192.900125 -117.521645)
			(xy 192.921463 -117.582536) (xy 192.935861 -117.645431) (xy 192.939924 -117.677438) (xy 192.94094 -117.686328)
			(xy 192.948306 -117.701568) (xy 193.208656 -117.961918) (xy 193.209164 -117.962426) (xy 193.216545 -117.969009)
			(xy 193.234844 -117.97646) (xy 193.244724 -117.976904) (xy 200.133204 -117.976904) (xy 200.143274 -117.977328)
			(xy 200.161877 -117.985044) (xy 200.169272 -117.99189) (xy 200.843388 -118.666006) (xy 208.794348 -118.666006)
			(xy 208.798419 -118.610384) (xy 208.810545 -118.555947) (xy 208.830468 -118.503856) (xy 208.857764 -118.455221)
			(xy 208.89185 -118.411078) (xy 208.931999 -118.372369) (xy 208.977357 -118.339918) (xy 209.026957 -118.314417)
			(xy 209.079741 -118.29641) (xy 209.134584 -118.28628) (xy 209.190318 -118.284243) (xy 209.245755 -118.290343)
			(xy 209.299712 -118.304449) (xy 209.351041 -118.326261) (xy 209.398647 -118.355315) (xy 209.441515 -118.39099)
			(xy 209.478732 -118.432527) (xy 209.509505 -118.47904) (xy 209.533177 -118.529537) (xy 209.549245 -118.582944)
			(xy 209.557365 -118.63812) (xy 209.557586 -118.650254) (xy 213.643446 -118.650254) (xy 213.643446 -118.590318)
			(xy 213.651269 -118.530896) (xy 213.666782 -118.473003) (xy 213.689718 -118.41763) (xy 213.719685 -118.365724)
			(xy 213.756172 -118.318174) (xy 213.798552 -118.275794) (xy 213.846102 -118.239307) (xy 213.898008 -118.20934)
			(xy 213.953381 -118.186404) (xy 214.011274 -118.170891) (xy 214.070696 -118.163068) (xy 214.130632 -118.163068)
			(xy 214.190054 -118.170891) (xy 214.247947 -118.186404) (xy 214.30332 -118.20934) (xy 214.355226 -118.239307)
			(xy 214.402776 -118.275794) (xy 214.445156 -118.318174) (xy 214.481643 -118.365724) (xy 214.51161 -118.41763)
			(xy 214.534546 -118.473003) (xy 214.550059 -118.530896) (xy 214.557882 -118.590318) (xy 214.558372 -118.620286)
			(xy 214.557882 -118.650254) (xy 214.550059 -118.709676) (xy 214.534546 -118.767569) (xy 214.51161 -118.822942)
			(xy 214.481643 -118.874848) (xy 214.445156 -118.922398) (xy 214.402776 -118.964778) (xy 214.355226 -119.001265)
			(xy 214.30332 -119.031232) (xy 214.247947 -119.054168) (xy 214.190054 -119.069681) (xy 214.130632 -119.077504)
			(xy 214.070696 -119.077504) (xy 214.011274 -119.069681) (xy 213.953381 -119.054168) (xy 213.898008 -119.031232)
			(xy 213.846102 -119.001265) (xy 213.798552 -118.964778) (xy 213.756172 -118.922398) (xy 213.719685 -118.874848)
			(xy 213.689718 -118.822942) (xy 213.666782 -118.767569) (xy 213.651269 -118.709676) (xy 213.643446 -118.650254)
			(xy 209.557586 -118.650254) (xy 209.557874 -118.666006) (xy 209.557365 -118.693892) (xy 209.549245 -118.749068)
			(xy 209.533177 -118.802475) (xy 209.509505 -118.852972) (xy 209.478732 -118.899485) (xy 209.441515 -118.941022)
			(xy 209.398647 -118.976697) (xy 209.351041 -119.005751) (xy 209.299712 -119.027563) (xy 209.245755 -119.041669)
			(xy 209.190318 -119.047769) (xy 209.134584 -119.045732) (xy 209.079741 -119.035602) (xy 209.026957 -119.017595)
			(xy 208.977357 -118.992094) (xy 208.931999 -118.959643) (xy 208.89185 -118.920934) (xy 208.857764 -118.876791)
			(xy 208.830468 -118.828156) (xy 208.810545 -118.776065) (xy 208.798419 -118.721628) (xy 208.794348 -118.666006)
			(xy 200.843388 -118.666006) (xy 201.430378 -119.252996) (xy 215.62871 -119.252996) (xy 215.62871 -119.19306)
			(xy 215.636533 -119.133638) (xy 215.652046 -119.075745) (xy 215.674982 -119.020372) (xy 215.704949 -118.968466)
			(xy 215.741436 -118.920916) (xy 215.783816 -118.878536) (xy 215.831366 -118.842049) (xy 215.883272 -118.812082)
			(xy 215.938645 -118.789146) (xy 215.996538 -118.773633) (xy 216.05596 -118.76581) (xy 216.115896 -118.76581)
			(xy 216.175318 -118.773633) (xy 216.233211 -118.789146) (xy 216.288584 -118.812082) (xy 216.34049 -118.842049)
			(xy 216.38804 -118.878536) (xy 216.43042 -118.920916) (xy 216.466907 -118.968466) (xy 216.496874 -119.020372)
			(xy 216.51981 -119.075745) (xy 216.535323 -119.133638) (xy 216.543146 -119.19306) (xy 216.543636 -119.223028)
			(xy 216.543146 -119.252996) (xy 216.535323 -119.312418) (xy 216.51981 -119.370311) (xy 216.496874 -119.425684)
			(xy 216.466907 -119.47759) (xy 216.43042 -119.52514) (xy 216.38804 -119.56752) (xy 216.34049 -119.604007)
			(xy 216.288584 -119.633974) (xy 216.233211 -119.65691) (xy 216.175318 -119.672423) (xy 216.115896 -119.680246)
			(xy 216.05596 -119.680246) (xy 215.996538 -119.672423) (xy 215.938645 -119.65691) (xy 215.883272 -119.633974)
			(xy 215.831366 -119.604007) (xy 215.783816 -119.56752) (xy 215.741436 -119.52514) (xy 215.704949 -119.47759)
			(xy 215.674982 -119.425684) (xy 215.652046 -119.370311) (xy 215.636533 -119.312418) (xy 215.62871 -119.252996)
			(xy 201.430378 -119.252996) (xy 202.368654 -120.191272) (xy 213.608648 -120.191272) (xy 213.608648 -120.131336)
			(xy 213.616471 -120.071914) (xy 213.631984 -120.014021) (xy 213.65492 -119.958648) (xy 213.684887 -119.906742)
			(xy 213.721374 -119.859192) (xy 213.763754 -119.816812) (xy 213.811304 -119.780325) (xy 213.86321 -119.750358)
			(xy 213.918583 -119.727422) (xy 213.976476 -119.711909) (xy 214.035898 -119.704086) (xy 214.095834 -119.704086)
			(xy 214.155256 -119.711909) (xy 214.213149 -119.727422) (xy 214.268522 -119.750358) (xy 214.320428 -119.780325)
			(xy 214.367978 -119.816812) (xy 214.410358 -119.859192) (xy 214.446845 -119.906742) (xy 214.476812 -119.958648)
			(xy 214.499748 -120.014021) (xy 214.515261 -120.071914) (xy 214.523084 -120.131336) (xy 214.523574 -120.161304)
			(xy 214.523084 -120.191272) (xy 214.516797 -120.239028) (xy 215.72931 -120.239028) (xy 215.733381 -120.183406)
			(xy 215.745507 -120.128969) (xy 215.76543 -120.076878) (xy 215.792726 -120.028243) (xy 215.826812 -119.9841)
			(xy 215.866961 -119.945391) (xy 215.912319 -119.91294) (xy 215.961919 -119.887439) (xy 216.014703 -119.869432)
			(xy 216.069546 -119.859302) (xy 216.12528 -119.857265) (xy 216.180717 -119.863365) (xy 216.234674 -119.877471)
			(xy 216.286003 -119.899283) (xy 216.333609 -119.928337) (xy 216.376477 -119.964012) (xy 216.413694 -120.005549)
			(xy 216.444467 -120.052062) (xy 216.468139 -120.102559) (xy 216.484207 -120.155966) (xy 216.492327 -120.211142)
			(xy 216.492836 -120.239028) (xy 216.492327 -120.266914) (xy 216.484207 -120.32209) (xy 216.468139 -120.375497)
			(xy 216.444467 -120.425994) (xy 216.413694 -120.472507) (xy 216.376477 -120.514044) (xy 216.333609 -120.549719)
			(xy 216.286003 -120.578773) (xy 216.234674 -120.600585) (xy 216.180717 -120.614691) (xy 216.12528 -120.620791)
			(xy 216.069546 -120.618754) (xy 216.014703 -120.608624) (xy 215.961919 -120.590617) (xy 215.912319 -120.565116)
			(xy 215.866961 -120.532665) (xy 215.826812 -120.493956) (xy 215.792726 -120.449813) (xy 215.76543 -120.401178)
			(xy 215.745507 -120.349087) (xy 215.733381 -120.29465) (xy 215.72931 -120.239028) (xy 214.516797 -120.239028)
			(xy 214.515261 -120.250694) (xy 214.499748 -120.308587) (xy 214.476812 -120.36396) (xy 214.446845 -120.415866)
			(xy 214.410358 -120.463416) (xy 214.367978 -120.505796) (xy 214.320428 -120.542283) (xy 214.268522 -120.57225)
			(xy 214.213149 -120.595186) (xy 214.155256 -120.610699) (xy 214.095834 -120.618522) (xy 214.035898 -120.618522)
			(xy 213.976476 -120.610699) (xy 213.918583 -120.595186) (xy 213.86321 -120.57225) (xy 213.811304 -120.542283)
			(xy 213.763754 -120.505796) (xy 213.721374 -120.463416) (xy 213.684887 -120.415866) (xy 213.65492 -120.36396)
			(xy 213.631984 -120.308587) (xy 213.616471 -120.250694) (xy 213.608648 -120.191272) (xy 202.368654 -120.191272)
			(xy 202.681332 -120.50395) (xy 202.688178 -120.511348) (xy 202.695905 -120.529947) (xy 202.696318 -120.540018)
			(xy 202.696318 -121.255028) (xy 215.705434 -121.255028) (xy 215.709505 -121.199406) (xy 215.721631 -121.144969)
			(xy 215.741554 -121.092878) (xy 215.76885 -121.044243) (xy 215.802936 -121.0001) (xy 215.843085 -120.961391)
			(xy 215.888443 -120.92894) (xy 215.938043 -120.903439) (xy 215.990827 -120.885432) (xy 216.04567 -120.875302)
			(xy 216.101404 -120.873265) (xy 216.156841 -120.879365) (xy 216.210798 -120.893471) (xy 216.262127 -120.915283)
			(xy 216.309733 -120.944337) (xy 216.352601 -120.980012) (xy 216.389818 -121.021549) (xy 216.420591 -121.068062)
			(xy 216.444263 -121.118559) (xy 216.460331 -121.171966) (xy 216.468451 -121.227142) (xy 216.46896 -121.255028)
			(xy 216.468451 -121.282914) (xy 216.460331 -121.33809) (xy 216.444263 -121.391497) (xy 216.420591 -121.441994)
			(xy 216.389818 -121.488507) (xy 216.352601 -121.530044) (xy 216.309733 -121.565719) (xy 216.262127 -121.594773)
			(xy 216.210798 -121.616585) (xy 216.156841 -121.630691) (xy 216.101404 -121.636791) (xy 216.04567 -121.634754)
			(xy 215.990827 -121.624624) (xy 215.938043 -121.606617) (xy 215.888443 -121.581116) (xy 215.843085 -121.548665)
			(xy 215.802936 -121.509956) (xy 215.76885 -121.465813) (xy 215.741554 -121.417178) (xy 215.721631 -121.365087)
			(xy 215.709505 -121.31065) (xy 215.705434 -121.255028) (xy 202.696318 -121.255028) (xy 202.696318 -122.094549)
			(xy 210.164198 -122.094549) (xy 210.164198 -122.040051) (xy 210.171954 -121.986109) (xy 210.187306 -121.933819)
			(xy 210.209944 -121.884247) (xy 210.239406 -121.8384) (xy 210.275093 -121.797213) (xy 210.316278 -121.761523)
			(xy 210.362122 -121.732058) (xy 210.411693 -121.709416) (xy 210.463982 -121.694059) (xy 210.517924 -121.6863)
			(xy 210.545172 -121.685812) (xy 210.572542 -121.686292) (xy 210.62672 -121.694106) (xy 210.679223 -121.709591)
			(xy 210.728971 -121.73243) (xy 210.774938 -121.762152) (xy 210.79587 -121.779792) (xy 210.802982 -121.785888)
			(xy 210.82 -121.792238) (xy 210.905344 -121.792238) (xy 210.922362 -121.785888) (xy 210.929474 -121.779792)
			(xy 210.950407 -121.762151) (xy 210.996375 -121.732427) (xy 211.046121 -121.709581) (xy 211.098623 -121.694085)
			(xy 211.152801 -121.686256) (xy 211.207543 -121.686256) (xy 211.261721 -121.694085) (xy 211.314223 -121.709581)
			(xy 211.363969 -121.732427) (xy 211.409937 -121.762151) (xy 211.43087 -121.779792) (xy 211.437982 -121.785888)
			(xy 211.455 -121.792238) (xy 211.540344 -121.792238) (xy 211.557362 -121.785888) (xy 211.564474 -121.779792)
			(xy 211.585404 -121.76215) (xy 211.631378 -121.732439) (xy 211.681126 -121.709604) (xy 211.733627 -121.694113)
			(xy 211.787803 -121.686286) (xy 211.815172 -121.685812) (xy 211.842428 -121.686233) (xy 211.896384 -121.693987)
			(xy 211.948688 -121.709342) (xy 211.998275 -121.731984) (xy 212.044134 -121.761452) (xy 212.085332 -121.797148)
			(xy 212.121031 -121.838344) (xy 212.150503 -121.884201) (xy 212.173149 -121.933785) (xy 212.188507 -121.986088)
			(xy 212.196265 -122.040044) (xy 212.196265 -122.094556) (xy 212.188507 -122.148512) (xy 212.173149 -122.200815)
			(xy 212.150503 -122.250399) (xy 212.121031 -122.296256) (xy 212.085332 -122.337452) (xy 212.044134 -122.373148)
			(xy 211.998275 -122.402616) (xy 211.948688 -122.425258) (xy 211.896384 -122.440613) (xy 211.842428 -122.448367)
			(xy 211.815172 -122.448828) (xy 211.7878 -122.448396) (xy 211.733619 -122.440573) (xy 211.681115 -122.425077)
			(xy 211.631369 -122.402227) (xy 211.585404 -122.372494) (xy 211.564474 -122.354848) (xy 211.557362 -122.348752)
			(xy 211.540344 -122.342402) (xy 211.455 -122.342402) (xy 211.437982 -122.348752) (xy 211.43087 -122.354848)
			(xy 211.409937 -122.372489) (xy 211.363969 -122.402213) (xy 211.314223 -122.425059) (xy 211.261721 -122.440555)
			(xy 211.207543 -122.448384) (xy 211.152801 -122.448384) (xy 211.098623 -122.440555) (xy 211.046121 -122.425059)
			(xy 210.996375 -122.402213) (xy 210.950407 -122.372489) (xy 210.929474 -122.354848) (xy 210.922362 -122.348752)
			(xy 210.905344 -122.342402) (xy 210.82 -122.342402) (xy 210.802982 -122.348752) (xy 210.79587 -122.354848)
			(xy 210.774916 -122.37246) (xy 210.72895 -122.402177) (xy 210.679208 -122.425019) (xy 210.626712 -122.440517)
			(xy 210.57254 -122.448351) (xy 210.545172 -122.448828) (xy 210.517924 -122.4483) (xy 210.463982 -122.440541)
			(xy 210.411693 -122.425184) (xy 210.362122 -122.402542) (xy 210.316278 -122.373077) (xy 210.275093 -122.337387)
			(xy 210.239406 -122.2962) (xy 210.209944 -122.250353) (xy 210.187306 -122.200781) (xy 210.171954 -122.148491)
			(xy 210.164198 -122.094549) (xy 202.696318 -122.094549) (xy 202.696318 -124.743972) (xy 205.550516 -124.743972)
			(xy 205.550962 -124.716601) (xy 205.558784 -124.662421) (xy 205.574278 -124.609917) (xy 205.597124 -124.560171)
			(xy 205.626853 -124.514205) (xy 205.644496 -124.493274) (xy 205.650592 -124.486162) (xy 205.656942 -124.469144)
			(xy 205.656942 -124.3838) (xy 205.650592 -124.366782) (xy 205.644496 -124.35967) (xy 205.626829 -124.338759)
			(xy 205.597108 -124.292787) (xy 205.574266 -124.243037) (xy 205.558773 -124.190531) (xy 205.550948 -124.13635)
			(xy 205.550951 -124.081607) (xy 205.558782 -124.027427) (xy 205.574281 -123.974924) (xy 205.597128 -123.925176)
			(xy 205.626855 -123.879207) (xy 205.644496 -123.858274) (xy 205.650592 -123.851162) (xy 205.656942 -123.834144)
			(xy 205.656942 -123.7488) (xy 205.650592 -123.731782) (xy 205.644496 -123.72467) (xy 205.626829 -123.703759)
			(xy 205.597108 -123.657787) (xy 205.574266 -123.608037) (xy 205.558773 -123.555531) (xy 205.550948 -123.50135)
			(xy 205.550951 -123.446607) (xy 205.558782 -123.392427) (xy 205.574281 -123.339924) (xy 205.597128 -123.290176)
			(xy 205.626855 -123.244207) (xy 205.644496 -123.223274) (xy 205.650592 -123.216162) (xy 205.656942 -123.199144)
			(xy 205.656942 -123.1138) (xy 205.650592 -123.096782) (xy 205.644496 -123.08967) (xy 205.626876 -123.068723)
			(xy 205.597161 -123.022754) (xy 205.574322 -122.97301) (xy 205.558826 -122.920513) (xy 205.550993 -122.86634)
			(xy 205.550516 -122.838972) (xy 205.551002 -122.811721) (xy 205.558758 -122.757773) (xy 205.574113 -122.705478)
			(xy 205.596755 -122.655901) (xy 205.626221 -122.610051) (xy 205.661912 -122.56886) (xy 205.703103 -122.533169)
			(xy 205.748953 -122.503703) (xy 205.79853 -122.481061) (xy 205.850825 -122.465706) (xy 205.904773 -122.45795)
			(xy 205.959275 -122.45795) (xy 206.013223 -122.465706) (xy 206.065518 -122.481061) (xy 206.115095 -122.503703)
			(xy 206.160945 -122.533169) (xy 206.202136 -122.56886) (xy 206.237827 -122.610051) (xy 206.267293 -122.655901)
			(xy 206.289935 -122.705478) (xy 206.30529 -122.757773) (xy 206.313046 -122.811721) (xy 206.313532 -122.838972)
			(xy 206.313066 -122.866342) (xy 206.305251 -122.920522) (xy 206.289763 -122.973026) (xy 206.26692 -123.022773)
			(xy 206.237194 -123.068739) (xy 206.219552 -123.08967) (xy 206.213456 -123.096782) (xy 206.207106 -123.1138)
			(xy 206.207106 -123.199144) (xy 206.210328 -123.20778) (xy 208.512664 -123.20778) (xy 208.513103 -123.180409)
			(xy 208.520925 -123.126228) (xy 208.536419 -123.073724) (xy 208.559268 -123.023977) (xy 208.588999 -122.978012)
			(xy 208.606644 -122.957082) (xy 208.61274 -122.94997) (xy 208.61909 -122.932952) (xy 208.61909 -122.847608)
			(xy 208.61274 -122.83059) (xy 208.606644 -122.823478) (xy 208.589035 -122.802522) (xy 208.559317 -122.756556)
			(xy 208.536475 -122.706815) (xy 208.520977 -122.654319) (xy 208.513141 -122.600148) (xy 208.512664 -122.57278)
			(xy 208.51315 -122.545529) (xy 208.520906 -122.491581) (xy 208.536261 -122.439286) (xy 208.558903 -122.389709)
			(xy 208.588369 -122.343859) (xy 208.62406 -122.302668) (xy 208.665251 -122.266977) (xy 208.711101 -122.237511)
			(xy 208.760678 -122.214869) (xy 208.812973 -122.199514) (xy 208.866921 -122.191758) (xy 208.921423 -122.191758)
			(xy 208.975371 -122.199514) (xy 209.027666 -122.214869) (xy 209.077243 -122.237511) (xy 209.123093 -122.266977)
			(xy 209.164284 -122.302668) (xy 209.199975 -122.343859) (xy 209.229441 -122.389709) (xy 209.252083 -122.439286)
			(xy 209.267438 -122.491581) (xy 209.272247 -122.525028) (xy 213.607396 -122.525028) (xy 213.607877 -122.49828)
			(xy 213.615373 -122.44531) (xy 213.630194 -122.393907) (xy 213.65205 -122.345077) (xy 213.680512 -122.29978)
			(xy 213.715021 -122.258901) (xy 213.754902 -122.223244) (xy 213.799373 -122.193506) (xy 213.847561 -122.170271)
			(xy 213.898522 -122.153995) (xy 213.951257 -122.144996) (xy 213.977982 -122.143774) (xy 213.991505 -122.142968)
			(xy 214.017415 -122.135085) (xy 214.040341 -122.120668) (xy 214.058671 -122.100731) (xy 214.071115 -122.076676)
			(xy 214.076798 -122.050197) (xy 214.075319 -122.023155) (xy 214.071454 -122.01017) (xy 214.062437 -121.980956)
			(xy 214.052736 -121.920596) (xy 214.05215 -121.890028) (xy 214.052636 -121.862777) (xy 214.060392 -121.808829)
			(xy 214.075747 -121.756534) (xy 214.098389 -121.706957) (xy 214.127855 -121.661107) (xy 214.163546 -121.619916)
			(xy 214.204737 -121.584225) (xy 214.250587 -121.554759) (xy 214.300164 -121.532117) (xy 214.352459 -121.516762)
			(xy 214.406407 -121.509006) (xy 214.460909 -121.509006) (xy 214.514857 -121.516762) (xy 214.567152 -121.532117)
			(xy 214.616729 -121.554759) (xy 214.662579 -121.584225) (xy 214.70377 -121.619916) (xy 214.739461 -121.661107)
			(xy 214.768927 -121.706957) (xy 214.791569 -121.756534) (xy 214.806924 -121.808829) (xy 214.81468 -121.862777)
			(xy 214.815166 -121.890028) (xy 214.814681 -121.916777) (xy 214.80719 -121.969748) (xy 214.792372 -122.021154)
			(xy 214.770519 -122.069985) (xy 214.742059 -122.115285) (xy 214.707549 -122.156165) (xy 214.667667 -122.191823)
			(xy 214.623195 -122.221561) (xy 214.575005 -122.244794) (xy 214.524042 -122.261067) (xy 214.471305 -122.270062)
			(xy 214.44458 -122.271282) (xy 214.431061 -122.272115) (xy 214.40516 -122.280002) (xy 214.382241 -122.294418)
			(xy 214.363916 -122.314349) (xy 214.351472 -122.338396) (xy 214.345783 -122.364867) (xy 214.34725 -122.391903)
			(xy 214.351108 -122.404886) (xy 214.360139 -122.434096) (xy 214.369831 -122.494459) (xy 214.370412 -122.525028)
			(xy 215.748868 -122.525028) (xy 215.752939 -122.469406) (xy 215.765065 -122.414969) (xy 215.784988 -122.362878)
			(xy 215.812284 -122.314243) (xy 215.84637 -122.2701) (xy 215.886519 -122.231391) (xy 215.931877 -122.19894)
			(xy 215.981477 -122.173439) (xy 216.034261 -122.155432) (xy 216.089104 -122.145302) (xy 216.144838 -122.143265)
			(xy 216.200275 -122.149365) (xy 216.254232 -122.163471) (xy 216.305561 -122.185283) (xy 216.353167 -122.214337)
			(xy 216.396035 -122.250012) (xy 216.433252 -122.291549) (xy 216.464025 -122.338062) (xy 216.487697 -122.388559)
			(xy 216.503765 -122.441966) (xy 216.511885 -122.497142) (xy 216.512394 -122.525028) (xy 216.511885 -122.552914)
			(xy 216.503765 -122.60809) (xy 216.487697 -122.661497) (xy 216.464025 -122.711994) (xy 216.433252 -122.758507)
			(xy 216.432844 -122.758962) (xy 218.430854 -122.758962) (xy 218.434925 -122.70334) (xy 218.447051 -122.648903)
			(xy 218.466974 -122.596812) (xy 218.49427 -122.548177) (xy 218.528356 -122.504034) (xy 218.568505 -122.465325)
			(xy 218.613863 -122.432874) (xy 218.663463 -122.407373) (xy 218.716247 -122.389366) (xy 218.77109 -122.379236)
			(xy 218.826824 -122.377199) (xy 218.882261 -122.383299) (xy 218.936218 -122.397405) (xy 218.987547 -122.419217)
			(xy 219.035153 -122.448271) (xy 219.078021 -122.483946) (xy 219.115238 -122.525483) (xy 219.146011 -122.571996)
			(xy 219.169683 -122.622493) (xy 219.185751 -122.6759) (xy 219.193871 -122.731076) (xy 219.19438 -122.758962)
			(xy 219.193871 -122.786848) (xy 219.185751 -122.842024) (xy 219.169683 -122.895431) (xy 219.146011 -122.945928)
			(xy 219.115238 -122.992441) (xy 219.078021 -123.033978) (xy 219.035153 -123.069653) (xy 218.987547 -123.098707)
			(xy 218.936218 -123.120519) (xy 218.882261 -123.134625) (xy 218.826824 -123.140725) (xy 218.77109 -123.138688)
			(xy 218.716247 -123.128558) (xy 218.663463 -123.110551) (xy 218.613863 -123.08505) (xy 218.568505 -123.052599)
			(xy 218.528356 -123.01389) (xy 218.49427 -122.969747) (xy 218.466974 -122.921112) (xy 218.447051 -122.869021)
			(xy 218.434925 -122.814584) (xy 218.430854 -122.758962) (xy 216.432844 -122.758962) (xy 216.396035 -122.800044)
			(xy 216.353167 -122.835719) (xy 216.305561 -122.864773) (xy 216.254232 -122.886585) (xy 216.200275 -122.900691)
			(xy 216.144838 -122.906791) (xy 216.089104 -122.904754) (xy 216.034261 -122.894624) (xy 215.981477 -122.876617)
			(xy 215.931877 -122.851116) (xy 215.886519 -122.818665) (xy 215.84637 -122.779956) (xy 215.812284 -122.735813)
			(xy 215.784988 -122.687178) (xy 215.765065 -122.635087) (xy 215.752939 -122.58065) (xy 215.748868 -122.525028)
			(xy 214.370412 -122.525028) (xy 214.369926 -122.552279) (xy 214.36217 -122.606227) (xy 214.346815 -122.658522)
			(xy 214.324173 -122.708099) (xy 214.294707 -122.753949) (xy 214.259016 -122.79514) (xy 214.217825 -122.830831)
			(xy 214.171975 -122.860297) (xy 214.122398 -122.882939) (xy 214.070103 -122.898294) (xy 214.016155 -122.90605)
			(xy 213.961653 -122.90605) (xy 213.907705 -122.898294) (xy 213.85541 -122.882939) (xy 213.805833 -122.860297)
			(xy 213.759983 -122.830831) (xy 213.718792 -122.79514) (xy 213.683101 -122.753949) (xy 213.653635 -122.708099)
			(xy 213.630993 -122.658522) (xy 213.615638 -122.606227) (xy 213.607882 -122.552279) (xy 213.607396 -122.525028)
			(xy 209.272247 -122.525028) (xy 209.275194 -122.545529) (xy 209.27568 -122.57278) (xy 209.275207 -122.60015)
			(xy 209.267392 -122.654329) (xy 209.251904 -122.706832) (xy 209.229064 -122.756579) (xy 209.199341 -122.802546)
			(xy 209.1817 -122.823478) (xy 209.175604 -122.83059) (xy 209.169254 -122.847608) (xy 209.169254 -122.932952)
			(xy 209.175604 -122.94997) (xy 209.1817 -122.957082) (xy 209.19457 -122.972347) (xy 210.707522 -122.972347)
			(xy 210.707522 -122.917853) (xy 210.715277 -122.863913) (xy 210.730629 -122.811626) (xy 210.753266 -122.762057)
			(xy 210.782727 -122.716213) (xy 210.818412 -122.675028) (xy 210.859595 -122.63934) (xy 210.905437 -122.609877)
			(xy 210.955006 -122.587237) (xy 211.007292 -122.571882) (xy 211.061231 -122.564124) (xy 211.088478 -122.563636)
			(xy 211.116082 -122.564094) (xy 211.170715 -122.572036) (xy 211.223632 -122.587773) (xy 211.273727 -122.610975)
			(xy 211.319953 -122.641157) (xy 211.361345 -122.677689) (xy 211.397036 -122.719807) (xy 211.412074 -122.74296)
			(xy 211.420048 -122.754782) (xy 211.441213 -122.773872) (xy 211.466832 -122.786362) (xy 211.494906 -122.791279)
			(xy 211.523245 -122.78824) (xy 211.549637 -122.77748) (xy 211.572024 -122.759841) (xy 211.58073 -122.748548)
			(xy 211.596147 -122.7278) (xy 211.631687 -122.690264) (xy 211.67197 -122.657871) (xy 211.716258 -122.631215)
			(xy 211.76374 -122.610784) (xy 211.813546 -122.596953) (xy 211.864764 -122.589973) (xy 211.89061 -122.589544)
			(xy 211.917857 -122.590127) (xy 211.971797 -122.597884) (xy 212.024084 -122.613238) (xy 212.073654 -122.635876)
			(xy 212.119497 -122.665339) (xy 212.160681 -122.701026) (xy 212.196367 -122.742211) (xy 212.225828 -122.788055)
			(xy 212.248466 -122.837625) (xy 212.263819 -122.889913) (xy 212.271574 -122.943853) (xy 212.271574 -122.998347)
			(xy 212.263819 -123.052287) (xy 212.248466 -123.104575) (xy 212.225828 -123.154145) (xy 212.196367 -123.199989)
			(xy 212.160681 -123.241174) (xy 212.119497 -123.276861) (xy 212.073654 -123.306324) (xy 212.024084 -123.328962)
			(xy 211.971797 -123.344316) (xy 211.917857 -123.352073) (xy 211.89061 -123.35256) (xy 211.863008 -123.352036)
			(xy 211.808378 -123.344106) (xy 211.755463 -123.328381) (xy 211.705368 -123.30519) (xy 211.659141 -123.275018)
			(xy 211.617747 -123.238495) (xy 211.582053 -123.196385) (xy 211.567014 -123.173236) (xy 211.559055 -123.161403)
			(xy 211.537887 -123.142314) (xy 211.512265 -123.129824) (xy 211.484188 -123.124908) (xy 211.455847 -123.12795)
			(xy 211.429452 -123.138712) (xy 211.407064 -123.156354) (xy 211.398358 -123.167648) (xy 211.382947 -123.188401)
			(xy 211.347407 -123.225937) (xy 211.307123 -123.258329) (xy 211.262833 -123.284985) (xy 211.21535 -123.305415)
			(xy 211.165543 -123.319246) (xy 211.114324 -123.326223) (xy 211.088478 -123.326652) (xy 211.061231 -123.326076)
			(xy 211.007292 -123.318318) (xy 210.955006 -123.302963) (xy 210.905437 -123.280323) (xy 210.859595 -123.25086)
			(xy 210.818412 -123.215172) (xy 210.782727 -123.173987) (xy 210.753266 -123.128143) (xy 210.730629 -123.078574)
			(xy 210.715277 -123.026287) (xy 210.707522 -122.972347) (xy 209.19457 -122.972347) (xy 209.199344 -122.97801)
			(xy 209.229055 -123.023984) (xy 209.25189 -123.073732) (xy 209.26738 -123.126234) (xy 209.275207 -123.180411)
			(xy 209.27568 -123.20778) (xy 209.275194 -123.235031) (xy 209.267438 -123.288979) (xy 209.252083 -123.341274)
			(xy 209.229441 -123.390851) (xy 209.199975 -123.436701) (xy 209.164284 -123.477892) (xy 209.123093 -123.513583)
			(xy 209.077243 -123.543049) (xy 209.027666 -123.565691) (xy 208.975371 -123.581046) (xy 208.921423 -123.588802)
			(xy 208.866921 -123.588802) (xy 208.812973 -123.581046) (xy 208.760678 -123.565691) (xy 208.711101 -123.543049)
			(xy 208.665251 -123.513583) (xy 208.62406 -123.477892) (xy 208.588369 -123.436701) (xy 208.558903 -123.390851)
			(xy 208.536261 -123.341274) (xy 208.520906 -123.288979) (xy 208.51315 -123.235031) (xy 208.512664 -123.20778)
			(xy 206.210328 -123.20778) (xy 206.213456 -123.216162) (xy 206.219552 -123.223274) (xy 206.235255 -123.241829)
			(xy 206.262323 -123.282204) (xy 206.284063 -123.325681) (xy 206.29245 -123.348496) (xy 206.296514 -123.360688)
			(xy 206.315818 -123.378214) (xy 206.424022 -123.404376) (xy 206.448914 -123.397772) (xy 206.458312 -123.388628)
			(xy 206.479736 -123.369007) (xy 206.527411 -123.335812) (xy 206.579562 -123.310221) (xy 206.634988 -123.292822)
			(xy 206.69241 -123.284018) (xy 206.721456 -123.283472) (xy 206.748826 -123.283946) (xy 206.803006 -123.291759)
			(xy 206.855509 -123.307246) (xy 206.905256 -123.330086) (xy 206.951223 -123.35981) (xy 206.972154 -123.377452)
			(xy 206.979266 -123.383548) (xy 206.996284 -123.389898) (xy 207.081628 -123.389898) (xy 207.098646 -123.383548)
			(xy 207.105758 -123.377452) (xy 207.126702 -123.359827) (xy 207.172671 -123.330111) (xy 207.222415 -123.307272)
			(xy 207.274913 -123.291778) (xy 207.329087 -123.283947) (xy 207.356456 -123.283472) (xy 207.383707 -123.283996)
			(xy 207.437655 -123.291747) (xy 207.48995 -123.307096) (xy 207.539529 -123.329732) (xy 207.585381 -123.359194)
			(xy 207.626574 -123.394881) (xy 207.662268 -123.436068) (xy 207.691737 -123.481915) (xy 207.714382 -123.53149)
			(xy 207.72974 -123.583783) (xy 207.737499 -123.637729) (xy 207.737964 -123.66498) (xy 207.737202 -123.689872)
			(xy 207.736186 -123.70308) (xy 207.747362 -123.726448) (xy 207.838548 -123.792488) (xy 207.864202 -123.79579)
			(xy 207.876394 -123.79071) (xy 207.899166 -123.78196) (xy 207.946365 -123.769632) (xy 207.99475 -123.763413)
			(xy 208.019142 -123.763024) (xy 208.046396 -123.763439) (xy 208.100348 -123.771202) (xy 208.152646 -123.786564)
			(xy 208.202225 -123.809212) (xy 208.248077 -123.838686) (xy 208.289268 -123.874385) (xy 208.324958 -123.915582)
			(xy 208.354423 -123.96144) (xy 208.377062 -124.011024) (xy 208.392414 -124.063325) (xy 208.400166 -124.117278)
			(xy 208.40065 -124.144532) (xy 208.400215 -124.171903) (xy 208.392391 -124.226084) (xy 208.376896 -124.278588)
			(xy 208.354047 -124.328335) (xy 208.324315 -124.3743) (xy 208.30667 -124.39523) (xy 208.300574 -124.402342)
			(xy 208.294224 -124.41936) (xy 208.294224 -124.504704) (xy 208.300574 -124.521722) (xy 208.30667 -124.528834)
			(xy 208.324287 -124.549784) (xy 208.354003 -124.595751) (xy 208.365847 -124.621544) (xy 211.274914 -124.621544)
			(xy 211.275345 -124.595227) (xy 211.282569 -124.543092) (xy 211.296886 -124.492443) (xy 211.318025 -124.444241)
			(xy 211.345584 -124.3994) (xy 211.379042 -124.358769) (xy 211.398104 -124.34062) (xy 211.405499 -124.333093)
			(xy 211.414027 -124.313817) (xy 211.414614 -124.303282) (xy 211.414614 -124.228606) (xy 211.414091 -124.218056)
			(xy 211.405551 -124.198761) (xy 211.398104 -124.191268) (xy 211.37901 -124.173148) (xy 211.345533 -124.132525)
			(xy 211.317964 -124.087681) (xy 211.296828 -124.039471) (xy 211.282527 -123.988811) (xy 211.275333 -123.936664)
			(xy 211.274914 -123.910344) (xy 211.2754 -123.883093) (xy 211.283156 -123.829145) (xy 211.298511 -123.77685)
			(xy 211.321153 -123.727273) (xy 211.350619 -123.681423) (xy 211.38631 -123.640232) (xy 211.427501 -123.604541)
			(xy 211.473351 -123.575075) (xy 211.522928 -123.552433) (xy 211.575223 -123.537078) (xy 211.629171 -123.529322)
			(xy 211.683673 -123.529322) (xy 211.737621 -123.537078) (xy 211.789916 -123.552433) (xy 211.839493 -123.575075)
			(xy 211.885343 -123.604541) (xy 211.926534 -123.640232) (xy 211.962225 -123.681423) (xy 211.991691 -123.727273)
			(xy 212.014333 -123.77685) (xy 212.029688 -123.829145) (xy 212.037444 -123.883093) (xy 212.03793 -123.910344)
			(xy 212.037476 -123.93666) (xy 212.030255 -123.988794) (xy 212.015941 -124.039441) (xy 211.994807 -124.087643)
			(xy 211.967252 -124.132485) (xy 211.9338 -124.173117) (xy 211.91474 -124.191268) (xy 211.907357 -124.198805)
			(xy 211.898821 -124.218073) (xy 211.89823 -124.228606) (xy 211.89823 -124.303282) (xy 211.898746 -124.313833)
			(xy 211.90729 -124.333129) (xy 211.91474 -124.34062) (xy 211.933818 -124.358757) (xy 211.967298 -124.399375)
			(xy 211.99487 -124.444215) (xy 212.01601 -124.492422) (xy 212.030314 -124.54308) (xy 212.037511 -124.595224)
			(xy 212.03793 -124.621544) (xy 212.037444 -124.648795) (xy 212.029688 -124.702743) (xy 212.014333 -124.755038)
			(xy 211.997926 -124.790962) (xy 218.430854 -124.790962) (xy 218.434925 -124.73534) (xy 218.447051 -124.680903)
			(xy 218.466974 -124.628812) (xy 218.49427 -124.580177) (xy 218.528356 -124.536034) (xy 218.568505 -124.497325)
			(xy 218.613863 -124.464874) (xy 218.663463 -124.439373) (xy 218.716247 -124.421366) (xy 218.77109 -124.411236)
			(xy 218.826824 -124.409199) (xy 218.882261 -124.415299) (xy 218.936218 -124.429405) (xy 218.987547 -124.451217)
			(xy 219.035153 -124.480271) (xy 219.078021 -124.515946) (xy 219.115238 -124.557483) (xy 219.146011 -124.603996)
			(xy 219.169683 -124.654493) (xy 219.185751 -124.7079) (xy 219.193871 -124.763076) (xy 219.19438 -124.790962)
			(xy 219.193871 -124.818848) (xy 219.185751 -124.874024) (xy 219.169683 -124.927431) (xy 219.146011 -124.977928)
			(xy 219.115238 -125.024441) (xy 219.078021 -125.065978) (xy 219.035153 -125.101653) (xy 218.987547 -125.130707)
			(xy 218.936218 -125.152519) (xy 218.882261 -125.166625) (xy 218.826824 -125.172725) (xy 218.77109 -125.170688)
			(xy 218.716247 -125.160558) (xy 218.663463 -125.142551) (xy 218.613863 -125.11705) (xy 218.568505 -125.084599)
			(xy 218.528356 -125.04589) (xy 218.49427 -125.001747) (xy 218.466974 -124.953112) (xy 218.447051 -124.901021)
			(xy 218.434925 -124.846584) (xy 218.430854 -124.790962) (xy 211.997926 -124.790962) (xy 211.991691 -124.804615)
			(xy 211.962225 -124.850465) (xy 211.926534 -124.891656) (xy 211.885343 -124.927347) (xy 211.839493 -124.956813)
			(xy 211.789916 -124.979455) (xy 211.737621 -124.99481) (xy 211.683673 -125.002566) (xy 211.629171 -125.002566)
			(xy 211.575223 -124.99481) (xy 211.522928 -124.979455) (xy 211.473351 -124.956813) (xy 211.427501 -124.927347)
			(xy 211.38631 -124.891656) (xy 211.350619 -124.850465) (xy 211.321153 -124.804615) (xy 211.298511 -124.755038)
			(xy 211.283156 -124.702743) (xy 211.2754 -124.648795) (xy 211.274914 -124.621544) (xy 208.365847 -124.621544)
			(xy 208.376844 -124.645494) (xy 208.39234 -124.697991) (xy 208.400173 -124.752164) (xy 208.40065 -124.779532)
			(xy 208.400164 -124.806783) (xy 208.392408 -124.860731) (xy 208.377053 -124.913026) (xy 208.354411 -124.962603)
			(xy 208.324945 -125.008453) (xy 208.289254 -125.049644) (xy 208.248063 -125.085335) (xy 208.202213 -125.114801)
			(xy 208.152636 -125.137443) (xy 208.100341 -125.152798) (xy 208.046393 -125.160554) (xy 207.991891 -125.160554)
			(xy 207.937943 -125.152798) (xy 207.885648 -125.137443) (xy 207.836071 -125.114801) (xy 207.790221 -125.085335)
			(xy 207.74903 -125.049644) (xy 207.713339 -125.008453) (xy 207.683873 -124.962603) (xy 207.661231 -124.913026)
			(xy 207.645876 -124.860731) (xy 207.63812 -124.806783) (xy 207.637634 -124.779532) (xy 207.638111 -124.752162)
			(xy 207.645925 -124.697983) (xy 207.661411 -124.64548) (xy 207.68425 -124.595733) (xy 207.713973 -124.549766)
			(xy 207.731614 -124.528834) (xy 207.73771 -124.521722) (xy 207.74406 -124.504704) (xy 207.74406 -124.41936)
			(xy 207.73771 -124.402342) (xy 207.731614 -124.39523) (xy 207.713978 -124.374296) (xy 207.684265 -124.328324)
			(xy 207.661428 -124.278577) (xy 207.645937 -124.226077) (xy 207.638108 -124.171901) (xy 207.637634 -124.144532)
			(xy 207.638396 -124.11964) (xy 207.639412 -124.106432) (xy 207.628236 -124.083064) (xy 207.53705 -124.017024)
			(xy 207.511396 -124.013722) (xy 207.499204 -124.018802) (xy 207.476433 -124.027553) (xy 207.429233 -124.039881)
			(xy 207.380848 -124.046099) (xy 207.356456 -124.046488) (xy 207.329087 -124.045992) (xy 207.274909 -124.038182)
			(xy 207.222406 -124.0227) (xy 207.172659 -123.999865) (xy 207.126691 -123.970146) (xy 207.105758 -123.952508)
			(xy 207.098646 -123.946412) (xy 207.081628 -123.940062) (xy 206.996284 -123.940062) (xy 206.979266 -123.946412)
			(xy 206.972154 -123.952508) (xy 206.951213 -123.970136) (xy 206.905243 -123.99985) (xy 206.855497 -124.022687)
			(xy 206.802999 -124.038181) (xy 206.748825 -124.046012) (xy 206.721456 -124.046488) (xy 206.693631 -124.046006)
			(xy 206.638569 -124.037937) (xy 206.585266 -124.021948) (xy 206.534854 -123.998378) (xy 206.488405 -123.967728)
			(xy 206.446906 -123.93065) (xy 206.411239 -123.887932) (xy 206.382163 -123.840483) (xy 206.360295 -123.789309)
			(xy 206.3461 -123.7355) (xy 206.342488 -123.707906) (xy 206.340829 -123.69761) (xy 206.330548 -123.679493)
			(xy 206.313923 -123.666942) (xy 206.293683 -123.662017) (xy 206.27315 -123.665527) (xy 206.255695 -123.676895)
			(xy 206.249524 -123.6853) (xy 206.242601 -123.695564) (xy 206.227601 -123.715263) (xy 206.219552 -123.72467)
			(xy 206.213456 -123.731782) (xy 206.207106 -123.7488) (xy 206.207106 -123.834144) (xy 206.213456 -123.851162)
			(xy 206.219552 -123.858274) (xy 206.237166 -123.879229) (xy 206.266894 -123.925192) (xy 206.289742 -123.974935)
			(xy 206.305241 -124.027433) (xy 206.313073 -124.081609) (xy 206.313076 -124.136348) (xy 206.30525 -124.190525)
			(xy 206.289757 -124.243026) (xy 206.266914 -124.292771) (xy 206.237192 -124.338738) (xy 206.219552 -124.35967)
			(xy 206.213456 -124.366782) (xy 206.207106 -124.3838) (xy 206.207106 -124.469144) (xy 206.213456 -124.486162)
			(xy 206.219552 -124.493274) (xy 206.237185 -124.514211) (xy 206.266899 -124.560182) (xy 206.289737 -124.609928)
			(xy 206.30523 -124.662428) (xy 206.313058 -124.716603) (xy 206.313532 -124.743972) (xy 206.313046 -124.771223)
			(xy 206.30529 -124.825171) (xy 206.289935 -124.877466) (xy 206.267293 -124.927043) (xy 206.237827 -124.972893)
			(xy 206.202136 -125.014084) (xy 206.160945 -125.049775) (xy 206.115095 -125.079241) (xy 206.065518 -125.101883)
			(xy 206.013223 -125.117238) (xy 205.959275 -125.124994) (xy 205.904773 -125.124994) (xy 205.850825 -125.117238)
			(xy 205.79853 -125.101883) (xy 205.748953 -125.079241) (xy 205.703103 -125.049775) (xy 205.661912 -125.014084)
			(xy 205.626221 -124.972893) (xy 205.596755 -124.927043) (xy 205.574113 -124.877466) (xy 205.558758 -124.825171)
			(xy 205.551002 -124.771223) (xy 205.550516 -124.743972) (xy 202.696318 -124.743972) (xy 202.696318 -125.738128)
			(xy 217.592908 -125.738128) (xy 217.596979 -125.682506) (xy 217.609105 -125.628069) (xy 217.629028 -125.575978)
			(xy 217.656324 -125.527343) (xy 217.69041 -125.4832) (xy 217.730559 -125.444491) (xy 217.775917 -125.41204)
			(xy 217.825517 -125.386539) (xy 217.878301 -125.368532) (xy 217.933144 -125.358402) (xy 217.988878 -125.356365)
			(xy 218.044315 -125.362465) (xy 218.098272 -125.376571) (xy 218.149601 -125.398383) (xy 218.197207 -125.427437)
			(xy 218.240075 -125.463112) (xy 218.277292 -125.504649) (xy 218.308065 -125.551162) (xy 218.331737 -125.601659)
			(xy 218.347805 -125.655066) (xy 218.355925 -125.710242) (xy 218.356434 -125.738128) (xy 218.355925 -125.766014)
			(xy 218.347805 -125.82119) (xy 218.331737 -125.874597) (xy 218.308065 -125.925094) (xy 218.277292 -125.971607)
			(xy 218.240075 -126.013144) (xy 218.197207 -126.048819) (xy 218.149601 -126.077873) (xy 218.098272 -126.099685)
			(xy 218.044315 -126.113791) (xy 217.988878 -126.119891) (xy 217.933144 -126.117854) (xy 217.878301 -126.107724)
			(xy 217.825517 -126.089717) (xy 217.775917 -126.064216) (xy 217.730559 -126.031765) (xy 217.69041 -125.993056)
			(xy 217.656324 -125.948913) (xy 217.629028 -125.900278) (xy 217.609105 -125.848187) (xy 217.596979 -125.79375)
			(xy 217.592908 -125.738128) (xy 202.696318 -125.738128) (xy 202.696318 -128.697482) (xy 211.268308 -128.697482)
			(xy 211.272379 -128.64186) (xy 211.284505 -128.587423) (xy 211.304428 -128.535332) (xy 211.331724 -128.486697)
			(xy 211.36581 -128.442554) (xy 211.405959 -128.403845) (xy 211.451317 -128.371394) (xy 211.500917 -128.345893)
			(xy 211.553701 -128.327886) (xy 211.608544 -128.317756) (xy 211.664278 -128.315719) (xy 211.719715 -128.321819)
			(xy 211.773672 -128.335925) (xy 211.825001 -128.357737) (xy 211.872607 -128.386791) (xy 211.915475 -128.422466)
			(xy 211.952692 -128.464003) (xy 211.983465 -128.510516) (xy 212.007137 -128.561013) (xy 212.023205 -128.61442)
			(xy 212.031325 -128.669596) (xy 212.031834 -128.697482) (xy 212.031325 -128.725368) (xy 212.023205 -128.780544)
			(xy 212.007137 -128.833951) (xy 211.983465 -128.884448) (xy 211.952692 -128.930961) (xy 211.915475 -128.972498)
			(xy 211.872607 -129.008173) (xy 211.825001 -129.037227) (xy 211.773672 -129.059039) (xy 211.719715 -129.073145)
			(xy 211.664278 -129.079245) (xy 211.608544 -129.077208) (xy 211.553701 -129.067078) (xy 211.500917 -129.049071)
			(xy 211.451317 -129.02357) (xy 211.405959 -128.991119) (xy 211.36581 -128.95241) (xy 211.331724 -128.908267)
			(xy 211.304428 -128.859632) (xy 211.284505 -128.807541) (xy 211.272379 -128.753104) (xy 211.268308 -128.697482)
			(xy 202.696318 -128.697482) (xy 202.696318 -129.905252) (xy 202.696784 -129.915126) (xy 202.704238 -129.933414)
			(xy 202.710796 -129.940812) (xy 202.71105 -129.941066) (xy 202.969622 -130.199638) (xy 202.97013 -130.200146)
			(xy 202.97751 -130.206733) (xy 202.995809 -130.214192) (xy 203.00569 -130.214624)
		)
		(stroke
			(width 0)
			(type solid)
		)
		(fill yes)
		(layer "B.Cu")
		(net "P3V3_NIC3")
	)
	(gr_poly
		(pts
			(xy 277.330154 -296.619676) (xy 277.330662 -296.619676) (xy 277.338178 -296.61807) (xy 277.351858 -296.611086)
			(xy 277.357586 -296.60596) (xy 277.48738 -296.476166) (xy 277.491446 -296.471843) (xy 277.4976 -296.461698)
			(xy 277.499572 -296.4561) (xy 277.50008 -296.454576) (xy 277.502112 -296.443146) (xy 277.502112 -291.472112)
			(xy 277.502533 -291.462041) (xy 277.510246 -291.443435) (xy 277.517098 -291.436044) (xy 277.752556 -291.200586)
			(xy 277.759953 -291.193739) (xy 277.778553 -291.186012) (xy 277.788624 -291.1856) (xy 279.14346 -291.1856)
			(xy 279.151842 -291.184838) (xy 279.159452 -291.183333) (xy 279.173301 -291.176361) (xy 279.17902 -291.171122)
			(xy 279.31237 -291.037772) (xy 279.317571 -291.032024) (xy 279.324556 -291.018193) (xy 279.326086 -291.010594)
			(xy 279.326848 -291.002212) (xy 279.326848 -290.078668) (xy 279.326427 -290.069859) (xy 279.320382 -290.053305)
			(xy 279.309115 -290.039755) (xy 279.301702 -290.03498) (xy 279.237694 -289.99815) (xy 279.231818 -289.995003)
			(xy 279.218956 -289.99152) (xy 279.212294 -289.991292) (xy 279.199086 -289.991292) (xy 279.187148 -289.998404)
			(xy 279.162427 -290.012317) (xy 279.109274 -290.032117) (xy 279.053456 -290.042203) (xy 279.025096 -290.042854)
			(xy 279.01773 -290.042854) (xy 278.993108 -290.041843) (xy 278.944604 -290.03316) (xy 278.898019 -290.017097)
			(xy 278.854471 -289.994039) (xy 278.815002 -289.964538) (xy 278.780557 -289.929301) (xy 278.75196 -289.889172)
			(xy 278.729898 -289.845111) (xy 278.714898 -289.798174) (xy 278.707319 -289.749484) (xy 278.706834 -289.724846)
			(xy 278.707296 -289.699854) (xy 278.715109 -289.650484) (xy 278.730551 -289.602944) (xy 278.753241 -289.558406)
			(xy 278.782619 -289.517967) (xy 278.817964 -289.482622) (xy 278.858403 -289.453243) (xy 278.90294 -289.430552)
			(xy 278.95048 -289.41511) (xy 278.99985 -289.407296) (xy 279.024842 -289.406838) (xy 279.025096 -289.406838)
			(xy 279.05346 -289.407456) (xy 279.109288 -289.41752) (xy 279.162439 -289.437346) (xy 279.187148 -289.451288)
			(xy 279.19299 -289.454844) (xy 279.206198 -289.4584) (xy 279.212548 -289.4584) (xy 279.219214 -289.458199)
			(xy 279.232081 -289.454713) (xy 279.237948 -289.451542) (xy 279.269444 -289.433508) (xy 279.301194 -289.41522)
			(xy 279.306041 -289.412271) (xy 279.314375 -289.404575) (xy 279.317704 -289.39998) (xy 279.320244 -289.395662)
			(xy 279.321768 -289.392614) (xy 279.32409 -289.387451) (xy 279.326651 -289.376427) (xy 279.326848 -289.37077)
			(xy 279.326848 -289.128708) (xy 279.326433 -289.119896) (xy 279.320397 -289.103332) (xy 279.309133 -289.089771)
			(xy 279.301702 -289.08502) (xy 279.237694 -289.04819) (xy 279.231817 -289.045046) (xy 279.218955 -289.041567)
			(xy 279.212294 -289.041332) (xy 279.199086 -289.041332) (xy 279.187148 -289.048444) (xy 279.162428 -289.06236)
			(xy 279.109275 -289.082164) (xy 279.053457 -289.092251) (xy 279.025096 -289.092894) (xy 279.01773 -289.092894)
			(xy 278.993107 -289.091883) (xy 278.9446 -289.0832) (xy 278.898013 -289.067138) (xy 278.854462 -289.044081)
			(xy 278.814989 -289.014581) (xy 278.78054 -288.979344) (xy 278.75194 -288.939215) (xy 278.729872 -288.895154)
			(xy 278.714867 -288.848216) (xy 278.707282 -288.799525) (xy 278.706834 -288.774886) (xy 278.707264 -288.751304)
			(xy 278.714235 -288.704658) (xy 278.728023 -288.659554) (xy 278.748323 -288.616982) (xy 278.774691 -288.577878)
			(xy 278.806548 -288.543098) (xy 278.843194 -288.513408) (xy 278.863298 -288.501074) (xy 278.872966 -288.493743)
			(xy 278.884655 -288.472524) (xy 278.88565 -288.460434) (xy 278.88565 -288.140902) (xy 278.88565 -288.139378)
			(xy 278.884594 -288.127307) (xy 278.872912 -288.106118) (xy 278.863298 -288.098738) (xy 278.843195 -288.0864)
			(xy 278.806537 -288.05672) (xy 278.774671 -288.021945) (xy 278.748297 -287.982841) (xy 278.727995 -287.940267)
			(xy 278.714211 -287.89516) (xy 278.707248 -287.84851) (xy 278.706834 -287.824926) (xy 278.707297 -287.799935)
			(xy 278.715113 -287.750567) (xy 278.730557 -287.70303) (xy 278.753247 -287.658495) (xy 278.782627 -287.618058)
			(xy 278.817971 -287.582716) (xy 278.858409 -287.553339) (xy 278.902945 -287.53065) (xy 278.950483 -287.515209)
			(xy 278.999851 -287.507396) (xy 279.024842 -287.506918) (xy 279.025096 -287.506918) (xy 279.05346 -287.507536)
			(xy 279.109289 -287.517599) (xy 279.16244 -287.537424) (xy 279.187148 -287.551368) (xy 279.19299 -287.554924)
			(xy 279.206198 -287.55848) (xy 279.212548 -287.55848) (xy 279.219214 -287.55828) (xy 279.232084 -287.554799)
			(xy 279.237948 -287.551622) (xy 279.269444 -287.533588) (xy 279.301194 -287.5153) (xy 279.30604 -287.51235)
			(xy 279.314371 -287.504652) (xy 279.317704 -287.50006) (xy 279.320244 -287.495742) (xy 279.321768 -287.492694)
			(xy 279.324088 -287.487531) (xy 279.326645 -287.476507) (xy 279.326848 -287.47085) (xy 279.326848 -287.228788)
			(xy 279.32643 -287.219977) (xy 279.32039 -287.203419) (xy 279.309124 -287.189863) (xy 279.301702 -287.1851)
			(xy 279.237694 -287.14827) (xy 279.231818 -287.145122) (xy 279.218956 -287.141638) (xy 279.212294 -287.141412)
			(xy 279.199086 -287.141412) (xy 279.187148 -287.148524) (xy 279.162428 -287.162441) (xy 279.109275 -287.182246)
			(xy 279.053457 -287.192334) (xy 279.025096 -287.192974) (xy 279.01773 -287.192974) (xy 278.993108 -287.191963)
			(xy 278.944602 -287.18328) (xy 278.898016 -287.167217) (xy 278.854467 -287.14416) (xy 278.814996 -287.114659)
			(xy 278.780548 -287.079423) (xy 278.75195 -287.039294) (xy 278.729885 -286.995233) (xy 278.714882 -286.948295)
			(xy 278.7073 -286.899605) (xy 278.706834 -286.874966) (xy 278.707301 -286.849978) (xy 278.715125 -286.800617)
			(xy 278.730574 -286.753089) (xy 278.753268 -286.708562) (xy 278.782648 -286.668133) (xy 278.817991 -286.632799)
			(xy 278.858427 -286.603428) (xy 278.902959 -286.580745) (xy 278.950491 -286.565307) (xy 278.999854 -286.557496)
			(xy 279.024842 -286.556958) (xy 279.025096 -286.556958) (xy 279.05346 -286.557576) (xy 279.109288 -286.56764)
			(xy 279.162438 -286.587468) (xy 279.187148 -286.601408) (xy 279.19299 -286.604964) (xy 279.206198 -286.60852)
			(xy 279.212548 -286.60852) (xy 279.219214 -286.608319) (xy 279.232081 -286.604834) (xy 279.237948 -286.601662)
			(xy 279.269444 -286.583628) (xy 279.301194 -286.56534) (xy 279.306042 -286.562392) (xy 279.314378 -286.554697)
			(xy 279.317704 -286.5501) (xy 279.320244 -286.545782) (xy 279.321768 -286.542734) (xy 279.324092 -286.537572)
			(xy 279.326657 -286.526548) (xy 279.326848 -286.52089) (xy 279.326848 -286.278574) (xy 279.326428 -286.269765)
			(xy 279.320385 -286.253209) (xy 279.309118 -286.239657) (xy 279.301702 -286.234886) (xy 279.237694 -286.198056)
			(xy 279.231818 -286.194908) (xy 279.218956 -286.191425) (xy 279.212294 -286.191198) (xy 279.199086 -286.191198)
			(xy 279.187148 -286.19831) (xy 279.162427 -286.212223) (xy 279.109274 -286.232023) (xy 279.053456 -286.242108)
			(xy 279.025096 -286.24276) (xy 279.01773 -286.24276) (xy 278.993108 -286.241749) (xy 278.944603 -286.233066)
			(xy 278.898018 -286.217003) (xy 278.85447 -286.193945) (xy 278.815 -286.164445) (xy 278.780554 -286.129208)
			(xy 278.751957 -286.089078) (xy 278.729894 -286.045017) (xy 278.714893 -285.99808) (xy 278.707313 -285.94939)
			(xy 278.706834 -285.924752) (xy 278.707328 -285.899766) (xy 278.715153 -285.850412) (xy 278.730601 -285.802889)
			(xy 278.753294 -285.758367) (xy 278.782672 -285.717944) (xy 278.818012 -285.682614) (xy 278.858444 -285.653247)
			(xy 278.902972 -285.630567) (xy 278.950499 -285.615131) (xy 278.999856 -285.607321) (xy 279.024842 -285.606744)
			(xy 279.025096 -285.606744) (xy 279.05346 -285.607362) (xy 279.109288 -285.617426) (xy 279.162439 -285.637253)
			(xy 279.187148 -285.651194) (xy 279.19299 -285.65475) (xy 279.206198 -285.658306) (xy 279.212548 -285.658306)
			(xy 279.219214 -285.658105) (xy 279.232081 -285.654619) (xy 279.237948 -285.651448) (xy 279.269444 -285.633414)
			(xy 279.301194 -285.615126) (xy 279.306042 -285.612177) (xy 279.314376 -285.604481) (xy 279.317704 -285.599886)
			(xy 279.320244 -285.595568) (xy 279.321768 -285.59252) (xy 279.32409 -285.587357) (xy 279.326653 -285.576334)
			(xy 279.326848 -285.570676) (xy 279.326848 -285.378398) (xy 279.327273 -285.368329) (xy 279.334993 -285.34973)
			(xy 279.341834 -285.34233) (xy 279.371044 -285.31312) (xy 279.376242 -285.307371) (xy 279.383216 -285.293538)
			(xy 279.38476 -285.285942) (xy 279.385522 -285.27756) (xy 279.385522 -285.17469) (xy 279.385522 -285.171134)
			(xy 279.38441 -285.161434) (xy 279.375913 -285.143873) (xy 279.361498 -285.130728) (xy 279.352502 -285.126938)
			(xy 279.348946 -285.125922) (xy 279.340974 -285.123832) (xy 279.324511 -285.124347) (xy 279.316688 -285.126938)
			(xy 279.309322 -285.129732) (xy 279.296876 -285.139892) (xy 279.29205 -285.147258) (xy 279.277264 -285.169205)
			(xy 279.24161 -285.208307) (xy 279.199974 -285.240966) (xy 279.153506 -285.26628) (xy 279.103488 -285.283552)
			(xy 279.0513 -285.292304) (xy 279.024842 -285.2928) (xy 278.999849 -285.292339) (xy 278.950478 -285.284525)
			(xy 278.902938 -285.269084) (xy 278.858398 -285.246395) (xy 278.817957 -285.217018) (xy 278.78261 -285.181675)
			(xy 278.753227 -285.141237) (xy 278.730532 -285.096701) (xy 278.715085 -285.049163) (xy 278.707265 -284.999793)
			(xy 278.707265 -284.949807) (xy 278.715085 -284.900437) (xy 278.730532 -284.852899) (xy 278.753227 -284.808363)
			(xy 278.78261 -284.767925) (xy 278.817957 -284.732582) (xy 278.858398 -284.703205) (xy 278.902938 -284.680516)
			(xy 278.950478 -284.665075) (xy 278.999849 -284.657261) (xy 279.024842 -284.656784) (xy 279.025096 -284.656784)
			(xy 279.050607 -284.657284) (xy 279.100976 -284.665427) (xy 279.149394 -284.681519) (xy 279.194616 -284.705148)
			(xy 279.215342 -284.72003) (xy 279.221692 -284.724856) (xy 279.252172 -284.73527) (xy 279.258024 -284.735163)
			(xy 279.26944 -284.732592) (xy 279.274778 -284.73019) (xy 279.35682 -284.690312) (xy 279.364694 -284.68574)
			(xy 279.372752 -284.679233) (xy 279.383244 -284.6614) (xy 279.385014 -284.651196) (xy 279.385522 -284.644592)
			(xy 279.385522 -284.355032) (xy 279.385014 -284.348428) (xy 279.383231 -284.338229) (xy 279.372737 -284.320405)
			(xy 279.364694 -284.313884) (xy 279.35682 -284.309312) (xy 279.274778 -284.269434) (xy 279.269439 -284.267035)
			(xy 279.258024 -284.264463) (xy 279.252172 -284.264354) (xy 279.221438 -284.275022) (xy 279.217882 -284.277562)
			(xy 279.196952 -284.292902) (xy 279.151147 -284.317285) (xy 279.10199 -284.333905) (xy 279.050787 -284.342322)
			(xy 279.024842 -284.34284) (xy 278.999846 -284.342379) (xy 278.950469 -284.334564) (xy 278.902922 -284.319121)
			(xy 278.858377 -284.296429) (xy 278.817931 -284.267048) (xy 278.782579 -284.231701) (xy 278.753193 -284.191258)
			(xy 278.730495 -284.146716) (xy 278.715046 -284.099172) (xy 278.707225 -284.049796) (xy 278.707225 -283.999804)
			(xy 278.715046 -283.950428) (xy 278.730495 -283.902884) (xy 278.753193 -283.858342) (xy 278.782579 -283.817899)
			(xy 278.817931 -283.782552) (xy 278.858377 -283.753171) (xy 278.902922 -283.730479) (xy 278.950469 -283.715036)
			(xy 278.999846 -283.707221) (xy 279.024842 -283.706824) (xy 279.050899 -283.707348) (xy 279.102317 -283.715843)
			(xy 279.151665 -283.732598) (xy 279.197626 -283.757166) (xy 279.238971 -283.788892) (xy 279.274598 -283.826927)
			(xy 279.28951 -283.848302) (xy 279.292304 -283.85262) (xy 279.298306 -283.861027) (xy 279.315442 -283.872524)
			(xy 279.335732 -283.876289) (xy 279.345898 -283.874464) (xy 279.357582 -283.871162) (xy 279.365456 -283.868622)
			(xy 279.375362 -283.855414) (xy 279.380034 -283.848674) (xy 279.385224 -283.833128) (xy 279.385522 -283.824934)
			(xy 279.385522 -283.758132) (xy 279.38518 -283.749439) (xy 279.379341 -283.733065) (xy 279.374092 -283.726128)
			(xy 279.37079 -283.722318) (xy 279.056084 -283.407612) (xy 279.052608 -283.404319) (xy 279.044688 -283.39894)
			(xy 279.040336 -283.396944) (xy 279.031192 -283.39288) (xy 279.021032 -283.39288) (xy 278.994965 -283.392039)
			(xy 278.943619 -283.382908) (xy 278.894451 -283.365523) (xy 278.848777 -283.340352) (xy 278.807821 -283.308067)
			(xy 278.772679 -283.269534) (xy 278.744293 -283.225785) (xy 278.723423 -283.177992) (xy 278.716486 -283.15285)
			(xy 278.713438 -283.144214) (xy 278.709016 -283.135553) (xy 278.69496 -283.12214) (xy 278.676925 -283.114913)
			(xy 278.66721 -283.114496) (xy 278.432514 -283.114496) (xy 278.4228 -283.114924) (xy 278.404763 -283.122143)
			(xy 278.390704 -283.135552) (xy 278.386286 -283.144214) (xy 278.383238 -283.15285) (xy 278.376708 -283.176746)
			(xy 278.357265 -283.222307) (xy 278.330994 -283.264303) (xy 278.298529 -283.301718) (xy 278.260657 -283.333648)
			(xy 278.218292 -283.35932) (xy 278.17246 -283.378114) (xy 278.124268 -283.389575) (xy 278.074882 -283.393427)
			(xy 278.025496 -283.389575) (xy 277.977304 -283.378114) (xy 277.931472 -283.35932) (xy 277.889107 -283.333648)
			(xy 277.851235 -283.301718) (xy 277.81877 -283.264303) (xy 277.792499 -283.222307) (xy 277.773056 -283.176746)
			(xy 277.766526 -283.15285) (xy 277.763478 -283.144214) (xy 277.759053 -283.13556) (xy 277.744994 -283.122163)
			(xy 277.726961 -283.114957) (xy 277.71725 -283.114496) (xy 277.482554 -283.114496) (xy 277.472846 -283.114934)
			(xy 277.454827 -283.122167) (xy 277.440786 -283.135578) (xy 277.436326 -283.144214) (xy 277.433278 -283.15285)
			(xy 277.426748 -283.176746) (xy 277.407305 -283.222307) (xy 277.381034 -283.264303) (xy 277.348569 -283.301718)
			(xy 277.310697 -283.333648) (xy 277.268332 -283.35932) (xy 277.2225 -283.378114) (xy 277.174308 -283.389575)
			(xy 277.124922 -283.393427) (xy 277.075536 -283.389575) (xy 277.027344 -283.378114) (xy 276.981512 -283.35932)
			(xy 276.939147 -283.333648) (xy 276.901275 -283.301718) (xy 276.86881 -283.264303) (xy 276.842539 -283.222307)
			(xy 276.823096 -283.176746) (xy 276.816566 -283.15285) (xy 276.813518 -283.144214) (xy 276.809095 -283.135556)
			(xy 276.795038 -283.122148) (xy 276.777003 -283.114928) (xy 276.76729 -283.114496) (xy 276.514814 -283.114496)
			(xy 276.487382 -283.135832) (xy 276.483064 -283.15285) (xy 276.476534 -283.176746) (xy 276.457091 -283.222307)
			(xy 276.43082 -283.264303) (xy 276.398355 -283.301718) (xy 276.360483 -283.333648) (xy 276.318118 -283.35932)
			(xy 276.272286 -283.378114) (xy 276.224094 -283.389575) (xy 276.174708 -283.393427) (xy 276.125322 -283.389575)
			(xy 276.07713 -283.378114) (xy 276.031298 -283.35932) (xy 275.988933 -283.333648) (xy 275.951061 -283.301718)
			(xy 275.918596 -283.264303) (xy 275.892325 -283.222307) (xy 275.872882 -283.176746) (xy 275.866352 -283.15285)
			(xy 275.862034 -283.135832) (xy 275.834602 -283.114496) (xy 275.580094 -283.114496) (xy 275.57514 -283.114615)
			(xy 275.565419 -283.116535) (xy 275.56079 -283.118306) (xy 275.554186 -283.1211) (xy 275.550814 -283.122408)
			(xy 275.543803 -283.124186) (xy 275.540216 -283.124656) (xy 275.533104 -283.15285) (xy 275.526153 -283.178236)
			(xy 275.505021 -283.226438) (xy 275.476239 -283.270502) (xy 275.440593 -283.309225) (xy 275.399057 -283.341548)
			(xy 275.352765 -283.366588) (xy 275.30298 -283.383664) (xy 275.251064 -283.392307) (xy 275.224748 -283.39288)
			(xy 275.199015 -283.39238) (xy 275.148223 -283.384083) (xy 275.09943 -283.367715) (xy 275.05391 -283.343703)
			(xy 275.012851 -283.312673) (xy 274.977326 -283.275436) (xy 274.948261 -283.232964) (xy 274.926415 -283.186365)
			(xy 274.918932 -283.16174) (xy 274.918932 -283.161486) (xy 274.91536 -283.151122) (xy 274.901034 -283.134557)
			(xy 274.881114 -283.125457) (xy 274.870164 -283.12491) (xy 274.629626 -283.12491) (xy 274.621343 -283.125224)
			(xy 274.605652 -283.130529) (xy 274.598892 -283.135324) (xy 274.592034 -283.140404) (xy 274.58289 -283.153612)
			(xy 274.580604 -283.161994) (xy 274.573097 -283.186607) (xy 274.551249 -283.233195) (xy 274.522183 -283.275655)
			(xy 274.486658 -283.31288) (xy 274.445602 -283.343899) (xy 274.400087 -283.3679) (xy 274.3513 -283.384257)
			(xy 274.300516 -283.392544) (xy 274.24906 -283.392544) (xy 274.198276 -283.384257) (xy 274.149489 -283.3679)
			(xy 274.103974 -283.343899) (xy 274.062918 -283.31288) (xy 274.027393 -283.275655) (xy 273.998327 -283.233195)
			(xy 273.976479 -283.186607) (xy 273.968972 -283.161994) (xy 273.966686 -283.153612) (xy 273.957542 -283.140404)
			(xy 273.950684 -283.135324) (xy 273.943903 -283.130566) (xy 273.928226 -283.125244) (xy 273.91995 -283.12491)
			(xy 273.679666 -283.12491) (xy 273.671387 -283.125233) (xy 273.655707 -283.130554) (xy 273.648932 -283.135324)
			(xy 273.642074 -283.140404) (xy 273.63293 -283.153612) (xy 273.630644 -283.161994) (xy 273.623118 -283.186589)
			(xy 273.601241 -283.233138) (xy 273.572158 -283.275559) (xy 273.536628 -283.312748) (xy 273.495577 -283.343734)
			(xy 273.450074 -283.367711) (xy 273.401307 -283.384052) (xy 273.350544 -283.392333) (xy 273.324828 -283.39288)
			(xy 273.298378 -283.392358) (xy 273.246205 -283.38361) (xy 273.196199 -283.366352) (xy 273.149737 -283.341059)
			(xy 273.1081 -283.308428) (xy 273.089878 -283.289248) (xy 273.089116 -283.288232) (xy 273.087846 -283.286962)
			(xy 273.080421 -283.280444) (xy 273.062101 -283.273097) (xy 273.042362 -283.273162) (xy 273.024091 -283.280632)
			(xy 273.016726 -283.287216) (xy 273.016472 -283.28747) (xy 272.981674 -283.322268) (xy 272.97815 -283.325997)
			(xy 272.972514 -283.334568) (xy 272.970498 -283.339286) (xy 272.966942 -283.347922) (xy 272.966942 -284.049821)
			(xy 274.90723 -284.049821) (xy 274.90723 -283.999843) (xy 274.915049 -283.95048) (xy 274.930493 -283.902948)
			(xy 274.953183 -283.858416) (xy 274.982559 -283.817983) (xy 275.017899 -283.782643) (xy 275.058332 -283.753267)
			(xy 275.102864 -283.730577) (xy 275.150396 -283.715133) (xy 275.199759 -283.707314) (xy 275.249737 -283.707314)
			(xy 275.2991 -283.715133) (xy 275.346632 -283.730577) (xy 275.391164 -283.753267) (xy 275.431597 -283.782643)
			(xy 275.466937 -283.817983) (xy 275.496313 -283.858416) (xy 275.519003 -283.902948) (xy 275.534447 -283.95048)
			(xy 275.542266 -283.999843) (xy 275.542756 -284.024832) (xy 275.542266 -284.049821) (xy 275.85719 -284.049821)
			(xy 275.85719 -283.999843) (xy 275.865009 -283.95048) (xy 275.880453 -283.902948) (xy 275.903143 -283.858416)
			(xy 275.932519 -283.817983) (xy 275.967859 -283.782643) (xy 276.008292 -283.753267) (xy 276.052824 -283.730577)
			(xy 276.100356 -283.715133) (xy 276.149719 -283.707314) (xy 276.199697 -283.707314) (xy 276.24906 -283.715133)
			(xy 276.296592 -283.730577) (xy 276.341124 -283.753267) (xy 276.381557 -283.782643) (xy 276.416897 -283.817983)
			(xy 276.446273 -283.858416) (xy 276.468963 -283.902948) (xy 276.484407 -283.95048) (xy 276.492226 -283.999843)
			(xy 276.492716 -284.024832) (xy 276.492226 -284.049821) (xy 276.807404 -284.049821) (xy 276.807404 -283.999843)
			(xy 276.815223 -283.95048) (xy 276.830667 -283.902948) (xy 276.853357 -283.858416) (xy 276.882733 -283.817983)
			(xy 276.918073 -283.782643) (xy 276.958506 -283.753267) (xy 277.003038 -283.730577) (xy 277.05057 -283.715133)
			(xy 277.099933 -283.707314) (xy 277.149911 -283.707314) (xy 277.199274 -283.715133) (xy 277.246806 -283.730577)
			(xy 277.291338 -283.753267) (xy 277.331771 -283.782643) (xy 277.367111 -283.817983) (xy 277.396487 -283.858416)
			(xy 277.419177 -283.902948) (xy 277.434621 -283.95048) (xy 277.44244 -283.999843) (xy 277.44293 -284.024832)
			(xy 277.44244 -284.049821) (xy 277.757364 -284.049821) (xy 277.757364 -283.999843) (xy 277.765183 -283.95048)
			(xy 277.780627 -283.902948) (xy 277.803317 -283.858416) (xy 277.832693 -283.817983) (xy 277.868033 -283.782643)
			(xy 277.908466 -283.753267) (xy 277.952998 -283.730577) (xy 278.00053 -283.715133) (xy 278.049893 -283.707314)
			(xy 278.099871 -283.707314) (xy 278.149234 -283.715133) (xy 278.196766 -283.730577) (xy 278.241298 -283.753267)
			(xy 278.281731 -283.782643) (xy 278.317071 -283.817983) (xy 278.346447 -283.858416) (xy 278.369137 -283.902948)
			(xy 278.384581 -283.95048) (xy 278.3924 -283.999843) (xy 278.39289 -284.024832) (xy 278.3924 -284.049821)
			(xy 278.384581 -284.099184) (xy 278.369137 -284.146716) (xy 278.346447 -284.191248) (xy 278.317071 -284.231681)
			(xy 278.281731 -284.267021) (xy 278.241298 -284.296397) (xy 278.196766 -284.319087) (xy 278.149234 -284.334531)
			(xy 278.099871 -284.34235) (xy 278.049893 -284.34235) (xy 278.00053 -284.334531) (xy 277.952998 -284.319087)
			(xy 277.908466 -284.296397) (xy 277.868033 -284.267021) (xy 277.832693 -284.231681) (xy 277.803317 -284.191248)
			(xy 277.780627 -284.146716) (xy 277.765183 -284.099184) (xy 277.757364 -284.049821) (xy 277.44244 -284.049821)
			(xy 277.434621 -284.099184) (xy 277.419177 -284.146716) (xy 277.396487 -284.191248) (xy 277.367111 -284.231681)
			(xy 277.331771 -284.267021) (xy 277.291338 -284.296397) (xy 277.246806 -284.319087) (xy 277.199274 -284.334531)
			(xy 277.149911 -284.34235) (xy 277.099933 -284.34235) (xy 277.05057 -284.334531) (xy 277.003038 -284.319087)
			(xy 276.958506 -284.296397) (xy 276.918073 -284.267021) (xy 276.882733 -284.231681) (xy 276.853357 -284.191248)
			(xy 276.830667 -284.146716) (xy 276.815223 -284.099184) (xy 276.807404 -284.049821) (xy 276.492226 -284.049821)
			(xy 276.484407 -284.099184) (xy 276.468963 -284.146716) (xy 276.446273 -284.191248) (xy 276.416897 -284.231681)
			(xy 276.381557 -284.267021) (xy 276.341124 -284.296397) (xy 276.296592 -284.319087) (xy 276.24906 -284.334531)
			(xy 276.199697 -284.34235) (xy 276.149719 -284.34235) (xy 276.100356 -284.334531) (xy 276.052824 -284.319087)
			(xy 276.008292 -284.296397) (xy 275.967859 -284.267021) (xy 275.932519 -284.231681) (xy 275.903143 -284.191248)
			(xy 275.880453 -284.146716) (xy 275.865009 -284.099184) (xy 275.85719 -284.049821) (xy 275.542266 -284.049821)
			(xy 275.534447 -284.099184) (xy 275.519003 -284.146716) (xy 275.496313 -284.191248) (xy 275.466937 -284.231681)
			(xy 275.431597 -284.267021) (xy 275.391164 -284.296397) (xy 275.346632 -284.319087) (xy 275.2991 -284.334531)
			(xy 275.249737 -284.34235) (xy 275.199759 -284.34235) (xy 275.150396 -284.334531) (xy 275.102864 -284.319087)
			(xy 275.058332 -284.296397) (xy 275.017899 -284.267021) (xy 274.982559 -284.231681) (xy 274.953183 -284.191248)
			(xy 274.930493 -284.146716) (xy 274.915049 -284.099184) (xy 274.90723 -284.049821) (xy 272.966942 -284.049821)
			(xy 272.966942 -285.0769) (xy 272.967704 -285.085282) (xy 272.969216 -285.092888) (xy 272.9762 -285.106725)
			(xy 272.98142 -285.11246) (xy 273.084798 -285.215838) (xy 273.091314 -285.221919) (xy 273.10745 -285.229459)
			(xy 273.116294 -285.23057) (xy 273.125946 -285.23057) (xy 273.156426 -285.228792) (xy 273.75612 -285.228792)
			(xy 273.763698 -285.228481) (xy 273.778168 -285.22397) (xy 273.784568 -285.219902) (xy 273.803714 -285.207377)
			(xy 273.844941 -285.187542) (xy 273.888663 -285.174072) (xy 273.933905 -285.167267) (xy 273.95678 -285.166816)
			(xy 274.79244 -285.166816) (xy 274.792948 -285.166816) (xy 274.809458 -285.16707) (xy 274.821396 -285.167832)
			(xy 274.84324 -285.158434) (xy 274.911312 -285.07817) (xy 274.9169 -285.055564) (xy 274.91563 -285.04896)
			(xy 274.911494 -285.030697) (xy 274.907038 -284.993515) (xy 274.90674 -284.974792) (xy 274.907231 -284.949808)
			(xy 274.915049 -284.900454) (xy 274.93049 -284.852931) (xy 274.953176 -284.808408) (xy 274.982547 -284.767983)
			(xy 275.017881 -284.732649) (xy 275.058306 -284.703278) (xy 275.102828 -284.680591) (xy 275.150351 -284.665149)
			(xy 275.199705 -284.657331) (xy 275.249674 -284.657329) (xy 275.299028 -284.665144) (xy 275.346552 -284.680583)
			(xy 275.391076 -284.703266) (xy 275.431503 -284.732635) (xy 275.466839 -284.767966) (xy 275.496213 -284.80839)
			(xy 275.518901 -284.852911) (xy 275.534346 -284.900433) (xy 275.542168 -284.949786) (xy 275.542172 -284.999755)
			(xy 275.542168 -284.999781) (xy 276.807404 -284.999781) (xy 276.807404 -284.949803) (xy 276.815223 -284.90044)
			(xy 276.830667 -284.852908) (xy 276.853357 -284.808376) (xy 276.882733 -284.767943) (xy 276.918073 -284.732603)
			(xy 276.958506 -284.703227) (xy 277.003038 -284.680537) (xy 277.05057 -284.665093) (xy 277.099933 -284.657274)
			(xy 277.149911 -284.657274) (xy 277.199274 -284.665093) (xy 277.246806 -284.680537) (xy 277.291338 -284.703227)
			(xy 277.331771 -284.732603) (xy 277.367111 -284.767943) (xy 277.396487 -284.808376) (xy 277.419177 -284.852908)
			(xy 277.434621 -284.90044) (xy 277.44244 -284.949803) (xy 277.44293 -284.974792) (xy 277.44244 -284.999781)
			(xy 277.757364 -284.999781) (xy 277.757364 -284.949803) (xy 277.765183 -284.90044) (xy 277.780627 -284.852908)
			(xy 277.803317 -284.808376) (xy 277.832693 -284.767943) (xy 277.868033 -284.732603) (xy 277.908466 -284.703227)
			(xy 277.952998 -284.680537) (xy 278.00053 -284.665093) (xy 278.049893 -284.657274) (xy 278.099871 -284.657274)
			(xy 278.149234 -284.665093) (xy 278.196766 -284.680537) (xy 278.241298 -284.703227) (xy 278.281731 -284.732603)
			(xy 278.317071 -284.767943) (xy 278.346447 -284.808376) (xy 278.369137 -284.852908) (xy 278.384581 -284.90044)
			(xy 278.3924 -284.949803) (xy 278.39289 -284.974792) (xy 278.3924 -284.999781) (xy 278.384581 -285.049144)
			(xy 278.369137 -285.096676) (xy 278.346447 -285.141208) (xy 278.317071 -285.181641) (xy 278.281731 -285.216981)
			(xy 278.241298 -285.246357) (xy 278.196766 -285.269047) (xy 278.149234 -285.284491) (xy 278.099871 -285.29231)
			(xy 278.049893 -285.29231) (xy 278.00053 -285.284491) (xy 277.952998 -285.269047) (xy 277.908466 -285.246357)
			(xy 277.868033 -285.216981) (xy 277.832693 -285.181641) (xy 277.803317 -285.141208) (xy 277.780627 -285.096676)
			(xy 277.765183 -285.049144) (xy 277.757364 -284.999781) (xy 277.44244 -284.999781) (xy 277.434621 -285.049144)
			(xy 277.419177 -285.096676) (xy 277.396487 -285.141208) (xy 277.367111 -285.181641) (xy 277.331771 -285.216981)
			(xy 277.291338 -285.246357) (xy 277.246806 -285.269047) (xy 277.199274 -285.284491) (xy 277.149911 -285.29231)
			(xy 277.099933 -285.29231) (xy 277.05057 -285.284491) (xy 277.003038 -285.269047) (xy 276.958506 -285.246357)
			(xy 276.918073 -285.216981) (xy 276.882733 -285.181641) (xy 276.853357 -285.141208) (xy 276.830667 -285.096676)
			(xy 276.815223 -285.049144) (xy 276.807404 -284.999781) (xy 275.542168 -284.999781) (xy 275.53436 -285.04911)
			(xy 275.518924 -285.096635) (xy 275.496243 -285.14116) (xy 275.466877 -285.181589) (xy 275.431548 -285.216927)
			(xy 275.391126 -285.246303) (xy 275.346606 -285.268994) (xy 275.299085 -285.284442) (xy 275.249732 -285.292266)
			(xy 275.224748 -285.2928) (xy 275.212569 -285.292667) (xy 275.188285 -285.290759) (xy 275.176234 -285.28899)
			(xy 275.166074 -285.28772) (xy 275.157692 -285.291276) (xy 275.153628 -285.2928) (xy 275.147961 -285.29524)
			(xy 275.137944 -285.302438) (xy 275.133816 -285.307024) (xy 275.097748 -285.353252) (xy 275.091052 -285.362773)
			(xy 275.086295 -285.385531) (xy 275.088604 -285.39694) (xy 275.092674 -285.414252) (xy 275.097256 -285.449521)
			(xy 275.097748 -285.467298) (xy 275.111464 -285.481014) (xy 275.118312 -285.488412) (xy 275.126047 -285.50701)
			(xy 275.12645 -285.517082) (xy 275.12645 -285.949741) (xy 276.807404 -285.949741) (xy 276.807404 -285.899763)
			(xy 276.815223 -285.8504) (xy 276.830667 -285.802868) (xy 276.853357 -285.758336) (xy 276.882733 -285.717903)
			(xy 276.918073 -285.682563) (xy 276.958506 -285.653187) (xy 277.003038 -285.630497) (xy 277.05057 -285.615053)
			(xy 277.099933 -285.607234) (xy 277.149911 -285.607234) (xy 277.199274 -285.615053) (xy 277.246806 -285.630497)
			(xy 277.291338 -285.653187) (xy 277.331771 -285.682563) (xy 277.367111 -285.717903) (xy 277.396487 -285.758336)
			(xy 277.419177 -285.802868) (xy 277.434621 -285.8504) (xy 277.44244 -285.899763) (xy 277.44293 -285.924752)
			(xy 277.44244 -285.949741) (xy 277.757364 -285.949741) (xy 277.757364 -285.899763) (xy 277.765183 -285.8504)
			(xy 277.780627 -285.802868) (xy 277.803317 -285.758336) (xy 277.832693 -285.717903) (xy 277.868033 -285.682563)
			(xy 277.908466 -285.653187) (xy 277.952998 -285.630497) (xy 278.00053 -285.615053) (xy 278.049893 -285.607234)
			(xy 278.099871 -285.607234) (xy 278.149234 -285.615053) (xy 278.196766 -285.630497) (xy 278.241298 -285.653187)
			(xy 278.281731 -285.682563) (xy 278.317071 -285.717903) (xy 278.346447 -285.758336) (xy 278.369137 -285.802868)
			(xy 278.384581 -285.8504) (xy 278.3924 -285.899763) (xy 278.39289 -285.924752) (xy 278.3924 -285.949741)
			(xy 278.384581 -285.999104) (xy 278.369137 -286.046636) (xy 278.346447 -286.091168) (xy 278.317071 -286.131601)
			(xy 278.281731 -286.166941) (xy 278.241298 -286.196317) (xy 278.196766 -286.219007) (xy 278.149234 -286.234451)
			(xy 278.099871 -286.24227) (xy 278.049893 -286.24227) (xy 278.00053 -286.234451) (xy 277.952998 -286.219007)
			(xy 277.908466 -286.196317) (xy 277.868033 -286.166941) (xy 277.832693 -286.131601) (xy 277.803317 -286.091168)
			(xy 277.780627 -286.046636) (xy 277.765183 -285.999104) (xy 277.757364 -285.949741) (xy 277.44244 -285.949741)
			(xy 277.434621 -285.999104) (xy 277.419177 -286.046636) (xy 277.396487 -286.091168) (xy 277.367111 -286.131601)
			(xy 277.331771 -286.166941) (xy 277.291338 -286.196317) (xy 277.246806 -286.219007) (xy 277.199274 -286.234451)
			(xy 277.149911 -286.24227) (xy 277.099933 -286.24227) (xy 277.05057 -286.234451) (xy 277.003038 -286.219007)
			(xy 276.958506 -286.196317) (xy 276.918073 -286.166941) (xy 276.882733 -286.131601) (xy 276.853357 -286.091168)
			(xy 276.830667 -286.046636) (xy 276.815223 -285.999104) (xy 276.807404 -285.949741) (xy 275.12645 -285.949741)
			(xy 275.12645 -286.442404) (xy 275.126807 -286.45166) (xy 275.133325 -286.468983) (xy 275.13915 -286.476186)
			(xy 275.191728 -286.529018) (xy 275.195338 -286.532509) (xy 275.203656 -286.538137) (xy 275.208238 -286.540194)
			(xy 275.21662 -286.54375) (xy 275.227288 -286.544004) (xy 275.253147 -286.544698) (xy 275.304181 -286.553136)
			(xy 275.353279 -286.569417) (xy 275.399243 -286.593143) (xy 275.440953 -286.623736) (xy 275.47739 -286.660451)
			(xy 275.507668 -286.702391) (xy 275.531046 -286.748533) (xy 275.546955 -286.797752) (xy 275.555006 -286.848849)
			(xy 275.555456 -286.874712) (xy 275.555023 -286.898757) (xy 275.554885 -286.899701) (xy 275.85719 -286.899701)
			(xy 275.85719 -286.849723) (xy 275.865009 -286.80036) (xy 275.880453 -286.752828) (xy 275.903143 -286.708296)
			(xy 275.932519 -286.667863) (xy 275.967859 -286.632523) (xy 276.008292 -286.603147) (xy 276.052824 -286.580457)
			(xy 276.100356 -286.565013) (xy 276.149719 -286.557194) (xy 276.199697 -286.557194) (xy 276.24906 -286.565013)
			(xy 276.296592 -286.580457) (xy 276.341124 -286.603147) (xy 276.381557 -286.632523) (xy 276.416897 -286.667863)
			(xy 276.446273 -286.708296) (xy 276.468963 -286.752828) (xy 276.484407 -286.80036) (xy 276.492226 -286.849723)
			(xy 276.492716 -286.874712) (xy 276.492226 -286.899701) (xy 276.492186 -286.899955) (xy 276.807404 -286.899955)
			(xy 276.807404 -286.849977) (xy 276.815223 -286.800614) (xy 276.830667 -286.753082) (xy 276.853357 -286.70855)
			(xy 276.882733 -286.668117) (xy 276.918073 -286.632777) (xy 276.958506 -286.603401) (xy 277.003038 -286.580711)
			(xy 277.05057 -286.565267) (xy 277.099933 -286.557448) (xy 277.149911 -286.557448) (xy 277.199274 -286.565267)
			(xy 277.246806 -286.580711) (xy 277.291338 -286.603401) (xy 277.331771 -286.632777) (xy 277.367111 -286.668117)
			(xy 277.396487 -286.70855) (xy 277.419177 -286.753082) (xy 277.434621 -286.800614) (xy 277.44244 -286.849977)
			(xy 277.44293 -286.874966) (xy 277.44244 -286.899955) (xy 277.757364 -286.899955) (xy 277.757364 -286.849977)
			(xy 277.765183 -286.800614) (xy 277.780627 -286.753082) (xy 277.803317 -286.70855) (xy 277.832693 -286.668117)
			(xy 277.868033 -286.632777) (xy 277.908466 -286.603401) (xy 277.952998 -286.580711) (xy 278.00053 -286.565267)
			(xy 278.049893 -286.557448) (xy 278.099871 -286.557448) (xy 278.149234 -286.565267) (xy 278.196766 -286.580711)
			(xy 278.241298 -286.603401) (xy 278.281731 -286.632777) (xy 278.317071 -286.668117) (xy 278.346447 -286.70855)
			(xy 278.369137 -286.753082) (xy 278.384581 -286.800614) (xy 278.3924 -286.849977) (xy 278.39289 -286.874966)
			(xy 278.3924 -286.899955) (xy 278.384581 -286.949318) (xy 278.369137 -286.99685) (xy 278.346447 -287.041382)
			(xy 278.317071 -287.081815) (xy 278.281731 -287.117155) (xy 278.241298 -287.146531) (xy 278.196766 -287.169221)
			(xy 278.149234 -287.184665) (xy 278.099871 -287.192484) (xy 278.049893 -287.192484) (xy 278.00053 -287.184665)
			(xy 277.952998 -287.169221) (xy 277.908466 -287.146531) (xy 277.868033 -287.117155) (xy 277.832693 -287.081815)
			(xy 277.803317 -287.041382) (xy 277.780627 -286.99685) (xy 277.765183 -286.949318) (xy 277.757364 -286.899955)
			(xy 277.44244 -286.899955) (xy 277.434621 -286.949318) (xy 277.419177 -286.99685) (xy 277.396487 -287.041382)
			(xy 277.367111 -287.081815) (xy 277.331771 -287.117155) (xy 277.291338 -287.146531) (xy 277.246806 -287.169221)
			(xy 277.199274 -287.184665) (xy 277.149911 -287.192484) (xy 277.099933 -287.192484) (xy 277.05057 -287.184665)
			(xy 277.003038 -287.169221) (xy 276.958506 -287.146531) (xy 276.918073 -287.117155) (xy 276.882733 -287.081815)
			(xy 276.853357 -287.041382) (xy 276.830667 -286.99685) (xy 276.815223 -286.949318) (xy 276.807404 -286.899955)
			(xy 276.492186 -286.899955) (xy 276.484407 -286.949064) (xy 276.468963 -286.996596) (xy 276.446273 -287.041128)
			(xy 276.416897 -287.081561) (xy 276.381557 -287.116901) (xy 276.341124 -287.146277) (xy 276.296592 -287.168967)
			(xy 276.24906 -287.184411) (xy 276.199697 -287.19223) (xy 276.149719 -287.19223) (xy 276.100356 -287.184411)
			(xy 276.052824 -287.168967) (xy 276.008292 -287.146277) (xy 275.967859 -287.116901) (xy 275.932519 -287.081561)
			(xy 275.903143 -287.041128) (xy 275.880453 -286.996596) (xy 275.865009 -286.949064) (xy 275.85719 -286.899701)
			(xy 275.554885 -286.899701) (xy 275.548055 -286.946338) (xy 275.534268 -286.992409) (xy 275.513953 -287.035996)
			(xy 275.5011 -287.056322) (xy 275.496782 -287.062926) (xy 275.49475 -287.06953) (xy 275.493783 -287.073071)
			(xy 275.492758 -287.080338) (xy 275.492718 -287.084008) (xy 275.492718 -287.177734) (xy 275.492289 -287.187802)
			(xy 275.484568 -287.206399) (xy 275.477732 -287.213802) (xy 274.841619 -287.849915) (xy 276.807404 -287.849915)
			(xy 276.807404 -287.799937) (xy 276.815223 -287.750574) (xy 276.830667 -287.703042) (xy 276.853357 -287.65851)
			(xy 276.882733 -287.618077) (xy 276.918073 -287.582737) (xy 276.958506 -287.553361) (xy 277.003038 -287.530671)
			(xy 277.05057 -287.515227) (xy 277.099933 -287.507408) (xy 277.149911 -287.507408) (xy 277.199274 -287.515227)
			(xy 277.246806 -287.530671) (xy 277.291338 -287.553361) (xy 277.331771 -287.582737) (xy 277.367111 -287.618077)
			(xy 277.396487 -287.65851) (xy 277.419177 -287.703042) (xy 277.434621 -287.750574) (xy 277.44244 -287.799937)
			(xy 277.44293 -287.824926) (xy 277.44244 -287.849915) (xy 277.757364 -287.849915) (xy 277.757364 -287.799937)
			(xy 277.765183 -287.750574) (xy 277.780627 -287.703042) (xy 277.803317 -287.65851) (xy 277.832693 -287.618077)
			(xy 277.868033 -287.582737) (xy 277.908466 -287.553361) (xy 277.952998 -287.530671) (xy 278.00053 -287.515227)
			(xy 278.049893 -287.507408) (xy 278.099871 -287.507408) (xy 278.149234 -287.515227) (xy 278.196766 -287.530671)
			(xy 278.241298 -287.553361) (xy 278.281731 -287.582737) (xy 278.317071 -287.618077) (xy 278.346447 -287.65851)
			(xy 278.369137 -287.703042) (xy 278.384581 -287.750574) (xy 278.3924 -287.799937) (xy 278.39289 -287.824926)
			(xy 278.3924 -287.849915) (xy 278.384581 -287.899278) (xy 278.369137 -287.94681) (xy 278.346447 -287.991342)
			(xy 278.317071 -288.031775) (xy 278.281731 -288.067115) (xy 278.241298 -288.096491) (xy 278.196766 -288.119181)
			(xy 278.149234 -288.134625) (xy 278.099871 -288.142444) (xy 278.049893 -288.142444) (xy 278.00053 -288.134625)
			(xy 277.952998 -288.119181) (xy 277.908466 -288.096491) (xy 277.868033 -288.067115) (xy 277.832693 -288.031775)
			(xy 277.803317 -287.991342) (xy 277.780627 -287.94681) (xy 277.765183 -287.899278) (xy 277.757364 -287.849915)
			(xy 277.44244 -287.849915) (xy 277.434621 -287.899278) (xy 277.419177 -287.94681) (xy 277.396487 -287.991342)
			(xy 277.367111 -288.031775) (xy 277.331771 -288.067115) (xy 277.291338 -288.096491) (xy 277.246806 -288.119181)
			(xy 277.199274 -288.134625) (xy 277.149911 -288.142444) (xy 277.099933 -288.142444) (xy 277.05057 -288.134625)
			(xy 277.003038 -288.119181) (xy 276.958506 -288.096491) (xy 276.918073 -288.067115) (xy 276.882733 -288.031775)
			(xy 276.853357 -287.991342) (xy 276.830667 -287.94681) (xy 276.815223 -287.899278) (xy 276.807404 -287.849915)
			(xy 274.841619 -287.849915) (xy 274.55114 -288.140394) (xy 274.543739 -288.147232) (xy 274.52514 -288.154945)
			(xy 274.515072 -288.15538) (xy 273.511518 -288.15538) (xy 273.501506 -288.155864) (xy 273.483005 -288.16352)
			(xy 273.468841 -288.177673) (xy 273.461172 -288.196169) (xy 273.460718 -288.20618) (xy 273.460718 -288.55924)
			(xy 273.46148 -288.567622) (xy 273.462997 -288.575226) (xy 273.469986 -288.589057) (xy 273.475196 -288.5948)
			(xy 273.556222 -288.675826) (xy 273.561972 -288.681023) (xy 273.575804 -288.688002) (xy 273.5834 -288.689542)
			(xy 273.591782 -288.690304) (xy 273.931634 -288.690304) (xy 273.939277 -288.690041) (xy 273.953878 -288.685511)
			(xy 273.960336 -288.681414) (xy 273.966432 -288.677096) (xy 273.97583 -288.665412) (xy 273.978878 -288.658046)
			(xy 273.988661 -288.634659) (xy 274.01455 -288.591077) (xy 274.04702 -288.552149) (xy 274.08525 -288.518862)
			(xy 274.128274 -288.492056) (xy 274.175004 -288.472409) (xy 274.224257 -288.460419) (xy 274.274788 -288.456388)
			(xy 274.325319 -288.460419) (xy 274.374572 -288.472409) (xy 274.421302 -288.492056) (xy 274.464326 -288.518862)
			(xy 274.502556 -288.552149) (xy 274.535026 -288.591077) (xy 274.560915 -288.634659) (xy 274.570698 -288.658046)
			(xy 274.570698 -288.6583) (xy 274.573783 -288.665277) (xy 274.583342 -288.677156) (xy 274.589494 -288.681668)
			(xy 274.59559 -288.685986) (xy 274.610068 -288.690304) (xy 274.867878 -288.690304) (xy 274.876426 -288.689981)
			(xy 274.892571 -288.684359) (xy 274.905965 -288.673735) (xy 274.910804 -288.666682) (xy 274.914868 -288.6583)
			(xy 274.91563 -288.656522) (xy 274.924953 -288.63336) (xy 274.94955 -288.589912) (xy 274.98039 -288.550648)
			(xy 275.016774 -288.516458) (xy 275.057877 -288.488115) (xy 275.102768 -288.466262) (xy 275.150431 -288.451395)
			(xy 275.199785 -288.443849) (xy 275.224748 -288.443416) (xy 276.174708 -288.443416) (xy 276.200716 -288.443927)
			(xy 276.252093 -288.452065) (xy 276.301563 -288.46814) (xy 276.34791 -288.491756) (xy 276.389992 -288.522332)
			(xy 276.426773 -288.559114) (xy 276.457348 -288.601196) (xy 276.480963 -288.647544) (xy 276.497037 -288.697015)
			(xy 276.505174 -288.748392) (xy 276.505174 -288.799875) (xy 276.807404 -288.799875) (xy 276.807404 -288.749897)
			(xy 276.815223 -288.700534) (xy 276.830667 -288.653002) (xy 276.853357 -288.60847) (xy 276.882733 -288.568037)
			(xy 276.918073 -288.532697) (xy 276.958506 -288.503321) (xy 277.003038 -288.480631) (xy 277.05057 -288.465187)
			(xy 277.099933 -288.457368) (xy 277.149911 -288.457368) (xy 277.199274 -288.465187) (xy 277.246806 -288.480631)
			(xy 277.291338 -288.503321) (xy 277.331771 -288.532697) (xy 277.367111 -288.568037) (xy 277.396487 -288.60847)
			(xy 277.419177 -288.653002) (xy 277.434621 -288.700534) (xy 277.44244 -288.749897) (xy 277.44293 -288.774886)
			(xy 277.44244 -288.799875) (xy 277.757364 -288.799875) (xy 277.757364 -288.749897) (xy 277.765183 -288.700534)
			(xy 277.780627 -288.653002) (xy 277.803317 -288.60847) (xy 277.832693 -288.568037) (xy 277.868033 -288.532697)
			(xy 277.908466 -288.503321) (xy 277.952998 -288.480631) (xy 278.00053 -288.465187) (xy 278.049893 -288.457368)
			(xy 278.099871 -288.457368) (xy 278.149234 -288.465187) (xy 278.196766 -288.480631) (xy 278.241298 -288.503321)
			(xy 278.281731 -288.532697) (xy 278.317071 -288.568037) (xy 278.346447 -288.60847) (xy 278.369137 -288.653002)
			(xy 278.384581 -288.700534) (xy 278.3924 -288.749897) (xy 278.39289 -288.774886) (xy 278.3924 -288.799875)
			(xy 278.384581 -288.849238) (xy 278.369137 -288.89677) (xy 278.346447 -288.941302) (xy 278.317071 -288.981735)
			(xy 278.281731 -289.017075) (xy 278.241298 -289.046451) (xy 278.196766 -289.069141) (xy 278.149234 -289.084585)
			(xy 278.099871 -289.092404) (xy 278.049893 -289.092404) (xy 278.00053 -289.084585) (xy 277.952998 -289.069141)
			(xy 277.908466 -289.046451) (xy 277.868033 -289.017075) (xy 277.832693 -288.981735) (xy 277.803317 -288.941302)
			(xy 277.780627 -288.89677) (xy 277.765183 -288.849238) (xy 277.757364 -288.799875) (xy 277.44244 -288.799875)
			(xy 277.434621 -288.849238) (xy 277.419177 -288.89677) (xy 277.396487 -288.941302) (xy 277.367111 -288.981735)
			(xy 277.331771 -289.017075) (xy 277.291338 -289.046451) (xy 277.246806 -289.069141) (xy 277.199274 -289.084585)
			(xy 277.149911 -289.092404) (xy 277.099933 -289.092404) (xy 277.05057 -289.084585) (xy 277.003038 -289.069141)
			(xy 276.958506 -289.046451) (xy 276.918073 -289.017075) (xy 276.882733 -288.981735) (xy 276.853357 -288.941302)
			(xy 276.830667 -288.89677) (xy 276.815223 -288.849238) (xy 276.807404 -288.799875) (xy 276.505174 -288.799875)
			(xy 276.505174 -288.800408) (xy 276.497037 -288.851785) (xy 276.480963 -288.901256) (xy 276.457348 -288.947604)
			(xy 276.426773 -288.989686) (xy 276.389992 -289.026468) (xy 276.34791 -289.057044) (xy 276.301563 -289.08066)
			(xy 276.252093 -289.096735) (xy 276.200716 -289.104873) (xy 276.174708 -289.10534) (xy 275.543518 -289.10534)
			(xy 275.533497 -289.105757) (xy 275.514981 -289.113425) (xy 275.500813 -289.1276) (xy 275.493153 -289.146119)
			(xy 275.492718 -289.15614) (xy 275.492718 -289.515296) (xy 275.492939 -289.522336) (xy 275.496802 -289.535875)
			(xy 275.500338 -289.541966) (xy 275.51339 -289.56239) (xy 275.534018 -289.606251) (xy 275.548018 -289.652654)
			(xy 275.555092 -289.700604) (xy 275.555086 -289.749073) (xy 275.554973 -289.749835) (xy 275.85719 -289.749835)
			(xy 275.85719 -289.699857) (xy 275.865009 -289.650494) (xy 275.880453 -289.602962) (xy 275.903143 -289.55843)
			(xy 275.932519 -289.517997) (xy 275.967859 -289.482657) (xy 276.008292 -289.453281) (xy 276.052824 -289.430591)
			(xy 276.100356 -289.415147) (xy 276.149719 -289.407328) (xy 276.199697 -289.407328) (xy 276.24906 -289.415147)
			(xy 276.296592 -289.430591) (xy 276.341124 -289.453281) (xy 276.381557 -289.482657) (xy 276.416897 -289.517997)
			(xy 276.446273 -289.55843) (xy 276.468963 -289.602962) (xy 276.484407 -289.650494) (xy 276.492226 -289.699857)
			(xy 276.492716 -289.724846) (xy 276.492226 -289.749835) (xy 276.807404 -289.749835) (xy 276.807404 -289.699857)
			(xy 276.815223 -289.650494) (xy 276.830667 -289.602962) (xy 276.853357 -289.55843) (xy 276.882733 -289.517997)
			(xy 276.918073 -289.482657) (xy 276.958506 -289.453281) (xy 277.003038 -289.430591) (xy 277.05057 -289.415147)
			(xy 277.099933 -289.407328) (xy 277.149911 -289.407328) (xy 277.199274 -289.415147) (xy 277.246806 -289.430591)
			(xy 277.291338 -289.453281) (xy 277.331771 -289.482657) (xy 277.367111 -289.517997) (xy 277.396487 -289.55843)
			(xy 277.419177 -289.602962) (xy 277.434621 -289.650494) (xy 277.44244 -289.699857) (xy 277.44293 -289.724846)
			(xy 277.44244 -289.749835) (xy 277.434621 -289.799198) (xy 277.419177 -289.84673) (xy 277.396487 -289.891262)
			(xy 277.367111 -289.931695) (xy 277.331771 -289.967035) (xy 277.291338 -289.996411) (xy 277.246806 -290.019101)
			(xy 277.199274 -290.034545) (xy 277.149911 -290.042364) (xy 277.099933 -290.042364) (xy 277.05057 -290.034545)
			(xy 277.003038 -290.019101) (xy 276.958506 -289.996411) (xy 276.918073 -289.967035) (xy 276.882733 -289.931695)
			(xy 276.853357 -289.891262) (xy 276.830667 -289.84673) (xy 276.815223 -289.799198) (xy 276.807404 -289.749835)
			(xy 276.492226 -289.749835) (xy 276.484407 -289.799198) (xy 276.468963 -289.84673) (xy 276.446273 -289.891262)
			(xy 276.416897 -289.931695) (xy 276.381557 -289.967035) (xy 276.341124 -289.996411) (xy 276.296592 -290.019101)
			(xy 276.24906 -290.034545) (xy 276.199697 -290.042364) (xy 276.149719 -290.042364) (xy 276.100356 -290.034545)
			(xy 276.052824 -290.019101) (xy 276.008292 -289.996411) (xy 275.967859 -289.967035) (xy 275.932519 -289.931695)
			(xy 275.903143 -289.891262) (xy 275.880453 -289.84673) (xy 275.865009 -289.799198) (xy 275.85719 -289.749835)
			(xy 275.554973 -289.749835) (xy 275.548001 -289.797021) (xy 275.53399 -289.843421) (xy 275.513352 -289.887277)
			(xy 275.500338 -289.907726) (xy 275.49683 -289.91383) (xy 275.492952 -289.92736) (xy 275.492718 -289.934396)
			(xy 275.492718 -290.465256) (xy 275.492947 -290.472293) (xy 275.496824 -290.485823) (xy 275.500338 -290.491926)
			(xy 275.513329 -290.512277) (xy 275.533905 -290.555953) (xy 275.547903 -290.602158) (xy 275.555026 -290.64991)
			(xy 275.555121 -290.698189) (xy 275.554888 -290.699795) (xy 275.85719 -290.699795) (xy 275.85719 -290.649817)
			(xy 275.865009 -290.600454) (xy 275.880453 -290.552922) (xy 275.903143 -290.50839) (xy 275.932519 -290.467957)
			(xy 275.967859 -290.432617) (xy 276.008292 -290.403241) (xy 276.052824 -290.380551) (xy 276.100356 -290.365107)
			(xy 276.149719 -290.357288) (xy 276.199697 -290.357288) (xy 276.24906 -290.365107) (xy 276.296592 -290.380551)
			(xy 276.341124 -290.403241) (xy 276.381557 -290.432617) (xy 276.416897 -290.467957) (xy 276.446273 -290.50839)
			(xy 276.468963 -290.552922) (xy 276.484407 -290.600454) (xy 276.492226 -290.649817) (xy 276.492716 -290.674806)
			(xy 277.756874 -290.674806) (xy 277.757295 -290.649568) (xy 277.765261 -290.599724) (xy 277.781008 -290.551766)
			(xy 277.80414 -290.506902) (xy 277.834076 -290.466261) (xy 277.870062 -290.430865) (xy 277.911193 -290.401604)
			(xy 277.956432 -290.379216) (xy 277.980394 -290.371276) (xy 278.009858 -290.362132) (xy 278.016208 -290.355528)
			(xy 278.016208 -290.07689) (xy 278.015764 -290.066098) (xy 278.006936 -290.046402) (xy 277.9908 -290.032069)
			(xy 277.980648 -290.028376) (xy 277.980394 -290.028376) (xy 277.95644 -290.02043) (xy 277.911223 -289.998019)
			(xy 277.870114 -289.968746) (xy 277.834146 -289.933347) (xy 277.804222 -289.892709) (xy 277.781094 -289.847855)
			(xy 277.765342 -289.79991) (xy 277.757362 -289.750079) (xy 277.756874 -289.724846) (xy 277.757364 -289.699857)
			(xy 277.765183 -289.650494) (xy 277.780627 -289.602962) (xy 277.803317 -289.55843) (xy 277.832693 -289.517997)
			(xy 277.868033 -289.482657) (xy 277.908466 -289.453281) (xy 277.952998 -289.430591) (xy 278.00053 -289.415147)
			(xy 278.049893 -289.407328) (xy 278.099871 -289.407328) (xy 278.149234 -289.415147) (xy 278.196766 -289.430591)
			(xy 278.241298 -289.453281) (xy 278.281731 -289.482657) (xy 278.317071 -289.517997) (xy 278.346447 -289.55843)
			(xy 278.369137 -289.602962) (xy 278.384581 -289.650494) (xy 278.3924 -289.699857) (xy 278.39289 -289.724846)
			(xy 278.392236 -289.754509) (xy 278.381237 -289.812805) (xy 278.371046 -289.84067) (xy 278.36749 -289.84956)
			(xy 278.36749 -289.859212) (xy 278.367978 -289.869219) (xy 278.37564 -289.887709) (xy 278.389792 -289.901861)
			(xy 278.408283 -289.909522) (xy 278.41829 -289.910012) (xy 278.435562 -289.910012) (xy 278.45058 -289.910525)
			(xy 278.479595 -289.918289) (xy 278.505612 -289.933299) (xy 278.526857 -289.954531) (xy 278.541883 -289.980538)
			(xy 278.549666 -290.009548) (xy 278.550116 -290.024566) (xy 278.550116 -290.455858) (xy 278.55037 -290.466526)
			(xy 278.549804 -290.491595) (xy 278.540468 -290.540855) (xy 278.522109 -290.58751) (xy 278.509222 -290.60902)
			(xy 278.501108 -290.621519) (xy 278.482522 -290.644814) (xy 278.472138 -290.655502) (xy 278.391112 -290.736528)
			(xy 278.384508 -290.747958) (xy 278.38273 -290.754308) (xy 278.38273 -290.754816) (xy 278.375622 -290.780021)
			(xy 278.354303 -290.82785) (xy 278.325442 -290.871543) (xy 278.289816 -290.909921) (xy 278.248387 -290.941948)
			(xy 278.202274 -290.966761) (xy 278.152721 -290.983689) (xy 278.101064 -290.992276) (xy 278.074882 -290.992814)
			(xy 278.049893 -290.992334) (xy 278.00053 -290.984513) (xy 277.952998 -290.969067) (xy 277.908467 -290.946376)
			(xy 277.868034 -290.916998) (xy 277.832694 -290.881657) (xy 277.803318 -290.841223) (xy 277.780628 -290.796691)
			(xy 277.765184 -290.749159) (xy 277.757365 -290.699795) (xy 277.756874 -290.674806) (xy 276.492716 -290.674806)
			(xy 276.492226 -290.699795) (xy 276.484407 -290.749158) (xy 276.468963 -290.79669) (xy 276.446273 -290.841222)
			(xy 276.416897 -290.881655) (xy 276.381557 -290.916995) (xy 276.341124 -290.946371) (xy 276.296592 -290.969061)
			(xy 276.24906 -290.984505) (xy 276.199697 -290.992324) (xy 276.149719 -290.992324) (xy 276.100356 -290.984505)
			(xy 276.052824 -290.969061) (xy 276.008292 -290.946371) (xy 275.967859 -290.916995) (xy 275.932519 -290.881655)
			(xy 275.903143 -290.841222) (xy 275.880453 -290.79669) (xy 275.865009 -290.749158) (xy 275.85719 -290.699795)
			(xy 275.554888 -290.699795) (xy 275.548186 -290.745968) (xy 275.53437 -290.792229) (xy 275.513967 -290.835985)
			(xy 275.5011 -290.856416) (xy 275.496782 -290.86302) (xy 275.49475 -290.869624) (xy 275.493782 -290.873164)
			(xy 275.492757 -290.880432) (xy 275.492718 -290.884102) (xy 275.492718 -290.907978) (xy 275.493734 -290.91763)
			(xy 275.495359 -290.924875) (xy 275.502196 -290.938048) (xy 275.507196 -290.943538) (xy 275.798534 -291.234876)
			(xy 275.805915 -291.241459) (xy 275.824214 -291.248913) (xy 275.834094 -291.249354) (xy 275.847556 -291.249354)
			(xy 275.853906 -291.2491) (xy 276.404578 -291.2491) (xy 276.410928 -291.249354) (xy 276.555454 -291.249354)
			(xy 276.565519 -291.249789) (xy 276.584104 -291.257523) (xy 276.591522 -291.26434) (xy 276.749256 -291.422074)
			(xy 276.756096 -291.429474) (xy 276.76381 -291.448073) (xy 276.764242 -291.458142) (xy 276.764242 -296.548556)
			(xy 276.765258 -296.558208) (xy 276.766881 -296.565454) (xy 276.773717 -296.578629) (xy 276.77872 -296.584116)
			(xy 276.800564 -296.60596) (xy 276.806067 -296.610939) (xy 276.819237 -296.617765) (xy 276.826472 -296.619422)
			(xy 276.836124 -296.620438) (xy 277.322026 -296.620438)
		)
		(stroke
			(width 0)
			(type solid)
		)
		(fill yes)
		(layer "B.Cu")
		(net "P1V8_PEX")
	)
	(gr_poly
		(pts
			(xy 393.430252 -296.619676) (xy 393.43076 -296.619676) (xy 393.438109 -296.618135) (xy 393.451537 -296.611426)
			(xy 393.457176 -296.606468) (xy 393.590272 -296.473118) (xy 393.59342 -296.469183) (xy 393.598276 -296.460354)
			(xy 393.599924 -296.455592) (xy 393.600178 -296.454576) (xy 393.601956 -296.444416) (xy 393.601956 -291.62375)
			(xy 393.60221 -291.620194) (xy 393.60221 -291.472112) (xy 393.602631 -291.462041) (xy 393.610344 -291.443434)
			(xy 393.617196 -291.436044) (xy 393.852654 -291.200586) (xy 393.860051 -291.193739) (xy 393.878651 -291.186011)
			(xy 393.888722 -291.1856) (xy 395.243558 -291.1856) (xy 395.25194 -291.184838) (xy 395.259543 -291.18332)
			(xy 395.273372 -291.176329) (xy 395.279118 -291.171122) (xy 395.412468 -291.037772) (xy 395.41767 -291.032024)
			(xy 395.424655 -291.018193) (xy 395.426184 -291.010594) (xy 395.426946 -291.002212) (xy 395.426946 -290.078922)
			(xy 395.426609 -290.070032) (xy 395.420522 -290.053325) (xy 395.409077 -290.039717) (xy 395.401546 -290.03498)
			(xy 395.365478 -290.014152) (xy 395.338046 -289.99815) (xy 395.33211 -289.994984) (xy 395.319116 -289.991512)
			(xy 395.312392 -289.991292) (xy 395.299184 -289.991292) (xy 395.286992 -289.998658) (xy 395.262307 -290.01253)
			(xy 395.209232 -290.032248) (xy 395.153504 -290.042246) (xy 395.125194 -290.042854) (xy 395.117828 -290.042854)
			(xy 395.093207 -290.041843) (xy 395.044702 -290.033159) (xy 394.998118 -290.017096) (xy 394.95457 -289.994038)
			(xy 394.915101 -289.964538) (xy 394.880656 -289.929301) (xy 394.85206 -289.889171) (xy 394.829998 -289.845111)
			(xy 394.814997 -289.798173) (xy 394.807419 -289.749484) (xy 394.806932 -289.724846) (xy 394.807394 -289.699854)
			(xy 394.815207 -289.650483) (xy 394.830649 -289.602944) (xy 394.853339 -289.558406) (xy 394.882717 -289.517966)
			(xy 394.918062 -289.482621) (xy 394.9585 -289.453242) (xy 395.003038 -289.430551) (xy 395.050578 -289.415108)
			(xy 395.099948 -289.407294) (xy 395.12494 -289.406838) (xy 395.125194 -289.406838) (xy 395.153501 -289.40746)
			(xy 395.209222 -289.417478) (xy 395.262297 -289.437182) (xy 395.286992 -289.451034) (xy 395.293046 -289.454469)
			(xy 395.30645 -289.458207) (xy 395.313408 -289.4584) (xy 395.326108 -289.4584) (xy 395.35735 -289.440366)
			(xy 395.398498 -289.416744) (xy 395.402054 -289.414712) (xy 395.407463 -289.411265) (xy 395.416471 -289.402139)
			(xy 395.419834 -289.396678) (xy 395.42339 -289.389566) (xy 395.426692 -289.37712) (xy 395.426946 -289.37077)
			(xy 395.426946 -289.128962) (xy 395.426615 -289.120068) (xy 395.420537 -289.103351) (xy 395.409095 -289.089732)
			(xy 395.401546 -289.08502) (xy 395.365478 -289.064192) (xy 395.338046 -289.04819) (xy 395.33211 -289.045022)
			(xy 395.319117 -289.041548) (xy 395.312392 -289.041332) (xy 395.299184 -289.041332) (xy 395.286992 -289.048698)
			(xy 395.262306 -289.062569) (xy 395.209232 -289.082284) (xy 395.153503 -289.092281) (xy 395.125194 -289.092894)
			(xy 395.117828 -289.092894) (xy 395.093205 -289.091883) (xy 395.044698 -289.0832) (xy 394.998112 -289.067137)
			(xy 394.954561 -289.04408) (xy 394.915088 -289.01458) (xy 394.88064 -288.979344) (xy 394.852039 -288.939215)
			(xy 394.829972 -288.895154) (xy 394.814966 -288.848216) (xy 394.807382 -288.799525) (xy 394.806932 -288.774886)
			(xy 394.807498 -288.747585) (xy 394.816824 -288.693784) (xy 394.835201 -288.642367) (xy 394.862089 -288.594843)
			(xy 394.896696 -288.552609) (xy 394.938008 -288.516904) (xy 394.96111 -288.502344) (xy 394.968398 -288.497535)
			(xy 394.979466 -288.484045) (xy 394.985394 -288.467633) (xy 394.985748 -288.45891) (xy 394.985748 -288.140902)
			(xy 394.985399 -288.13217) (xy 394.979523 -288.115726) (xy 394.96843 -288.102241) (xy 394.96111 -288.097468)
			(xy 394.938004 -288.082917) (xy 394.896701 -288.047205) (xy 394.862101 -288.004967) (xy 394.835219 -287.957442)
			(xy 394.816846 -287.906025) (xy 394.80752 -287.852226) (xy 394.806932 -287.824926) (xy 394.807395 -287.799935)
			(xy 394.815211 -287.750567) (xy 394.830655 -287.70303) (xy 394.853345 -287.658495) (xy 394.882725 -287.618058)
			(xy 394.918068 -287.582715) (xy 394.958506 -287.553338) (xy 395.003043 -287.530649) (xy 395.05058 -287.515208)
			(xy 395.099949 -287.507394) (xy 395.12494 -287.506918) (xy 395.125194 -287.506918) (xy 395.153501 -287.507541)
			(xy 395.209221 -287.517561) (xy 395.262293 -287.53727) (xy 395.286992 -287.551114) (xy 395.293048 -287.554545)
			(xy 395.306451 -287.558276) (xy 395.313408 -287.55848) (xy 395.326108 -287.55848) (xy 395.35735 -287.540446)
			(xy 395.398498 -287.516824) (xy 395.402054 -287.514792) (xy 395.407462 -287.511344) (xy 395.416466 -287.502216)
			(xy 395.419834 -287.496758) (xy 395.42339 -287.489646) (xy 395.426692 -287.4772) (xy 395.426946 -287.47085)
			(xy 395.426946 -287.229042) (xy 395.426612 -287.22015) (xy 395.420529 -287.203438) (xy 395.409086 -287.189825)
			(xy 395.401546 -287.1851) (xy 395.365478 -287.164272) (xy 395.338046 -287.14827) (xy 395.33211 -287.145103)
			(xy 395.319117 -287.14163) (xy 395.312392 -287.141412) (xy 395.299184 -287.141412) (xy 395.286992 -287.148778)
			(xy 395.262307 -287.162649) (xy 395.209232 -287.182366) (xy 395.153504 -287.192364) (xy 395.125194 -287.192974)
			(xy 395.117828 -287.192974) (xy 395.093206 -287.191963) (xy 395.0447 -287.18328) (xy 394.998115 -287.167217)
			(xy 394.954565 -287.144159) (xy 394.915095 -287.114659) (xy 394.880648 -287.079422) (xy 394.85205 -287.039293)
			(xy 394.829985 -286.995232) (xy 394.814982 -286.948295) (xy 394.8074 -286.899605) (xy 394.806932 -286.874966)
			(xy 394.807399 -286.849978) (xy 394.815223 -286.800617) (xy 394.830672 -286.753088) (xy 394.853366 -286.708561)
			(xy 394.882746 -286.668133) (xy 394.918089 -286.632798) (xy 394.958524 -286.603427) (xy 395.003057 -286.580743)
			(xy 395.050589 -286.565306) (xy 395.099952 -286.557494) (xy 395.12494 -286.556958) (xy 395.125194 -286.556958)
			(xy 395.153501 -286.55758) (xy 395.209222 -286.567599) (xy 395.262296 -286.587304) (xy 395.286992 -286.601154)
			(xy 395.293047 -286.604588) (xy 395.30645 -286.608324) (xy 395.313408 -286.60852) (xy 395.326108 -286.60852)
			(xy 395.35735 -286.590486) (xy 395.398498 -286.566864) (xy 395.402054 -286.564832) (xy 395.407464 -286.561386)
			(xy 395.416475 -286.552262) (xy 395.419834 -286.546798) (xy 395.42339 -286.539686) (xy 395.426692 -286.52724)
			(xy 395.426946 -286.52089) (xy 395.426946 -286.278828) (xy 395.42661 -286.269937) (xy 395.420524 -286.253229)
			(xy 395.40908 -286.23962) (xy 395.401546 -286.234886) (xy 395.365478 -286.214058) (xy 395.338046 -286.198056)
			(xy 395.33211 -286.19489) (xy 395.319117 -286.191418) (xy 395.312392 -286.191198) (xy 395.299184 -286.191198)
			(xy 395.286992 -286.198564) (xy 395.262307 -286.212436) (xy 395.209232 -286.232153) (xy 395.153504 -286.242151)
			(xy 395.125194 -286.24276) (xy 395.117828 -286.24276) (xy 395.093206 -286.241749) (xy 395.044701 -286.233065)
			(xy 394.998117 -286.217002) (xy 394.954569 -286.193945) (xy 394.915099 -286.164444) (xy 394.880653 -286.129207)
			(xy 394.852057 -286.089078) (xy 394.829994 -286.045017) (xy 394.814993 -285.99808) (xy 394.807413 -285.94939)
			(xy 394.806932 -285.924752) (xy 394.807426 -285.899766) (xy 394.815251 -285.850412) (xy 394.830699 -285.802888)
			(xy 394.853392 -285.758367) (xy 394.88277 -285.717943) (xy 394.91811 -285.682613) (xy 394.958542 -285.653246)
			(xy 395.00307 -285.630566) (xy 395.050597 -285.61513) (xy 395.099954 -285.607319) (xy 395.12494 -285.606744)
			(xy 395.125194 -285.606744) (xy 395.153501 -285.607366) (xy 395.209222 -285.617384) (xy 395.262297 -285.637089)
			(xy 395.286992 -285.65094) (xy 395.293046 -285.654375) (xy 395.30645 -285.658112) (xy 395.313408 -285.658306)
			(xy 395.326108 -285.658306) (xy 395.35735 -285.640272) (xy 395.398498 -285.61665) (xy 395.402054 -285.614618)
			(xy 395.407464 -285.611172) (xy 395.416472 -285.602046) (xy 395.419834 -285.596584) (xy 395.42339 -285.589472)
			(xy 395.426692 -285.577026) (xy 395.426946 -285.570676) (xy 395.426946 -285.378398) (xy 395.427371 -285.368329)
			(xy 395.435091 -285.349729) (xy 395.441932 -285.34233) (xy 395.471142 -285.31312) (xy 395.47634 -285.307371)
			(xy 395.483314 -285.293538) (xy 395.484858 -285.285942) (xy 395.48562 -285.27756) (xy 395.48562 -285.17469)
			(xy 395.48562 -285.171134) (xy 395.484508 -285.161434) (xy 395.476011 -285.143874) (xy 395.461596 -285.130729)
			(xy 395.4526 -285.126938) (xy 395.449044 -285.125922) (xy 395.441072 -285.123832) (xy 395.42461 -285.124348)
			(xy 395.416786 -285.126938) (xy 395.40942 -285.129732) (xy 395.396974 -285.139892) (xy 395.392148 -285.147258)
			(xy 395.392148 -285.147512) (xy 395.377341 -285.169428) (xy 395.34166 -285.208466) (xy 395.300014 -285.241064)
			(xy 395.25355 -285.266325) (xy 395.203547 -285.283554) (xy 395.151384 -285.292275) (xy 395.12494 -285.2928)
			(xy 395.099947 -285.292339) (xy 395.050577 -285.284525) (xy 395.003036 -285.269083) (xy 394.958497 -285.246394)
			(xy 394.918056 -285.217017) (xy 394.882709 -285.181674) (xy 394.853327 -285.141237) (xy 394.830632 -285.096701)
			(xy 394.815185 -285.049162) (xy 394.807365 -284.999793) (xy 394.807365 -284.949807) (xy 394.815185 -284.900438)
			(xy 394.830632 -284.852899) (xy 394.853327 -284.808363) (xy 394.882709 -284.767926) (xy 394.918056 -284.732583)
			(xy 394.958497 -284.703206) (xy 395.003036 -284.680517) (xy 395.050577 -284.665075) (xy 395.099947 -284.657261)
			(xy 395.12494 -284.656784) (xy 395.125194 -284.656784) (xy 395.150705 -284.657284) (xy 395.201074 -284.665426)
			(xy 395.249492 -284.681519) (xy 395.294714 -284.705147) (xy 395.31544 -284.72003) (xy 395.322044 -284.724856)
			(xy 395.35227 -284.73527) (xy 395.358122 -284.735163) (xy 395.369538 -284.732592) (xy 395.374876 -284.73019)
			(xy 395.40688 -284.714696) (xy 395.407388 -284.714696) (xy 395.459966 -284.688788) (xy 395.469263 -284.68288)
			(xy 395.482022 -284.664955) (xy 395.484604 -284.654244) (xy 395.48562 -284.644592) (xy 395.48562 -284.355032)
			(xy 395.484604 -284.34538) (xy 395.481984 -284.33469) (xy 395.469227 -284.316781) (xy 395.459966 -284.310836)
			(xy 395.407388 -284.284928) (xy 395.40688 -284.284928) (xy 395.374876 -284.269434) (xy 395.369537 -284.267035)
			(xy 395.358122 -284.264463) (xy 395.35227 -284.264354) (xy 395.329156 -284.272228) (xy 395.325431 -284.273592)
			(xy 395.318411 -284.277284) (xy 395.315186 -284.279594) (xy 395.294443 -284.294449) (xy 395.249217 -284.318057)
			(xy 395.200806 -284.334153) (xy 395.150448 -284.342325) (xy 395.12494 -284.34284) (xy 395.099944 -284.342378)
			(xy 395.050567 -284.334564) (xy 395.003021 -284.31912) (xy 394.958476 -284.296429) (xy 394.91803 -284.267047)
			(xy 394.882679 -284.2317) (xy 394.853292 -284.191258) (xy 394.830595 -284.146716) (xy 394.815146 -284.099172)
			(xy 394.807325 -284.049796) (xy 394.807325 -283.999804) (xy 394.815146 -283.950428) (xy 394.830595 -283.902884)
			(xy 394.853292 -283.858342) (xy 394.882679 -283.8179) (xy 394.91803 -283.782553) (xy 394.958476 -283.753171)
			(xy 395.003021 -283.73048) (xy 395.050567 -283.715036) (xy 395.099944 -283.707222) (xy 395.12494 -283.706824)
			(xy 395.150997 -283.707348) (xy 395.202416 -283.715842) (xy 395.251764 -283.732597) (xy 395.297724 -283.757165)
			(xy 395.33907 -283.788891) (xy 395.374697 -283.826926) (xy 395.389608 -283.848302) (xy 395.392656 -283.853128)
			(xy 395.398726 -283.861359) (xy 395.415817 -283.872559) (xy 395.43592 -283.876221) (xy 395.445996 -283.874464)
			(xy 395.45768 -283.871162) (xy 395.465554 -283.868622) (xy 395.47546 -283.855414) (xy 395.480132 -283.848674)
			(xy 395.485322 -283.833129) (xy 395.48562 -283.824934) (xy 395.48562 -283.758132) (xy 395.485278 -283.749439)
			(xy 395.479439 -283.733065) (xy 395.47419 -283.726128) (xy 395.470888 -283.722318) (xy 395.156182 -283.407612)
			(xy 395.152705 -283.40432) (xy 395.144785 -283.398941) (xy 395.140434 -283.396944) (xy 395.13129 -283.39288)
			(xy 395.12113 -283.39288) (xy 395.095063 -283.392039) (xy 395.043718 -283.382907) (xy 394.99455 -283.365523)
			(xy 394.948876 -283.340351) (xy 394.90792 -283.308066) (xy 394.872778 -283.269533) (xy 394.844392 -283.225784)
			(xy 394.823523 -283.177991) (xy 394.816584 -283.15285) (xy 394.813536 -283.144214) (xy 394.809114 -283.135554)
			(xy 394.795058 -283.12214) (xy 394.777022 -283.114914) (xy 394.767308 -283.114496) (xy 394.532612 -283.114496)
			(xy 394.522898 -283.114924) (xy 394.504862 -283.122144) (xy 394.490803 -283.135553) (xy 394.486384 -283.144214)
			(xy 394.483336 -283.15285) (xy 394.476806 -283.176746) (xy 394.457363 -283.222307) (xy 394.431092 -283.264303)
			(xy 394.398627 -283.301718) (xy 394.360755 -283.333648) (xy 394.31839 -283.35932) (xy 394.272558 -283.378114)
			(xy 394.224366 -283.389575) (xy 394.17498 -283.393427) (xy 394.125594 -283.389575) (xy 394.077402 -283.378114)
			(xy 394.03157 -283.35932) (xy 393.989205 -283.333648) (xy 393.951333 -283.301718) (xy 393.918868 -283.264303)
			(xy 393.892597 -283.222307) (xy 393.873154 -283.176746) (xy 393.866624 -283.15285) (xy 393.863576 -283.144214)
			(xy 393.859151 -283.135561) (xy 393.845092 -283.122164) (xy 393.827058 -283.114959) (xy 393.817348 -283.114496)
			(xy 393.582652 -283.114496) (xy 393.572944 -283.114935) (xy 393.554926 -283.122167) (xy 393.540885 -283.135578)
			(xy 393.536424 -283.144214) (xy 393.533376 -283.15285) (xy 393.526846 -283.176746) (xy 393.507403 -283.222307)
			(xy 393.481132 -283.264303) (xy 393.448667 -283.301718) (xy 393.410795 -283.333648) (xy 393.36843 -283.35932)
			(xy 393.322598 -283.378114) (xy 393.274406 -283.389575) (xy 393.22502 -283.393427) (xy 393.175634 -283.389575)
			(xy 393.127442 -283.378114) (xy 393.08161 -283.35932) (xy 393.039245 -283.333648) (xy 393.001373 -283.301718)
			(xy 392.968908 -283.264303) (xy 392.942637 -283.222307) (xy 392.923194 -283.176746) (xy 392.916664 -283.15285)
			(xy 392.913616 -283.144214) (xy 392.909193 -283.135556) (xy 392.895136 -283.122148) (xy 392.877101 -283.114929)
			(xy 392.867388 -283.114496) (xy 392.632184 -283.114496) (xy 392.620974 -283.115145) (xy 392.600727 -283.124794)
			(xy 392.586492 -283.142126) (xy 392.583162 -283.15285) (xy 392.576632 -283.176746) (xy 392.557189 -283.222307)
			(xy 392.530918 -283.264303) (xy 392.498453 -283.301718) (xy 392.460581 -283.333648) (xy 392.418216 -283.35932)
			(xy 392.372384 -283.378114) (xy 392.324192 -283.389575) (xy 392.274806 -283.393427) (xy 392.22542 -283.389575)
			(xy 392.177228 -283.378114) (xy 392.131396 -283.35932) (xy 392.089031 -283.333648) (xy 392.051159 -283.301718)
			(xy 392.018694 -283.264303) (xy 391.992423 -283.222307) (xy 391.97298 -283.176746) (xy 391.96645 -283.15285)
			(xy 391.963134 -283.142118) (xy 391.948902 -283.124775) (xy 391.928643 -283.115136) (xy 391.917428 -283.114496)
			(xy 391.680192 -283.114496) (xy 391.675238 -283.114615) (xy 391.665517 -283.116536) (xy 391.660888 -283.118306)
			(xy 391.654284 -283.1211) (xy 391.650557 -283.12254) (xy 391.642772 -283.124334) (xy 391.63879 -283.124656)
			(xy 391.63444 -283.149265) (xy 391.619027 -283.1968) (xy 391.596361 -283.241337) (xy 391.567003 -283.281775)
			(xy 391.531674 -283.317118) (xy 391.491248 -283.346493) (xy 391.446721 -283.369177) (xy 391.399192 -283.384609)
			(xy 391.349832 -283.392409) (xy 391.324846 -283.39288) (xy 391.299114 -283.39238) (xy 391.248322 -283.384083)
			(xy 391.199529 -283.367714) (xy 391.154009 -283.343702) (xy 391.112951 -283.312672) (xy 391.077425 -283.275435)
			(xy 391.04836 -283.232963) (xy 391.026515 -283.186365) (xy 391.01903 -283.16174) (xy 391.014458 -283.145484)
			(xy 390.98728 -283.12491) (xy 390.729724 -283.12491) (xy 390.722149 -283.125229) (xy 390.707688 -283.129753)
			(xy 390.701276 -283.1338) (xy 390.699244 -283.135324) (xy 390.695633 -283.138043) (xy 390.68937 -283.144561)
			(xy 390.686798 -283.148278) (xy 390.683242 -283.153612) (xy 390.680702 -283.161994) (xy 390.673195 -283.186607)
			(xy 390.651347 -283.233195) (xy 390.622281 -283.275655) (xy 390.586756 -283.31288) (xy 390.5457 -283.343899)
			(xy 390.500185 -283.3679) (xy 390.451398 -283.384257) (xy 390.400614 -283.392544) (xy 390.349158 -283.392544)
			(xy 390.298374 -283.384257) (xy 390.249587 -283.3679) (xy 390.204072 -283.343899) (xy 390.163016 -283.31288)
			(xy 390.127491 -283.275655) (xy 390.098425 -283.233195) (xy 390.076577 -283.186607) (xy 390.06907 -283.161994)
			(xy 390.06653 -283.153612) (xy 390.062974 -283.148278) (xy 390.060375 -283.144583) (xy 390.054117 -283.138068)
			(xy 390.050528 -283.135324) (xy 390.048496 -283.1338) (xy 390.042085 -283.129755) (xy 390.027622 -283.125247)
			(xy 390.020048 -283.12491) (xy 389.779764 -283.12491) (xy 389.772187 -283.125223) (xy 389.757719 -283.129738)
			(xy 389.751316 -283.1338) (xy 389.749284 -283.135324) (xy 389.745676 -283.138046) (xy 389.73942 -283.144568)
			(xy 389.736838 -283.148278) (xy 389.733282 -283.153612) (xy 389.730742 -283.161994) (xy 389.723216 -283.186589)
			(xy 389.701339 -283.233138) (xy 389.672256 -283.275559) (xy 389.636726 -283.312747) (xy 389.595675 -283.343733)
			(xy 389.550172 -283.367709) (xy 389.501404 -283.384051) (xy 389.450642 -283.392332) (xy 389.424926 -283.39288)
			(xy 389.398476 -283.392358) (xy 389.346304 -283.38361) (xy 389.296297 -283.366352) (xy 389.249836 -283.341058)
			(xy 389.208199 -283.308427) (xy 389.189976 -283.289248) (xy 389.189214 -283.288232) (xy 389.187944 -283.286962)
			(xy 389.180519 -283.280444) (xy 389.162199 -283.273098) (xy 389.142461 -283.273164) (xy 389.12419 -283.280634)
			(xy 389.116824 -283.287216) (xy 389.11657 -283.28747) (xy 389.081772 -283.322268) (xy 389.078248 -283.325997)
			(xy 389.072613 -283.334569) (xy 389.070596 -283.339286) (xy 389.06704 -283.347922) (xy 389.06704 -284.049821)
			(xy 391.007328 -284.049821) (xy 391.007328 -283.999843) (xy 391.015147 -283.95048) (xy 391.030591 -283.902948)
			(xy 391.053281 -283.858416) (xy 391.082657 -283.817983) (xy 391.117997 -283.782643) (xy 391.15843 -283.753267)
			(xy 391.202962 -283.730577) (xy 391.250494 -283.715133) (xy 391.299857 -283.707314) (xy 391.349835 -283.707314)
			(xy 391.399198 -283.715133) (xy 391.44673 -283.730577) (xy 391.491262 -283.753267) (xy 391.531695 -283.782643)
			(xy 391.567035 -283.817983) (xy 391.596411 -283.858416) (xy 391.619101 -283.902948) (xy 391.634545 -283.95048)
			(xy 391.642364 -283.999843) (xy 391.642854 -284.024832) (xy 391.642364 -284.049821) (xy 391.957288 -284.049821)
			(xy 391.957288 -283.999843) (xy 391.965107 -283.95048) (xy 391.980551 -283.902948) (xy 392.003241 -283.858416)
			(xy 392.032617 -283.817983) (xy 392.067957 -283.782643) (xy 392.10839 -283.753267) (xy 392.152922 -283.730577)
			(xy 392.200454 -283.715133) (xy 392.249817 -283.707314) (xy 392.299795 -283.707314) (xy 392.349158 -283.715133)
			(xy 392.39669 -283.730577) (xy 392.441222 -283.753267) (xy 392.481655 -283.782643) (xy 392.516995 -283.817983)
			(xy 392.546371 -283.858416) (xy 392.569061 -283.902948) (xy 392.584505 -283.95048) (xy 392.592324 -283.999843)
			(xy 392.592814 -284.024832) (xy 392.592324 -284.049821) (xy 392.907502 -284.049821) (xy 392.907502 -283.999843)
			(xy 392.915321 -283.95048) (xy 392.930765 -283.902948) (xy 392.953455 -283.858416) (xy 392.982831 -283.817983)
			(xy 393.018171 -283.782643) (xy 393.058604 -283.753267) (xy 393.103136 -283.730577) (xy 393.150668 -283.715133)
			(xy 393.200031 -283.707314) (xy 393.250009 -283.707314) (xy 393.299372 -283.715133) (xy 393.346904 -283.730577)
			(xy 393.391436 -283.753267) (xy 393.431869 -283.782643) (xy 393.467209 -283.817983) (xy 393.496585 -283.858416)
			(xy 393.519275 -283.902948) (xy 393.534719 -283.95048) (xy 393.542538 -283.999843) (xy 393.543028 -284.024832)
			(xy 393.542538 -284.049821) (xy 393.857462 -284.049821) (xy 393.857462 -283.999843) (xy 393.865281 -283.95048)
			(xy 393.880725 -283.902948) (xy 393.903415 -283.858416) (xy 393.932791 -283.817983) (xy 393.968131 -283.782643)
			(xy 394.008564 -283.753267) (xy 394.053096 -283.730577) (xy 394.100628 -283.715133) (xy 394.149991 -283.707314)
			(xy 394.199969 -283.707314) (xy 394.249332 -283.715133) (xy 394.296864 -283.730577) (xy 394.341396 -283.753267)
			(xy 394.381829 -283.782643) (xy 394.417169 -283.817983) (xy 394.446545 -283.858416) (xy 394.469235 -283.902948)
			(xy 394.484679 -283.95048) (xy 394.492498 -283.999843) (xy 394.492988 -284.024832) (xy 394.492498 -284.049821)
			(xy 394.484679 -284.099184) (xy 394.469235 -284.146716) (xy 394.446545 -284.191248) (xy 394.417169 -284.231681)
			(xy 394.381829 -284.267021) (xy 394.341396 -284.296397) (xy 394.296864 -284.319087) (xy 394.249332 -284.334531)
			(xy 394.199969 -284.34235) (xy 394.149991 -284.34235) (xy 394.100628 -284.334531) (xy 394.053096 -284.319087)
			(xy 394.008564 -284.296397) (xy 393.968131 -284.267021) (xy 393.932791 -284.231681) (xy 393.903415 -284.191248)
			(xy 393.880725 -284.146716) (xy 393.865281 -284.099184) (xy 393.857462 -284.049821) (xy 393.542538 -284.049821)
			(xy 393.534719 -284.099184) (xy 393.519275 -284.146716) (xy 393.496585 -284.191248) (xy 393.467209 -284.231681)
			(xy 393.431869 -284.267021) (xy 393.391436 -284.296397) (xy 393.346904 -284.319087) (xy 393.299372 -284.334531)
			(xy 393.250009 -284.34235) (xy 393.200031 -284.34235) (xy 393.150668 -284.334531) (xy 393.103136 -284.319087)
			(xy 393.058604 -284.296397) (xy 393.018171 -284.267021) (xy 392.982831 -284.231681) (xy 392.953455 -284.191248)
			(xy 392.930765 -284.146716) (xy 392.915321 -284.099184) (xy 392.907502 -284.049821) (xy 392.592324 -284.049821)
			(xy 392.584505 -284.099184) (xy 392.569061 -284.146716) (xy 392.546371 -284.191248) (xy 392.516995 -284.231681)
			(xy 392.481655 -284.267021) (xy 392.441222 -284.296397) (xy 392.39669 -284.319087) (xy 392.349158 -284.334531)
			(xy 392.299795 -284.34235) (xy 392.249817 -284.34235) (xy 392.200454 -284.334531) (xy 392.152922 -284.319087)
			(xy 392.10839 -284.296397) (xy 392.067957 -284.267021) (xy 392.032617 -284.231681) (xy 392.003241 -284.191248)
			(xy 391.980551 -284.146716) (xy 391.965107 -284.099184) (xy 391.957288 -284.049821) (xy 391.642364 -284.049821)
			(xy 391.634545 -284.099184) (xy 391.619101 -284.146716) (xy 391.596411 -284.191248) (xy 391.567035 -284.231681)
			(xy 391.531695 -284.267021) (xy 391.491262 -284.296397) (xy 391.44673 -284.319087) (xy 391.399198 -284.334531)
			(xy 391.349835 -284.34235) (xy 391.299857 -284.34235) (xy 391.250494 -284.334531) (xy 391.202962 -284.319087)
			(xy 391.15843 -284.296397) (xy 391.117997 -284.267021) (xy 391.082657 -284.231681) (xy 391.053281 -284.191248)
			(xy 391.030591 -284.146716) (xy 391.015147 -284.099184) (xy 391.007328 -284.049821) (xy 389.06704 -284.049821)
			(xy 389.06704 -285.0769) (xy 389.067802 -285.085282) (xy 389.069314 -285.092888) (xy 389.076298 -285.106725)
			(xy 389.081518 -285.11246) (xy 389.184896 -285.215838) (xy 389.191412 -285.221919) (xy 389.207548 -285.22946)
			(xy 389.216392 -285.23057) (xy 389.226044 -285.23057) (xy 389.256524 -285.228792) (xy 389.855964 -285.228792)
			(xy 389.863539 -285.228475) (xy 389.878003 -285.223953) (xy 389.884412 -285.219902) (xy 389.90353 -285.207389)
			(xy 389.944694 -285.187566) (xy 389.98835 -285.174088) (xy 390.033526 -285.167256) (xy 390.05637 -285.166816)
			(xy 390.893046 -285.166816) (xy 390.893554 -285.166816) (xy 390.909556 -285.16707) (xy 390.921494 -285.167832)
			(xy 390.943338 -285.158434) (xy 391.01141 -285.07817) (xy 391.017252 -285.055056) (xy 391.016998 -285.05404)
			(xy 391.012262 -285.03457) (xy 391.007165 -284.994826) (xy 391.006838 -284.974792) (xy 391.007329 -284.949807)
			(xy 391.015147 -284.900453) (xy 391.030589 -284.85293) (xy 391.053275 -284.808407) (xy 391.082646 -284.767981)
			(xy 391.11798 -284.732647) (xy 391.158405 -284.703276) (xy 391.202928 -284.680589) (xy 391.250451 -284.665147)
			(xy 391.299805 -284.657329) (xy 391.349775 -284.657327) (xy 391.399129 -284.665142) (xy 391.446653 -284.680582)
			(xy 391.491178 -284.703265) (xy 391.531605 -284.732634) (xy 391.566941 -284.767966) (xy 391.596315 -284.80839)
			(xy 391.619004 -284.852911) (xy 391.634449 -284.900434) (xy 391.64227 -284.949787) (xy 391.642274 -284.999757)
			(xy 391.64227 -284.999781) (xy 392.907502 -284.999781) (xy 392.907502 -284.949803) (xy 392.915321 -284.90044)
			(xy 392.930765 -284.852908) (xy 392.953455 -284.808376) (xy 392.982831 -284.767943) (xy 393.018171 -284.732603)
			(xy 393.058604 -284.703227) (xy 393.103136 -284.680537) (xy 393.150668 -284.665093) (xy 393.200031 -284.657274)
			(xy 393.250009 -284.657274) (xy 393.299372 -284.665093) (xy 393.346904 -284.680537) (xy 393.391436 -284.703227)
			(xy 393.431869 -284.732603) (xy 393.467209 -284.767943) (xy 393.496585 -284.808376) (xy 393.519275 -284.852908)
			(xy 393.534719 -284.90044) (xy 393.542538 -284.949803) (xy 393.543028 -284.974792) (xy 393.542538 -284.999781)
			(xy 393.857462 -284.999781) (xy 393.857462 -284.949803) (xy 393.865281 -284.90044) (xy 393.880725 -284.852908)
			(xy 393.903415 -284.808376) (xy 393.932791 -284.767943) (xy 393.968131 -284.732603) (xy 394.008564 -284.703227)
			(xy 394.053096 -284.680537) (xy 394.100628 -284.665093) (xy 394.149991 -284.657274) (xy 394.199969 -284.657274)
			(xy 394.249332 -284.665093) (xy 394.296864 -284.680537) (xy 394.341396 -284.703227) (xy 394.381829 -284.732603)
			(xy 394.417169 -284.767943) (xy 394.446545 -284.808376) (xy 394.469235 -284.852908) (xy 394.484679 -284.90044)
			(xy 394.492498 -284.949803) (xy 394.492988 -284.974792) (xy 394.492498 -284.999781) (xy 394.484679 -285.049144)
			(xy 394.469235 -285.096676) (xy 394.446545 -285.141208) (xy 394.417169 -285.181641) (xy 394.381829 -285.216981)
			(xy 394.341396 -285.246357) (xy 394.296864 -285.269047) (xy 394.249332 -285.284491) (xy 394.199969 -285.29231)
			(xy 394.149991 -285.29231) (xy 394.100628 -285.284491) (xy 394.053096 -285.269047) (xy 394.008564 -285.246357)
			(xy 393.968131 -285.216981) (xy 393.932791 -285.181641) (xy 393.903415 -285.141208) (xy 393.880725 -285.096676)
			(xy 393.865281 -285.049144) (xy 393.857462 -284.999781) (xy 393.542538 -284.999781) (xy 393.534719 -285.049144)
			(xy 393.519275 -285.096676) (xy 393.496585 -285.141208) (xy 393.467209 -285.181641) (xy 393.431869 -285.216981)
			(xy 393.391436 -285.246357) (xy 393.346904 -285.269047) (xy 393.299372 -285.284491) (xy 393.250009 -285.29231)
			(xy 393.200031 -285.29231) (xy 393.150668 -285.284491) (xy 393.103136 -285.269047) (xy 393.058604 -285.246357)
			(xy 393.018171 -285.216981) (xy 392.982831 -285.181641) (xy 392.953455 -285.141208) (xy 392.930765 -285.096676)
			(xy 392.915321 -285.049144) (xy 392.907502 -284.999781) (xy 391.64227 -284.999781) (xy 391.634462 -285.049112)
			(xy 391.619025 -285.096637) (xy 391.596344 -285.141162) (xy 391.566977 -285.181592) (xy 391.531648 -285.216929)
			(xy 391.491225 -285.246305) (xy 391.446705 -285.268997) (xy 391.399184 -285.284444) (xy 391.349831 -285.292268)
			(xy 391.324846 -285.2928) (xy 391.31363 -285.292664) (xy 391.291257 -285.291008) (xy 391.280142 -285.289498)
			(xy 391.279634 -285.289498) (xy 391.266934 -285.28772) (xy 391.254234 -285.292546) (xy 391.253726 -285.2928)
			(xy 391.248412 -285.295128) (xy 391.238922 -285.301798) (xy 391.23493 -285.306008) (xy 391.197846 -285.353252)
			(xy 391.191151 -285.362773) (xy 391.186394 -285.385531) (xy 391.188702 -285.39694) (xy 391.192772 -285.414252)
			(xy 391.197354 -285.449521) (xy 391.197846 -285.467298) (xy 391.211562 -285.481014) (xy 391.21841 -285.488411)
			(xy 391.226146 -285.50701) (xy 391.226548 -285.517082) (xy 391.226548 -285.949741) (xy 392.907502 -285.949741)
			(xy 392.907502 -285.899763) (xy 392.915321 -285.8504) (xy 392.930765 -285.802868) (xy 392.953455 -285.758336)
			(xy 392.982831 -285.717903) (xy 393.018171 -285.682563) (xy 393.058604 -285.653187) (xy 393.103136 -285.630497)
			(xy 393.150668 -285.615053) (xy 393.200031 -285.607234) (xy 393.250009 -285.607234) (xy 393.299372 -285.615053)
			(xy 393.346904 -285.630497) (xy 393.391436 -285.653187) (xy 393.431869 -285.682563) (xy 393.467209 -285.717903)
			(xy 393.496585 -285.758336) (xy 393.519275 -285.802868) (xy 393.534719 -285.8504) (xy 393.542538 -285.899763)
			(xy 393.543028 -285.924752) (xy 393.542538 -285.949741) (xy 393.857462 -285.949741) (xy 393.857462 -285.899763)
			(xy 393.865281 -285.8504) (xy 393.880725 -285.802868) (xy 393.903415 -285.758336) (xy 393.932791 -285.717903)
			(xy 393.968131 -285.682563) (xy 394.008564 -285.653187) (xy 394.053096 -285.630497) (xy 394.100628 -285.615053)
			(xy 394.149991 -285.607234) (xy 394.199969 -285.607234) (xy 394.249332 -285.615053) (xy 394.296864 -285.630497)
			(xy 394.341396 -285.653187) (xy 394.381829 -285.682563) (xy 394.417169 -285.717903) (xy 394.446545 -285.758336)
			(xy 394.469235 -285.802868) (xy 394.484679 -285.8504) (xy 394.492498 -285.899763) (xy 394.492988 -285.924752)
			(xy 394.492498 -285.949741) (xy 394.484679 -285.999104) (xy 394.469235 -286.046636) (xy 394.446545 -286.091168)
			(xy 394.417169 -286.131601) (xy 394.381829 -286.166941) (xy 394.341396 -286.196317) (xy 394.296864 -286.219007)
			(xy 394.249332 -286.234451) (xy 394.199969 -286.24227) (xy 394.149991 -286.24227) (xy 394.100628 -286.234451)
			(xy 394.053096 -286.219007) (xy 394.008564 -286.196317) (xy 393.968131 -286.166941) (xy 393.932791 -286.131601)
			(xy 393.903415 -286.091168) (xy 393.880725 -286.046636) (xy 393.865281 -285.999104) (xy 393.857462 -285.949741)
			(xy 393.542538 -285.949741) (xy 393.534719 -285.999104) (xy 393.519275 -286.046636) (xy 393.496585 -286.091168)
			(xy 393.467209 -286.131601) (xy 393.431869 -286.166941) (xy 393.391436 -286.196317) (xy 393.346904 -286.219007)
			(xy 393.299372 -286.234451) (xy 393.250009 -286.24227) (xy 393.200031 -286.24227) (xy 393.150668 -286.234451)
			(xy 393.103136 -286.219007) (xy 393.058604 -286.196317) (xy 393.018171 -286.166941) (xy 392.982831 -286.131601)
			(xy 392.953455 -286.091168) (xy 392.930765 -286.046636) (xy 392.915321 -285.999104) (xy 392.907502 -285.949741)
			(xy 391.226548 -285.949741) (xy 391.226548 -286.442404) (xy 391.227024 -286.45237) (xy 391.234601 -286.470806)
			(xy 391.24128 -286.478218) (xy 391.249662 -286.4866) (xy 391.292334 -286.529526) (xy 391.295951 -286.53296)
			(xy 391.304269 -286.538462) (xy 391.308844 -286.540448) (xy 391.316464 -286.54375) (xy 391.327386 -286.544004)
			(xy 391.32764 -286.544004) (xy 391.353486 -286.544717) (xy 391.404489 -286.553186) (xy 391.453554 -286.569488)
			(xy 391.499483 -286.593228) (xy 391.541159 -286.623826) (xy 391.577565 -286.660536) (xy 391.607815 -286.702465)
			(xy 391.631172 -286.74859) (xy 391.647065 -286.797789) (xy 391.655109 -286.848861) (xy 391.655554 -286.874712)
			(xy 391.655121 -286.898757) (xy 391.654983 -286.899701) (xy 391.957288 -286.899701) (xy 391.957288 -286.849723)
			(xy 391.965107 -286.80036) (xy 391.980551 -286.752828) (xy 392.003241 -286.708296) (xy 392.032617 -286.667863)
			(xy 392.067957 -286.632523) (xy 392.10839 -286.603147) (xy 392.152922 -286.580457) (xy 392.200454 -286.565013)
			(xy 392.249817 -286.557194) (xy 392.299795 -286.557194) (xy 392.349158 -286.565013) (xy 392.39669 -286.580457)
			(xy 392.441222 -286.603147) (xy 392.481655 -286.632523) (xy 392.516995 -286.667863) (xy 392.546371 -286.708296)
			(xy 392.569061 -286.752828) (xy 392.584505 -286.80036) (xy 392.592324 -286.849723) (xy 392.592814 -286.874712)
			(xy 392.592324 -286.899701) (xy 392.592284 -286.899955) (xy 392.907502 -286.899955) (xy 392.907502 -286.849977)
			(xy 392.915321 -286.800614) (xy 392.930765 -286.753082) (xy 392.953455 -286.70855) (xy 392.982831 -286.668117)
			(xy 393.018171 -286.632777) (xy 393.058604 -286.603401) (xy 393.103136 -286.580711) (xy 393.150668 -286.565267)
			(xy 393.200031 -286.557448) (xy 393.250009 -286.557448) (xy 393.299372 -286.565267) (xy 393.346904 -286.580711)
			(xy 393.391436 -286.603401) (xy 393.431869 -286.632777) (xy 393.467209 -286.668117) (xy 393.496585 -286.70855)
			(xy 393.519275 -286.753082) (xy 393.534719 -286.800614) (xy 393.542538 -286.849977) (xy 393.543028 -286.874966)
			(xy 393.542538 -286.899955) (xy 393.857462 -286.899955) (xy 393.857462 -286.849977) (xy 393.865281 -286.800614)
			(xy 393.880725 -286.753082) (xy 393.903415 -286.70855) (xy 393.932791 -286.668117) (xy 393.968131 -286.632777)
			(xy 394.008564 -286.603401) (xy 394.053096 -286.580711) (xy 394.100628 -286.565267) (xy 394.149991 -286.557448)
			(xy 394.199969 -286.557448) (xy 394.249332 -286.565267) (xy 394.296864 -286.580711) (xy 394.341396 -286.603401)
			(xy 394.381829 -286.632777) (xy 394.417169 -286.668117) (xy 394.446545 -286.70855) (xy 394.469235 -286.753082)
			(xy 394.484679 -286.800614) (xy 394.492498 -286.849977) (xy 394.492988 -286.874966) (xy 394.492498 -286.899955)
			(xy 394.484679 -286.949318) (xy 394.469235 -286.99685) (xy 394.446545 -287.041382) (xy 394.417169 -287.081815)
			(xy 394.381829 -287.117155) (xy 394.341396 -287.146531) (xy 394.296864 -287.169221) (xy 394.249332 -287.184665)
			(xy 394.199969 -287.192484) (xy 394.149991 -287.192484) (xy 394.100628 -287.184665) (xy 394.053096 -287.169221)
			(xy 394.008564 -287.146531) (xy 393.968131 -287.117155) (xy 393.932791 -287.081815) (xy 393.903415 -287.041382)
			(xy 393.880725 -286.99685) (xy 393.865281 -286.949318) (xy 393.857462 -286.899955) (xy 393.542538 -286.899955)
			(xy 393.534719 -286.949318) (xy 393.519275 -286.99685) (xy 393.496585 -287.041382) (xy 393.467209 -287.081815)
			(xy 393.431869 -287.117155) (xy 393.391436 -287.146531) (xy 393.346904 -287.169221) (xy 393.299372 -287.184665)
			(xy 393.250009 -287.192484) (xy 393.200031 -287.192484) (xy 393.150668 -287.184665) (xy 393.103136 -287.169221)
			(xy 393.058604 -287.146531) (xy 393.018171 -287.117155) (xy 392.982831 -287.081815) (xy 392.953455 -287.041382)
			(xy 392.930765 -286.99685) (xy 392.915321 -286.949318) (xy 392.907502 -286.899955) (xy 392.592284 -286.899955)
			(xy 392.584505 -286.949064) (xy 392.569061 -286.996596) (xy 392.546371 -287.041128) (xy 392.516995 -287.081561)
			(xy 392.481655 -287.116901) (xy 392.441222 -287.146277) (xy 392.39669 -287.168967) (xy 392.349158 -287.184411)
			(xy 392.299795 -287.19223) (xy 392.249817 -287.19223) (xy 392.200454 -287.184411) (xy 392.152922 -287.168967)
			(xy 392.10839 -287.146277) (xy 392.067957 -287.116901) (xy 392.032617 -287.081561) (xy 392.003241 -287.041128)
			(xy 391.980551 -286.996596) (xy 391.965107 -286.949064) (xy 391.957288 -286.899701) (xy 391.654983 -286.899701)
			(xy 391.648153 -286.946338) (xy 391.634366 -286.992409) (xy 391.614051 -287.035996) (xy 391.601198 -287.056322)
			(xy 391.59688 -287.062926) (xy 391.594848 -287.06953) (xy 391.593881 -287.073071) (xy 391.592856 -287.080338)
			(xy 391.592816 -287.084008) (xy 391.592816 -287.177734) (xy 391.592387 -287.187802) (xy 391.584666 -287.206399)
			(xy 391.57783 -287.213802) (xy 390.941717 -287.849915) (xy 392.907502 -287.849915) (xy 392.907502 -287.799937)
			(xy 392.915321 -287.750574) (xy 392.930765 -287.703042) (xy 392.953455 -287.65851) (xy 392.982831 -287.618077)
			(xy 393.018171 -287.582737) (xy 393.058604 -287.553361) (xy 393.103136 -287.530671) (xy 393.150668 -287.515227)
			(xy 393.200031 -287.507408) (xy 393.250009 -287.507408) (xy 393.299372 -287.515227) (xy 393.346904 -287.530671)
			(xy 393.391436 -287.553361) (xy 393.431869 -287.582737) (xy 393.467209 -287.618077) (xy 393.496585 -287.65851)
			(xy 393.519275 -287.703042) (xy 393.534719 -287.750574) (xy 393.542538 -287.799937) (xy 393.543028 -287.824926)
			(xy 393.542538 -287.849915) (xy 393.857462 -287.849915) (xy 393.857462 -287.799937) (xy 393.865281 -287.750574)
			(xy 393.880725 -287.703042) (xy 393.903415 -287.65851) (xy 393.932791 -287.618077) (xy 393.968131 -287.582737)
			(xy 394.008564 -287.553361) (xy 394.053096 -287.530671) (xy 394.100628 -287.515227) (xy 394.149991 -287.507408)
			(xy 394.199969 -287.507408) (xy 394.249332 -287.515227) (xy 394.296864 -287.530671) (xy 394.341396 -287.553361)
			(xy 394.381829 -287.582737) (xy 394.417169 -287.618077) (xy 394.446545 -287.65851) (xy 394.469235 -287.703042)
			(xy 394.484679 -287.750574) (xy 394.492498 -287.799937) (xy 394.492988 -287.824926) (xy 394.492498 -287.849915)
			(xy 394.484679 -287.899278) (xy 394.469235 -287.94681) (xy 394.446545 -287.991342) (xy 394.417169 -288.031775)
			(xy 394.381829 -288.067115) (xy 394.341396 -288.096491) (xy 394.296864 -288.119181) (xy 394.249332 -288.134625)
			(xy 394.199969 -288.142444) (xy 394.149991 -288.142444) (xy 394.100628 -288.134625) (xy 394.053096 -288.119181)
			(xy 394.008564 -288.096491) (xy 393.968131 -288.067115) (xy 393.932791 -288.031775) (xy 393.903415 -287.991342)
			(xy 393.880725 -287.94681) (xy 393.865281 -287.899278) (xy 393.857462 -287.849915) (xy 393.542538 -287.849915)
			(xy 393.534719 -287.899278) (xy 393.519275 -287.94681) (xy 393.496585 -287.991342) (xy 393.467209 -288.031775)
			(xy 393.431869 -288.067115) (xy 393.391436 -288.096491) (xy 393.346904 -288.119181) (xy 393.299372 -288.134625)
			(xy 393.250009 -288.142444) (xy 393.200031 -288.142444) (xy 393.150668 -288.134625) (xy 393.103136 -288.119181)
			(xy 393.058604 -288.096491) (xy 393.018171 -288.067115) (xy 392.982831 -288.031775) (xy 392.953455 -287.991342)
			(xy 392.930765 -287.94681) (xy 392.915321 -287.899278) (xy 392.907502 -287.849915) (xy 390.941717 -287.849915)
			(xy 390.651238 -288.140394) (xy 390.643837 -288.147231) (xy 390.625238 -288.154944) (xy 390.61517 -288.15538)
			(xy 389.611616 -288.15538) (xy 389.601605 -288.155865) (xy 389.583104 -288.163521) (xy 389.568941 -288.177674)
			(xy 389.561272 -288.196169) (xy 389.560816 -288.20618) (xy 389.560816 -288.55924) (xy 389.561578 -288.567622)
			(xy 389.563094 -288.575226) (xy 389.570083 -288.589057) (xy 389.575294 -288.5948) (xy 389.65632 -288.675826)
			(xy 389.66207 -288.681023) (xy 389.675901 -288.688003) (xy 389.683498 -288.689542) (xy 389.69188 -288.690304)
			(xy 390.031732 -288.690304) (xy 390.039375 -288.690041) (xy 390.053976 -288.685512) (xy 390.060434 -288.681414)
			(xy 390.066022 -288.677604) (xy 390.075928 -288.665412) (xy 390.078976 -288.658046) (xy 390.088759 -288.634659)
			(xy 390.114648 -288.591077) (xy 390.147118 -288.552149) (xy 390.185348 -288.518862) (xy 390.228372 -288.492056)
			(xy 390.275102 -288.472409) (xy 390.324355 -288.460419) (xy 390.374886 -288.456388) (xy 390.425417 -288.460419)
			(xy 390.47467 -288.472409) (xy 390.5214 -288.492056) (xy 390.564424 -288.518862) (xy 390.602654 -288.552149)
			(xy 390.635124 -288.591077) (xy 390.661013 -288.634659) (xy 390.670796 -288.658046) (xy 390.670796 -288.6583)
			(xy 390.673881 -288.665277) (xy 390.68344 -288.677156) (xy 390.689592 -288.681668) (xy 390.695688 -288.685986)
			(xy 390.710166 -288.690304) (xy 390.967976 -288.690304) (xy 390.976466 -288.690001) (xy 390.992513 -288.684456)
			(xy 391.005844 -288.673941) (xy 391.010648 -288.666936) (xy 391.01522 -288.657538) (xy 391.015982 -288.655506)
			(xy 391.025348 -288.632424) (xy 391.050003 -288.589143) (xy 391.080865 -288.550044) (xy 391.117237 -288.516011)
			(xy 391.158298 -288.487812) (xy 391.20312 -288.466084) (xy 391.250693 -288.451318) (xy 391.29994 -288.443846)
			(xy 391.324846 -288.443416) (xy 392.274806 -288.443416) (xy 392.300815 -288.443927) (xy 392.352191 -288.452065)
			(xy 392.401662 -288.46814) (xy 392.448009 -288.491756) (xy 392.490092 -288.522331) (xy 392.526873 -288.559113)
			(xy 392.557447 -288.601196) (xy 392.581062 -288.647544) (xy 392.597136 -288.697015) (xy 392.605274 -288.748391)
			(xy 392.605274 -288.799875) (xy 392.907502 -288.799875) (xy 392.907502 -288.749897) (xy 392.915321 -288.700534)
			(xy 392.930765 -288.653002) (xy 392.953455 -288.60847) (xy 392.982831 -288.568037) (xy 393.018171 -288.532697)
			(xy 393.058604 -288.503321) (xy 393.103136 -288.480631) (xy 393.150668 -288.465187) (xy 393.200031 -288.457368)
			(xy 393.250009 -288.457368) (xy 393.299372 -288.465187) (xy 393.346904 -288.480631) (xy 393.391436 -288.503321)
			(xy 393.431869 -288.532697) (xy 393.467209 -288.568037) (xy 393.496585 -288.60847) (xy 393.519275 -288.653002)
			(xy 393.534719 -288.700534) (xy 393.542538 -288.749897) (xy 393.543028 -288.774886) (xy 393.542538 -288.799875)
			(xy 393.857462 -288.799875) (xy 393.857462 -288.749897) (xy 393.865281 -288.700534) (xy 393.880725 -288.653002)
			(xy 393.903415 -288.60847) (xy 393.932791 -288.568037) (xy 393.968131 -288.532697) (xy 394.008564 -288.503321)
			(xy 394.053096 -288.480631) (xy 394.100628 -288.465187) (xy 394.149991 -288.457368) (xy 394.199969 -288.457368)
			(xy 394.249332 -288.465187) (xy 394.296864 -288.480631) (xy 394.341396 -288.503321) (xy 394.381829 -288.532697)
			(xy 394.417169 -288.568037) (xy 394.446545 -288.60847) (xy 394.469235 -288.653002) (xy 394.484679 -288.700534)
			(xy 394.492498 -288.749897) (xy 394.492988 -288.774886) (xy 394.492498 -288.799875) (xy 394.484679 -288.849238)
			(xy 394.469235 -288.89677) (xy 394.446545 -288.941302) (xy 394.417169 -288.981735) (xy 394.381829 -289.017075)
			(xy 394.341396 -289.046451) (xy 394.296864 -289.069141) (xy 394.249332 -289.084585) (xy 394.199969 -289.092404)
			(xy 394.149991 -289.092404) (xy 394.100628 -289.084585) (xy 394.053096 -289.069141) (xy 394.008564 -289.046451)
			(xy 393.968131 -289.017075) (xy 393.932791 -288.981735) (xy 393.903415 -288.941302) (xy 393.880725 -288.89677)
			(xy 393.865281 -288.849238) (xy 393.857462 -288.799875) (xy 393.542538 -288.799875) (xy 393.534719 -288.849238)
			(xy 393.519275 -288.89677) (xy 393.496585 -288.941302) (xy 393.467209 -288.981735) (xy 393.431869 -289.017075)
			(xy 393.391436 -289.046451) (xy 393.346904 -289.069141) (xy 393.299372 -289.084585) (xy 393.250009 -289.092404)
			(xy 393.200031 -289.092404) (xy 393.150668 -289.084585) (xy 393.103136 -289.069141) (xy 393.058604 -289.046451)
			(xy 393.018171 -289.017075) (xy 392.982831 -288.981735) (xy 392.953455 -288.941302) (xy 392.930765 -288.89677)
			(xy 392.915321 -288.849238) (xy 392.907502 -288.799875) (xy 392.605274 -288.799875) (xy 392.605274 -288.800409)
			(xy 392.597136 -288.851785) (xy 392.581062 -288.901256) (xy 392.557447 -288.947604) (xy 392.526873 -288.989687)
			(xy 392.490092 -289.026469) (xy 392.448009 -289.057044) (xy 392.401662 -289.08066) (xy 392.352191 -289.096735)
			(xy 392.300815 -289.104873) (xy 392.274806 -289.10534) (xy 391.643616 -289.10534) (xy 391.633596 -289.105757)
			(xy 391.61508 -289.113426) (xy 391.600912 -289.1276) (xy 391.593253 -289.146119) (xy 391.592816 -289.15614)
			(xy 391.592816 -289.515296) (xy 391.593037 -289.522336) (xy 391.5969 -289.535875) (xy 391.600436 -289.541966)
			(xy 391.613488 -289.56239) (xy 391.634116 -289.606251) (xy 391.648117 -289.652653) (xy 391.65519 -289.700604)
			(xy 391.655184 -289.749073) (xy 391.655071 -289.749835) (xy 391.957288 -289.749835) (xy 391.957288 -289.699857)
			(xy 391.965107 -289.650494) (xy 391.980551 -289.602962) (xy 392.003241 -289.55843) (xy 392.032617 -289.517997)
			(xy 392.067957 -289.482657) (xy 392.10839 -289.453281) (xy 392.152922 -289.430591) (xy 392.200454 -289.415147)
			(xy 392.249817 -289.407328) (xy 392.299795 -289.407328) (xy 392.349158 -289.415147) (xy 392.39669 -289.430591)
			(xy 392.441222 -289.453281) (xy 392.481655 -289.482657) (xy 392.516995 -289.517997) (xy 392.546371 -289.55843)
			(xy 392.569061 -289.602962) (xy 392.584505 -289.650494) (xy 392.592324 -289.699857) (xy 392.592814 -289.724846)
			(xy 392.592324 -289.749835) (xy 392.907502 -289.749835) (xy 392.907502 -289.699857) (xy 392.915321 -289.650494)
			(xy 392.930765 -289.602962) (xy 392.953455 -289.55843) (xy 392.982831 -289.517997) (xy 393.018171 -289.482657)
			(xy 393.058604 -289.453281) (xy 393.103136 -289.430591) (xy 393.150668 -289.415147) (xy 393.200031 -289.407328)
			(xy 393.250009 -289.407328) (xy 393.299372 -289.415147) (xy 393.346904 -289.430591) (xy 393.391436 -289.453281)
			(xy 393.431869 -289.482657) (xy 393.467209 -289.517997) (xy 393.496585 -289.55843) (xy 393.519275 -289.602962)
			(xy 393.534719 -289.650494) (xy 393.542538 -289.699857) (xy 393.543028 -289.724846) (xy 393.542538 -289.749835)
			(xy 393.857462 -289.749835) (xy 393.857462 -289.699857) (xy 393.865281 -289.650494) (xy 393.880725 -289.602962)
			(xy 393.903415 -289.55843) (xy 393.932791 -289.517997) (xy 393.968131 -289.482657) (xy 394.008564 -289.453281)
			(xy 394.053096 -289.430591) (xy 394.100628 -289.415147) (xy 394.149991 -289.407328) (xy 394.199969 -289.407328)
			(xy 394.249332 -289.415147) (xy 394.296864 -289.430591) (xy 394.341396 -289.453281) (xy 394.381829 -289.482657)
			(xy 394.417169 -289.517997) (xy 394.446545 -289.55843) (xy 394.469235 -289.602962) (xy 394.484679 -289.650494)
			(xy 394.492498 -289.699857) (xy 394.492988 -289.724846) (xy 394.492498 -289.749835) (xy 394.484679 -289.799198)
			(xy 394.469235 -289.84673) (xy 394.446545 -289.891262) (xy 394.417169 -289.931695) (xy 394.381829 -289.967035)
			(xy 394.341396 -289.996411) (xy 394.296864 -290.019101) (xy 394.249332 -290.034545) (xy 394.199969 -290.042364)
			(xy 394.149991 -290.042364) (xy 394.100628 -290.034545) (xy 394.053096 -290.019101) (xy 394.008564 -289.996411)
			(xy 393.968131 -289.967035) (xy 393.932791 -289.931695) (xy 393.903415 -289.891262) (xy 393.880725 -289.84673)
			(xy 393.865281 -289.799198) (xy 393.857462 -289.749835) (xy 393.542538 -289.749835) (xy 393.534719 -289.799198)
			(xy 393.519275 -289.84673) (xy 393.496585 -289.891262) (xy 393.467209 -289.931695) (xy 393.431869 -289.967035)
			(xy 393.391436 -289.996411) (xy 393.346904 -290.019101) (xy 393.299372 -290.034545) (xy 393.250009 -290.042364)
			(xy 393.200031 -290.042364) (xy 393.150668 -290.034545) (xy 393.103136 -290.019101) (xy 393.058604 -289.996411)
			(xy 393.018171 -289.967035) (xy 392.982831 -289.931695) (xy 392.953455 -289.891262) (xy 392.930765 -289.84673)
			(xy 392.915321 -289.799198) (xy 392.907502 -289.749835) (xy 392.592324 -289.749835) (xy 392.584505 -289.799198)
			(xy 392.569061 -289.84673) (xy 392.546371 -289.891262) (xy 392.516995 -289.931695) (xy 392.481655 -289.967035)
			(xy 392.441222 -289.996411) (xy 392.39669 -290.019101) (xy 392.349158 -290.034545) (xy 392.299795 -290.042364)
			(xy 392.249817 -290.042364) (xy 392.200454 -290.034545) (xy 392.152922 -290.019101) (xy 392.10839 -289.996411)
			(xy 392.067957 -289.967035) (xy 392.032617 -289.931695) (xy 392.003241 -289.891262) (xy 391.980551 -289.84673)
			(xy 391.965107 -289.799198) (xy 391.957288 -289.749835) (xy 391.655071 -289.749835) (xy 391.6481 -289.797021)
			(xy 391.634088 -289.843421) (xy 391.613451 -289.887277) (xy 391.600436 -289.907726) (xy 391.596928 -289.913831)
			(xy 391.59305 -289.92736) (xy 391.592816 -289.934396) (xy 391.592816 -290.465256) (xy 391.593045 -290.472293)
			(xy 391.596922 -290.485823) (xy 391.600436 -290.491926) (xy 391.613427 -290.512277) (xy 391.634003 -290.555953)
			(xy 391.648001 -290.602158) (xy 391.655124 -290.64991) (xy 391.655219 -290.698189) (xy 391.654986 -290.699795)
			(xy 391.957288 -290.699795) (xy 391.957288 -290.649817) (xy 391.965107 -290.600454) (xy 391.980551 -290.552922)
			(xy 392.003241 -290.50839) (xy 392.032617 -290.467957) (xy 392.067957 -290.432617) (xy 392.10839 -290.403241)
			(xy 392.152922 -290.380551) (xy 392.200454 -290.365107) (xy 392.249817 -290.357288) (xy 392.299795 -290.357288)
			(xy 392.349158 -290.365107) (xy 392.39669 -290.380551) (xy 392.441222 -290.403241) (xy 392.481655 -290.432617)
			(xy 392.516995 -290.467957) (xy 392.546371 -290.50839) (xy 392.569061 -290.552922) (xy 392.584505 -290.600454)
			(xy 392.592324 -290.649817) (xy 392.592814 -290.674806) (xy 392.592324 -290.699788) (xy 393.857488 -290.699788)
			(xy 393.857488 -290.649812) (xy 393.865306 -290.600452) (xy 393.880748 -290.552922) (xy 393.903436 -290.508394)
			(xy 393.93281 -290.467962) (xy 393.968147 -290.432623) (xy 394.008577 -290.403246) (xy 394.053104 -290.380556)
			(xy 394.100633 -290.36511) (xy 394.149992 -290.35729) (xy 394.17498 -290.356798) (xy 394.196 -290.357176)
			(xy 394.237667 -290.362779) (xy 394.258038 -290.367974) (xy 394.264642 -290.369752) (xy 394.53566 -290.369752)
			(xy 394.550684 -290.370315) (xy 394.579713 -290.378071) (xy 394.605752 -290.393066) (xy 394.627029 -290.414282)
			(xy 394.642101 -290.440277) (xy 394.649941 -290.469283) (xy 394.650468 -290.484306) (xy 394.650468 -290.865306)
			(xy 394.649973 -290.880301) (xy 394.642221 -290.909272) (xy 394.627245 -290.935255) (xy 394.606063 -290.956485)
			(xy 394.580115 -290.97152) (xy 394.551162 -290.979338) (xy 394.536168 -290.97986) (xy 394.264642 -290.97986)
			(xy 394.258038 -290.981638) (xy 394.237668 -290.986841) (xy 394.196001 -290.992444) (xy 394.17498 -290.992814)
			(xy 394.149992 -290.99231) (xy 394.100633 -290.98449) (xy 394.053104 -290.969044) (xy 394.008577 -290.946354)
			(xy 393.968147 -290.916977) (xy 393.93281 -290.881638) (xy 393.903436 -290.841206) (xy 393.880748 -290.796678)
			(xy 393.865306 -290.749148) (xy 393.857488 -290.699788) (xy 392.592324 -290.699788) (xy 392.592324 -290.699795)
			(xy 392.584505 -290.749158) (xy 392.569061 -290.79669) (xy 392.546371 -290.841222) (xy 392.516995 -290.881655)
			(xy 392.481655 -290.916995) (xy 392.441222 -290.946371) (xy 392.39669 -290.969061) (xy 392.349158 -290.984505)
			(xy 392.299795 -290.992324) (xy 392.249817 -290.992324) (xy 392.200454 -290.984505) (xy 392.152922 -290.969061)
			(xy 392.10839 -290.946371) (xy 392.067957 -290.916995) (xy 392.032617 -290.881655) (xy 392.003241 -290.841222)
			(xy 391.980551 -290.79669) (xy 391.965107 -290.749158) (xy 391.957288 -290.699795) (xy 391.654986 -290.699795)
			(xy 391.648285 -290.745968) (xy 391.634469 -290.792229) (xy 391.614065 -290.835985) (xy 391.601198 -290.856416)
			(xy 391.59688 -290.86302) (xy 391.594848 -290.869624) (xy 391.59388 -290.873164) (xy 391.592855 -290.880432)
			(xy 391.592816 -290.884102) (xy 391.592816 -290.907978) (xy 391.592987 -290.913987) (xy 391.595817 -290.925666)
			(xy 391.598404 -290.931092) (xy 391.600242 -290.934567) (xy 391.604834 -290.940948) (xy 391.607548 -290.943792)
			(xy 391.898378 -291.234622) (xy 391.90123 -291.237327) (xy 391.907609 -291.241917) (xy 391.911078 -291.243766)
			(xy 391.916505 -291.246347) (xy 391.928185 -291.249165) (xy 391.934192 -291.249354) (xy 391.951718 -291.249354)
			(xy 391.956544 -291.2491) (xy 392.502136 -291.2491) (xy 392.506962 -291.249354) (xy 392.655552 -291.249354)
			(xy 392.665617 -291.249788) (xy 392.684202 -291.257522) (xy 392.69162 -291.26434) (xy 392.849354 -291.422074)
			(xy 392.856194 -291.429474) (xy 392.863909 -291.448073) (xy 392.86434 -291.458142) (xy 392.86434 -296.548556)
			(xy 392.864507 -296.554566) (xy 392.867329 -296.566249) (xy 392.869928 -296.57167) (xy 392.871766 -296.575145)
			(xy 392.876357 -296.581527) (xy 392.879072 -296.58437) (xy 392.900408 -296.605706) (xy 392.90326 -296.60841)
			(xy 392.909641 -296.612999) (xy 392.913108 -296.61485) (xy 392.918533 -296.617439) (xy 392.930213 -296.620274)
			(xy 392.936222 -296.620438) (xy 393.422124 -296.620438)
		)
		(stroke
			(width 0)
			(type solid)
		)
		(fill yes)
		(layer "B.Cu")
		(net "P1V8_PEX")
	)
	(gr_poly
		(pts
			(xy 462.542128 -321.566286) (xy 462.552004 -321.565824) (xy 462.570299 -321.558377) (xy 462.577688 -321.551808)
			(xy 462.577942 -321.551554) (xy 462.909158 -321.220338) (xy 462.909666 -321.21983) (xy 462.916244 -321.212447)
			(xy 462.923687 -321.194148) (xy 462.924144 -321.18427) (xy 462.924144 -317.052706) (xy 462.92367 -317.042473)
			(xy 462.91568 -317.023629) (xy 462.900993 -317.009372) (xy 462.891632 -317.005208) (xy 462.815757 -316.97563)
			(xy 462.666642 -316.910124) (xy 462.520857 -316.837508) (xy 462.37874 -316.757953) (xy 462.240621 -316.671642)
			(xy 462.106821 -316.578776) (xy 461.977652 -316.479571) (xy 461.853412 -316.374258) (xy 461.734392 -316.26308)
			(xy 461.620867 -316.146297) (xy 461.5131 -316.024178) (xy 461.411344 -315.89701) (xy 461.315832 -315.765085)
			(xy 461.226789 -315.628712) (xy 461.14442 -315.488207) (xy 461.068917 -315.343896) (xy 461.000455 -315.196115)
			(xy 460.939193 -315.045206) (xy 460.885274 -314.891521) (xy 460.838823 -314.735416) (xy 460.799948 -314.577255)
			(xy 460.768738 -314.417404) (xy 460.745268 -314.256235) (xy 460.72959 -314.094122) (xy 460.721742 -313.931442)
			(xy 460.721742 -313.768573) (xy 460.729589 -313.605893) (xy 460.745266 -313.44378) (xy 460.768736 -313.28261)
			(xy 460.799945 -313.122759) (xy 460.838819 -312.964597) (xy 460.88527 -312.808493) (xy 460.939188 -312.654807)
			(xy 461.000449 -312.503898) (xy 461.068911 -312.356117) (xy 461.144413 -312.211806) (xy 461.226781 -312.0713)
			(xy 461.315824 -311.934926) (xy 461.411335 -311.803002) (xy 461.513091 -311.675832) (xy 461.620857 -311.553714)
			(xy 461.734382 -311.43693) (xy 461.853402 -311.325752) (xy 461.977641 -311.220438) (xy 462.10681 -311.121232)
			(xy 462.240609 -311.028366) (xy 462.378727 -310.942054) (xy 462.520844 -310.862498) (xy 462.666629 -310.789882)
			(xy 462.815744 -310.724376) (xy 462.891632 -310.694832) (xy 462.901026 -310.690721) (xy 462.915737 -310.676465)
			(xy 462.923675 -310.65758) (xy 462.924144 -310.647334) (xy 462.924144 -309.820818) (xy 462.923704 -309.810756)
			(xy 462.915963 -309.792178) (xy 462.909158 -309.78475) (xy 462.415128 -309.29072) (xy 462.408291 -309.283319)
			(xy 462.400581 -309.26472) (xy 462.400142 -309.254652) (xy 462.400142 -308.533292) (xy 462.399653 -308.523282)
			(xy 462.391994 -308.504786) (xy 462.377843 -308.490625) (xy 462.359351 -308.482954) (xy 462.349342 -308.482492)
			(xy 462.256124 -308.482492) (xy 462.230941 -308.481978) (xy 462.181199 -308.474066) (xy 462.133305 -308.45848)
			(xy 462.088433 -308.435603) (xy 462.047687 -308.405996) (xy 462.029556 -308.388512) (xy 461.981296 -308.340252)
			(xy 461.95488 -308.333394) (xy 461.941418 -308.337204) (xy 461.926111 -308.341204) (xy 461.894754 -308.345414)
			(xy 461.878934 -308.345586) (xy 461.878934 -308.345332) (xy 461.579722 -308.345332) (xy 461.579722 -308.345586)
			(xy 461.557388 -308.345246) (xy 461.513526 -308.336843) (xy 461.472162 -308.320003) (xy 461.434903 -308.29538)
			(xy 461.403194 -308.26393) (xy 461.378268 -308.226873) (xy 461.36109 -308.185649) (xy 461.352329 -308.141856)
			(xy 461.351884 -308.119526) (xy 461.351884 -307.902864) (xy 461.352378 -307.89286) (xy 461.360043 -307.874378)
			(xy 461.374194 -307.860232) (xy 461.39268 -307.852574) (xy 461.402684 -307.852064) (xy 461.411828 -307.852064)
			(xy 461.411828 -307.377592) (xy 461.411339 -307.367583) (xy 461.403679 -307.349089) (xy 461.389527 -307.334932)
			(xy 461.371036 -307.327265) (xy 461.361028 -307.326792) (xy 461.351884 -307.326792) (xy 461.351884 -307.05933)
			(xy 461.352679 -307.033225) (xy 461.364736 -306.982423) (xy 461.37576 -306.958746) (xy 461.382872 -306.944014)
			(xy 461.377792 -306.91201) (xy 461.366108 -306.900326) (xy 461.358674 -306.89361) (xy 461.340174 -306.885974)
			(xy 461.32016 -306.885974) (xy 461.30166 -306.89361) (xy 461.294226 -306.900326) (xy 460.960216 -307.234336)
			(xy 460.953536 -307.241747) (xy 460.945964 -307.260183) (xy 460.945484 -307.27015) (xy 460.945484 -307.904388)
			(xy 460.944969 -307.929571) (xy 460.937056 -307.979311) (xy 460.921468 -308.027204) (xy 460.898589 -308.072074)
			(xy 460.868981 -308.112818) (xy 460.851504 -308.130956) (xy 460.562198 -308.420262) (xy 460.555397 -308.427611)
			(xy 460.547688 -308.446073) (xy 460.547212 -308.456076) (xy 460.547212 -308.666642) (xy 460.547582 -308.675686)
			(xy 460.55387 -308.692645) (xy 460.565651 -308.706371) (xy 460.573374 -308.711092) (xy 460.66329 -308.760876)
			(xy 460.690722 -308.760114) (xy 460.70266 -308.753002) (xy 460.729971 -308.73665) (xy 460.788153 -308.71083)
			(xy 460.849352 -308.693321) (xy 460.912387 -308.684461) (xy 460.944214 -308.683914) (xy 460.97418 -308.684405)
			(xy 461.033598 -308.692229) (xy 461.091487 -308.707742) (xy 461.146855 -308.730678) (xy 461.198757 -308.760645)
			(xy 461.246303 -308.797129) (xy 461.28868 -308.839508) (xy 461.325163 -308.887055) (xy 461.355128 -308.938957)
			(xy 461.378063 -308.994327) (xy 461.393574 -309.052216) (xy 461.401396 -309.111634) (xy 461.401396 -309.171566)
			(xy 461.393574 -309.230984) (xy 461.378063 -309.288873) (xy 461.355128 -309.344243) (xy 461.325163 -309.396145)
			(xy 461.28868 -309.443692) (xy 461.246303 -309.486071) (xy 461.198757 -309.522555) (xy 461.146855 -309.552522)
			(xy 461.091487 -309.575458) (xy 461.033598 -309.590971) (xy 460.97418 -309.598795) (xy 460.944214 -309.59933)
			(xy 460.912388 -309.598763) (xy 460.849356 -309.589904) (xy 460.788159 -309.572397) (xy 460.729978 -309.54658)
			(xy 460.70266 -309.530242) (xy 460.690722 -309.52313) (xy 460.66329 -309.522368) (xy 460.573374 -309.572152)
			(xy 460.565647 -309.576861) (xy 460.553878 -309.590592) (xy 460.547621 -309.607559) (xy 460.547212 -309.616602)
			(xy 460.547212 -310.2483) (xy 460.546766 -310.273477) (xy 460.538924 -310.323216) (xy 460.523388 -310.371112)
			(xy 460.50054 -310.415983) (xy 460.470944 -310.456721) (xy 460.453486 -310.474868) (xy 459.416912 -311.511442)
			(xy 459.73441 -311.511442) (xy 459.738481 -311.45582) (xy 459.750607 -311.401383) (xy 459.77053 -311.349292)
			(xy 459.797826 -311.300657) (xy 459.831912 -311.256514) (xy 459.872061 -311.217805) (xy 459.917419 -311.185354)
			(xy 459.967019 -311.159853) (xy 460.019803 -311.141846) (xy 460.074646 -311.131716) (xy 460.13038 -311.129679)
			(xy 460.185817 -311.135779) (xy 460.239774 -311.149885) (xy 460.291103 -311.171697) (xy 460.338709 -311.200751)
			(xy 460.381577 -311.236426) (xy 460.418794 -311.277963) (xy 460.449567 -311.324476) (xy 460.473239 -311.374973)
			(xy 460.489307 -311.42838) (xy 460.497427 -311.483556) (xy 460.497936 -311.511442) (xy 460.497427 -311.539328)
			(xy 460.489307 -311.594504) (xy 460.473239 -311.647911) (xy 460.449567 -311.698408) (xy 460.418794 -311.744921)
			(xy 460.381577 -311.786458) (xy 460.338709 -311.822133) (xy 460.291103 -311.851187) (xy 460.239774 -311.872999)
			(xy 460.185817 -311.887105) (xy 460.13038 -311.893205) (xy 460.074646 -311.891168) (xy 460.019803 -311.881038)
			(xy 459.967019 -311.863031) (xy 459.917419 -311.83753) (xy 459.872061 -311.805079) (xy 459.831912 -311.76637)
			(xy 459.797826 -311.722227) (xy 459.77053 -311.673592) (xy 459.750607 -311.621501) (xy 459.738481 -311.567064)
			(xy 459.73441 -311.511442) (xy 459.416912 -311.511442) (xy 459.362556 -311.565798) (xy 459.344394 -311.583236)
			(xy 459.303645 -311.612804) (xy 459.258776 -311.63564) (xy 459.210889 -311.651182) (xy 459.161161 -311.659049)
			(xy 459.135988 -311.659524) (xy 458.849476 -311.659524) (xy 458.839931 -311.659972) (xy 458.822184 -311.667019)
			(xy 458.814932 -311.67324) (xy 458.793664 -311.69255) (xy 458.747155 -311.726269) (xy 458.696793 -311.753904)
			(xy 458.643368 -311.775019) (xy 458.587721 -311.789284) (xy 458.530727 -311.796473) (xy 458.502004 -311.796938)
			(xy 458.472033 -311.796469) (xy 458.412603 -311.788646) (xy 458.354703 -311.773132) (xy 458.299324 -311.750193)
			(xy 458.247412 -311.720222) (xy 458.199856 -311.683732) (xy 458.157471 -311.641347) (xy 458.12098 -311.593791)
			(xy 458.091009 -311.54188) (xy 458.06807 -311.4865) (xy 458.052555 -311.428601) (xy 458.044731 -311.369171)
			(xy 458.044731 -311.309229) (xy 458.052555 -311.249799) (xy 458.06807 -311.1919) (xy 458.091009 -311.13652)
			(xy 458.12098 -311.084609) (xy 458.157471 -311.037053) (xy 458.199856 -310.994668) (xy 458.247412 -310.958178)
			(xy 458.299324 -310.928207) (xy 458.354703 -310.905268) (xy 458.412603 -310.889754) (xy 458.472033 -310.881931)
			(xy 458.502004 -310.881522) (xy 458.530727 -310.881971) (xy 458.587721 -310.889162) (xy 458.643367 -310.903431)
			(xy 458.696789 -310.924553) (xy 458.747148 -310.952196) (xy 458.793649 -310.985925) (xy 458.814932 -311.00522)
			(xy 458.822168 -311.011469) (xy 458.839924 -311.018517) (xy 458.849476 -311.018936) (xy 458.982318 -311.018936)
			(xy 458.992305 -311.018396) (xy 459.010736 -311.010682) (xy 459.018132 -311.00395) (xy 459.891638 -310.130444)
			(xy 459.898447 -310.123099) (xy 459.906169 -310.104635) (xy 459.906624 -310.09463) (xy 459.906624 -308.302406)
			(xy 459.90707 -308.277229) (xy 459.914911 -308.22749) (xy 459.930449 -308.179594) (xy 459.953298 -308.134724)
			(xy 459.982895 -308.093988) (xy 460.00035 -308.075838) (xy 460.289656 -307.786532) (xy 460.296339 -307.779121)
			(xy 460.303924 -307.760686) (xy 460.304388 -307.750718) (xy 460.304388 -307.11648) (xy 460.304905 -307.091299)
			(xy 460.312825 -307.041562) (xy 460.328419 -306.993674) (xy 460.351305 -306.948811) (xy 460.380919 -306.908076)
			(xy 460.398368 -306.889912) (xy 461.324198 -305.964082) (xy 461.335438 -305.953078) (xy 461.359739 -305.9331)
			(xy 461.372712 -305.924204) (xy 461.382742 -305.916681) (xy 461.394485 -305.894563) (xy 461.395064 -305.88204)
			(xy 461.395064 -305.787806) (xy 461.393286 -305.786282) (xy 461.386377 -305.781115) (xy 461.370153 -305.77528)
			(xy 461.361536 -305.774852) (xy 460.763874 -305.774852) (xy 460.754977 -305.775293) (xy 460.738287 -305.781477)
			(xy 460.724712 -305.792987) (xy 460.719932 -305.800506) (xy 460.669386 -305.888644) (xy 460.669386 -305.916076)
			(xy 460.676244 -305.92776) (xy 460.69109 -305.954135) (xy 460.71447 -306.009963) (xy 460.730285 -306.068386)
			(xy 460.738259 -306.128383) (xy 460.738728 -306.158646) (xy 460.738238 -306.188614) (xy 460.730415 -306.248036)
			(xy 460.714902 -306.305929) (xy 460.691966 -306.361302) (xy 460.661999 -306.413208) (xy 460.625512 -306.460758)
			(xy 460.583132 -306.503138) (xy 460.535582 -306.539625) (xy 460.483676 -306.569592) (xy 460.428303 -306.592528)
			(xy 460.37041 -306.608041) (xy 460.310988 -306.615864) (xy 460.251052 -306.615864) (xy 460.19163 -306.608041)
			(xy 460.133737 -306.592528) (xy 460.078364 -306.569592) (xy 460.026458 -306.539625) (xy 459.978908 -306.503138)
			(xy 459.936528 -306.460758) (xy 459.900041 -306.413208) (xy 459.870074 -306.361302) (xy 459.847138 -306.305929)
			(xy 459.831625 -306.248036) (xy 459.823802 -306.188614) (xy 459.823312 -306.158646) (xy 459.823803 -306.128385)
			(xy 459.831783 -306.068391) (xy 459.847598 -306.009972) (xy 459.87097 -305.954145) (xy 459.885796 -305.92776)
			(xy 459.892654 -305.916076) (xy 459.892654 -305.888644) (xy 459.842108 -305.800506) (xy 459.83741 -305.792916)
			(xy 459.823819 -305.78136) (xy 459.807085 -305.775177) (xy 459.798166 -305.774852) (xy 459.583028 -305.774852)
			(xy 459.572965 -305.77529) (xy 459.554384 -305.783028) (xy 459.54696 -305.789838) (xy 458.798168 -306.53863)
			(xy 458.795536 -306.541359) (xy 458.791062 -306.547478) (xy 458.789278 -306.550822) (xy 458.774524 -306.577624)
			(xy 458.739547 -306.627822) (xy 458.6988 -306.673461) (xy 458.652872 -306.713882) (xy 458.602427 -306.748502)
			(xy 458.548193 -306.77682) (xy 458.490954 -306.798428) (xy 458.431536 -306.813013) (xy 458.370797 -306.820366)
			(xy 458.340206 -306.820824) (xy 453.73925 -306.820824) (xy 453.729184 -306.821257) (xy 453.710595 -306.828987)
			(xy 453.703182 -306.83581) (xy 453.312022 -307.22697) (xy 453.288107 -307.250127) (xy 453.235307 -307.290668)
			(xy 453.17767 -307.323977) (xy 453.116181 -307.349483) (xy 453.05189 -307.366752) (xy 452.985896 -307.375488)
			(xy 452.952612 -307.376068) (xy 452.92188 -307.375623) (xy 452.860865 -307.368215) (xy 452.801187 -307.353507)
			(xy 452.743718 -307.331712) (xy 452.689295 -307.303148) (xy 452.638712 -307.268232) (xy 452.592707 -307.227473)
			(xy 452.551951 -307.181466) (xy 452.517038 -307.130881) (xy 452.488477 -307.076456) (xy 452.466685 -307.018986)
			(xy 452.45198 -306.959308) (xy 452.444575 -306.898292) (xy 452.444104 -306.86756) (xy 452.444641 -306.834273)
			(xy 452.453365 -306.768272) (xy 452.470633 -306.703976) (xy 452.496148 -306.642485) (xy 452.529474 -306.584852)
			(xy 452.57004 -306.532064) (xy 452.593202 -306.50815) (xy 453.148192 -305.95316) (xy 453.172091 -305.929994)
			(xy 453.224896 -305.889472) (xy 453.282539 -305.856192) (xy 453.344034 -305.830723) (xy 453.408329 -305.813502)
			(xy 453.474322 -305.804825) (xy 453.507602 -305.804316) (xy 458.07376 -305.804316) (xy 458.083826 -305.803882)
			(xy 458.102416 -305.796155) (xy 458.109828 -305.78933) (xy 458.99197 -304.907188) (xy 459.015868 -304.884019)
			(xy 459.068671 -304.843493) (xy 459.126314 -304.810209) (xy 459.18781 -304.784736) (xy 459.252105 -304.767512)
			(xy 459.318099 -304.75883) (xy 459.35138 -304.758344) (xy 461.588612 -304.758344) (xy 461.62189 -304.758888)
			(xy 461.687877 -304.767574) (xy 461.752167 -304.784795) (xy 461.81366 -304.810258) (xy 461.871305 -304.843526)
			(xy 461.924116 -304.884032) (xy 461.948022 -304.907188) (xy 462.071974 -305.03114) (xy 462.095133 -305.055054)
			(xy 462.135678 -305.107854) (xy 462.16899 -305.16549) (xy 462.194501 -305.226979) (xy 462.211774 -305.29127)
			(xy 462.220515 -305.357265) (xy 462.221072 -305.39055) (xy 462.220598 -305.421496) (xy 462.213057 -305.482928)
			(xy 462.198116 -305.54299) (xy 462.175996 -305.600795) (xy 462.147025 -305.655489) (xy 462.111631 -305.706262)
			(xy 462.070336 -305.752364) (xy 462.047336 -305.773074) (xy 462.039507 -305.780664) (xy 462.030576 -305.800534)
			(xy 462.030064 -305.811428) (xy 462.030064 -306.002436) (xy 462.030558 -306.012442) (xy 462.038222 -306.030927)
			(xy 462.052373 -306.045078) (xy 462.070858 -306.052742) (xy 462.080864 -306.053236) (xy 462.090008 -306.053236)
			(xy 462.090008 -306.320698) (xy 462.089512 -306.341242) (xy 462.081992 -306.381639) (xy 462.067291 -306.420011)
			(xy 462.056988 -306.437792) (xy 462.053432 -306.443888) (xy 462.049876 -306.457096) (xy 462.049876 -306.891436)
			(xy 462.050198 -306.899716) (xy 462.055517 -306.915397) (xy 462.06029 -306.92217) (xy 462.074747 -306.942084)
			(xy 462.095508 -306.98669) (xy 462.106137 -307.034729) (xy 462.106772 -307.05933) (xy 462.106772 -307.275992)
			(xy 462.106353 -307.286012) (xy 462.098684 -307.304527) (xy 462.08451 -307.318695) (xy 462.065992 -307.326357)
			(xy 462.055972 -307.326792) (xy 462.046828 -307.326792) (xy 462.046828 -307.598064) (xy 462.047215 -307.60783)
			(xy 462.054391 -307.625991) (xy 462.060798 -307.63337) (xy 462.08188 -307.655214) (xy 462.088455 -307.661497)
			(xy 462.104861 -307.669314) (xy 462.113884 -307.670454) (xy 462.141399 -307.673648) (xy 462.194819 -307.688277)
			(xy 462.244926 -307.711877) (xy 462.290227 -307.743744) (xy 462.310226 -307.76291) (xy 462.313528 -307.766212)
			(xy 462.32097 -307.772907) (xy 462.339467 -307.780504) (xy 462.359463 -307.780478) (xy 462.3689 -307.777134)
			(xy 462.383124 -307.771292) (xy 462.400142 -307.745892) (xy 462.400142 -306.979066) (xy 462.400573 -306.969)
			(xy 462.4083 -306.950408) (xy 462.415128 -306.942998) (xy 462.909158 -306.448968) (xy 462.916004 -306.44157)
			(xy 462.923733 -306.422971) (xy 462.924144 -306.4129) (xy 462.924144 -297.224196) (xy 462.924569 -297.214127)
			(xy 462.93229 -297.195528) (xy 462.93913 -297.188128) (xy 464.362292 -295.764966) (xy 464.369134 -295.757566)
			(xy 464.376857 -295.738968) (xy 464.377278 -295.728898) (xy 464.377278 -278.78532) (xy 464.352132 -278.756872)
			(xy 464.332828 -278.754332) (xy 464.305555 -278.750364) (xy 464.252459 -278.735597) (xy 464.20204 -278.713343)
			(xy 464.155348 -278.684066) (xy 464.113355 -278.648375) (xy 464.076934 -278.607013) (xy 464.046844 -278.560841)
			(xy 464.023711 -278.51082) (xy 464.008016 -278.45799) (xy 464.000087 -278.403452) (xy 464.000087 -278.348341)
			(xy 464.008018 -278.293803) (xy 464.023713 -278.240974) (xy 464.046847 -278.190953) (xy 464.076938 -278.144781)
			(xy 464.11336 -278.10342) (xy 464.155354 -278.06773) (xy 464.202046 -278.038454) (xy 464.252466 -278.016201)
			(xy 464.305562 -278.001435) (xy 464.332828 -277.997412) (xy 464.352132 -277.994872) (xy 464.377278 -277.966424)
			(xy 464.377278 -273.246596) (xy 464.376854 -273.236527) (xy 464.369136 -273.217925) (xy 464.362292 -273.210528)
			(xy 463.737198 -272.585434) (xy 463.729801 -272.578584) (xy 463.711203 -272.570845) (xy 463.70113 -272.570448)
			(xy 458.892402 -272.570448) (xy 458.882333 -272.570872) (xy 458.863732 -272.578591) (xy 458.856334 -272.585434)
			(xy 458.852016 -272.589752) (xy 458.845176 -272.597152) (xy 458.837458 -272.615751) (xy 458.83703 -272.62582)
			(xy 458.83703 -273.516598) (xy 458.836608 -273.526669) (xy 458.828898 -273.545277) (xy 458.822044 -273.552666)
			(xy 458.77988 -273.59483) (xy 463.155028 -273.59483) (xy 463.159099 -273.539208) (xy 463.171225 -273.484771)
			(xy 463.191148 -273.43268) (xy 463.218444 -273.384045) (xy 463.25253 -273.339902) (xy 463.292679 -273.301193)
			(xy 463.338037 -273.268742) (xy 463.387637 -273.243241) (xy 463.440421 -273.225234) (xy 463.495264 -273.215104)
			(xy 463.550998 -273.213067) (xy 463.606435 -273.219167) (xy 463.660392 -273.233273) (xy 463.711721 -273.255085)
			(xy 463.759327 -273.284139) (xy 463.802195 -273.319814) (xy 463.839412 -273.361351) (xy 463.870185 -273.407864)
			(xy 463.893857 -273.458361) (xy 463.909925 -273.511768) (xy 463.918045 -273.566944) (xy 463.918554 -273.59483)
			(xy 463.918045 -273.622716) (xy 463.909925 -273.677892) (xy 463.893857 -273.731299) (xy 463.870185 -273.781796)
			(xy 463.839412 -273.828309) (xy 463.802195 -273.869846) (xy 463.759327 -273.905521) (xy 463.711721 -273.934575)
			(xy 463.660392 -273.956387) (xy 463.606435 -273.970493) (xy 463.550998 -273.976593) (xy 463.495264 -273.974556)
			(xy 463.440421 -273.964426) (xy 463.387637 -273.946419) (xy 463.338037 -273.920918) (xy 463.292679 -273.888467)
			(xy 463.25253 -273.849758) (xy 463.218444 -273.805615) (xy 463.191148 -273.75698) (xy 463.171225 -273.704889)
			(xy 463.159099 -273.650452) (xy 463.155028 -273.59483) (xy 458.77988 -273.59483) (xy 458.523848 -273.850862)
			(xy 458.516448 -273.857704) (xy 458.49785 -273.865426) (xy 458.48778 -273.865848) (xy 457.834492 -273.865848)
			(xy 457.824424 -273.866274) (xy 457.805826 -273.873996) (xy 457.798424 -273.880834) (xy 457.548996 -274.130262)
			(xy 457.541827 -274.138136) (xy 457.534088 -274.157947) (xy 457.535051 -274.179194) (xy 457.539344 -274.188936)
			(xy 457.589636 -274.290028) (xy 457.618338 -274.305014) (xy 457.634848 -274.302728) (xy 457.650579 -274.300686)
			(xy 457.682231 -274.298522) (xy 457.698094 -274.29841) (xy 457.72806 -274.2989) (xy 457.78748 -274.306722)
			(xy 457.845371 -274.322232) (xy 457.900742 -274.345167) (xy 457.952645 -274.375132) (xy 458.000194 -274.411616)
			(xy 458.042573 -274.453994) (xy 458.079059 -274.501541) (xy 458.109026 -274.553444) (xy 458.131962 -274.608814)
			(xy 458.147475 -274.666704) (xy 458.155299 -274.726124) (xy 458.155301 -274.786056) (xy 458.147479 -274.845476)
			(xy 458.131969 -274.903367) (xy 458.124472 -274.921468) (xy 459.370666 -274.921468) (xy 459.370666 -274.861532)
			(xy 459.378489 -274.80211) (xy 459.394002 -274.744217) (xy 459.416938 -274.688844) (xy 459.446905 -274.636938)
			(xy 459.483392 -274.589388) (xy 459.525772 -274.547008) (xy 459.573322 -274.510521) (xy 459.625228 -274.480554)
			(xy 459.680601 -274.457618) (xy 459.738494 -274.442105) (xy 459.797916 -274.434282) (xy 459.857852 -274.434282)
			(xy 459.917274 -274.442105) (xy 459.975167 -274.457618) (xy 460.03054 -274.480554) (xy 460.082446 -274.510521)
			(xy 460.129996 -274.547008) (xy 460.172376 -274.589388) (xy 460.208863 -274.636938) (xy 460.23883 -274.688844)
			(xy 460.261766 -274.744217) (xy 460.277279 -274.80211) (xy 460.285102 -274.861532) (xy 460.285592 -274.8915)
			(xy 460.285102 -274.921468) (xy 460.277279 -274.98089) (xy 460.261766 -275.038783) (xy 460.23883 -275.094156)
			(xy 460.208863 -275.146062) (xy 460.172376 -275.193612) (xy 460.129996 -275.235992) (xy 460.082446 -275.272479)
			(xy 460.03054 -275.302446) (xy 459.975167 -275.325382) (xy 459.917274 -275.340895) (xy 459.857852 -275.348718)
			(xy 459.797916 -275.348718) (xy 459.738494 -275.340895) (xy 459.680601 -275.325382) (xy 459.625228 -275.302446)
			(xy 459.573322 -275.272479) (xy 459.525772 -275.235992) (xy 459.483392 -275.193612) (xy 459.446905 -275.146062)
			(xy 459.416938 -275.094156) (xy 459.394002 -275.038783) (xy 459.378489 -274.98089) (xy 459.370666 -274.921468)
			(xy 458.124472 -274.921468) (xy 458.109035 -274.958738) (xy 458.07907 -275.010642) (xy 458.042587 -275.058191)
			(xy 458.000209 -275.100571) (xy 457.952662 -275.137057) (xy 457.90076 -275.167024) (xy 457.84539 -275.189961)
			(xy 457.7875 -275.205475) (xy 457.72808 -275.213299) (xy 457.668148 -275.213301) (xy 457.608728 -275.20548)
			(xy 457.550837 -275.18997) (xy 457.495465 -275.167037) (xy 457.443561 -275.137072) (xy 457.396012 -275.100589)
			(xy 457.353632 -275.058212) (xy 457.317146 -275.010665) (xy 457.287177 -274.958763) (xy 457.26424 -274.903394)
			(xy 457.248726 -274.845504) (xy 457.240901 -274.786084) (xy 457.240386 -274.756118) (xy 457.240503 -274.740255)
			(xy 457.242662 -274.708603) (xy 457.244704 -274.692872) (xy 457.24699 -274.676362) (xy 457.232004 -274.64766)
			(xy 457.130912 -274.597368) (xy 457.121155 -274.593134) (xy 457.099931 -274.592188) (xy 457.080132 -274.599891)
			(xy 457.072238 -274.60702) (xy 456.32091 -275.358348) (xy 460.866472 -275.358348) (xy 460.866472 -275.298412)
			(xy 460.874295 -275.23899) (xy 460.889808 -275.181097) (xy 460.912744 -275.125724) (xy 460.942711 -275.073818)
			(xy 460.979198 -275.026268) (xy 461.021578 -274.983888) (xy 461.069128 -274.947401) (xy 461.121034 -274.917434)
			(xy 461.176407 -274.894498) (xy 461.2343 -274.878985) (xy 461.293722 -274.871162) (xy 461.353658 -274.871162)
			(xy 461.41308 -274.878985) (xy 461.470973 -274.894498) (xy 461.526346 -274.917434) (xy 461.578252 -274.947401)
			(xy 461.625802 -274.983888) (xy 461.668182 -275.026268) (xy 461.704669 -275.073818) (xy 461.734636 -275.125724)
			(xy 461.757572 -275.181097) (xy 461.773085 -275.23899) (xy 461.780908 -275.298412) (xy 461.781398 -275.32838)
			(xy 461.780908 -275.358348) (xy 461.773085 -275.41777) (xy 461.757572 -275.475663) (xy 461.734636 -275.531036)
			(xy 461.704669 -275.582942) (xy 461.670992 -275.62683) (xy 463.093306 -275.62683) (xy 463.097377 -275.571208)
			(xy 463.109503 -275.516771) (xy 463.129426 -275.46468) (xy 463.156722 -275.416045) (xy 463.190808 -275.371902)
			(xy 463.230957 -275.333193) (xy 463.276315 -275.300742) (xy 463.325915 -275.275241) (xy 463.378699 -275.257234)
			(xy 463.433542 -275.247104) (xy 463.489276 -275.245067) (xy 463.544713 -275.251167) (xy 463.59867 -275.265273)
			(xy 463.649999 -275.287085) (xy 463.697605 -275.316139) (xy 463.740473 -275.351814) (xy 463.77769 -275.393351)
			(xy 463.808463 -275.439864) (xy 463.832135 -275.490361) (xy 463.848203 -275.543768) (xy 463.856323 -275.598944)
			(xy 463.856832 -275.62683) (xy 463.856323 -275.654716) (xy 463.848203 -275.709892) (xy 463.832135 -275.763299)
			(xy 463.808463 -275.813796) (xy 463.77769 -275.860309) (xy 463.740473 -275.901846) (xy 463.697605 -275.937521)
			(xy 463.649999 -275.966575) (xy 463.59867 -275.988387) (xy 463.544713 -276.002493) (xy 463.489276 -276.008593)
			(xy 463.433542 -276.006556) (xy 463.378699 -275.996426) (xy 463.325915 -275.978419) (xy 463.276315 -275.952918)
			(xy 463.230957 -275.920467) (xy 463.190808 -275.881758) (xy 463.156722 -275.837615) (xy 463.129426 -275.78898)
			(xy 463.109503 -275.736889) (xy 463.097377 -275.682452) (xy 463.093306 -275.62683) (xy 461.670992 -275.62683)
			(xy 461.668182 -275.630492) (xy 461.625802 -275.672872) (xy 461.578252 -275.709359) (xy 461.526346 -275.739326)
			(xy 461.470973 -275.762262) (xy 461.41308 -275.777775) (xy 461.353658 -275.785598) (xy 461.293722 -275.785598)
			(xy 461.2343 -275.777775) (xy 461.176407 -275.762262) (xy 461.121034 -275.739326) (xy 461.069128 -275.709359)
			(xy 461.021578 -275.672872) (xy 460.979198 -275.630492) (xy 460.942711 -275.582942) (xy 460.912744 -275.531036)
			(xy 460.889808 -275.475663) (xy 460.874295 -275.41777) (xy 460.866472 -275.358348) (xy 456.32091 -275.358348)
			(xy 455.156828 -276.52243) (xy 455.680808 -276.52243) (xy 455.680808 -276.462494) (xy 455.688631 -276.403072)
			(xy 455.704144 -276.345179) (xy 455.72708 -276.289806) (xy 455.757047 -276.2379) (xy 455.793534 -276.19035)
			(xy 455.835914 -276.14797) (xy 455.883464 -276.111483) (xy 455.93537 -276.081516) (xy 455.990743 -276.05858)
			(xy 456.048636 -276.043067) (xy 456.108058 -276.035244) (xy 456.167994 -276.035244) (xy 456.227416 -276.043067)
			(xy 456.285309 -276.05858) (xy 456.340682 -276.081516) (xy 456.392588 -276.111483) (xy 456.440138 -276.14797)
			(xy 456.482518 -276.19035) (xy 456.519005 -276.2379) (xy 456.548972 -276.289806) (xy 456.571908 -276.345179)
			(xy 456.587421 -276.403072) (xy 456.595244 -276.462494) (xy 456.595734 -276.492462) (xy 456.595244 -276.52243)
			(xy 456.587421 -276.581852) (xy 456.571908 -276.639745) (xy 456.558217 -276.672798) (xy 460.998806 -276.672798)
			(xy 460.998806 -276.612862) (xy 461.006629 -276.55344) (xy 461.022142 -276.495547) (xy 461.045078 -276.440174)
			(xy 461.075045 -276.388268) (xy 461.111532 -276.340718) (xy 461.153912 -276.298338) (xy 461.201462 -276.261851)
			(xy 461.253368 -276.231884) (xy 461.308741 -276.208948) (xy 461.366634 -276.193435) (xy 461.426056 -276.185612)
			(xy 461.485992 -276.185612) (xy 461.545414 -276.193435) (xy 461.603307 -276.208948) (xy 461.65868 -276.231884)
			(xy 461.710586 -276.261851) (xy 461.758136 -276.298338) (xy 461.800516 -276.340718) (xy 461.837003 -276.388268)
			(xy 461.86697 -276.440174) (xy 461.889906 -276.495547) (xy 461.905419 -276.55344) (xy 461.913242 -276.612862)
			(xy 461.913732 -276.64283) (xy 461.913242 -276.672798) (xy 461.905419 -276.73222) (xy 461.889906 -276.790113)
			(xy 461.86697 -276.845486) (xy 461.837003 -276.897392) (xy 461.800516 -276.944942) (xy 461.758136 -276.987322)
			(xy 461.710586 -277.023809) (xy 461.65868 -277.053776) (xy 461.603307 -277.076712) (xy 461.545414 -277.092225)
			(xy 461.485992 -277.100048) (xy 461.426056 -277.100048) (xy 461.366634 -277.092225) (xy 461.308741 -277.076712)
			(xy 461.253368 -277.053776) (xy 461.201462 -277.023809) (xy 461.153912 -276.987322) (xy 461.111532 -276.944942)
			(xy 461.075045 -276.897392) (xy 461.045078 -276.845486) (xy 461.022142 -276.790113) (xy 461.006629 -276.73222)
			(xy 460.998806 -276.672798) (xy 456.558217 -276.672798) (xy 456.548972 -276.695118) (xy 456.519005 -276.747024)
			(xy 456.482518 -276.794574) (xy 456.440138 -276.836954) (xy 456.392588 -276.873441) (xy 456.340682 -276.903408)
			(xy 456.285309 -276.926344) (xy 456.227416 -276.941857) (xy 456.167994 -276.94968) (xy 456.108058 -276.94968)
			(xy 456.048636 -276.941857) (xy 455.990743 -276.926344) (xy 455.93537 -276.903408) (xy 455.883464 -276.873441)
			(xy 455.835914 -276.836954) (xy 455.793534 -276.794574) (xy 455.757047 -276.747024) (xy 455.72708 -276.695118)
			(xy 455.704144 -276.639745) (xy 455.688631 -276.581852) (xy 455.680808 -276.52243) (xy 455.156828 -276.52243)
			(xy 455.037952 -276.641306) (xy 455.031274 -276.648718) (xy 455.023702 -276.667154) (xy 455.02322 -276.67712)
			(xy 455.02322 -277.91283) (xy 460.998316 -277.91283) (xy 460.998806 -277.882862) (xy 461.006629 -277.82344)
			(xy 461.022142 -277.765547) (xy 461.045078 -277.710174) (xy 461.075045 -277.658268) (xy 461.111532 -277.610718)
			(xy 461.153912 -277.568338) (xy 461.201462 -277.531851) (xy 461.253368 -277.501884) (xy 461.308741 -277.478948)
			(xy 461.366634 -277.463435) (xy 461.426056 -277.455612) (xy 461.485992 -277.455612) (xy 461.545414 -277.463435)
			(xy 461.603307 -277.478948) (xy 461.65868 -277.501884) (xy 461.710586 -277.531851) (xy 461.758136 -277.568338)
			(xy 461.800516 -277.610718) (xy 461.837003 -277.658268) (xy 461.838061 -277.6601) (xy 463.093306 -277.6601)
			(xy 463.097377 -277.604478) (xy 463.109503 -277.550041) (xy 463.129426 -277.49795) (xy 463.156722 -277.449315)
			(xy 463.190808 -277.405172) (xy 463.230957 -277.366463) (xy 463.276315 -277.334012) (xy 463.325915 -277.308511)
			(xy 463.378699 -277.290504) (xy 463.433542 -277.280374) (xy 463.489276 -277.278337) (xy 463.544713 -277.284437)
			(xy 463.59867 -277.298543) (xy 463.649999 -277.320355) (xy 463.697605 -277.349409) (xy 463.740473 -277.385084)
			(xy 463.77769 -277.426621) (xy 463.808463 -277.473134) (xy 463.832135 -277.523631) (xy 463.848203 -277.577038)
			(xy 463.856323 -277.632214) (xy 463.856832 -277.6601) (xy 463.856323 -277.687986) (xy 463.848203 -277.743162)
			(xy 463.832135 -277.796569) (xy 463.808463 -277.847066) (xy 463.77769 -277.893579) (xy 463.740473 -277.935116)
			(xy 463.697605 -277.970791) (xy 463.649999 -277.999845) (xy 463.59867 -278.021657) (xy 463.544713 -278.035763)
			(xy 463.489276 -278.041863) (xy 463.433542 -278.039826) (xy 463.378699 -278.029696) (xy 463.325915 -278.011689)
			(xy 463.276315 -277.986188) (xy 463.230957 -277.953737) (xy 463.190808 -277.915028) (xy 463.156722 -277.870885)
			(xy 463.129426 -277.82225) (xy 463.109503 -277.770159) (xy 463.097377 -277.715722) (xy 463.093306 -277.6601)
			(xy 461.838061 -277.6601) (xy 461.86697 -277.710174) (xy 461.889906 -277.765547) (xy 461.905419 -277.82344)
			(xy 461.913242 -277.882862) (xy 461.913732 -277.91283) (xy 461.913261 -277.941792) (xy 461.905946 -277.999252)
			(xy 461.891437 -278.055329) (xy 461.869965 -278.109126) (xy 461.841875 -278.159782) (xy 461.807615 -278.206488)
			(xy 461.767734 -278.248496) (xy 461.745584 -278.26716) (xy 461.737456 -278.274018) (xy 461.727804 -278.29256)
			(xy 461.7212 -278.387556) (xy 461.728312 -278.407368) (xy 461.735424 -278.414988) (xy 461.754527 -278.436275)
			(xy 461.786778 -278.48351) (xy 461.811619 -278.535029) (xy 461.828494 -278.589677) (xy 461.837024 -278.646233)
			(xy 461.837532 -278.67483) (xy 461.837046 -278.702081) (xy 461.82929 -278.756029) (xy 461.813935 -278.808324)
			(xy 461.791293 -278.857901) (xy 461.761827 -278.903751) (xy 461.726136 -278.944942) (xy 461.684945 -278.980633)
			(xy 461.639095 -279.010099) (xy 461.589518 -279.032741) (xy 461.537223 -279.048096) (xy 461.483275 -279.055852)
			(xy 461.428773 -279.055852) (xy 461.374825 -279.048096) (xy 461.32253 -279.032741) (xy 461.272953 -279.010099)
			(xy 461.227103 -278.980633) (xy 461.185912 -278.944942) (xy 461.150221 -278.903751) (xy 461.120755 -278.857901)
			(xy 461.098113 -278.808324) (xy 461.082758 -278.756029) (xy 461.075002 -278.702081) (xy 461.074516 -278.67483)
			(xy 461.075038 -278.646234) (xy 461.083578 -278.589684) (xy 461.100454 -278.535039) (xy 461.125292 -278.483522)
			(xy 461.157534 -278.436285) (xy 461.176624 -278.414988) (xy 461.183736 -278.407368) (xy 461.190848 -278.387556)
			(xy 461.184244 -278.29256) (xy 461.174592 -278.274018) (xy 461.166464 -278.26716) (xy 461.14428 -278.248532)
			(xy 461.104393 -278.206523) (xy 461.070129 -278.159813) (xy 461.042037 -278.10915) (xy 461.020568 -278.055346)
			(xy 461.006064 -277.999262) (xy 460.998758 -277.941795) (xy 460.998316 -277.91283) (xy 455.02322 -277.91283)
			(xy 455.02322 -278.823928) (xy 455.022678 -278.833914) (xy 455.01496 -278.85234) (xy 455.008234 -278.859742)
			(xy 454.96226 -278.90597) (xy 454.955454 -278.913316) (xy 454.947737 -278.931779) (xy 454.947274 -278.941784)
			(xy 454.947274 -279.162256) (xy 454.94684 -279.172321) (xy 454.939108 -279.190908) (xy 454.932288 -279.198324)
			(xy 454.858882 -279.27173) (xy 454.851486 -279.278581) (xy 454.832887 -279.28632) (xy 454.822814 -279.286716)
			(xy 454.158604 -279.286716) (xy 454.148534 -279.287139) (xy 454.12993 -279.294854) (xy 454.122536 -279.301702)
			(xy 454.029064 -279.395174) (xy 454.022222 -279.402574) (xy 454.014505 -279.421172) (xy 454.014078 -279.431242)
			(xy 454.014078 -279.720798) (xy 460.998806 -279.720798) (xy 460.998806 -279.660862) (xy 461.006629 -279.60144)
			(xy 461.022142 -279.543547) (xy 461.045078 -279.488174) (xy 461.075045 -279.436268) (xy 461.111532 -279.388718)
			(xy 461.153912 -279.346338) (xy 461.201462 -279.309851) (xy 461.253368 -279.279884) (xy 461.308741 -279.256948)
			(xy 461.366634 -279.241435) (xy 461.426056 -279.233612) (xy 461.485992 -279.233612) (xy 461.545414 -279.241435)
			(xy 461.603307 -279.256948) (xy 461.65868 -279.279884) (xy 461.710586 -279.309851) (xy 461.758136 -279.346338)
			(xy 461.800516 -279.388718) (xy 461.837003 -279.436268) (xy 461.843193 -279.44699) (xy 463.093306 -279.44699)
			(xy 463.097377 -279.391368) (xy 463.109503 -279.336931) (xy 463.129426 -279.28484) (xy 463.156722 -279.236205)
			(xy 463.190808 -279.192062) (xy 463.230957 -279.153353) (xy 463.276315 -279.120902) (xy 463.325915 -279.095401)
			(xy 463.378699 -279.077394) (xy 463.433542 -279.067264) (xy 463.489276 -279.065227) (xy 463.544713 -279.071327)
			(xy 463.59867 -279.085433) (xy 463.649999 -279.107245) (xy 463.697605 -279.136299) (xy 463.740473 -279.171974)
			(xy 463.77769 -279.213511) (xy 463.808463 -279.260024) (xy 463.832135 -279.310521) (xy 463.848203 -279.363928)
			(xy 463.856323 -279.419104) (xy 463.856832 -279.44699) (xy 463.856323 -279.474876) (xy 463.848203 -279.530052)
			(xy 463.832135 -279.583459) (xy 463.808463 -279.633956) (xy 463.77769 -279.680469) (xy 463.740473 -279.722006)
			(xy 463.697605 -279.757681) (xy 463.649999 -279.786735) (xy 463.59867 -279.808547) (xy 463.544713 -279.822653)
			(xy 463.489276 -279.828753) (xy 463.433542 -279.826716) (xy 463.378699 -279.816586) (xy 463.325915 -279.798579)
			(xy 463.276315 -279.773078) (xy 463.230957 -279.740627) (xy 463.190808 -279.701918) (xy 463.156722 -279.657775)
			(xy 463.129426 -279.60914) (xy 463.109503 -279.557049) (xy 463.097377 -279.502612) (xy 463.093306 -279.44699)
			(xy 461.843193 -279.44699) (xy 461.86697 -279.488174) (xy 461.889906 -279.543547) (xy 461.905419 -279.60144)
			(xy 461.913242 -279.660862) (xy 461.913732 -279.69083) (xy 461.913242 -279.720798) (xy 461.905419 -279.78022)
			(xy 461.889906 -279.838113) (xy 461.86697 -279.893486) (xy 461.837003 -279.945392) (xy 461.800516 -279.992942)
			(xy 461.758136 -280.035322) (xy 461.710586 -280.071809) (xy 461.65868 -280.101776) (xy 461.603307 -280.124712)
			(xy 461.545414 -280.140225) (xy 461.485992 -280.148048) (xy 461.426056 -280.148048) (xy 461.366634 -280.140225)
			(xy 461.308741 -280.124712) (xy 461.253368 -280.101776) (xy 461.201462 -280.071809) (xy 461.153912 -280.035322)
			(xy 461.111532 -279.992942) (xy 461.075045 -279.945392) (xy 461.045078 -279.893486) (xy 461.022142 -279.838113)
			(xy 461.006629 -279.78022) (xy 460.998806 -279.720798) (xy 454.014078 -279.720798) (xy 454.014078 -280.349706)
			(xy 454.014502 -280.359776) (xy 454.022215 -280.378381) (xy 454.029064 -280.385774) (xy 454.078086 -280.434796)
			(xy 454.085489 -280.441629) (xy 454.104087 -280.449333) (xy 454.114154 -280.449782) (xy 456.939396 -280.449782)
			(xy 456.951134 -280.449266) (xy 456.972213 -280.438953) (xy 456.979782 -280.42997) (xy 457.03617 -280.356564)
			(xy 457.040742 -280.333704) (xy 457.037694 -280.322274) (xy 457.031751 -280.298265) (xy 457.025381 -280.249215)
			(xy 457.024994 -280.224484) (xy 457.02548 -280.197233) (xy 457.033236 -280.143285) (xy 457.048591 -280.09099)
			(xy 457.071233 -280.041413) (xy 457.100699 -279.995563) (xy 457.13639 -279.954372) (xy 457.177581 -279.918681)
			(xy 457.223431 -279.889215) (xy 457.273008 -279.866573) (xy 457.325303 -279.851218) (xy 457.379251 -279.843462)
			(xy 457.433753 -279.843462) (xy 457.487701 -279.851218) (xy 457.539996 -279.866573) (xy 457.589573 -279.889215)
			(xy 457.635423 -279.918681) (xy 457.676614 -279.954372) (xy 457.712305 -279.995563) (xy 457.741771 -280.041413)
			(xy 457.764413 -280.09099) (xy 457.779768 -280.143285) (xy 457.787524 -280.197233) (xy 457.78801 -280.224484)
			(xy 457.787634 -280.249216) (xy 457.781263 -280.298266) (xy 457.77531 -280.322274) (xy 457.772262 -280.333704)
			(xy 457.776834 -280.356564) (xy 457.833222 -280.42997) (xy 457.840853 -280.438883) (xy 457.86189 -280.449218)
			(xy 457.873608 -280.449782) (xy 459.36281 -280.449782) (xy 459.372235 -280.449401) (xy 459.389806 -280.442573)
			(xy 459.403713 -280.429847) (xy 459.408276 -280.421588) (xy 459.422853 -280.393277) (xy 459.458667 -280.340626)
			(xy 459.501433 -280.293447) (xy 459.550325 -280.252651) (xy 459.604399 -280.219025) (xy 459.662612 -280.193219)
			(xy 459.72384 -280.17573) (xy 459.786902 -280.166896) (xy 459.81874 -280.166318) (xy 459.848705 -280.166811)
			(xy 459.908123 -280.174638) (xy 459.96601 -280.190154) (xy 460.021377 -280.213093) (xy 460.073276 -280.243062)
			(xy 460.12082 -280.279549) (xy 460.163194 -280.32193) (xy 460.199674 -280.369479) (xy 460.229636 -280.421382)
			(xy 460.252567 -280.476753) (xy 460.268075 -280.534642) (xy 460.275894 -280.594061) (xy 460.276448 -280.624026)
			(xy 460.276448 -280.629868) (xy 460.276194 -280.640282) (xy 460.283814 -280.658824) (xy 460.319628 -280.694638)
			(xy 460.326476 -280.702035) (xy 460.334208 -280.720634) (xy 460.334614 -280.730706) (xy 460.334614 -280.96083)
			(xy 463.093306 -280.96083) (xy 463.097377 -280.905208) (xy 463.109503 -280.850771) (xy 463.129426 -280.79868)
			(xy 463.156722 -280.750045) (xy 463.190808 -280.705902) (xy 463.230957 -280.667193) (xy 463.276315 -280.634742)
			(xy 463.325915 -280.609241) (xy 463.378699 -280.591234) (xy 463.433542 -280.581104) (xy 463.489276 -280.579067)
			(xy 463.544713 -280.585167) (xy 463.59867 -280.599273) (xy 463.649999 -280.621085) (xy 463.697605 -280.650139)
			(xy 463.740473 -280.685814) (xy 463.77769 -280.727351) (xy 463.808463 -280.773864) (xy 463.832135 -280.824361)
			(xy 463.848203 -280.877768) (xy 463.856323 -280.932944) (xy 463.856832 -280.96083) (xy 463.856323 -280.988716)
			(xy 463.848203 -281.043892) (xy 463.832135 -281.097299) (xy 463.808463 -281.147796) (xy 463.77769 -281.194309)
			(xy 463.740473 -281.235846) (xy 463.697605 -281.271521) (xy 463.649999 -281.300575) (xy 463.59867 -281.322387)
			(xy 463.544713 -281.336493) (xy 463.489276 -281.342593) (xy 463.433542 -281.340556) (xy 463.378699 -281.330426)
			(xy 463.325915 -281.312419) (xy 463.276315 -281.286918) (xy 463.230957 -281.254467) (xy 463.190808 -281.215758)
			(xy 463.156722 -281.171615) (xy 463.129426 -281.12298) (xy 463.109503 -281.070889) (xy 463.097377 -281.016452)
			(xy 463.093306 -280.96083) (xy 460.334614 -280.96083) (xy 460.334614 -281.709114) (xy 460.33504 -281.719183)
			(xy 460.34276 -281.737782) (xy 460.3496 -281.745182) (xy 460.351886 -281.747468) (xy 460.34833 -281.751024)
			(xy 460.341484 -281.758422) (xy 460.333754 -281.777021) (xy 460.333344 -281.787092) (xy 460.333344 -293.39667)
			(xy 460.332907 -293.406733) (xy 460.325168 -293.425314) (xy 460.318358 -293.432738) (xy 459.659482 -294.091614)
			(xy 459.652087 -294.098467) (xy 459.633488 -294.106208) (xy 459.623414 -294.1066) (xy 451.872858 -294.1066)
			(xy 451.862791 -294.106169) (xy 451.844198 -294.098444) (xy 451.83679 -294.091614) (xy 451.753478 -294.008302)
			(xy 451.746623 -294.000907) (xy 451.738875 -293.982308) (xy 451.738492 -293.972234) (xy 451.738492 -285.348934)
			(xy 451.738057 -285.338869) (xy 451.730324 -285.320283) (xy 451.723506 -285.312866) (xy 450.792342 -284.381702)
			(xy 450.78494 -284.374864) (xy 450.766342 -284.367151) (xy 450.756274 -284.366716) (xy 447.078608 -284.366716)
			(xy 447.068587 -284.367134) (xy 447.05007 -284.374803) (xy 447.035899 -284.388977) (xy 447.028233 -284.407495)
			(xy 447.027808 -284.417516) (xy 447.027808 -295.331388) (xy 447.028229 -295.341459) (xy 447.035941 -295.360066)
			(xy 447.042794 -295.367456) (xy 448.831208 -297.15587) (xy 448.838043 -297.163273) (xy 448.84575 -297.181871)
			(xy 448.846194 -297.191938) (xy 448.846194 -305.4858) (xy 448.846427 -305.493069) (xy 448.850565 -305.507004)
			(xy 448.854322 -305.513232) (xy 448.871594 -305.54041) (xy 448.882262 -305.549808) (xy 448.888866 -305.552856)
			(xy 448.963809 -305.588693) (xy 449.110465 -305.666757) (xy 449.253107 -305.751933) (xy 449.391391 -305.844018)
			(xy 449.524982 -305.942787) (xy 449.653557 -306.048002) (xy 449.776807 -306.159409) (xy 449.894432 -306.276739)
			(xy 450.006148 -306.399707) (xy 450.111687 -306.528018) (xy 450.210791 -306.66136) (xy 450.303223 -306.799412)
			(xy 450.388758 -306.941839) (xy 450.46719 -307.088299) (xy 450.53833 -307.238436) (xy 450.602005 -307.391887)
			(xy 450.658061 -307.548283) (xy 450.673727 -307.599838) (xy 457.420962 -307.599838) (xy 457.420962 -307.539902)
			(xy 457.428785 -307.48048) (xy 457.444298 -307.422587) (xy 457.467234 -307.367214) (xy 457.497201 -307.315308)
			(xy 457.533688 -307.267758) (xy 457.576068 -307.225378) (xy 457.623618 -307.188891) (xy 457.675524 -307.158924)
			(xy 457.730897 -307.135988) (xy 457.78879 -307.120475) (xy 457.848212 -307.112652) (xy 457.908148 -307.112652)
			(xy 457.96757 -307.120475) (xy 458.025463 -307.135988) (xy 458.080836 -307.158924) (xy 458.132742 -307.188891)
			(xy 458.180292 -307.225378) (xy 458.222672 -307.267758) (xy 458.259159 -307.315308) (xy 458.289126 -307.367214)
			(xy 458.312062 -307.422587) (xy 458.327575 -307.48048) (xy 458.335398 -307.539902) (xy 458.335888 -307.56987)
			(xy 458.335398 -307.599838) (xy 458.327575 -307.65926) (xy 458.312062 -307.717153) (xy 458.289126 -307.772526)
			(xy 458.259159 -307.824432) (xy 458.222672 -307.871982) (xy 458.180292 -307.914362) (xy 458.132742 -307.950849)
			(xy 458.080836 -307.980816) (xy 458.025463 -308.003752) (xy 457.96757 -308.019265) (xy 457.908148 -308.027088)
			(xy 457.848212 -308.027088) (xy 457.78879 -308.019265) (xy 457.730897 -308.003752) (xy 457.675524 -307.980816)
			(xy 457.623618 -307.950849) (xy 457.576068 -307.914362) (xy 457.533688 -307.871982) (xy 457.497201 -307.824432)
			(xy 457.467234 -307.772526) (xy 457.444298 -307.717153) (xy 457.428785 -307.65926) (xy 457.420962 -307.599838)
			(xy 450.673727 -307.599838) (xy 450.706363 -307.707244) (xy 450.746795 -307.868388) (xy 450.779258 -308.031324)
			(xy 450.803674 -308.195658) (xy 450.819985 -308.360993) (xy 450.82815 -308.526931) (xy 450.82815 -308.55564)
			(xy 458.478872 -308.55564) (xy 458.478872 -308.495704) (xy 458.486695 -308.436282) (xy 458.502208 -308.378389)
			(xy 458.525144 -308.323016) (xy 458.555111 -308.27111) (xy 458.591598 -308.22356) (xy 458.633978 -308.18118)
			(xy 458.681528 -308.144693) (xy 458.733434 -308.114726) (xy 458.788807 -308.09179) (xy 458.8467 -308.076277)
			(xy 458.906122 -308.068454) (xy 458.966058 -308.068454) (xy 459.02548 -308.076277) (xy 459.083373 -308.09179)
			(xy 459.138746 -308.114726) (xy 459.190652 -308.144693) (xy 459.238202 -308.18118) (xy 459.280582 -308.22356)
			(xy 459.317069 -308.27111) (xy 459.347036 -308.323016) (xy 459.369972 -308.378389) (xy 459.385485 -308.436282)
			(xy 459.393308 -308.495704) (xy 459.393798 -308.525672) (xy 459.393308 -308.55564) (xy 459.385485 -308.615062)
			(xy 459.369972 -308.672955) (xy 459.347036 -308.728328) (xy 459.317069 -308.780234) (xy 459.280582 -308.827784)
			(xy 459.238202 -308.870164) (xy 459.190652 -308.906651) (xy 459.138746 -308.936618) (xy 459.083373 -308.959554)
			(xy 459.02548 -308.975067) (xy 458.966058 -308.98289) (xy 458.906122 -308.98289) (xy 458.8467 -308.975067)
			(xy 458.788807 -308.959554) (xy 458.733434 -308.936618) (xy 458.681528 -308.906651) (xy 458.633978 -308.870164)
			(xy 458.591598 -308.827784) (xy 458.555111 -308.780234) (xy 458.525144 -308.728328) (xy 458.502208 -308.672955)
			(xy 458.486695 -308.615062) (xy 458.478872 -308.55564) (xy 450.82815 -308.55564) (xy 450.82815 -308.693069)
			(xy 450.819985 -308.859007) (xy 450.803674 -309.024342) (xy 450.779258 -309.188676) (xy 450.746795 -309.351612)
			(xy 450.706363 -309.512756) (xy 450.658061 -309.671717) (xy 450.602005 -309.828113) (xy 450.53833 -309.981564)
			(xy 450.500283 -310.06186) (xy 456.866988 -310.06186) (xy 456.866988 -310.001924) (xy 456.874811 -309.942502)
			(xy 456.890324 -309.884609) (xy 456.91326 -309.829236) (xy 456.943227 -309.77733) (xy 456.979714 -309.72978)
			(xy 457.022094 -309.6874) (xy 457.069644 -309.650913) (xy 457.12155 -309.620946) (xy 457.176923 -309.59801)
			(xy 457.234816 -309.582497) (xy 457.294238 -309.574674) (xy 457.354174 -309.574674) (xy 457.413596 -309.582497)
			(xy 457.471489 -309.59801) (xy 457.526862 -309.620946) (xy 457.578768 -309.650913) (xy 457.626318 -309.6874)
			(xy 457.668698 -309.72978) (xy 457.705185 -309.77733) (xy 457.735152 -309.829236) (xy 457.758088 -309.884609)
			(xy 457.76182 -309.898538) (xy 458.582504 -309.898538) (xy 458.582504 -309.838602) (xy 458.590327 -309.77918)
			(xy 458.60584 -309.721287) (xy 458.628776 -309.665914) (xy 458.658743 -309.614008) (xy 458.69523 -309.566458)
			(xy 458.73761 -309.524078) (xy 458.78516 -309.487591) (xy 458.837066 -309.457624) (xy 458.892439 -309.434688)
			(xy 458.950332 -309.419175) (xy 459.009754 -309.411352) (xy 459.06969 -309.411352) (xy 459.129112 -309.419175)
			(xy 459.187005 -309.434688) (xy 459.242378 -309.457624) (xy 459.294284 -309.487591) (xy 459.341834 -309.524078)
			(xy 459.384214 -309.566458) (xy 459.420701 -309.614008) (xy 459.450668 -309.665914) (xy 459.473604 -309.721287)
			(xy 459.489117 -309.77918) (xy 459.49694 -309.838602) (xy 459.49743 -309.86857) (xy 459.49694 -309.898538)
			(xy 459.489117 -309.95796) (xy 459.473604 -310.015853) (xy 459.450668 -310.071226) (xy 459.420701 -310.123132)
			(xy 459.384214 -310.170682) (xy 459.341834 -310.213062) (xy 459.294284 -310.249549) (xy 459.242378 -310.279516)
			(xy 459.187005 -310.302452) (xy 459.129112 -310.317965) (xy 459.06969 -310.325788) (xy 459.009754 -310.325788)
			(xy 458.950332 -310.317965) (xy 458.892439 -310.302452) (xy 458.837066 -310.279516) (xy 458.78516 -310.249549)
			(xy 458.73761 -310.213062) (xy 458.69523 -310.170682) (xy 458.658743 -310.123132) (xy 458.628776 -310.071226)
			(xy 458.60584 -310.015853) (xy 458.590327 -309.95796) (xy 458.582504 -309.898538) (xy 457.76182 -309.898538)
			(xy 457.773601 -309.942502) (xy 457.781424 -310.001924) (xy 457.781914 -310.031892) (xy 457.781424 -310.06186)
			(xy 457.773601 -310.121282) (xy 457.758088 -310.179175) (xy 457.735152 -310.234548) (xy 457.705185 -310.286454)
			(xy 457.668698 -310.334004) (xy 457.626318 -310.376384) (xy 457.578768 -310.412871) (xy 457.526862 -310.442838)
			(xy 457.471489 -310.465774) (xy 457.413596 -310.481287) (xy 457.354174 -310.48911) (xy 457.294238 -310.48911)
			(xy 457.234816 -310.481287) (xy 457.176923 -310.465774) (xy 457.12155 -310.442838) (xy 457.069644 -310.412871)
			(xy 457.022094 -310.376384) (xy 456.979714 -310.334004) (xy 456.943227 -310.286454) (xy 456.91326 -310.234548)
			(xy 456.890324 -310.179175) (xy 456.874811 -310.121282) (xy 456.866988 -310.06186) (xy 450.500283 -310.06186)
			(xy 450.46719 -310.131701) (xy 450.388758 -310.278161) (xy 450.303223 -310.420588) (xy 450.210791 -310.55864)
			(xy 450.111687 -310.691982) (xy 450.006148 -310.820293) (xy 449.894432 -310.943261) (xy 449.776807 -311.060591)
			(xy 449.653557 -311.171998) (xy 449.524982 -311.277213) (xy 449.391391 -311.375982) (xy 449.253107 -311.468067)
			(xy 449.110465 -311.553243) (xy 448.963809 -311.631307) (xy 448.888866 -311.667144) (xy 448.882262 -311.670192)
			(xy 448.871594 -311.67959) (xy 448.854322 -311.706768) (xy 448.850613 -311.713016) (xy 448.84648 -311.72694)
			(xy 448.846194 -311.7342) (xy 448.846194 -320.43116) (xy 448.846628 -320.441226) (xy 448.854357 -320.459815)
			(xy 448.86118 -320.467228) (xy 449.334128 -320.940176) (xy 455.509122 -320.940176) (xy 455.509569 -320.912805)
			(xy 455.51739 -320.858625) (xy 455.532884 -320.806121) (xy 455.55573 -320.756375) (xy 455.585459 -320.710409)
			(xy 455.603102 -320.689478) (xy 455.609198 -320.682366) (xy 455.615548 -320.665348) (xy 455.615548 -320.580004)
			(xy 455.609198 -320.562986) (xy 455.603102 -320.555874) (xy 455.585484 -320.534925) (xy 455.555769 -320.488957)
			(xy 455.532929 -320.439213) (xy 455.517433 -320.386717) (xy 455.509599 -320.332544) (xy 455.509122 -320.305176)
			(xy 455.509533 -320.277921) (xy 455.517294 -320.223967) (xy 455.532654 -320.171666) (xy 455.555302 -320.122084)
			(xy 455.584775 -320.076229) (xy 455.620474 -320.035036) (xy 455.661673 -319.999343) (xy 455.707531 -319.969876)
			(xy 455.757117 -319.947235) (xy 455.80942 -319.931882) (xy 455.863375 -319.924129) (xy 455.89063 -319.923668)
			(xy 455.918002 -319.9241) (xy 455.972183 -319.931923) (xy 456.024687 -319.94742) (xy 456.074433 -319.970269)
			(xy 456.120398 -320.000002) (xy 456.141328 -320.017648) (xy 456.14844 -320.023744) (xy 456.165458 -320.030094)
			(xy 456.250802 -320.030094) (xy 456.26782 -320.023744) (xy 456.274932 -320.017648) (xy 456.295865 -320.000007)
			(xy 456.341833 -319.970283) (xy 456.391579 -319.947437) (xy 456.444081 -319.931941) (xy 456.498259 -319.924112)
			(xy 456.553001 -319.924112) (xy 456.607179 -319.931941) (xy 456.659681 -319.947437) (xy 456.709427 -319.970283)
			(xy 456.755395 -320.000007) (xy 456.776328 -320.017648) (xy 456.78344 -320.023744) (xy 456.800458 -320.030094)
			(xy 456.885802 -320.030094) (xy 456.90282 -320.023744) (xy 456.909932 -320.017648) (xy 456.930885 -320.000035)
			(xy 456.976851 -319.970317) (xy 457.026593 -319.947476) (xy 457.07909 -319.931979) (xy 457.133262 -319.924145)
			(xy 457.16063 -319.923668) (xy 457.187881 -319.92415) (xy 457.241828 -319.93191) (xy 457.294121 -319.947268)
			(xy 457.343697 -319.96991) (xy 457.389546 -319.999378) (xy 457.430735 -320.035069) (xy 457.466426 -320.076259)
			(xy 457.495892 -320.122109) (xy 457.518535 -320.171685) (xy 457.533891 -320.223978) (xy 457.541651 -320.277925)
			(xy 457.542138 -320.305176) (xy 457.541673 -320.332546) (xy 457.533857 -320.386726) (xy 457.518369 -320.43923)
			(xy 457.495526 -320.488977) (xy 457.4658 -320.534943) (xy 457.448158 -320.555874) (xy 457.442062 -320.562986)
			(xy 457.435712 -320.580004) (xy 457.435712 -320.665348) (xy 457.442062 -320.682366) (xy 457.448158 -320.689478)
			(xy 457.465794 -320.710413) (xy 457.495507 -320.756384) (xy 457.518345 -320.806131) (xy 457.533836 -320.858631)
			(xy 457.541664 -320.912807) (xy 457.542138 -320.940176) (xy 457.5416 -320.967425) (xy 457.533847 -321.021369)
			(xy 457.518496 -321.073661) (xy 457.49586 -321.123236) (xy 457.466399 -321.169085) (xy 457.430713 -321.210275)
			(xy 457.389529 -321.245967) (xy 457.343684 -321.275434) (xy 457.294112 -321.298078) (xy 457.241822 -321.313436)
			(xy 457.187879 -321.321196) (xy 457.16063 -321.321684) (xy 457.13326 -321.321204) (xy 457.079082 -321.31339)
			(xy 457.026578 -321.297905) (xy 456.976831 -321.275066) (xy 456.930864 -321.245344) (xy 456.909932 -321.227704)
			(xy 456.90282 -321.221608) (xy 456.885802 -321.215258) (xy 456.800458 -321.215258) (xy 456.78344 -321.221608)
			(xy 456.776328 -321.227704) (xy 456.755395 -321.245345) (xy 456.709427 -321.275069) (xy 456.659681 -321.297915)
			(xy 456.607179 -321.313411) (xy 456.553001 -321.32124) (xy 456.498259 -321.32124) (xy 456.444081 -321.313411)
			(xy 456.391579 -321.297915) (xy 456.341833 -321.275069) (xy 456.295865 -321.245345) (xy 456.274932 -321.227704)
			(xy 456.26782 -321.221608) (xy 456.250802 -321.215258) (xy 456.165458 -321.215258) (xy 456.14844 -321.221608)
			(xy 456.141328 -321.227704) (xy 456.120397 -321.245344) (xy 456.074424 -321.275056) (xy 456.024676 -321.297891)
			(xy 455.972175 -321.313382) (xy 455.917999 -321.32121) (xy 455.89063 -321.321684) (xy 455.863377 -321.321217)
			(xy 455.809425 -321.313463) (xy 455.757126 -321.29811) (xy 455.707544 -321.275469) (xy 455.661689 -321.246002)
			(xy 455.620496 -321.210308) (xy 455.584802 -321.169115) (xy 455.555334 -321.123261) (xy 455.532692 -321.07368)
			(xy 455.517338 -321.021381) (xy 455.509584 -320.967429) (xy 455.509122 -320.940176) (xy 449.334128 -320.940176)
			(xy 449.945252 -321.5513) (xy 449.952653 -321.558138) (xy 449.971251 -321.565854) (xy 449.98132 -321.566286)
		)
		(stroke
			(width 0)
			(type solid)
		)
		(fill yes)
		(layer "B.Cu")
		(net "GND")
	)
	(gr_poly
		(pts
			(xy 333.270606 -218.262962) (xy 333.274476 -218.262911) (xy 333.282129 -218.261756) (xy 333.285846 -218.260676)
			(xy 333.300832 -218.25585) (xy 333.301086 -218.25585) (xy 333.304798 -218.254724) (xy 333.31245 -218.253452)
			(xy 333.316326 -218.25331) (xy 333.34833 -218.25331) (xy 333.357556 -218.252904) (xy 333.374805 -218.246346)
			(xy 333.388603 -218.234094) (xy 333.393288 -218.226132) (xy 333.406496 -218.20124) (xy 333.405734 -218.17457)
			(xy 333.39913 -218.16314) (xy 333.387623 -218.143131) (xy 333.369492 -218.100684) (xy 333.357217 -218.056189)
			(xy 333.351019 -218.01045) (xy 333.350616 -217.987372) (xy 333.351096 -217.961673) (xy 333.358757 -217.910849)
			(xy 333.373906 -217.861735) (xy 333.396207 -217.815427) (xy 333.42516 -217.77296) (xy 333.46012 -217.735283)
			(xy 333.500304 -217.703237) (xy 333.544816 -217.677538) (xy 333.592661 -217.658761) (xy 333.64277 -217.647323)
			(xy 333.694024 -217.643483) (xy 333.745278 -217.647323) (xy 333.795387 -217.658761) (xy 333.843232 -217.677538)
			(xy 333.887744 -217.703237) (xy 333.927928 -217.735283) (xy 333.962888 -217.77296) (xy 333.991841 -217.815427)
			(xy 334.014142 -217.861735) (xy 334.029291 -217.910849) (xy 334.036952 -217.961673) (xy 334.037432 -217.987372)
			(xy 334.037026 -218.010902) (xy 334.030559 -218.057516) (xy 334.017785 -218.10281) (xy 334.00873 -218.124532)
			(xy 334.00365 -218.136724) (xy 334.005936 -218.162378) (xy 334.051656 -218.230704) (xy 334.059165 -218.24078)
			(xy 334.081273 -218.252665) (xy 334.09382 -218.25331) (xy 334.094328 -218.25331) (xy 334.106881 -218.252663)
			(xy 334.129009 -218.240804) (xy 334.136492 -218.230704) (xy 334.182212 -218.162378) (xy 334.184498 -218.136724)
			(xy 334.179418 -218.124532) (xy 334.170353 -218.102813) (xy 334.157578 -218.057518) (xy 334.151105 -218.010903)
			(xy 334.150716 -217.987372) (xy 334.151196 -217.961673) (xy 334.158857 -217.910849) (xy 334.174006 -217.861735)
			(xy 334.196307 -217.815427) (xy 334.22526 -217.77296) (xy 334.26022 -217.735283) (xy 334.300404 -217.703237)
			(xy 334.344916 -217.677538) (xy 334.392761 -217.658761) (xy 334.44287 -217.647323) (xy 334.494124 -217.643483)
			(xy 334.545378 -217.647323) (xy 334.595487 -217.658761) (xy 334.643332 -217.677538) (xy 334.687844 -217.703237)
			(xy 334.728028 -217.735283) (xy 334.762988 -217.77296) (xy 334.791941 -217.815427) (xy 334.814242 -217.861735)
			(xy 334.829391 -217.910849) (xy 334.837052 -217.961673) (xy 334.837532 -217.987372) (xy 334.837126 -218.010902)
			(xy 334.830659 -218.057516) (xy 334.817885 -218.10281) (xy 334.80883 -218.124532) (xy 334.80375 -218.136724)
			(xy 334.806036 -218.162378) (xy 334.851756 -218.230704) (xy 334.859265 -218.24078) (xy 334.881373 -218.252665)
			(xy 334.89392 -218.25331) (xy 334.894174 -218.25331) (xy 334.906734 -218.252675) (xy 334.928882 -218.240828)
			(xy 334.936338 -218.230704) (xy 334.982058 -218.162378) (xy 334.984344 -218.136724) (xy 334.979264 -218.124532)
			(xy 334.970201 -218.102813) (xy 334.957428 -218.057517) (xy 334.950955 -218.010903) (xy 334.950562 -217.987372)
			(xy 334.951042 -217.961673) (xy 334.958703 -217.910849) (xy 334.973852 -217.861735) (xy 334.996153 -217.815427)
			(xy 335.025106 -217.77296) (xy 335.060066 -217.735283) (xy 335.10025 -217.703237) (xy 335.144762 -217.677538)
			(xy 335.192607 -217.658761) (xy 335.242716 -217.647323) (xy 335.29397 -217.643483) (xy 335.345224 -217.647323)
			(xy 335.395333 -217.658761) (xy 335.443178 -217.677538) (xy 335.48769 -217.703237) (xy 335.527874 -217.735283)
			(xy 335.562834 -217.77296) (xy 335.591787 -217.815427) (xy 335.614088 -217.861735) (xy 335.629237 -217.910849)
			(xy 335.636898 -217.961673) (xy 335.637378 -217.987372) (xy 335.636972 -218.010902) (xy 335.630504 -218.057516)
			(xy 335.617728 -218.102809) (xy 335.608676 -218.124532) (xy 335.603596 -218.136724) (xy 335.605882 -218.162378)
			(xy 335.651602 -218.230704) (xy 335.659115 -218.240772) (xy 335.681223 -218.252637) (xy 335.693766 -218.25331)
			(xy 335.694274 -218.25331) (xy 335.706834 -218.252675) (xy 335.728982 -218.240828) (xy 335.736438 -218.230704)
			(xy 335.782158 -218.162378) (xy 335.784444 -218.136724) (xy 335.779364 -218.124532) (xy 335.770301 -218.102813)
			(xy 335.757528 -218.057517) (xy 335.751055 -218.010903) (xy 335.750662 -217.987372) (xy 335.751142 -217.961673)
			(xy 335.758803 -217.910849) (xy 335.773952 -217.861735) (xy 335.796253 -217.815427) (xy 335.825206 -217.77296)
			(xy 335.860166 -217.735283) (xy 335.90035 -217.703237) (xy 335.944862 -217.677538) (xy 335.992707 -217.658761)
			(xy 336.042816 -217.647323) (xy 336.09407 -217.643483) (xy 336.145324 -217.647323) (xy 336.195433 -217.658761)
			(xy 336.243278 -217.677538) (xy 336.28779 -217.703237) (xy 336.327974 -217.735283) (xy 336.362934 -217.77296)
			(xy 336.391887 -217.815427) (xy 336.414188 -217.861735) (xy 336.429337 -217.910849) (xy 336.436998 -217.961673)
			(xy 336.437478 -217.987372) (xy 336.437072 -218.010902) (xy 336.430604 -218.057516) (xy 336.417828 -218.102809)
			(xy 336.408776 -218.124532) (xy 336.403696 -218.136724) (xy 336.405982 -218.162378) (xy 336.451702 -218.230704)
			(xy 336.459215 -218.240772) (xy 336.481323 -218.252637) (xy 336.493866 -218.25331) (xy 336.494374 -218.25331)
			(xy 336.506934 -218.252675) (xy 336.529082 -218.240828) (xy 336.536538 -218.230704) (xy 336.582258 -218.162378)
			(xy 336.584544 -218.136724) (xy 336.579464 -218.124532) (xy 336.570401 -218.102813) (xy 336.557628 -218.057517)
			(xy 336.551155 -218.010903) (xy 336.550762 -217.987372) (xy 336.551242 -217.961673) (xy 336.558903 -217.910849)
			(xy 336.574052 -217.861735) (xy 336.596353 -217.815427) (xy 336.625306 -217.77296) (xy 336.660266 -217.735283)
			(xy 336.70045 -217.703237) (xy 336.744962 -217.677538) (xy 336.792807 -217.658761) (xy 336.842916 -217.647323)
			(xy 336.89417 -217.643483) (xy 336.945424 -217.647323) (xy 336.995533 -217.658761) (xy 337.043378 -217.677538)
			(xy 337.08789 -217.703237) (xy 337.128074 -217.735283) (xy 337.163034 -217.77296) (xy 337.191987 -217.815427)
			(xy 337.214288 -217.861735) (xy 337.229437 -217.910849) (xy 337.237098 -217.961673) (xy 337.237578 -217.987372)
			(xy 337.237172 -218.010902) (xy 337.230704 -218.057516) (xy 337.217928 -218.102809) (xy 337.208876 -218.124532)
			(xy 337.203796 -218.136724) (xy 337.206082 -218.162378) (xy 337.251802 -218.230704) (xy 337.259315 -218.240772)
			(xy 337.281423 -218.252637) (xy 337.293966 -218.25331) (xy 337.29422 -218.25331) (xy 337.306774 -218.252664)
			(xy 337.328905 -218.240807) (xy 337.336384 -218.230704) (xy 337.382104 -218.162378) (xy 337.38439 -218.136724)
			(xy 337.37931 -218.124532) (xy 337.370246 -218.102813) (xy 337.357471 -218.057518) (xy 337.350998 -218.010903)
			(xy 337.350608 -217.987372) (xy 337.351088 -217.961673) (xy 337.358749 -217.910849) (xy 337.373898 -217.861735)
			(xy 337.396199 -217.815427) (xy 337.425152 -217.77296) (xy 337.460112 -217.735283) (xy 337.500296 -217.703237)
			(xy 337.544808 -217.677538) (xy 337.592653 -217.658761) (xy 337.642762 -217.647323) (xy 337.694016 -217.643483)
			(xy 337.74527 -217.647323) (xy 337.795379 -217.658761) (xy 337.843224 -217.677538) (xy 337.887736 -217.703237)
			(xy 337.92792 -217.735283) (xy 337.96288 -217.77296) (xy 337.991833 -217.815427) (xy 338.014134 -217.861735)
			(xy 338.029283 -217.910849) (xy 338.036944 -217.961673) (xy 338.037424 -217.987372) (xy 338.037018 -218.010902)
			(xy 338.030551 -218.057516) (xy 338.017777 -218.10281) (xy 338.008722 -218.124532) (xy 338.003642 -218.136724)
			(xy 338.005928 -218.162378) (xy 338.051648 -218.230704) (xy 338.059164 -218.240764) (xy 338.081273 -218.25261)
			(xy 338.093812 -218.25331) (xy 338.09432 -218.25331) (xy 338.106874 -218.252664) (xy 338.129005 -218.240807)
			(xy 338.136484 -218.230704) (xy 338.182204 -218.162378) (xy 338.18449 -218.136724) (xy 338.17941 -218.124532)
			(xy 338.170346 -218.102813) (xy 338.157571 -218.057518) (xy 338.151098 -218.010903) (xy 338.150708 -217.987372)
			(xy 338.151188 -217.961673) (xy 338.158849 -217.910849) (xy 338.173998 -217.861735) (xy 338.196299 -217.815427)
			(xy 338.225252 -217.77296) (xy 338.260212 -217.735283) (xy 338.300396 -217.703237) (xy 338.344908 -217.677538)
			(xy 338.392753 -217.658761) (xy 338.442862 -217.647323) (xy 338.494116 -217.643483) (xy 338.54537 -217.647323)
			(xy 338.595479 -217.658761) (xy 338.643324 -217.677538) (xy 338.687836 -217.703237) (xy 338.72802 -217.735283)
			(xy 338.76298 -217.77296) (xy 338.791933 -217.815427) (xy 338.814234 -217.861735) (xy 338.829383 -217.910849)
			(xy 338.837044 -217.961673) (xy 338.837524 -217.987372) (xy 338.837118 -218.010902) (xy 338.830651 -218.057516)
			(xy 338.817877 -218.10281) (xy 338.808822 -218.124532) (xy 338.803742 -218.136724) (xy 338.806028 -218.162378)
			(xy 338.851748 -218.230704) (xy 338.859264 -218.240764) (xy 338.881373 -218.25261) (xy 338.893912 -218.25331)
			(xy 339.358224 -218.25331) (xy 339.358224 -218.247722) (xy 339.554566 -218.05138) (xy 339.56371 -218.05138)
			(xy 339.792564 -217.822526) (xy 339.79612 -217.816684) (xy 339.808852 -217.795351) (xy 339.839494 -217.756246)
			(xy 339.875434 -217.721947) (xy 339.895434 -217.70721) (xy 339.91677 -217.665808) (xy 339.91677 -217.509598)
			(xy 339.916346 -217.499529) (xy 339.908628 -217.480927) (xy 339.901784 -217.47353) (xy 339.895942 -217.467688)
			(xy 339.89264 -217.465402) (xy 339.873137 -217.450753) (xy 339.838076 -217.416845) (xy 339.82279 -217.397838)
			(xy 339.81525 -217.389046) (xy 339.79448 -217.378851) (xy 339.782912 -217.37828) (xy 339.78215 -217.37828)
			(xy 339.60562 -217.37828) (xy 339.5472 -217.286332) (xy 339.5472 -217.136472) (xy 339.546188 -217.127336)
			(xy 339.538515 -217.11065) (xy 339.532214 -217.10396) (xy 339.099144 -216.67089) (xy 339.092794 -216.665556)
			(xy 339.073223 -216.650848) (xy 339.038033 -216.616815) (xy 339.02269 -216.597738) (xy 339.01515 -216.588946)
			(xy 338.99438 -216.578751) (xy 338.982812 -216.57818) (xy 338.80044 -216.57818) (xy 338.794795 -216.578308)
			(xy 338.783773 -216.58075) (xy 338.778596 -216.583006) (xy 338.77504 -216.584784) (xy 338.758806 -216.60689)
			(xy 338.720494 -216.646134) (xy 338.676439 -216.678799) (xy 338.627757 -216.704056) (xy 338.575683 -216.721265)
			(xy 338.521538 -216.729989) (xy 338.494116 -216.73058) (xy 338.468417 -216.730125) (xy 338.417592 -216.722467)
			(xy 338.368476 -216.707318) (xy 338.322167 -216.685019) (xy 338.279698 -216.656066) (xy 338.242019 -216.621107)
			(xy 338.209972 -216.580923) (xy 338.184272 -216.53641) (xy 338.165493 -216.488565) (xy 338.154056 -216.438455)
			(xy 338.150214 -216.3872) (xy 338.154056 -216.335945) (xy 338.165493 -216.285835) (xy 338.184272 -216.23799)
			(xy 338.209972 -216.193477) (xy 338.242019 -216.153293) (xy 338.279698 -216.118334) (xy 338.322166 -216.089381)
			(xy 338.368476 -216.067082) (xy 338.417592 -216.051933) (xy 338.468417 -216.044275) (xy 338.494116 -216.043764)
			(xy 338.515198 -216.044526) (xy 338.520532 -216.04224) (xy 338.539582 -216.023698) (xy 338.546595 -216.016299)
			(xy 338.554577 -215.99756) (xy 338.555076 -215.987376) (xy 338.555076 -215.976962) (xy 338.547202 -215.957912)
			(xy 338.520532 -215.932258) (xy 338.515198 -215.929972) (xy 338.494116 -215.930734) (xy 338.468413 -215.930279)
			(xy 338.41758 -215.922619) (xy 338.368456 -215.907469) (xy 338.32214 -215.885166) (xy 338.279664 -215.856208)
			(xy 338.24198 -215.821244) (xy 338.209927 -215.781053) (xy 338.184223 -215.736534) (xy 338.165442 -215.688681)
			(xy 338.154002 -215.638563) (xy 338.15016 -215.5873) (xy 338.154002 -215.536037) (xy 338.165442 -215.485919)
			(xy 338.184223 -215.438066) (xy 338.209927 -215.393547) (xy 338.24198 -215.353356) (xy 338.279664 -215.318392)
			(xy 338.32214 -215.289434) (xy 338.368456 -215.267131) (xy 338.41758 -215.251981) (xy 338.468413 -215.244321)
			(xy 338.494116 -215.243918) (xy 338.520751 -215.244421) (xy 338.573382 -215.25265) (xy 338.62411 -215.268908)
			(xy 338.671719 -215.292805) (xy 338.715067 -215.323767) (xy 338.753114 -215.361052) (xy 338.769452 -215.382094)
			(xy 338.780628 -215.384634) (xy 338.884006 -215.34501) (xy 338.893376 -215.34093) (xy 338.90808 -215.326761)
			(xy 338.916081 -215.307975) (xy 338.916518 -215.297766) (xy 338.916518 -215.076786) (xy 338.91601 -215.06659)
			(xy 338.908003 -215.047828) (xy 338.893361 -215.033625) (xy 338.884006 -215.029542) (xy 338.780628 -214.989918)
			(xy 338.769452 -214.992458) (xy 338.753131 -215.013513) (xy 338.715079 -215.050796) (xy 338.671727 -215.081756)
			(xy 338.624115 -215.10565) (xy 338.573384 -215.121907) (xy 338.520752 -215.130135) (xy 338.494116 -215.130634)
			(xy 338.468413 -215.130179) (xy 338.41758 -215.122519) (xy 338.368456 -215.107369) (xy 338.32214 -215.085066)
			(xy 338.279664 -215.056108) (xy 338.24198 -215.021144) (xy 338.209927 -214.980953) (xy 338.184223 -214.936434)
			(xy 338.165442 -214.888581) (xy 338.154002 -214.838463) (xy 338.15016 -214.7872) (xy 338.154002 -214.735937)
			(xy 338.165442 -214.685819) (xy 338.184223 -214.637966) (xy 338.209927 -214.593447) (xy 338.24198 -214.553256)
			(xy 338.279664 -214.518292) (xy 338.32214 -214.489334) (xy 338.368456 -214.467031) (xy 338.41758 -214.451881)
			(xy 338.468413 -214.444221) (xy 338.494116 -214.443818) (xy 338.520751 -214.444321) (xy 338.573382 -214.45255)
			(xy 338.62411 -214.468808) (xy 338.671719 -214.492705) (xy 338.715067 -214.523667) (xy 338.753114 -214.560952)
			(xy 338.769452 -214.581994) (xy 338.780628 -214.584534) (xy 338.884006 -214.54491) (xy 338.893376 -214.54083)
			(xy 338.90808 -214.526661) (xy 338.916081 -214.507875) (xy 338.916518 -214.497666) (xy 338.916518 -214.475568)
			(xy 338.91609 -214.4655) (xy 338.908369 -214.446902) (xy 338.901532 -214.4395) (xy 338.731606 -214.269574)
			(xy 338.695792 -214.265764) (xy 338.680806 -214.27567) (xy 338.659851 -214.288717) (xy 338.614995 -214.30932)
			(xy 338.567652 -214.323291) (xy 338.518797 -214.330344) (xy 338.494116 -214.330788) (xy 338.467128 -214.330287)
			(xy 338.413818 -214.321846) (xy 338.362484 -214.305168) (xy 338.314391 -214.280664) (xy 338.270724 -214.248939)
			(xy 338.232559 -214.210772) (xy 338.200834 -214.167105) (xy 338.176331 -214.119012) (xy 338.159653 -214.067678)
			(xy 338.151212 -214.014368) (xy 338.150708 -213.98738) (xy 338.151135 -213.962699) (xy 338.158198 -213.913844)
			(xy 338.172175 -213.866502) (xy 338.19278 -213.821646) (xy 338.205826 -213.80069) (xy 338.215732 -213.785704)
			(xy 338.211922 -213.74989) (xy 337.928712 -213.46668) (xy 337.913218 -213.459314) (xy 337.904836 -213.458552)
			(xy 337.882109 -213.475453) (xy 337.832274 -213.502359) (xy 337.778701 -213.520724) (xy 337.72284 -213.530052)
			(xy 337.694524 -213.530688) (xy 337.694016 -213.530688) (xy 337.668813 -213.530239) (xy 337.61895 -213.522862)
			(xy 337.5707 -213.50828) (xy 337.525098 -213.486804) (xy 337.483124 -213.458895) (xy 337.445677 -213.425154)
			(xy 337.413562 -213.386304) (xy 337.387468 -213.343178) (xy 337.377278 -213.320122) (xy 337.373468 -213.310724)
			(xy 337.321398 -213.258908) (xy 337.313989 -213.252223) (xy 337.295552 -213.244641) (xy 337.285584 -213.244176)
			(xy 337.256374 -213.244176) (xy 337.229196 -213.26475) (xy 337.224624 -213.281006) (xy 337.217011 -213.306046)
			(xy 337.195259 -213.353646) (xy 337.166537 -213.397395) (xy 337.131511 -213.436281) (xy 337.090991 -213.469404)
			(xy 337.045916 -213.495996) (xy 336.997328 -213.515443) (xy 336.946353 -213.527294) (xy 336.89417 -213.531275)
			(xy 336.841987 -213.527294) (xy 336.791012 -213.515443) (xy 336.742424 -213.495996) (xy 336.697349 -213.469404)
			(xy 336.656829 -213.436281) (xy 336.621803 -213.397395) (xy 336.593081 -213.353646) (xy 336.571329 -213.306046)
			(xy 336.563716 -213.281006) (xy 336.559144 -213.26475) (xy 336.531966 -213.244176) (xy 336.455766 -213.244176)
			(xy 336.428842 -213.264496) (xy 336.424016 -213.281006) (xy 336.416405 -213.306023) (xy 336.394662 -213.353578)
			(xy 336.365959 -213.397284) (xy 336.330958 -213.436132) (xy 336.29047 -213.469221) (xy 336.245432 -213.495786)
			(xy 336.196885 -213.515213) (xy 336.145954 -213.527052) (xy 336.093816 -213.531029) (xy 336.041678 -213.527052)
			(xy 335.990747 -213.515213) (xy 335.9422 -213.495786) (xy 335.897162 -213.469221) (xy 335.856674 -213.436132)
			(xy 335.821673 -213.397284) (xy 335.79297 -213.353578) (xy 335.771227 -213.306023) (xy 335.763616 -213.281006)
			(xy 335.75879 -213.264496) (xy 335.731866 -213.244176) (xy 335.656174 -213.244176) (xy 335.628996 -213.26475)
			(xy 335.624424 -213.281006) (xy 335.616811 -213.306046) (xy 335.595059 -213.353646) (xy 335.566337 -213.397395)
			(xy 335.531311 -213.436281) (xy 335.490791 -213.469404) (xy 335.445716 -213.495996) (xy 335.397128 -213.515443)
			(xy 335.346153 -213.527294) (xy 335.29397 -213.531275) (xy 335.241787 -213.527294) (xy 335.190812 -213.515443)
			(xy 335.142224 -213.495996) (xy 335.097149 -213.469404) (xy 335.056629 -213.436281) (xy 335.021603 -213.397395)
			(xy 334.992881 -213.353646) (xy 334.971129 -213.306046) (xy 334.963516 -213.281006) (xy 334.958944 -213.26475)
			(xy 334.931766 -213.244176) (xy 334.856328 -213.244176) (xy 334.82915 -213.26475) (xy 334.824578 -213.281006)
			(xy 334.816436 -213.307731) (xy 334.792697 -213.358301) (xy 334.761071 -213.404352) (xy 334.722395 -213.444664)
			(xy 334.700372 -213.461854) (xy 334.69072 -213.46922) (xy 334.680052 -213.490302) (xy 334.680052 -213.672166)
			(xy 334.680662 -213.684018) (xy 334.691243 -213.705227) (xy 334.700372 -213.712806) (xy 334.721288 -213.729135)
			(xy 334.758306 -213.767149) (xy 334.789037 -213.810405) (xy 334.812749 -213.857872) (xy 334.82888 -213.908421)
			(xy 334.837043 -213.96085) (xy 334.837532 -213.98738) (xy 335.750157 -213.98738) (xy 335.754187 -213.934882)
			(xy 335.766184 -213.883614) (xy 335.785867 -213.834779) (xy 335.812773 -213.78952) (xy 335.846273 -213.748899)
			(xy 335.885581 -213.713868) (xy 335.929776 -213.685248) (xy 335.977821 -213.663709) (xy 336.028592 -213.649757)
			(xy 336.080897 -213.643719) (xy 336.133511 -213.645736) (xy 336.185201 -213.65576) (xy 336.234754 -213.673558)
			(xy 336.28101 -213.698711) (xy 336.322884 -213.73063) (xy 336.359396 -213.768568) (xy 336.389688 -213.811634)
			(xy 336.413051 -213.858819) (xy 336.428937 -213.909018) (xy 336.436974 -213.961054) (xy 336.437478 -213.98738)
			(xy 336.550257 -213.98738) (xy 336.554287 -213.934882) (xy 336.566284 -213.883614) (xy 336.585967 -213.834779)
			(xy 336.612873 -213.78952) (xy 336.646373 -213.748899) (xy 336.685681 -213.713868) (xy 336.729876 -213.685248)
			(xy 336.777921 -213.663709) (xy 336.828692 -213.649757) (xy 336.880997 -213.643719) (xy 336.933611 -213.645736)
			(xy 336.985301 -213.65576) (xy 337.034854 -213.673558) (xy 337.08111 -213.698711) (xy 337.122984 -213.73063)
			(xy 337.159496 -213.768568) (xy 337.189788 -213.811634) (xy 337.213151 -213.858819) (xy 337.229037 -213.909018)
			(xy 337.237074 -213.961054) (xy 337.237578 -213.98738) (xy 337.350103 -213.98738) (xy 337.354133 -213.934882)
			(xy 337.36613 -213.883614) (xy 337.385813 -213.834779) (xy 337.412719 -213.78952) (xy 337.446219 -213.748899)
			(xy 337.485527 -213.713868) (xy 337.529722 -213.685248) (xy 337.577767 -213.663709) (xy 337.628538 -213.649757)
			(xy 337.680843 -213.643719) (xy 337.733457 -213.645736) (xy 337.785147 -213.65576) (xy 337.8347 -213.673558)
			(xy 337.880956 -213.698711) (xy 337.92283 -213.73063) (xy 337.959342 -213.768568) (xy 337.989634 -213.811634)
			(xy 338.012997 -213.858819) (xy 338.028883 -213.909018) (xy 338.03692 -213.961054) (xy 338.037424 -213.98738)
			(xy 338.03692 -214.013706) (xy 338.028883 -214.065742) (xy 338.012997 -214.115941) (xy 337.989634 -214.163126)
			(xy 337.959342 -214.206192) (xy 337.92283 -214.24413) (xy 337.880956 -214.276049) (xy 337.8347 -214.301202)
			(xy 337.785147 -214.319) (xy 337.733457 -214.329024) (xy 337.680843 -214.331041) (xy 337.628538 -214.325003)
			(xy 337.577767 -214.311051) (xy 337.529722 -214.289512) (xy 337.485527 -214.260892) (xy 337.446219 -214.225861)
			(xy 337.412719 -214.18524) (xy 337.385813 -214.139981) (xy 337.36613 -214.091146) (xy 337.354133 -214.039878)
			(xy 337.350103 -213.98738) (xy 337.237578 -213.98738) (xy 337.237074 -214.013706) (xy 337.229037 -214.065742)
			(xy 337.213151 -214.115941) (xy 337.189788 -214.163126) (xy 337.159496 -214.206192) (xy 337.122984 -214.24413)
			(xy 337.08111 -214.276049) (xy 337.034854 -214.301202) (xy 336.985301 -214.319) (xy 336.933611 -214.329024)
			(xy 336.880997 -214.331041) (xy 336.828692 -214.325003) (xy 336.777921 -214.311051) (xy 336.729876 -214.289512)
			(xy 336.685681 -214.260892) (xy 336.646373 -214.225861) (xy 336.612873 -214.18524) (xy 336.585967 -214.139981)
			(xy 336.566284 -214.091146) (xy 336.554287 -214.039878) (xy 336.550257 -213.98738) (xy 336.437478 -213.98738)
			(xy 336.436974 -214.013706) (xy 336.428937 -214.065742) (xy 336.413051 -214.115941) (xy 336.389688 -214.163126)
			(xy 336.359396 -214.206192) (xy 336.322884 -214.24413) (xy 336.28101 -214.276049) (xy 336.234754 -214.301202)
			(xy 336.185201 -214.319) (xy 336.133511 -214.329024) (xy 336.080897 -214.331041) (xy 336.028592 -214.325003)
			(xy 335.977821 -214.311051) (xy 335.929776 -214.289512) (xy 335.885581 -214.260892) (xy 335.846273 -214.225861)
			(xy 335.812773 -214.18524) (xy 335.785867 -214.139981) (xy 335.766184 -214.091146) (xy 335.754187 -214.039878)
			(xy 335.750157 -213.98738) (xy 334.837532 -213.98738) (xy 334.837004 -214.014367) (xy 334.828564 -214.067677)
			(xy 334.811888 -214.11901) (xy 334.787388 -214.167102) (xy 334.755666 -214.210769) (xy 334.717503 -214.248937)
			(xy 334.673839 -214.280665) (xy 334.62575 -214.305172) (xy 334.574419 -214.321854) (xy 334.521111 -214.330301)
			(xy 334.494124 -214.330788) (xy 334.467378 -214.330279) (xy 334.414533 -214.321985) (xy 334.363613 -214.305596)
			(xy 334.315853 -214.281506) (xy 334.272407 -214.250299) (xy 334.234327 -214.212732) (xy 334.202535 -214.169712)
			(xy 334.177801 -214.122282) (xy 334.16875 -214.097108) (xy 334.16494 -214.085678) (xy 334.114902 -214.035894)
			(xy 334.10749 -214.02921) (xy 334.089057 -214.021613) (xy 334.069119 -214.021613) (xy 334.050686 -214.02921)
			(xy 334.043274 -214.035894) (xy 334.03794 -214.041228) (xy 334.031082 -214.053674) (xy 334.029558 -214.06104)
			(xy 334.023533 -214.086189) (xy 334.004954 -214.13445) (xy 333.979356 -214.179384) (xy 333.947314 -214.219975)
			(xy 333.909554 -214.255309) (xy 333.866927 -214.284587) (xy 333.820395 -214.307149) (xy 333.771008 -214.322486)
			(xy 333.719881 -214.330251) (xy 333.694024 -214.330788) (xy 333.69377 -214.330788) (xy 333.66581 -214.330243)
			(xy 333.610629 -214.321188) (xy 333.557645 -214.303307) (xy 333.508261 -214.277073) (xy 333.463784 -214.243179)
			(xy 333.425391 -214.202523) (xy 333.40929 -214.179658) (xy 333.402432 -214.169498) (xy 333.381096 -214.15756)
			(xy 333.307182 -214.155274) (xy 333.285592 -214.165434) (xy 333.277972 -214.17534) (xy 333.260375 -214.197119)
			(xy 333.219719 -214.235615) (xy 333.173713 -214.267527) (xy 333.123415 -214.292122) (xy 333.069978 -214.308836)
			(xy 333.014629 -214.317284) (xy 332.986634 -214.317834) (xy 332.959029 -214.317346) (xy 332.904434 -214.309122)
			(xy 332.851676 -214.292852) (xy 332.801931 -214.268901) (xy 332.756313 -214.237802) (xy 332.715839 -214.200252)
			(xy 332.681414 -214.157088) (xy 332.653807 -214.109275) (xy 332.633636 -214.057882) (xy 332.62135 -214.004056)
			(xy 332.617223 -213.949) (xy 332.62135 -213.893944) (xy 332.633636 -213.840118) (xy 332.653807 -213.788725)
			(xy 332.681414 -213.740912) (xy 332.715839 -213.697748) (xy 332.756313 -213.660198) (xy 332.801931 -213.629099)
			(xy 332.851676 -213.605148) (xy 332.904434 -213.588878) (xy 332.959029 -213.580654) (xy 332.986634 -213.580218)
			(xy 333.013483 -213.580706) (xy 333.066611 -213.588505) (xy 333.118045 -213.603932) (xy 333.166695 -213.626662)
			(xy 333.21153 -213.656212) (xy 333.251601 -213.691957) (xy 333.28606 -213.73314) (xy 333.300578 -213.755732)
			(xy 333.307182 -213.766146) (xy 333.327756 -213.778846) (xy 333.40167 -213.78418) (xy 333.423768 -213.775036)
			(xy 333.431896 -213.765638) (xy 333.450175 -213.744842) (xy 333.492247 -213.708854) (xy 333.53955 -213.680084)
			(xy 333.590857 -213.659278) (xy 333.644838 -213.646977) (xy 333.672434 -213.644734) (xy 333.68234 -213.643972)
			(xy 333.700374 -213.635336) (xy 333.740252 -213.591394) (xy 333.745615 -213.584931) (xy 333.752241 -213.56951)
			(xy 333.753206 -213.561168) (xy 333.75346 -213.557104) (xy 333.75346 -213.47557) (xy 333.753984 -213.465673)
			(xy 333.761567 -213.447382) (xy 333.768192 -213.44001) (xy 333.877158 -213.33079) (xy 333.88385 -213.323347)
			(xy 333.891447 -213.304849) (xy 333.891427 -213.284853) (xy 333.88808 -213.275418) (xy 333.882238 -213.261194)
			(xy 333.856838 -213.244176) (xy 332.349094 -213.244176) (xy 332.339024 -213.2446) (xy 332.320419 -213.252313)
			(xy 332.313026 -213.259162) (xy 331.493622 -214.078566) (xy 331.486256 -214.085678) (xy 331.478636 -214.104474)
			(xy 331.478636 -214.709756) (xy 331.478408 -214.716794) (xy 331.474534 -214.730326) (xy 331.471016 -214.736426)
			(xy 331.46746 -214.742522) (xy 331.46365 -214.75573) (xy 331.46365 -214.787226) (xy 334.950057 -214.787226)
			(xy 334.954087 -214.734728) (xy 334.966084 -214.68346) (xy 334.985767 -214.634625) (xy 335.012673 -214.589366)
			(xy 335.046173 -214.548745) (xy 335.085481 -214.513714) (xy 335.129676 -214.485094) (xy 335.177721 -214.463555)
			(xy 335.228492 -214.449603) (xy 335.280797 -214.443565) (xy 335.333411 -214.445582) (xy 335.385101 -214.455606)
			(xy 335.434654 -214.473404) (xy 335.48091 -214.498557) (xy 335.522784 -214.530476) (xy 335.559296 -214.568414)
			(xy 335.589588 -214.61148) (xy 335.612951 -214.658665) (xy 335.628837 -214.708864) (xy 335.636874 -214.7609)
			(xy 335.637378 -214.787226) (xy 335.750157 -214.787226) (xy 335.754187 -214.734728) (xy 335.766184 -214.68346)
			(xy 335.785867 -214.634625) (xy 335.812773 -214.589366) (xy 335.846273 -214.548745) (xy 335.885581 -214.513714)
			(xy 335.929776 -214.485094) (xy 335.977821 -214.463555) (xy 336.028592 -214.449603) (xy 336.080897 -214.443565)
			(xy 336.133511 -214.445582) (xy 336.185201 -214.455606) (xy 336.234754 -214.473404) (xy 336.28101 -214.498557)
			(xy 336.322884 -214.530476) (xy 336.359396 -214.568414) (xy 336.389688 -214.61148) (xy 336.413051 -214.658665)
			(xy 336.428937 -214.708864) (xy 336.436974 -214.7609) (xy 336.437478 -214.787226) (xy 336.550257 -214.787226)
			(xy 336.554287 -214.734728) (xy 336.566284 -214.68346) (xy 336.585967 -214.634625) (xy 336.612873 -214.589366)
			(xy 336.646373 -214.548745) (xy 336.685681 -214.513714) (xy 336.729876 -214.485094) (xy 336.777921 -214.463555)
			(xy 336.828692 -214.449603) (xy 336.880997 -214.443565) (xy 336.933611 -214.445582) (xy 336.985301 -214.455606)
			(xy 337.034854 -214.473404) (xy 337.08111 -214.498557) (xy 337.122984 -214.530476) (xy 337.159496 -214.568414)
			(xy 337.189788 -214.61148) (xy 337.213151 -214.658665) (xy 337.229037 -214.708864) (xy 337.237074 -214.7609)
			(xy 337.237578 -214.787226) (xy 337.350103 -214.787226) (xy 337.354133 -214.734728) (xy 337.36613 -214.68346)
			(xy 337.385813 -214.634625) (xy 337.412719 -214.589366) (xy 337.446219 -214.548745) (xy 337.485527 -214.513714)
			(xy 337.529722 -214.485094) (xy 337.577767 -214.463555) (xy 337.628538 -214.449603) (xy 337.680843 -214.443565)
			(xy 337.733457 -214.445582) (xy 337.785147 -214.455606) (xy 337.8347 -214.473404) (xy 337.880956 -214.498557)
			(xy 337.92283 -214.530476) (xy 337.959342 -214.568414) (xy 337.989634 -214.61148) (xy 338.012997 -214.658665)
			(xy 338.028883 -214.708864) (xy 338.03692 -214.7609) (xy 338.037424 -214.787226) (xy 338.03692 -214.813552)
			(xy 338.028883 -214.865588) (xy 338.012997 -214.915787) (xy 337.989634 -214.962972) (xy 337.959342 -215.006038)
			(xy 337.92283 -215.043976) (xy 337.880956 -215.075895) (xy 337.8347 -215.101048) (xy 337.785147 -215.118846)
			(xy 337.733457 -215.12887) (xy 337.680843 -215.130887) (xy 337.628538 -215.124849) (xy 337.577767 -215.110897)
			(xy 337.529722 -215.089358) (xy 337.485527 -215.060738) (xy 337.446219 -215.025707) (xy 337.412719 -214.985086)
			(xy 337.385813 -214.939827) (xy 337.36613 -214.890992) (xy 337.354133 -214.839724) (xy 337.350103 -214.787226)
			(xy 337.237578 -214.787226) (xy 337.237074 -214.813552) (xy 337.229037 -214.865588) (xy 337.213151 -214.915787)
			(xy 337.189788 -214.962972) (xy 337.159496 -215.006038) (xy 337.122984 -215.043976) (xy 337.08111 -215.075895)
			(xy 337.034854 -215.101048) (xy 336.985301 -215.118846) (xy 336.933611 -215.12887) (xy 336.880997 -215.130887)
			(xy 336.828692 -215.124849) (xy 336.777921 -215.110897) (xy 336.729876 -215.089358) (xy 336.685681 -215.060738)
			(xy 336.646373 -215.025707) (xy 336.612873 -214.985086) (xy 336.585967 -214.939827) (xy 336.566284 -214.890992)
			(xy 336.554287 -214.839724) (xy 336.550257 -214.787226) (xy 336.437478 -214.787226) (xy 336.436974 -214.813552)
			(xy 336.428937 -214.865588) (xy 336.413051 -214.915787) (xy 336.389688 -214.962972) (xy 336.359396 -215.006038)
			(xy 336.322884 -215.043976) (xy 336.28101 -215.075895) (xy 336.234754 -215.101048) (xy 336.185201 -215.118846)
			(xy 336.133511 -215.12887) (xy 336.080897 -215.130887) (xy 336.028592 -215.124849) (xy 335.977821 -215.110897)
			(xy 335.929776 -215.089358) (xy 335.885581 -215.060738) (xy 335.846273 -215.025707) (xy 335.812773 -214.985086)
			(xy 335.785867 -214.939827) (xy 335.766184 -214.890992) (xy 335.754187 -214.839724) (xy 335.750157 -214.787226)
			(xy 335.637378 -214.787226) (xy 335.636874 -214.813552) (xy 335.628837 -214.865588) (xy 335.612951 -214.915787)
			(xy 335.589588 -214.962972) (xy 335.559296 -215.006038) (xy 335.522784 -215.043976) (xy 335.48091 -215.075895)
			(xy 335.434654 -215.101048) (xy 335.385101 -215.118846) (xy 335.333411 -215.12887) (xy 335.280797 -215.130887)
			(xy 335.228492 -215.124849) (xy 335.177721 -215.110897) (xy 335.129676 -215.089358) (xy 335.085481 -215.060738)
			(xy 335.046173 -215.025707) (xy 335.012673 -214.985086) (xy 334.985767 -214.939827) (xy 334.966084 -214.890992)
			(xy 334.954087 -214.839724) (xy 334.950057 -214.787226) (xy 331.46365 -214.787226) (xy 331.46365 -215.56345)
			(xy 332.537057 -215.56345) (xy 332.541087 -215.510952) (xy 332.553084 -215.459684) (xy 332.572767 -215.410849)
			(xy 332.599673 -215.36559) (xy 332.633173 -215.324969) (xy 332.672481 -215.289938) (xy 332.716676 -215.261318)
			(xy 332.764721 -215.239779) (xy 332.815492 -215.225827) (xy 332.867797 -215.219789) (xy 332.920411 -215.221806)
			(xy 332.972101 -215.23183) (xy 333.021654 -215.249628) (xy 333.06791 -215.274781) (xy 333.109784 -215.3067)
			(xy 333.146296 -215.344638) (xy 333.176588 -215.387704) (xy 333.199951 -215.434889) (xy 333.215837 -215.485088)
			(xy 333.223874 -215.537124) (xy 333.224378 -215.56345) (xy 333.223921 -215.587326) (xy 333.350111 -215.587326)
			(xy 333.354141 -215.534828) (xy 333.366138 -215.48356) (xy 333.385821 -215.434725) (xy 333.412727 -215.389466)
			(xy 333.446227 -215.348845) (xy 333.485535 -215.313814) (xy 333.52973 -215.285194) (xy 333.577775 -215.263655)
			(xy 333.628546 -215.249703) (xy 333.680851 -215.243665) (xy 333.733465 -215.245682) (xy 333.785155 -215.255706)
			(xy 333.834708 -215.273504) (xy 333.880964 -215.298657) (xy 333.922838 -215.330576) (xy 333.95935 -215.368514)
			(xy 333.989642 -215.41158) (xy 334.013005 -215.458765) (xy 334.028891 -215.508964) (xy 334.036928 -215.561)
			(xy 334.037432 -215.587326) (xy 334.150211 -215.587326) (xy 334.154241 -215.534828) (xy 334.166238 -215.48356)
			(xy 334.185921 -215.434725) (xy 334.212827 -215.389466) (xy 334.246327 -215.348845) (xy 334.285635 -215.313814)
			(xy 334.32983 -215.285194) (xy 334.377875 -215.263655) (xy 334.428646 -215.249703) (xy 334.480951 -215.243665)
			(xy 334.533565 -215.245682) (xy 334.585255 -215.255706) (xy 334.634808 -215.273504) (xy 334.681064 -215.298657)
			(xy 334.722938 -215.330576) (xy 334.75945 -215.368514) (xy 334.789742 -215.41158) (xy 334.813105 -215.458765)
			(xy 334.828991 -215.508964) (xy 334.837028 -215.561) (xy 334.837532 -215.587326) (xy 334.950057 -215.587326)
			(xy 334.954087 -215.534828) (xy 334.966084 -215.48356) (xy 334.985767 -215.434725) (xy 335.012673 -215.389466)
			(xy 335.046173 -215.348845) (xy 335.085481 -215.313814) (xy 335.129676 -215.285194) (xy 335.177721 -215.263655)
			(xy 335.228492 -215.249703) (xy 335.280797 -215.243665) (xy 335.333411 -215.245682) (xy 335.385101 -215.255706)
			(xy 335.434654 -215.273504) (xy 335.48091 -215.298657) (xy 335.522784 -215.330576) (xy 335.559296 -215.368514)
			(xy 335.589588 -215.41158) (xy 335.612951 -215.458765) (xy 335.628837 -215.508964) (xy 335.636874 -215.561)
			(xy 335.637378 -215.587326) (xy 335.750157 -215.587326) (xy 335.754187 -215.534828) (xy 335.766184 -215.48356)
			(xy 335.785867 -215.434725) (xy 335.812773 -215.389466) (xy 335.846273 -215.348845) (xy 335.885581 -215.313814)
			(xy 335.929776 -215.285194) (xy 335.977821 -215.263655) (xy 336.028592 -215.249703) (xy 336.080897 -215.243665)
			(xy 336.133511 -215.245682) (xy 336.185201 -215.255706) (xy 336.234754 -215.273504) (xy 336.28101 -215.298657)
			(xy 336.322884 -215.330576) (xy 336.359396 -215.368514) (xy 336.389688 -215.41158) (xy 336.413051 -215.458765)
			(xy 336.428937 -215.508964) (xy 336.436974 -215.561) (xy 336.437478 -215.587326) (xy 336.550257 -215.587326)
			(xy 336.554287 -215.534828) (xy 336.566284 -215.48356) (xy 336.585967 -215.434725) (xy 336.612873 -215.389466)
			(xy 336.646373 -215.348845) (xy 336.685681 -215.313814) (xy 336.729876 -215.285194) (xy 336.777921 -215.263655)
			(xy 336.828692 -215.249703) (xy 336.880997 -215.243665) (xy 336.933611 -215.245682) (xy 336.985301 -215.255706)
			(xy 337.034854 -215.273504) (xy 337.08111 -215.298657) (xy 337.122984 -215.330576) (xy 337.159496 -215.368514)
			(xy 337.189788 -215.41158) (xy 337.213151 -215.458765) (xy 337.229037 -215.508964) (xy 337.237074 -215.561)
			(xy 337.237578 -215.587326) (xy 337.350103 -215.587326) (xy 337.354133 -215.534828) (xy 337.36613 -215.48356)
			(xy 337.385813 -215.434725) (xy 337.412719 -215.389466) (xy 337.446219 -215.348845) (xy 337.485527 -215.313814)
			(xy 337.529722 -215.285194) (xy 337.577767 -215.263655) (xy 337.628538 -215.249703) (xy 337.680843 -215.243665)
			(xy 337.733457 -215.245682) (xy 337.785147 -215.255706) (xy 337.8347 -215.273504) (xy 337.880956 -215.298657)
			(xy 337.92283 -215.330576) (xy 337.959342 -215.368514) (xy 337.989634 -215.41158) (xy 338.012997 -215.458765)
			(xy 338.028883 -215.508964) (xy 338.03692 -215.561) (xy 338.037424 -215.587326) (xy 338.03692 -215.613652)
			(xy 338.028883 -215.665688) (xy 338.012997 -215.715887) (xy 337.989634 -215.763072) (xy 337.959342 -215.806138)
			(xy 337.92283 -215.844076) (xy 337.880956 -215.875995) (xy 337.8347 -215.901148) (xy 337.785147 -215.918946)
			(xy 337.733457 -215.92897) (xy 337.680843 -215.930987) (xy 337.628538 -215.924949) (xy 337.577767 -215.910997)
			(xy 337.529722 -215.889458) (xy 337.485527 -215.860838) (xy 337.446219 -215.825807) (xy 337.412719 -215.785186)
			(xy 337.385813 -215.739927) (xy 337.36613 -215.691092) (xy 337.354133 -215.639824) (xy 337.350103 -215.587326)
			(xy 337.237578 -215.587326) (xy 337.237074 -215.613652) (xy 337.229037 -215.665688) (xy 337.213151 -215.715887)
			(xy 337.189788 -215.763072) (xy 337.159496 -215.806138) (xy 337.122984 -215.844076) (xy 337.08111 -215.875995)
			(xy 337.034854 -215.901148) (xy 336.985301 -215.918946) (xy 336.933611 -215.92897) (xy 336.880997 -215.930987)
			(xy 336.828692 -215.924949) (xy 336.777921 -215.910997) (xy 336.729876 -215.889458) (xy 336.685681 -215.860838)
			(xy 336.646373 -215.825807) (xy 336.612873 -215.785186) (xy 336.585967 -215.739927) (xy 336.566284 -215.691092)
			(xy 336.554287 -215.639824) (xy 336.550257 -215.587326) (xy 336.437478 -215.587326) (xy 336.436974 -215.613652)
			(xy 336.428937 -215.665688) (xy 336.413051 -215.715887) (xy 336.389688 -215.763072) (xy 336.359396 -215.806138)
			(xy 336.322884 -215.844076) (xy 336.28101 -215.875995) (xy 336.234754 -215.901148) (xy 336.185201 -215.918946)
			(xy 336.133511 -215.92897) (xy 336.080897 -215.930987) (xy 336.028592 -215.924949) (xy 335.977821 -215.910997)
			(xy 335.929776 -215.889458) (xy 335.885581 -215.860838) (xy 335.846273 -215.825807) (xy 335.812773 -215.785186)
			(xy 335.785867 -215.739927) (xy 335.766184 -215.691092) (xy 335.754187 -215.639824) (xy 335.750157 -215.587326)
			(xy 335.637378 -215.587326) (xy 335.636874 -215.613652) (xy 335.628837 -215.665688) (xy 335.612951 -215.715887)
			(xy 335.589588 -215.763072) (xy 335.559296 -215.806138) (xy 335.522784 -215.844076) (xy 335.48091 -215.875995)
			(xy 335.434654 -215.901148) (xy 335.385101 -215.918946) (xy 335.333411 -215.92897) (xy 335.280797 -215.930987)
			(xy 335.228492 -215.924949) (xy 335.177721 -215.910997) (xy 335.129676 -215.889458) (xy 335.085481 -215.860838)
			(xy 335.046173 -215.825807) (xy 335.012673 -215.785186) (xy 334.985767 -215.739927) (xy 334.966084 -215.691092)
			(xy 334.954087 -215.639824) (xy 334.950057 -215.587326) (xy 334.837532 -215.587326) (xy 334.837028 -215.613652)
			(xy 334.828991 -215.665688) (xy 334.813105 -215.715887) (xy 334.789742 -215.763072) (xy 334.75945 -215.806138)
			(xy 334.722938 -215.844076) (xy 334.681064 -215.875995) (xy 334.634808 -215.901148) (xy 334.585255 -215.918946)
			(xy 334.533565 -215.92897) (xy 334.480951 -215.930987) (xy 334.428646 -215.924949) (xy 334.377875 -215.910997)
			(xy 334.32983 -215.889458) (xy 334.285635 -215.860838) (xy 334.246327 -215.825807) (xy 334.212827 -215.785186)
			(xy 334.185921 -215.739927) (xy 334.166238 -215.691092) (xy 334.154241 -215.639824) (xy 334.150211 -215.587326)
			(xy 334.037432 -215.587326) (xy 334.036928 -215.613652) (xy 334.028891 -215.665688) (xy 334.013005 -215.715887)
			(xy 333.989642 -215.763072) (xy 333.95935 -215.806138) (xy 333.922838 -215.844076) (xy 333.880964 -215.875995)
			(xy 333.834708 -215.901148) (xy 333.785155 -215.918946) (xy 333.733465 -215.92897) (xy 333.680851 -215.930987)
			(xy 333.628546 -215.924949) (xy 333.577775 -215.910997) (xy 333.52973 -215.889458) (xy 333.485535 -215.860838)
			(xy 333.446227 -215.825807) (xy 333.412727 -215.785186) (xy 333.385821 -215.739927) (xy 333.366138 -215.691092)
			(xy 333.354141 -215.639824) (xy 333.350111 -215.587326) (xy 333.223921 -215.587326) (xy 333.223874 -215.589776)
			(xy 333.215837 -215.641812) (xy 333.199951 -215.692011) (xy 333.176588 -215.739196) (xy 333.146296 -215.782262)
			(xy 333.109784 -215.8202) (xy 333.06791 -215.852119) (xy 333.021654 -215.877272) (xy 332.972101 -215.89507)
			(xy 332.920411 -215.905094) (xy 332.867797 -215.907111) (xy 332.815492 -215.901073) (xy 332.764721 -215.887121)
			(xy 332.716676 -215.865582) (xy 332.672481 -215.836962) (xy 332.633173 -215.801931) (xy 332.599673 -215.76131)
			(xy 332.572767 -215.716051) (xy 332.553084 -215.667216) (xy 332.541087 -215.615948) (xy 332.537057 -215.56345)
			(xy 331.46365 -215.56345) (xy 331.46365 -215.96223) (xy 331.46408 -215.972297) (xy 331.471808 -215.990888)
			(xy 331.478636 -215.998298) (xy 331.48143 -216.001092) (xy 331.488285 -216.008487) (xy 331.496034 -216.027085)
			(xy 331.496416 -216.03716) (xy 331.496416 -216.114884) (xy 331.496416 -216.291414) (xy 331.46365 -216.312242)
			(xy 331.46365 -216.385648) (xy 331.463716 -216.387172) (xy 334.950057 -216.387172) (xy 334.954087 -216.334674)
			(xy 334.966084 -216.283406) (xy 334.985767 -216.234571) (xy 335.012673 -216.189312) (xy 335.046173 -216.148691)
			(xy 335.085481 -216.11366) (xy 335.129676 -216.08504) (xy 335.177721 -216.063501) (xy 335.228492 -216.049549)
			(xy 335.280797 -216.043511) (xy 335.333411 -216.045528) (xy 335.385101 -216.055552) (xy 335.434654 -216.07335)
			(xy 335.48091 -216.098503) (xy 335.522784 -216.130422) (xy 335.559296 -216.16836) (xy 335.589588 -216.211426)
			(xy 335.612951 -216.258611) (xy 335.628837 -216.30881) (xy 335.636874 -216.360846) (xy 335.637378 -216.387172)
			(xy 335.750157 -216.387172) (xy 335.754187 -216.334674) (xy 335.766184 -216.283406) (xy 335.785867 -216.234571)
			(xy 335.812773 -216.189312) (xy 335.846273 -216.148691) (xy 335.885581 -216.11366) (xy 335.929776 -216.08504)
			(xy 335.977821 -216.063501) (xy 336.028592 -216.049549) (xy 336.080897 -216.043511) (xy 336.133511 -216.045528)
			(xy 336.185201 -216.055552) (xy 336.234754 -216.07335) (xy 336.28101 -216.098503) (xy 336.322884 -216.130422)
			(xy 336.359396 -216.16836) (xy 336.389688 -216.211426) (xy 336.413051 -216.258611) (xy 336.428937 -216.30881)
			(xy 336.436974 -216.360846) (xy 336.437478 -216.387172) (xy 336.550257 -216.387172) (xy 336.554287 -216.334674)
			(xy 336.566284 -216.283406) (xy 336.585967 -216.234571) (xy 336.612873 -216.189312) (xy 336.646373 -216.148691)
			(xy 336.685681 -216.11366) (xy 336.729876 -216.08504) (xy 336.777921 -216.063501) (xy 336.828692 -216.049549)
			(xy 336.880997 -216.043511) (xy 336.933611 -216.045528) (xy 336.985301 -216.055552) (xy 337.034854 -216.07335)
			(xy 337.08111 -216.098503) (xy 337.122984 -216.130422) (xy 337.159496 -216.16836) (xy 337.189788 -216.211426)
			(xy 337.213151 -216.258611) (xy 337.229037 -216.30881) (xy 337.237074 -216.360846) (xy 337.237578 -216.387172)
			(xy 337.350103 -216.387172) (xy 337.354133 -216.334674) (xy 337.36613 -216.283406) (xy 337.385813 -216.234571)
			(xy 337.412719 -216.189312) (xy 337.446219 -216.148691) (xy 337.485527 -216.11366) (xy 337.529722 -216.08504)
			(xy 337.577767 -216.063501) (xy 337.628538 -216.049549) (xy 337.680843 -216.043511) (xy 337.733457 -216.045528)
			(xy 337.785147 -216.055552) (xy 337.8347 -216.07335) (xy 337.880956 -216.098503) (xy 337.92283 -216.130422)
			(xy 337.959342 -216.16836) (xy 337.989634 -216.211426) (xy 338.012997 -216.258611) (xy 338.028883 -216.30881)
			(xy 338.03692 -216.360846) (xy 338.037424 -216.387172) (xy 338.03692 -216.413498) (xy 338.028883 -216.465534)
			(xy 338.012997 -216.515733) (xy 337.989634 -216.562918) (xy 337.959342 -216.605984) (xy 337.92283 -216.643922)
			(xy 337.880956 -216.675841) (xy 337.8347 -216.700994) (xy 337.785147 -216.718792) (xy 337.733457 -216.728816)
			(xy 337.680843 -216.730833) (xy 337.628538 -216.724795) (xy 337.577767 -216.710843) (xy 337.529722 -216.689304)
			(xy 337.485527 -216.660684) (xy 337.446219 -216.625653) (xy 337.412719 -216.585032) (xy 337.385813 -216.539773)
			(xy 337.36613 -216.490938) (xy 337.354133 -216.43967) (xy 337.350103 -216.387172) (xy 337.237578 -216.387172)
			(xy 337.237074 -216.413498) (xy 337.229037 -216.465534) (xy 337.213151 -216.515733) (xy 337.189788 -216.562918)
			(xy 337.159496 -216.605984) (xy 337.122984 -216.643922) (xy 337.08111 -216.675841) (xy 337.034854 -216.700994)
			(xy 336.985301 -216.718792) (xy 336.933611 -216.728816) (xy 336.880997 -216.730833) (xy 336.828692 -216.724795)
			(xy 336.777921 -216.710843) (xy 336.729876 -216.689304) (xy 336.685681 -216.660684) (xy 336.646373 -216.625653)
			(xy 336.612873 -216.585032) (xy 336.585967 -216.539773) (xy 336.566284 -216.490938) (xy 336.554287 -216.43967)
			(xy 336.550257 -216.387172) (xy 336.437478 -216.387172) (xy 336.436974 -216.413498) (xy 336.428937 -216.465534)
			(xy 336.413051 -216.515733) (xy 336.389688 -216.562918) (xy 336.359396 -216.605984) (xy 336.322884 -216.643922)
			(xy 336.28101 -216.675841) (xy 336.234754 -216.700994) (xy 336.185201 -216.718792) (xy 336.133511 -216.728816)
			(xy 336.080897 -216.730833) (xy 336.028592 -216.724795) (xy 335.977821 -216.710843) (xy 335.929776 -216.689304)
			(xy 335.885581 -216.660684) (xy 335.846273 -216.625653) (xy 335.812773 -216.585032) (xy 335.785867 -216.539773)
			(xy 335.766184 -216.490938) (xy 335.754187 -216.43967) (xy 335.750157 -216.387172) (xy 335.637378 -216.387172)
			(xy 335.636874 -216.413498) (xy 335.628837 -216.465534) (xy 335.612951 -216.515733) (xy 335.589588 -216.562918)
			(xy 335.559296 -216.605984) (xy 335.522784 -216.643922) (xy 335.48091 -216.675841) (xy 335.434654 -216.700994)
			(xy 335.385101 -216.718792) (xy 335.333411 -216.728816) (xy 335.280797 -216.730833) (xy 335.228492 -216.724795)
			(xy 335.177721 -216.710843) (xy 335.129676 -216.689304) (xy 335.085481 -216.660684) (xy 335.046173 -216.625653)
			(xy 335.012673 -216.585032) (xy 334.985767 -216.539773) (xy 334.966084 -216.490938) (xy 334.954087 -216.43967)
			(xy 334.950057 -216.387172) (xy 331.463716 -216.387172) (xy 331.464083 -216.395713) (xy 331.471816 -216.4143)
			(xy 331.478636 -216.421716) (xy 331.479906 -216.422986) (xy 331.486738 -216.43039) (xy 331.49444 -216.448988)
			(xy 331.494892 -216.459054) (xy 331.494892 -217.178382) (xy 331.495257 -217.186764) (xy 333.350111 -217.186764)
			(xy 333.354141 -217.134266) (xy 333.366138 -217.082998) (xy 333.385821 -217.034163) (xy 333.412727 -216.988904)
			(xy 333.446227 -216.948283) (xy 333.485535 -216.913252) (xy 333.52973 -216.884632) (xy 333.577775 -216.863093)
			(xy 333.628546 -216.849141) (xy 333.680851 -216.843103) (xy 333.733465 -216.84512) (xy 333.785155 -216.855144)
			(xy 333.834708 -216.872942) (xy 333.880964 -216.898095) (xy 333.922838 -216.930014) (xy 333.95935 -216.967952)
			(xy 333.989642 -217.011018) (xy 334.013005 -217.058203) (xy 334.028891 -217.108402) (xy 334.036928 -217.160438)
			(xy 334.037432 -217.186764) (xy 334.037422 -217.187272) (xy 334.150211 -217.187272) (xy 334.154241 -217.134774)
			(xy 334.166238 -217.083506) (xy 334.185921 -217.034671) (xy 334.212827 -216.989412) (xy 334.246327 -216.948791)
			(xy 334.285635 -216.91376) (xy 334.32983 -216.88514) (xy 334.377875 -216.863601) (xy 334.428646 -216.849649)
			(xy 334.480951 -216.843611) (xy 334.533565 -216.845628) (xy 334.585255 -216.855652) (xy 334.634808 -216.87345)
			(xy 334.681064 -216.898603) (xy 334.722938 -216.930522) (xy 334.75945 -216.96846) (xy 334.789742 -217.011526)
			(xy 334.813105 -217.058711) (xy 334.828991 -217.10891) (xy 334.837028 -217.160946) (xy 334.837532 -217.187272)
			(xy 334.950057 -217.187272) (xy 334.954087 -217.134774) (xy 334.966084 -217.083506) (xy 334.985767 -217.034671)
			(xy 335.012673 -216.989412) (xy 335.046173 -216.948791) (xy 335.085481 -216.91376) (xy 335.129676 -216.88514)
			(xy 335.177721 -216.863601) (xy 335.228492 -216.849649) (xy 335.280797 -216.843611) (xy 335.333411 -216.845628)
			(xy 335.385101 -216.855652) (xy 335.434654 -216.87345) (xy 335.48091 -216.898603) (xy 335.522784 -216.930522)
			(xy 335.559296 -216.96846) (xy 335.589588 -217.011526) (xy 335.612951 -217.058711) (xy 335.628837 -217.10891)
			(xy 335.636874 -217.160946) (xy 335.637373 -217.187018) (xy 335.749903 -217.187018) (xy 335.753933 -217.13452)
			(xy 335.76593 -217.083252) (xy 335.785613 -217.034417) (xy 335.812519 -216.989158) (xy 335.846019 -216.948537)
			(xy 335.885327 -216.913506) (xy 335.929522 -216.884886) (xy 335.977567 -216.863347) (xy 336.028338 -216.849395)
			(xy 336.080643 -216.843357) (xy 336.133257 -216.845374) (xy 336.184947 -216.855398) (xy 336.2345 -216.873196)
			(xy 336.280756 -216.898349) (xy 336.32263 -216.930268) (xy 336.359142 -216.968206) (xy 336.389434 -217.011272)
			(xy 336.412797 -217.058457) (xy 336.428683 -217.108656) (xy 336.43672 -217.160692) (xy 336.437224 -217.187018)
			(xy 336.437219 -217.187272) (xy 336.550257 -217.187272) (xy 336.554287 -217.134774) (xy 336.566284 -217.083506)
			(xy 336.585967 -217.034671) (xy 336.612873 -216.989412) (xy 336.646373 -216.948791) (xy 336.685681 -216.91376)
			(xy 336.729876 -216.88514) (xy 336.777921 -216.863601) (xy 336.828692 -216.849649) (xy 336.880997 -216.843611)
			(xy 336.933611 -216.845628) (xy 336.985301 -216.855652) (xy 337.034854 -216.87345) (xy 337.08111 -216.898603)
			(xy 337.122984 -216.930522) (xy 337.159496 -216.96846) (xy 337.189788 -217.011526) (xy 337.213151 -217.058711)
			(xy 337.229037 -217.10891) (xy 337.237074 -217.160946) (xy 337.237578 -217.187272) (xy 337.350103 -217.187272)
			(xy 337.354133 -217.134774) (xy 337.36613 -217.083506) (xy 337.385813 -217.034671) (xy 337.412719 -216.989412)
			(xy 337.446219 -216.948791) (xy 337.485527 -216.91376) (xy 337.529722 -216.88514) (xy 337.577767 -216.863601)
			(xy 337.628538 -216.849649) (xy 337.680843 -216.843611) (xy 337.733457 -216.845628) (xy 337.785147 -216.855652)
			(xy 337.8347 -216.87345) (xy 337.880956 -216.898603) (xy 337.92283 -216.930522) (xy 337.959342 -216.96846)
			(xy 337.989634 -217.011526) (xy 338.012997 -217.058711) (xy 338.028883 -217.10891) (xy 338.03692 -217.160946)
			(xy 338.037424 -217.187272) (xy 338.150203 -217.187272) (xy 338.154233 -217.134774) (xy 338.16623 -217.083506)
			(xy 338.185913 -217.034671) (xy 338.212819 -216.989412) (xy 338.246319 -216.948791) (xy 338.285627 -216.91376)
			(xy 338.329822 -216.88514) (xy 338.377867 -216.863601) (xy 338.428638 -216.849649) (xy 338.480943 -216.843611)
			(xy 338.533557 -216.845628) (xy 338.585247 -216.855652) (xy 338.6348 -216.87345) (xy 338.681056 -216.898603)
			(xy 338.72293 -216.930522) (xy 338.759442 -216.96846) (xy 338.789734 -217.011526) (xy 338.813097 -217.058711)
			(xy 338.828983 -217.10891) (xy 338.83702 -217.160946) (xy 338.837524 -217.187272) (xy 338.83702 -217.213598)
			(xy 338.828983 -217.265634) (xy 338.813097 -217.315833) (xy 338.789734 -217.363018) (xy 338.759442 -217.406084)
			(xy 338.72293 -217.444022) (xy 338.681056 -217.475941) (xy 338.6348 -217.501094) (xy 338.585247 -217.518892)
			(xy 338.533557 -217.528916) (xy 338.480943 -217.530933) (xy 338.428638 -217.524895) (xy 338.377867 -217.510943)
			(xy 338.329822 -217.489404) (xy 338.285627 -217.460784) (xy 338.246319 -217.425753) (xy 338.212819 -217.385132)
			(xy 338.185913 -217.339873) (xy 338.16623 -217.291038) (xy 338.154233 -217.23977) (xy 338.150203 -217.187272)
			(xy 338.037424 -217.187272) (xy 338.03692 -217.213598) (xy 338.028883 -217.265634) (xy 338.012997 -217.315833)
			(xy 337.989634 -217.363018) (xy 337.959342 -217.406084) (xy 337.92283 -217.444022) (xy 337.880956 -217.475941)
			(xy 337.8347 -217.501094) (xy 337.785147 -217.518892) (xy 337.733457 -217.528916) (xy 337.680843 -217.530933)
			(xy 337.628538 -217.524895) (xy 337.577767 -217.510943) (xy 337.529722 -217.489404) (xy 337.485527 -217.460784)
			(xy 337.446219 -217.425753) (xy 337.412719 -217.385132) (xy 337.385813 -217.339873) (xy 337.36613 -217.291038)
			(xy 337.354133 -217.23977) (xy 337.350103 -217.187272) (xy 337.237578 -217.187272) (xy 337.237074 -217.213598)
			(xy 337.229037 -217.265634) (xy 337.213151 -217.315833) (xy 337.189788 -217.363018) (xy 337.159496 -217.406084)
			(xy 337.122984 -217.444022) (xy 337.08111 -217.475941) (xy 337.034854 -217.501094) (xy 336.985301 -217.518892)
			(xy 336.933611 -217.528916) (xy 336.880997 -217.530933) (xy 336.828692 -217.524895) (xy 336.777921 -217.510943)
			(xy 336.729876 -217.489404) (xy 336.685681 -217.460784) (xy 336.646373 -217.425753) (xy 336.612873 -217.385132)
			(xy 336.585967 -217.339873) (xy 336.566284 -217.291038) (xy 336.554287 -217.23977) (xy 336.550257 -217.187272)
			(xy 336.437219 -217.187272) (xy 336.43672 -217.213344) (xy 336.428683 -217.26538) (xy 336.412797 -217.315579)
			(xy 336.389434 -217.362764) (xy 336.359142 -217.40583) (xy 336.32263 -217.443768) (xy 336.280756 -217.475687)
			(xy 336.2345 -217.50084) (xy 336.184947 -217.518638) (xy 336.133257 -217.528662) (xy 336.080643 -217.530679)
			(xy 336.028338 -217.524641) (xy 335.977567 -217.510689) (xy 335.929522 -217.48915) (xy 335.885327 -217.46053)
			(xy 335.846019 -217.425499) (xy 335.812519 -217.384878) (xy 335.785613 -217.339619) (xy 335.76593 -217.290784)
			(xy 335.753933 -217.239516) (xy 335.749903 -217.187018) (xy 335.637373 -217.187018) (xy 335.637378 -217.187272)
			(xy 335.636874 -217.213598) (xy 335.628837 -217.265634) (xy 335.612951 -217.315833) (xy 335.589588 -217.363018)
			(xy 335.559296 -217.406084) (xy 335.522784 -217.444022) (xy 335.48091 -217.475941) (xy 335.434654 -217.501094)
			(xy 335.385101 -217.518892) (xy 335.333411 -217.528916) (xy 335.280797 -217.530933) (xy 335.228492 -217.524895)
			(xy 335.177721 -217.510943) (xy 335.129676 -217.489404) (xy 335.085481 -217.460784) (xy 335.046173 -217.425753)
			(xy 335.012673 -217.385132) (xy 334.985767 -217.339873) (xy 334.966084 -217.291038) (xy 334.954087 -217.23977)
			(xy 334.950057 -217.187272) (xy 334.837532 -217.187272) (xy 334.837028 -217.213598) (xy 334.828991 -217.265634)
			(xy 334.813105 -217.315833) (xy 334.789742 -217.363018) (xy 334.75945 -217.406084) (xy 334.722938 -217.444022)
			(xy 334.681064 -217.475941) (xy 334.634808 -217.501094) (xy 334.585255 -217.518892) (xy 334.533565 -217.528916)
			(xy 334.480951 -217.530933) (xy 334.428646 -217.524895) (xy 334.377875 -217.510943) (xy 334.32983 -217.489404)
			(xy 334.285635 -217.460784) (xy 334.246327 -217.425753) (xy 334.212827 -217.385132) (xy 334.185921 -217.339873)
			(xy 334.166238 -217.291038) (xy 334.154241 -217.23977) (xy 334.150211 -217.187272) (xy 334.037422 -217.187272)
			(xy 334.036928 -217.21309) (xy 334.028891 -217.265126) (xy 334.013005 -217.315325) (xy 333.989642 -217.36251)
			(xy 333.95935 -217.405576) (xy 333.922838 -217.443514) (xy 333.880964 -217.475433) (xy 333.834708 -217.500586)
			(xy 333.785155 -217.518384) (xy 333.733465 -217.528408) (xy 333.680851 -217.530425) (xy 333.628546 -217.524387)
			(xy 333.577775 -217.510435) (xy 333.52973 -217.488896) (xy 333.485535 -217.460276) (xy 333.446227 -217.425245)
			(xy 333.412727 -217.384624) (xy 333.385821 -217.339365) (xy 333.366138 -217.29053) (xy 333.354141 -217.239262)
			(xy 333.350111 -217.186764) (xy 331.495257 -217.186764) (xy 331.49533 -217.188446) (xy 331.503064 -217.207029)
			(xy 331.509878 -217.21445) (xy 332.543404 -218.247976) (xy 332.550802 -218.254824) (xy 332.5694 -218.262561)
			(xy 332.579472 -218.262962)
		)
		(stroke
			(width 0)
			(type solid)
		)
		(fill yes)
		(layer "B.Cu")
		(net "P3V3_FPGA_VCCIO3")
	)
	(gr_poly
		(pts
			(xy 161.968688 -142.106142) (xy 161.978649 -142.105653) (xy 161.997072 -142.098064) (xy 162.004502 -142.09141)
			(xy 162.044126 -142.05204) (xy 162.065716 -142.03045) (xy 162.071239 -142.023919) (xy 162.078003 -142.008219)
			(xy 162.078924 -141.999716) (xy 162.078924 -139.55903) (xy 162.078393 -139.549039) (xy 162.07069 -139.530597)
			(xy 162.063938 -139.523216) (xy 162.024822 -139.4841) (xy 162.01771 -139.476734) (xy 161.998914 -139.469114)
			(xy 160.52673 -139.469114) (xy 160.516665 -139.468679) (xy 160.498078 -139.460948) (xy 160.490662 -139.454128)
			(xy 158.472632 -137.436098) (xy 158.46552 -137.428732) (xy 158.446724 -137.421112) (xy 150.86076 -137.421112)
			(xy 150.850693 -137.420682) (xy 150.832098 -137.412959) (xy 150.824692 -137.406126) (xy 147.379436 -133.96087)
			(xy 147.37259 -133.953472) (xy 147.364861 -133.934873) (xy 147.36445 -133.924802) (xy 147.36445 -120.604534)
			(xy 147.364013 -120.59447) (xy 147.356277 -120.575888) (xy 147.349464 -120.568466) (xy 142.104618 -115.32362)
			(xy 142.097506 -115.316254) (xy 142.07871 -115.308634) (xy 130.46837 -115.308634) (xy 130.458434 -115.30907)
			(xy 130.44002 -115.316535) (xy 130.432556 -115.323112) (xy 130.374644 -115.380262) (xy 130.36677 -115.398296)
			(xy 130.36677 -115.408456) (xy 130.365879 -115.435181) (xy 130.35753 -115.487996) (xy 130.341875 -115.539125)
			(xy 130.319222 -115.587561) (xy 130.290016 -115.632352) (xy 130.27279 -115.652804) (xy 130.266694 -115.659916)
			(xy 130.260344 -115.676934) (xy 130.260344 -115.762278) (xy 130.266694 -115.779296) (xy 130.27279 -115.786408)
			(xy 130.29043 -115.807341) (xy 130.320152 -115.853309) (xy 130.342996 -115.903055) (xy 130.35849 -115.955557)
			(xy 130.366318 -116.009734) (xy 130.366317 -116.064475) (xy 130.358489 -116.118652) (xy 130.342993 -116.171153)
			(xy 130.320148 -116.220899) (xy 130.290424 -116.266866) (xy 130.27279 -116.287804) (xy 130.266694 -116.294916)
			(xy 130.260344 -116.311934) (xy 130.260344 -116.397278) (xy 130.266694 -116.414296) (xy 130.27279 -116.421408)
			(xy 130.290432 -116.442339) (xy 130.320158 -116.488306) (xy 130.343001 -116.538053) (xy 130.35849 -116.590556)
			(xy 130.366308 -116.644736) (xy 130.36677 -116.672106) (xy 130.366362 -116.69651) (xy 130.364595 -116.710202)
			(xy 131.175742 -116.710202) (xy 131.175742 -116.650266) (xy 131.183565 -116.590844) (xy 131.199078 -116.532951)
			(xy 131.222014 -116.477578) (xy 131.251981 -116.425672) (xy 131.288468 -116.378122) (xy 131.330848 -116.335742)
			(xy 131.378398 -116.299255) (xy 131.430304 -116.269288) (xy 131.485677 -116.246352) (xy 131.54357 -116.230839)
			(xy 131.602992 -116.223016) (xy 131.662928 -116.223016) (xy 131.72235 -116.230839) (xy 131.780243 -116.246352)
			(xy 131.835616 -116.269288) (xy 131.887522 -116.299255) (xy 131.935072 -116.335742) (xy 131.977452 -116.378122)
			(xy 132.013939 -116.425672) (xy 132.043906 -116.477578) (xy 132.066842 -116.532951) (xy 132.082355 -116.590844)
			(xy 132.090178 -116.650266) (xy 132.090668 -116.680234) (xy 132.090178 -116.710202) (xy 132.082355 -116.769624)
			(xy 132.066842 -116.827517) (xy 132.043906 -116.88289) (xy 132.013939 -116.934796) (xy 131.977452 -116.982346)
			(xy 131.935072 -117.024726) (xy 131.887522 -117.061213) (xy 131.835616 -117.09118) (xy 131.780243 -117.114116)
			(xy 131.72235 -117.129629) (xy 131.662928 -117.137452) (xy 131.602992 -117.137452) (xy 131.54357 -117.129629)
			(xy 131.485677 -117.114116) (xy 131.430304 -117.09118) (xy 131.378398 -117.061213) (xy 131.330848 -117.024726)
			(xy 131.288468 -116.982346) (xy 131.251981 -116.934796) (xy 131.222014 -116.88289) (xy 131.199078 -116.827517)
			(xy 131.183565 -116.769624) (xy 131.175742 -116.710202) (xy 130.364595 -116.710202) (xy 130.360116 -116.744916)
			(xy 130.354324 -116.768626) (xy 130.35153 -116.779294) (xy 130.35534 -116.80063) (xy 130.410204 -116.882164)
			(xy 130.428746 -116.893594) (xy 130.439668 -116.895118) (xy 130.469362 -116.899451) (xy 130.52735 -116.914893)
			(xy 130.582822 -116.93778) (xy 130.634828 -116.967721) (xy 130.682476 -117.004201) (xy 130.724947 -117.046595)
			(xy 130.761514 -117.094175) (xy 130.79155 -117.146127) (xy 130.814538 -117.201557) (xy 130.830086 -117.259517)
			(xy 130.837926 -117.319012) (xy 130.838147 -117.33174) (xy 132.322806 -117.33174) (xy 132.322806 -117.271804)
			(xy 132.330629 -117.212382) (xy 132.346142 -117.154489) (xy 132.369078 -117.099116) (xy 132.399045 -117.04721)
			(xy 132.435532 -116.99966) (xy 132.477912 -116.95728) (xy 132.525462 -116.920793) (xy 132.577368 -116.890826)
			(xy 132.632741 -116.86789) (xy 132.690634 -116.852377) (xy 132.750056 -116.844554) (xy 132.809992 -116.844554)
			(xy 132.869414 -116.852377) (xy 132.927307 -116.86789) (xy 132.98268 -116.890826) (xy 133.034586 -116.920793)
			(xy 133.082136 -116.95728) (xy 133.124516 -116.99966) (xy 133.161003 -117.04721) (xy 133.19097 -117.099116)
			(xy 133.213906 -117.154489) (xy 133.229419 -117.212382) (xy 133.237242 -117.271804) (xy 133.237732 -117.301772)
			(xy 133.237242 -117.33174) (xy 133.229419 -117.391162) (xy 133.213906 -117.449055) (xy 133.19097 -117.504428)
			(xy 133.161003 -117.556334) (xy 133.124516 -117.603884) (xy 133.082136 -117.646264) (xy 133.034586 -117.682751)
			(xy 132.98268 -117.712718) (xy 132.927307 -117.735654) (xy 132.869414 -117.751167) (xy 132.809992 -117.75899)
			(xy 132.750056 -117.75899) (xy 132.690634 -117.751167) (xy 132.632741 -117.735654) (xy 132.577368 -117.712718)
			(xy 132.525462 -117.682751) (xy 132.477912 -117.646264) (xy 132.435532 -117.603884) (xy 132.399045 -117.556334)
			(xy 132.369078 -117.504428) (xy 132.346142 -117.449055) (xy 132.330629 -117.391162) (xy 132.322806 -117.33174)
			(xy 130.838147 -117.33174) (xy 130.838448 -117.349016) (xy 130.837958 -117.378984) (xy 130.830135 -117.438406)
			(xy 130.814622 -117.496299) (xy 130.791686 -117.551672) (xy 130.761719 -117.603578) (xy 130.725232 -117.651128)
			(xy 130.682852 -117.693508) (xy 130.635302 -117.729995) (xy 130.583396 -117.759962) (xy 130.528023 -117.782898)
			(xy 130.47013 -117.798411) (xy 130.410708 -117.806234) (xy 130.350772 -117.806234) (xy 130.29135 -117.798411)
			(xy 130.233457 -117.782898) (xy 130.178084 -117.759962) (xy 130.126178 -117.729995) (xy 130.078628 -117.693508)
			(xy 130.036248 -117.651128) (xy 129.999761 -117.603578) (xy 129.969794 -117.551672) (xy 129.946858 -117.496299)
			(xy 129.931345 -117.438406) (xy 129.923522 -117.378984) (xy 129.923032 -117.349016) (xy 129.92349 -117.319677)
			(xy 129.930954 -117.261475) (xy 129.945775 -117.2047) (xy 129.956306 -117.177312) (xy 129.960624 -117.167152)
			(xy 129.959608 -117.145308) (xy 129.915666 -117.057678) (xy 129.898648 -117.043962) (xy 129.888234 -117.040914)
			(xy 129.860076 -117.032986) (xy 129.806421 -117.009685) (xy 129.756962 -116.978451) (xy 129.734564 -116.959634)
			(xy 129.727452 -116.953538) (xy 129.710434 -116.947188) (xy 129.62509 -116.947188) (xy 129.608072 -116.953538)
			(xy 129.60096 -116.959634) (xy 129.580027 -116.977272) (xy 129.534059 -117.006991) (xy 129.484312 -117.029827)
			(xy 129.431809 -117.04531) (xy 129.377631 -117.053122) (xy 129.350262 -117.053614) (xy 129.323012 -117.053126)
			(xy 129.269068 -117.045365) (xy 129.216778 -117.030006) (xy 129.167205 -117.007363) (xy 129.121359 -116.977896)
			(xy 129.080173 -116.942205) (xy 129.044485 -116.901015) (xy 129.015021 -116.855167) (xy 128.992382 -116.805592)
			(xy 128.977028 -116.7533) (xy 128.969272 -116.699356) (xy 128.968754 -116.672106) (xy 128.969225 -116.644736)
			(xy 128.977049 -116.590558) (xy 128.992538 -116.538055) (xy 129.015372 -116.488305) (xy 129.045083 -116.442331)
			(xy 129.062734 -116.421408) (xy 129.06883 -116.414296) (xy 129.07518 -116.397278) (xy 129.07518 -116.311934)
			(xy 129.06883 -116.294916) (xy 129.062734 -116.287804) (xy 129.045093 -116.266871) (xy 129.015366 -116.220904)
			(xy 128.99252 -116.171157) (xy 128.977022 -116.118655) (xy 128.969193 -116.064475) (xy 128.969192 -116.009734)
			(xy 128.977021 -115.955554) (xy 128.992517 -115.903051) (xy 129.015362 -115.853304) (xy 129.045087 -115.807336)
			(xy 129.062734 -115.786408) (xy 129.06883 -115.779296) (xy 129.07518 -115.762278) (xy 129.07518 -115.676934)
			(xy 129.06883 -115.659916) (xy 129.062734 -115.652804) (xy 129.045508 -115.632355) (xy 129.016343 -115.587543)
			(xy 128.993708 -115.539104) (xy 128.978044 -115.487983) (xy 128.969658 -115.435178) (xy 128.968754 -115.408456)
			(xy 128.968754 -115.398296) (xy 128.96088 -115.380262) (xy 128.902968 -115.323112) (xy 128.895533 -115.316495)
			(xy 128.877099 -115.309041) (xy 128.867154 -115.308634) (xy 128.330198 -115.308634) (xy 128.320945 -115.309082)
			(xy 128.303662 -115.315717) (xy 128.289833 -115.328023) (xy 128.28524 -115.336066) (xy 128.23698 -115.428776)
			(xy 128.239012 -115.45697) (xy 128.24714 -115.468654) (xy 128.263569 -115.4929) (xy 128.289585 -115.54537)
			(xy 128.307274 -115.601202) (xy 128.316218 -115.659081) (xy 128.316736 -115.688364) (xy 128.31625 -115.715615)
			(xy 128.308494 -115.769563) (xy 128.293139 -115.821858) (xy 128.270497 -115.871435) (xy 128.241031 -115.917285)
			(xy 128.20534 -115.958476) (xy 128.164149 -115.994167) (xy 128.118299 -116.023633) (xy 128.068722 -116.046275)
			(xy 128.016427 -116.06163) (xy 127.962479 -116.069386) (xy 127.907977 -116.069386) (xy 127.854029 -116.06163)
			(xy 127.801734 -116.046275) (xy 127.752157 -116.023633) (xy 127.706307 -115.994167) (xy 127.665116 -115.958476)
			(xy 127.629425 -115.917285) (xy 127.599959 -115.871435) (xy 127.577317 -115.821858) (xy 127.561962 -115.769563)
			(xy 127.554206 -115.715615) (xy 127.55372 -115.688364) (xy 127.554256 -115.659082) (xy 127.563207 -115.601207)
			(xy 127.580893 -115.545379) (xy 127.606899 -115.492907) (xy 127.623316 -115.468654) (xy 127.631444 -115.45697)
			(xy 127.633476 -115.428776) (xy 127.585216 -115.336066) (xy 127.580617 -115.328013) (xy 127.566823 -115.315641)
			(xy 127.549522 -115.309007) (xy 127.540258 -115.308634) (xy 125.945646 -115.308634) (xy 125.935581 -115.309068)
			(xy 125.916994 -115.3168) (xy 125.909578 -115.32362) (xy 124.793756 -116.439442) (xy 124.78639 -116.446554)
			(xy 124.77877 -116.46535) (xy 124.77877 -117.357394) (xy 125.711948 -117.357394) (xy 125.711948 -117.297458)
			(xy 125.719771 -117.238036) (xy 125.735284 -117.180143) (xy 125.75822 -117.12477) (xy 125.788187 -117.072864)
			(xy 125.824674 -117.025314) (xy 125.867054 -116.982934) (xy 125.914604 -116.946447) (xy 125.96651 -116.91648)
			(xy 126.021883 -116.893544) (xy 126.079776 -116.878031) (xy 126.139198 -116.870208) (xy 126.199134 -116.870208)
			(xy 126.258556 -116.878031) (xy 126.316449 -116.893544) (xy 126.371822 -116.91648) (xy 126.423728 -116.946447)
			(xy 126.471278 -116.982934) (xy 126.513658 -117.025314) (xy 126.550145 -117.072864) (xy 126.580112 -117.12477)
			(xy 126.603048 -117.180143) (xy 126.616513 -117.230394) (xy 127.743948 -117.230394) (xy 127.743948 -117.170458)
			(xy 127.751771 -117.111036) (xy 127.767284 -117.053143) (xy 127.79022 -116.99777) (xy 127.820187 -116.945864)
			(xy 127.856674 -116.898314) (xy 127.899054 -116.855934) (xy 127.946604 -116.819447) (xy 127.99851 -116.78948)
			(xy 128.053883 -116.766544) (xy 128.111776 -116.751031) (xy 128.171198 -116.743208) (xy 128.231134 -116.743208)
			(xy 128.290556 -116.751031) (xy 128.348449 -116.766544) (xy 128.403822 -116.78948) (xy 128.455728 -116.819447)
			(xy 128.503278 -116.855934) (xy 128.545658 -116.898314) (xy 128.582145 -116.945864) (xy 128.612112 -116.99777)
			(xy 128.635048 -117.053143) (xy 128.650561 -117.111036) (xy 128.658384 -117.170458) (xy 128.658874 -117.200426)
			(xy 128.658384 -117.230394) (xy 128.650561 -117.289816) (xy 128.635048 -117.347709) (xy 128.612112 -117.403082)
			(xy 128.582145 -117.454988) (xy 128.545658 -117.502538) (xy 128.503278 -117.544918) (xy 128.455728 -117.581405)
			(xy 128.403822 -117.611372) (xy 128.348449 -117.634308) (xy 128.290556 -117.649821) (xy 128.231134 -117.657644)
			(xy 128.171198 -117.657644) (xy 128.111776 -117.649821) (xy 128.053883 -117.634308) (xy 127.99851 -117.611372)
			(xy 127.946604 -117.581405) (xy 127.899054 -117.544918) (xy 127.856674 -117.502538) (xy 127.820187 -117.454988)
			(xy 127.79022 -117.403082) (xy 127.767284 -117.347709) (xy 127.751771 -117.289816) (xy 127.743948 -117.230394)
			(xy 126.616513 -117.230394) (xy 126.618561 -117.238036) (xy 126.626384 -117.297458) (xy 126.626874 -117.327426)
			(xy 126.626384 -117.357394) (xy 126.618561 -117.416816) (xy 126.603048 -117.474709) (xy 126.580112 -117.530082)
			(xy 126.550145 -117.581988) (xy 126.513658 -117.629538) (xy 126.471278 -117.671918) (xy 126.423728 -117.708405)
			(xy 126.371822 -117.738372) (xy 126.316449 -117.761308) (xy 126.258556 -117.776821) (xy 126.199134 -117.784644)
			(xy 126.139198 -117.784644) (xy 126.079776 -117.776821) (xy 126.021883 -117.761308) (xy 125.96651 -117.738372)
			(xy 125.914604 -117.708405) (xy 125.867054 -117.671918) (xy 125.824674 -117.629538) (xy 125.788187 -117.581988)
			(xy 125.75822 -117.530082) (xy 125.735284 -117.474709) (xy 125.719771 -117.416816) (xy 125.711948 -117.357394)
			(xy 124.77877 -117.357394) (xy 124.77877 -119.486426) (xy 125.787148 -119.486426) (xy 125.791219 -119.430804)
			(xy 125.803345 -119.376367) (xy 125.823268 -119.324276) (xy 125.850564 -119.275641) (xy 125.88465 -119.231498)
			(xy 125.924799 -119.192789) (xy 125.970157 -119.160338) (xy 126.019757 -119.134837) (xy 126.072541 -119.11683)
			(xy 126.127384 -119.1067) (xy 126.183118 -119.104663) (xy 126.238555 -119.110763) (xy 126.292512 -119.124869)
			(xy 126.343841 -119.146681) (xy 126.391447 -119.175735) (xy 126.434315 -119.21141) (xy 126.471532 -119.252947)
			(xy 126.502305 -119.29946) (xy 126.525977 -119.349957) (xy 126.527756 -119.35587) (xy 126.803148 -119.35587)
			(xy 126.807219 -119.300248) (xy 126.819345 -119.245811) (xy 126.839268 -119.19372) (xy 126.866564 -119.145085)
			(xy 126.90065 -119.100942) (xy 126.940799 -119.062233) (xy 126.986157 -119.029782) (xy 127.035757 -119.004281)
			(xy 127.088541 -118.986274) (xy 127.143384 -118.976144) (xy 127.199118 -118.974107) (xy 127.254555 -118.980207)
			(xy 127.308512 -118.994313) (xy 127.359841 -119.016125) (xy 127.407447 -119.045179) (xy 127.450315 -119.080854)
			(xy 127.487532 -119.122391) (xy 127.518305 -119.168904) (xy 127.541977 -119.219401) (xy 127.558045 -119.272808)
			(xy 127.566165 -119.327984) (xy 127.566674 -119.35587) (xy 128.835148 -119.35587) (xy 128.839219 -119.300248)
			(xy 128.851345 -119.245811) (xy 128.871268 -119.19372) (xy 128.898564 -119.145085) (xy 128.93265 -119.100942)
			(xy 128.972799 -119.062233) (xy 129.018157 -119.029782) (xy 129.067757 -119.004281) (xy 129.120541 -118.986274)
			(xy 129.175384 -118.976144) (xy 129.231118 -118.974107) (xy 129.286555 -118.980207) (xy 129.340512 -118.994313)
			(xy 129.391841 -119.016125) (xy 129.439447 -119.045179) (xy 129.482315 -119.080854) (xy 129.519532 -119.122391)
			(xy 129.550305 -119.168904) (xy 129.573977 -119.219401) (xy 129.590045 -119.272808) (xy 129.598165 -119.327984)
			(xy 129.598674 -119.35587) (xy 129.598165 -119.383756) (xy 129.597036 -119.39143) (xy 129.998722 -119.39143)
			(xy 130.002793 -119.335808) (xy 130.014919 -119.281371) (xy 130.034842 -119.22928) (xy 130.062138 -119.180645)
			(xy 130.096224 -119.136502) (xy 130.136373 -119.097793) (xy 130.181731 -119.065342) (xy 130.231331 -119.039841)
			(xy 130.284115 -119.021834) (xy 130.338958 -119.011704) (xy 130.394692 -119.009667) (xy 130.450129 -119.015767)
			(xy 130.504086 -119.029873) (xy 130.555415 -119.051685) (xy 130.603021 -119.080739) (xy 130.645889 -119.116414)
			(xy 130.683106 -119.157951) (xy 130.713879 -119.204464) (xy 130.737551 -119.254961) (xy 130.753619 -119.308368)
			(xy 130.761739 -119.363544) (xy 130.762248 -119.39143) (xy 131.014722 -119.39143) (xy 131.018793 -119.335808)
			(xy 131.030919 -119.281371) (xy 131.050842 -119.22928) (xy 131.078138 -119.180645) (xy 131.112224 -119.136502)
			(xy 131.152373 -119.097793) (xy 131.197731 -119.065342) (xy 131.247331 -119.039841) (xy 131.300115 -119.021834)
			(xy 131.354958 -119.011704) (xy 131.410692 -119.009667) (xy 131.466129 -119.015767) (xy 131.520086 -119.029873)
			(xy 131.571415 -119.051685) (xy 131.619021 -119.080739) (xy 131.661889 -119.116414) (xy 131.699106 -119.157951)
			(xy 131.729879 -119.204464) (xy 131.753551 -119.254961) (xy 131.769619 -119.308368) (xy 131.777739 -119.363544)
			(xy 131.778248 -119.39143) (xy 132.030722 -119.39143) (xy 132.034793 -119.335808) (xy 132.046919 -119.281371)
			(xy 132.066842 -119.22928) (xy 132.094138 -119.180645) (xy 132.128224 -119.136502) (xy 132.168373 -119.097793)
			(xy 132.213731 -119.065342) (xy 132.263331 -119.039841) (xy 132.316115 -119.021834) (xy 132.370958 -119.011704)
			(xy 132.426692 -119.009667) (xy 132.482129 -119.015767) (xy 132.536086 -119.029873) (xy 132.587415 -119.051685)
			(xy 132.635021 -119.080739) (xy 132.677889 -119.116414) (xy 132.715106 -119.157951) (xy 132.745879 -119.204464)
			(xy 132.769551 -119.254961) (xy 132.785619 -119.308368) (xy 132.793739 -119.363544) (xy 132.794248 -119.39143)
			(xy 132.793739 -119.419316) (xy 132.785619 -119.474492) (xy 132.769551 -119.527899) (xy 132.745879 -119.578396)
			(xy 132.715106 -119.624909) (xy 132.677889 -119.666446) (xy 132.635021 -119.702121) (xy 132.587415 -119.731175)
			(xy 132.536086 -119.752987) (xy 132.482129 -119.767093) (xy 132.426692 -119.773193) (xy 132.370958 -119.771156)
			(xy 132.316115 -119.761026) (xy 132.263331 -119.743019) (xy 132.213731 -119.717518) (xy 132.168373 -119.685067)
			(xy 132.128224 -119.646358) (xy 132.094138 -119.602215) (xy 132.066842 -119.55358) (xy 132.046919 -119.501489)
			(xy 132.034793 -119.447052) (xy 132.030722 -119.39143) (xy 131.778248 -119.39143) (xy 131.777739 -119.419316)
			(xy 131.769619 -119.474492) (xy 131.753551 -119.527899) (xy 131.729879 -119.578396) (xy 131.699106 -119.624909)
			(xy 131.661889 -119.666446) (xy 131.619021 -119.702121) (xy 131.571415 -119.731175) (xy 131.520086 -119.752987)
			(xy 131.466129 -119.767093) (xy 131.410692 -119.773193) (xy 131.354958 -119.771156) (xy 131.300115 -119.761026)
			(xy 131.247331 -119.743019) (xy 131.197731 -119.717518) (xy 131.152373 -119.685067) (xy 131.112224 -119.646358)
			(xy 131.078138 -119.602215) (xy 131.050842 -119.55358) (xy 131.030919 -119.501489) (xy 131.018793 -119.447052)
			(xy 131.014722 -119.39143) (xy 130.762248 -119.39143) (xy 130.761739 -119.419316) (xy 130.753619 -119.474492)
			(xy 130.737551 -119.527899) (xy 130.713879 -119.578396) (xy 130.683106 -119.624909) (xy 130.645889 -119.666446)
			(xy 130.603021 -119.702121) (xy 130.555415 -119.731175) (xy 130.504086 -119.752987) (xy 130.450129 -119.767093)
			(xy 130.394692 -119.773193) (xy 130.338958 -119.771156) (xy 130.284115 -119.761026) (xy 130.231331 -119.743019)
			(xy 130.181731 -119.717518) (xy 130.136373 -119.685067) (xy 130.096224 -119.646358) (xy 130.062138 -119.602215)
			(xy 130.034842 -119.55358) (xy 130.014919 -119.501489) (xy 130.002793 -119.447052) (xy 129.998722 -119.39143)
			(xy 129.597036 -119.39143) (xy 129.590045 -119.438932) (xy 129.573977 -119.492339) (xy 129.550305 -119.542836)
			(xy 129.519532 -119.589349) (xy 129.482315 -119.630886) (xy 129.439447 -119.666561) (xy 129.391841 -119.695615)
			(xy 129.340512 -119.717427) (xy 129.286555 -119.731533) (xy 129.231118 -119.737633) (xy 129.175384 -119.735596)
			(xy 129.120541 -119.725466) (xy 129.067757 -119.707459) (xy 129.018157 -119.681958) (xy 128.972799 -119.649507)
			(xy 128.93265 -119.610798) (xy 128.898564 -119.566655) (xy 128.871268 -119.51802) (xy 128.851345 -119.465929)
			(xy 128.839219 -119.411492) (xy 128.835148 -119.35587) (xy 127.566674 -119.35587) (xy 127.566165 -119.383756)
			(xy 127.558045 -119.438932) (xy 127.541977 -119.492339) (xy 127.518305 -119.542836) (xy 127.487532 -119.589349)
			(xy 127.450315 -119.630886) (xy 127.407447 -119.666561) (xy 127.359841 -119.695615) (xy 127.308512 -119.717427)
			(xy 127.254555 -119.731533) (xy 127.199118 -119.737633) (xy 127.143384 -119.735596) (xy 127.088541 -119.725466)
			(xy 127.035757 -119.707459) (xy 126.986157 -119.681958) (xy 126.940799 -119.649507) (xy 126.90065 -119.610798)
			(xy 126.866564 -119.566655) (xy 126.839268 -119.51802) (xy 126.819345 -119.465929) (xy 126.807219 -119.411492)
			(xy 126.803148 -119.35587) (xy 126.527756 -119.35587) (xy 126.542045 -119.403364) (xy 126.550165 -119.45854)
			(xy 126.550674 -119.486426) (xy 126.550165 -119.514312) (xy 126.542045 -119.569488) (xy 126.525977 -119.622895)
			(xy 126.502305 -119.673392) (xy 126.471532 -119.719905) (xy 126.434315 -119.761442) (xy 126.391447 -119.797117)
			(xy 126.343841 -119.826171) (xy 126.292512 -119.847983) (xy 126.238555 -119.862089) (xy 126.183118 -119.868189)
			(xy 126.127384 -119.866152) (xy 126.072541 -119.856022) (xy 126.019757 -119.838015) (xy 125.970157 -119.812514)
			(xy 125.924799 -119.780063) (xy 125.88465 -119.741354) (xy 125.850564 -119.697211) (xy 125.823268 -119.648576)
			(xy 125.803345 -119.596485) (xy 125.791219 -119.542048) (xy 125.787148 -119.486426) (xy 124.77877 -119.486426)
			(xy 124.77877 -120.85955) (xy 129.643632 -120.85955) (xy 129.644122 -120.829582) (xy 129.651945 -120.77016)
			(xy 129.667458 -120.712267) (xy 129.690394 -120.656894) (xy 129.720361 -120.604988) (xy 129.756848 -120.557438)
			(xy 129.799228 -120.515058) (xy 129.846778 -120.478571) (xy 129.898684 -120.448604) (xy 129.954057 -120.425668)
			(xy 130.01195 -120.410155) (xy 130.071372 -120.402332) (xy 130.131308 -120.402332) (xy 130.19073 -120.410155)
			(xy 130.248623 -120.425668) (xy 130.303996 -120.448604) (xy 130.355902 -120.478571) (xy 130.403452 -120.515058)
			(xy 130.445832 -120.557438) (xy 130.482319 -120.604988) (xy 130.512286 -120.656894) (xy 130.535222 -120.712267)
			(xy 130.550735 -120.77016) (xy 130.558558 -120.829582) (xy 130.559048 -120.85955) (xy 130.558545 -120.891097)
			(xy 130.54989 -120.953593) (xy 130.532739 -121.014311) (xy 130.507415 -121.072099) (xy 130.474398 -121.125863)
			(xy 130.434313 -121.174586) (xy 130.411474 -121.196354) (xy 130.404108 -121.202958) (xy 130.39598 -121.219976)
			(xy 130.388868 -121.308368) (xy 130.394456 -121.326402) (xy 130.400552 -121.334022) (xy 130.416072 -121.354318)
			(xy 130.442133 -121.398264) (xy 130.4621 -121.445295) (xy 130.475614 -121.494568) (xy 130.479752 -121.525284)
			(xy 133.4516 -121.525284) (xy 133.452057 -121.497913) (xy 133.459877 -121.443734) (xy 133.475368 -121.391231)
			(xy 133.498212 -121.341484) (xy 133.527938 -121.295518) (xy 133.54558 -121.274586) (xy 133.551676 -121.267474)
			(xy 133.558026 -121.250456) (xy 133.558026 -121.165112) (xy 133.551676 -121.148094) (xy 133.54558 -121.140982)
			(xy 133.527963 -121.120032) (xy 133.498248 -121.074064) (xy 133.475409 -121.024321) (xy 133.459912 -120.971824)
			(xy 133.452078 -120.917652) (xy 133.4516 -120.890284) (xy 133.452086 -120.863033) (xy 133.459842 -120.809085)
			(xy 133.475197 -120.75679) (xy 133.497839 -120.707213) (xy 133.527305 -120.661363) (xy 133.562996 -120.620172)
			(xy 133.604187 -120.584481) (xy 133.650037 -120.555015) (xy 133.699614 -120.532373) (xy 133.751909 -120.517018)
			(xy 133.805857 -120.509262) (xy 133.860359 -120.509262) (xy 133.914307 -120.517018) (xy 133.966602 -120.532373)
			(xy 134.016179 -120.555015) (xy 134.062029 -120.584481) (xy 134.10322 -120.620172) (xy 134.138911 -120.661363)
			(xy 134.168377 -120.707213) (xy 134.191019 -120.75679) (xy 134.206374 -120.809085) (xy 134.21413 -120.863033)
			(xy 134.214616 -120.890284) (xy 134.214161 -120.917655) (xy 134.206344 -120.971835) (xy 134.190853 -121.024339)
			(xy 134.168008 -121.074086) (xy 134.13828 -121.120052) (xy 134.120636 -121.140982) (xy 134.11454 -121.148094)
			(xy 134.10819 -121.165112) (xy 134.10819 -121.250456) (xy 134.11454 -121.267474) (xy 134.120636 -121.274586)
			(xy 134.138288 -121.295508) (xy 134.167996 -121.341484) (xy 134.190829 -121.391234) (xy 134.206318 -121.443737)
			(xy 134.214143 -121.497914) (xy 134.214616 -121.525284) (xy 134.214384 -121.543627) (xy 134.210821 -121.58014)
			(xy 134.207504 -121.598182) (xy 134.205472 -121.609104) (xy 134.210298 -121.629678) (xy 134.269226 -121.707656)
			(xy 134.288022 -121.71807) (xy 134.298944 -121.718832) (xy 134.32723 -121.72171) (xy 134.382568 -121.734751)
			(xy 134.435361 -121.755852) (xy 134.484444 -121.784544) (xy 134.528731 -121.820195) (xy 134.548372 -121.840752)
			(xy 134.555909 -121.848136) (xy 134.575177 -121.856672) (xy 134.58571 -121.857262) (xy 134.660386 -121.857262)
			(xy 134.670938 -121.85675) (xy 134.690234 -121.848204) (xy 134.697724 -121.840752) (xy 134.715857 -121.821671)
			(xy 134.756477 -121.788191) (xy 134.801317 -121.760619) (xy 134.849525 -121.739481) (xy 134.900183 -121.725177)
			(xy 134.952328 -121.717981) (xy 134.978648 -121.717562) (xy 135.005895 -121.718111) (xy 135.059833 -121.725873)
			(xy 135.112118 -121.741231) (xy 135.161685 -121.763873) (xy 135.207526 -121.793338) (xy 135.248707 -121.829027)
			(xy 135.284391 -121.870213) (xy 135.31385 -121.916057) (xy 135.336486 -121.965627) (xy 135.351837 -122.017914)
			(xy 135.359592 -122.071853) (xy 135.359592 -122.126347) (xy 135.351837 -122.180286) (xy 135.336486 -122.232573)
			(xy 135.31385 -122.282143) (xy 135.284391 -122.327987) (xy 135.248707 -122.369173) (xy 135.207526 -122.404862)
			(xy 135.161685 -122.434327) (xy 135.112118 -122.456969) (xy 135.059833 -122.472327) (xy 135.005895 -122.480089)
			(xy 134.978648 -122.480578) (xy 134.952331 -122.480146) (xy 134.900196 -122.472923) (xy 134.849547 -122.458606)
			(xy 134.801345 -122.437468) (xy 134.756504 -122.409908) (xy 134.715873 -122.37645) (xy 134.697724 -122.357388)
			(xy 134.690197 -122.349993) (xy 134.670921 -122.341465) (xy 134.660386 -122.340878) (xy 134.58571 -122.340878)
			(xy 134.57516 -122.341405) (xy 134.555865 -122.349942) (xy 134.548372 -122.357388) (xy 134.530249 -122.376479)
			(xy 134.489626 -122.409956) (xy 134.444783 -122.437525) (xy 134.396573 -122.458662) (xy 134.345914 -122.472964)
			(xy 134.293768 -122.480159) (xy 134.267448 -122.480578) (xy 134.240195 -122.4801) (xy 134.186243 -122.472349)
			(xy 134.133944 -122.456997) (xy 134.084362 -122.434358) (xy 134.038507 -122.404892) (xy 133.997313 -122.3692)
			(xy 133.961618 -122.328008) (xy 133.93215 -122.282154) (xy 133.909509 -122.232573) (xy 133.894155 -122.180275)
			(xy 133.886401 -122.126323) (xy 133.88594 -122.09907) (xy 133.886178 -122.080727) (xy 133.889737 -122.044214)
			(xy 133.893052 -122.026172) (xy 133.895084 -122.01525) (xy 133.890258 -121.994676) (xy 133.83133 -121.916698)
			(xy 133.812534 -121.906284) (xy 133.801612 -121.905522) (xy 133.773343 -121.902718) (xy 133.718054 -121.889674)
			(xy 133.665309 -121.868578) (xy 133.616274 -121.839896) (xy 133.572033 -121.804261) (xy 133.533564 -121.762461)
			(xy 133.501717 -121.715421) (xy 133.477195 -121.664179) (xy 133.46054 -121.609868) (xy 133.452121 -121.553688)
			(xy 133.4516 -121.525284) (xy 130.479752 -121.525284) (xy 130.482436 -121.545204) (xy 130.482848 -121.57075)
			(xy 130.482362 -121.598001) (xy 130.474606 -121.651949) (xy 130.459251 -121.704244) (xy 130.436609 -121.753821)
			(xy 130.407143 -121.799671) (xy 130.371452 -121.840862) (xy 130.330261 -121.876553) (xy 130.284411 -121.906019)
			(xy 130.234834 -121.928661) (xy 130.182539 -121.944016) (xy 130.128591 -121.951772) (xy 130.074089 -121.951772)
			(xy 130.020141 -121.944016) (xy 129.967846 -121.928661) (xy 129.918269 -121.906019) (xy 129.872419 -121.876553)
			(xy 129.831228 -121.840862) (xy 129.795537 -121.799671) (xy 129.766071 -121.753821) (xy 129.743429 -121.704244)
			(xy 129.728074 -121.651949) (xy 129.720318 -121.598001) (xy 129.719832 -121.57075) (xy 129.720248 -121.545202)
			(xy 129.727052 -121.494563) (xy 129.740559 -121.445286) (xy 129.760527 -121.398254) (xy 129.786597 -121.354311)
			(xy 129.802128 -121.334022) (xy 129.808224 -121.326402) (xy 129.813812 -121.308368) (xy 129.8067 -121.219976)
			(xy 129.798572 -121.202958) (xy 129.791206 -121.196354) (xy 129.768347 -121.174604) (xy 129.728245 -121.125889)
			(xy 129.69522 -121.072125) (xy 129.669899 -121.014331) (xy 129.652763 -120.953604) (xy 129.644137 -120.891099)
			(xy 129.643632 -120.85955) (xy 124.77877 -120.85955) (xy 124.77877 -121.263918) (xy 124.779173 -121.273146)
			(xy 124.785727 -121.2904) (xy 124.797976 -121.304206) (xy 124.805948 -121.308876) (xy 124.82449 -121.318782)
			(xy 124.854462 -121.315734) (xy 124.866654 -121.306082) (xy 124.891212 -121.286824) (xy 124.944559 -121.254437)
			(xy 125.001813 -121.229604) (xy 125.061912 -121.212785) (xy 125.12374 -121.204293) (xy 125.154944 -121.20372)
			(xy 125.184908 -121.204213) (xy 125.244323 -121.21204) (xy 125.302207 -121.227555) (xy 125.357572 -121.250493)
			(xy 125.409469 -121.28046) (xy 125.457011 -121.316945) (xy 125.499385 -121.359322) (xy 125.535864 -121.406868)
			(xy 125.565827 -121.458768) (xy 125.588759 -121.514134) (xy 125.604268 -121.572021) (xy 125.61209 -121.631436)
			(xy 125.61209 -121.691364) (xy 125.604268 -121.750779) (xy 125.588759 -121.808666) (xy 125.565827 -121.864032)
			(xy 125.535864 -121.915932) (xy 125.499385 -121.963478) (xy 125.457011 -122.005855) (xy 125.409469 -122.04234)
			(xy 125.357572 -122.072307) (xy 125.302207 -122.095245) (xy 125.244323 -122.11076) (xy 125.184908 -122.118587)
			(xy 125.154944 -122.119136) (xy 125.123739 -122.118591) (xy 125.061912 -122.110082) (xy 125.001812 -122.093257)
			(xy 124.944553 -122.068427) (xy 124.891196 -122.036053) (xy 124.866654 -122.016774) (xy 124.854462 -122.007122)
			(xy 124.82449 -122.004074) (xy 124.805948 -122.01398) (xy 124.79796 -122.018626) (xy 124.785713 -122.032445)
			(xy 124.779154 -122.049706) (xy 124.77877 -122.058938) (xy 124.77877 -122.292618) (xy 125.880112 -122.292618)
			(xy 125.884183 -122.236996) (xy 125.896309 -122.182559) (xy 125.916232 -122.130468) (xy 125.943528 -122.081833)
			(xy 125.977614 -122.03769) (xy 126.017763 -121.998981) (xy 126.063121 -121.96653) (xy 126.112721 -121.941029)
			(xy 126.165505 -121.923022) (xy 126.220348 -121.912892) (xy 126.276082 -121.910855) (xy 126.331519 -121.916955)
			(xy 126.385476 -121.931061) (xy 126.436805 -121.952873) (xy 126.484411 -121.981927) (xy 126.527279 -122.017602)
			(xy 126.564496 -122.059139) (xy 126.595269 -122.105652) (xy 126.618941 -122.156149) (xy 126.635009 -122.209556)
			(xy 126.643129 -122.264732) (xy 126.643638 -122.292618) (xy 126.643129 -122.320504) (xy 126.635009 -122.37568)
			(xy 126.618941 -122.429087) (xy 126.595269 -122.479584) (xy 126.581842 -122.499878) (xy 126.961628 -122.499878)
			(xy 126.961628 -122.439942) (xy 126.969451 -122.38052) (xy 126.984964 -122.322627) (xy 127.0079 -122.267254)
			(xy 127.037867 -122.215348) (xy 127.074354 -122.167798) (xy 127.116734 -122.125418) (xy 127.164284 -122.088931)
			(xy 127.21619 -122.058964) (xy 127.271563 -122.036028) (xy 127.329456 -122.020515) (xy 127.388878 -122.012692)
			(xy 127.448814 -122.012692) (xy 127.508236 -122.020515) (xy 127.566129 -122.036028) (xy 127.621502 -122.058964)
			(xy 127.673408 -122.088931) (xy 127.720958 -122.125418) (xy 127.763338 -122.167798) (xy 127.799825 -122.215348)
			(xy 127.829792 -122.267254) (xy 127.852728 -122.322627) (xy 127.868241 -122.38052) (xy 127.876064 -122.439942)
			(xy 127.876554 -122.46991) (xy 127.876064 -122.499878) (xy 127.868241 -122.5593) (xy 127.852728 -122.617193)
			(xy 127.829792 -122.672566) (xy 127.799825 -122.724472) (xy 127.763338 -122.772022) (xy 127.720958 -122.814402)
			(xy 127.673408 -122.850889) (xy 127.621502 -122.880856) (xy 127.566129 -122.903792) (xy 127.508236 -122.919305)
			(xy 127.448814 -122.927128) (xy 127.388878 -122.927128) (xy 127.329456 -122.919305) (xy 127.271563 -122.903792)
			(xy 127.21619 -122.880856) (xy 127.164284 -122.850889) (xy 127.116734 -122.814402) (xy 127.074354 -122.772022)
			(xy 127.037867 -122.724472) (xy 127.0079 -122.672566) (xy 126.984964 -122.617193) (xy 126.969451 -122.5593)
			(xy 126.961628 -122.499878) (xy 126.581842 -122.499878) (xy 126.564496 -122.526097) (xy 126.527279 -122.567634)
			(xy 126.484411 -122.603309) (xy 126.436805 -122.632363) (xy 126.385476 -122.654175) (xy 126.331519 -122.668281)
			(xy 126.276082 -122.674381) (xy 126.220348 -122.672344) (xy 126.165505 -122.662214) (xy 126.112721 -122.644207)
			(xy 126.063121 -122.618706) (xy 126.017763 -122.586255) (xy 125.977614 -122.547546) (xy 125.943528 -122.503403)
			(xy 125.916232 -122.454768) (xy 125.896309 -122.402677) (xy 125.884183 -122.34824) (xy 125.880112 -122.292618)
			(xy 124.77877 -122.292618) (xy 124.77877 -122.533918) (xy 124.779173 -122.543146) (xy 124.785727 -122.5604)
			(xy 124.797976 -122.574206) (xy 124.805948 -122.578876) (xy 124.88545 -122.620786) (xy 124.893836 -122.624734)
			(xy 124.912225 -122.626936) (xy 124.930189 -122.622432) (xy 124.938028 -122.617484) (xy 124.938282 -122.617484)
			(xy 124.962297 -122.601541) (xy 125.014115 -122.576298) (xy 125.069142 -122.559139) (xy 125.126124 -122.550457)
			(xy 125.154944 -122.54992) (xy 125.162056 -122.54992) (xy 125.188975 -122.550882) (xy 125.242154 -122.559445)
			(xy 125.2936 -122.575404) (xy 125.34229 -122.598441) (xy 125.387254 -122.6281) (xy 125.427598 -122.663788)
			(xy 125.462521 -122.704798) (xy 125.491327 -122.750313) (xy 125.513444 -122.799427) (xy 125.528431 -122.851164)
			(xy 125.535991 -122.904496) (xy 125.536452 -122.931428) (xy 125.535964 -122.958679) (xy 125.528205 -123.012626)
			(xy 125.512848 -123.06492) (xy 125.490206 -123.114497) (xy 125.460739 -123.160347) (xy 125.425048 -123.201537)
			(xy 125.383859 -123.23723) (xy 125.364377 -123.249752) (xy 128.009867 -123.249752) (xy 128.009867 -123.195248)
			(xy 128.017624 -123.141298) (xy 128.03298 -123.089002) (xy 128.055622 -123.039423) (xy 128.085089 -122.993571)
			(xy 128.120782 -122.95238) (xy 128.161974 -122.916687) (xy 128.207826 -122.88722) (xy 128.257405 -122.864579)
			(xy 128.309702 -122.849223) (xy 128.363652 -122.841467) (xy 128.390904 -122.841004) (xy 128.417934 -122.841497)
			(xy 128.471452 -122.849135) (xy 128.523353 -122.864259) (xy 128.572597 -122.886563) (xy 128.618196 -122.915602)
			(xy 128.659234 -122.950791) (xy 128.677416 -122.970798) (xy 128.684782 -122.978926) (xy 128.704594 -122.98807)
			(xy 128.802638 -122.988324) (xy 128.82245 -122.979434) (xy 128.829816 -122.971306) (xy 128.847975 -122.951581)
			(xy 128.888876 -122.916917) (xy 128.934232 -122.888329) (xy 128.983148 -122.86638) (xy 129.034657 -122.851505)
			(xy 129.087743 -122.843997) (xy 129.11455 -122.843544) (xy 129.14192 -122.844029) (xy 129.196098 -122.85184)
			(xy 129.248602 -122.867324) (xy 129.298349 -122.890162) (xy 129.344316 -122.919884) (xy 129.365248 -122.937524)
			(xy 129.37236 -122.94362) (xy 129.389378 -122.94997) (xy 129.474722 -122.94997) (xy 129.49174 -122.94362)
			(xy 129.498852 -122.937524) (xy 129.519785 -122.919883) (xy 129.565753 -122.890159) (xy 129.615499 -122.867313)
			(xy 129.668001 -122.851817) (xy 129.722179 -122.843988) (xy 129.776921 -122.843988) (xy 129.831099 -122.851817)
			(xy 129.883601 -122.867313) (xy 129.933347 -122.890159) (xy 129.979315 -122.919883) (xy 130.000248 -122.937524)
			(xy 130.00736 -122.94362) (xy 130.024378 -122.94997) (xy 130.109722 -122.94997) (xy 130.12674 -122.94362)
			(xy 130.133852 -122.937524) (xy 130.146653 -122.926579) (xy 130.173869 -122.906735) (xy 130.188208 -122.8979)
			(xy 130.197352 -122.892566) (xy 130.209544 -122.875548) (xy 130.22961 -122.78233) (xy 130.225546 -122.761756)
			(xy 130.21945 -122.75312) (xy 130.203451 -122.729056) (xy 130.178109 -122.677124) (xy 130.160884 -122.621966)
			(xy 130.152168 -122.564842) (xy 130.151632 -122.53595) (xy 130.152118 -122.508699) (xy 130.159874 -122.454751)
			(xy 130.175229 -122.402456) (xy 130.197871 -122.352879) (xy 130.227337 -122.307029) (xy 130.263028 -122.265838)
			(xy 130.304219 -122.230147) (xy 130.350069 -122.200681) (xy 130.399646 -122.178039) (xy 130.451941 -122.162684)
			(xy 130.505889 -122.154928) (xy 130.560391 -122.154928) (xy 130.614339 -122.162684) (xy 130.666634 -122.178039)
			(xy 130.716211 -122.200681) (xy 130.762061 -122.230147) (xy 130.803252 -122.265838) (xy 130.838943 -122.307029)
			(xy 130.868409 -122.352879) (xy 130.891051 -122.402456) (xy 130.906406 -122.454751) (xy 130.914162 -122.508699)
			(xy 130.914648 -122.53595) (xy 130.914099 -122.564039) (xy 130.90588 -122.619613) (xy 130.889597 -122.673381)
			(xy 130.865603 -122.724177) (xy 130.834417 -122.770905) (xy 130.796714 -122.812552) (xy 130.753308 -122.848217)
			(xy 130.729482 -122.863102) (xy 130.720338 -122.868436) (xy 130.708146 -122.885454) (xy 130.68808 -122.978672)
			(xy 130.692144 -122.999246) (xy 130.69824 -123.007882) (xy 130.714239 -123.031946) (xy 130.739581 -123.083878)
			(xy 130.74369 -123.097036) (xy 132.57657 -123.097036) (xy 132.57704 -123.069666) (xy 132.584854 -123.015486)
			(xy 132.600342 -122.962982) (xy 132.623183 -122.913235) (xy 132.652908 -122.867269) (xy 132.67055 -122.846338)
			(xy 132.676646 -122.839226) (xy 132.682996 -122.822208) (xy 132.682996 -122.736864) (xy 132.676646 -122.719846)
			(xy 132.67055 -122.712734) (xy 132.652921 -122.691794) (xy 132.623206 -122.645824) (xy 132.600367 -122.596079)
			(xy 132.584874 -122.543579) (xy 132.577044 -122.489405) (xy 132.57657 -122.462036) (xy 132.577056 -122.434785)
			(xy 132.584812 -122.380837) (xy 132.600167 -122.328542) (xy 132.622809 -122.278965) (xy 132.652275 -122.233115)
			(xy 132.687966 -122.191924) (xy 132.729157 -122.156233) (xy 132.775007 -122.126767) (xy 132.824584 -122.104125)
			(xy 132.876879 -122.08877) (xy 132.930827 -122.081014) (xy 132.985329 -122.081014) (xy 133.039277 -122.08877)
			(xy 133.091572 -122.104125) (xy 133.141149 -122.126767) (xy 133.186999 -122.156233) (xy 133.22819 -122.191924)
			(xy 133.263881 -122.233115) (xy 133.293347 -122.278965) (xy 133.315989 -122.328542) (xy 133.331344 -122.380837)
			(xy 133.3391 -122.434785) (xy 133.339586 -122.462036) (xy 133.339144 -122.489407) (xy 133.331321 -122.543587)
			(xy 133.315827 -122.596091) (xy 133.292979 -122.645837) (xy 133.26325 -122.691803) (xy 133.245606 -122.712734)
			(xy 133.23951 -122.719846) (xy 133.23316 -122.736864) (xy 133.23316 -122.822208) (xy 133.23951 -122.839226)
			(xy 133.245606 -122.846338) (xy 133.26323 -122.867282) (xy 133.288931 -122.907044) (xy 135.462518 -122.907044)
			(xy 135.463028 -122.875498) (xy 135.471683 -122.813002) (xy 135.488833 -122.752285) (xy 135.514156 -122.694497)
			(xy 135.547171 -122.640732) (xy 135.587254 -122.592008) (xy 135.610092 -122.57024) (xy 135.617458 -122.563636)
			(xy 135.625586 -122.546618) (xy 135.632698 -122.458226) (xy 135.62711 -122.440192) (xy 135.621014 -122.432572)
			(xy 135.605486 -122.412282) (xy 135.579427 -122.368333) (xy 135.559463 -122.321301) (xy 135.54595 -122.272027)
			(xy 135.53913 -122.221391) (xy 135.538718 -122.195844) (xy 135.539205 -122.168474) (xy 135.547017 -122.114296)
			(xy 135.562501 -122.061793) (xy 135.585338 -122.012046) (xy 135.615059 -121.966078) (xy 135.632698 -121.945146)
			(xy 135.638794 -121.938034) (xy 135.645144 -121.921016) (xy 135.645144 -121.835672) (xy 135.638794 -121.818654)
			(xy 135.632698 -121.811542) (xy 135.615102 -121.790574) (xy 135.585377 -121.744611) (xy 135.562531 -121.694871)
			(xy 135.547033 -121.642374) (xy 135.539201 -121.588201) (xy 135.539196 -121.533465) (xy 135.547018 -121.47929)
			(xy 135.562508 -121.426791) (xy 135.585345 -121.377047) (xy 135.615062 -121.331079) (xy 135.632698 -121.310146)
			(xy 135.638794 -121.303034) (xy 135.645144 -121.286016) (xy 135.645144 -121.200672) (xy 135.638794 -121.183654)
			(xy 135.632698 -121.176542) (xy 135.615065 -121.155605) (xy 135.585352 -121.109634) (xy 135.562515 -121.059887)
			(xy 135.547023 -121.007388) (xy 135.539193 -120.953213) (xy 135.538718 -120.925844) (xy 135.539204 -120.898593)
			(xy 135.54696 -120.844645) (xy 135.562315 -120.79235) (xy 135.584957 -120.742773) (xy 135.614423 -120.696923)
			(xy 135.650114 -120.655732) (xy 135.691305 -120.620041) (xy 135.737155 -120.590575) (xy 135.786732 -120.567933)
			(xy 135.839027 -120.552578) (xy 135.892975 -120.544822) (xy 135.947477 -120.544822) (xy 136.001425 -120.552578)
			(xy 136.05372 -120.567933) (xy 136.103297 -120.590575) (xy 136.149147 -120.620041) (xy 136.190338 -120.655732)
			(xy 136.226029 -120.696923) (xy 136.255495 -120.742773) (xy 136.278137 -120.79235) (xy 136.293492 -120.844645)
			(xy 136.301248 -120.898593) (xy 136.301734 -120.925844) (xy 136.301251 -120.953214) (xy 136.29344 -121.007393)
			(xy 136.277956 -121.059896) (xy 136.255117 -121.109644) (xy 136.225395 -121.15561) (xy 136.207754 -121.176542)
			(xy 136.201658 -121.183654) (xy 136.195308 -121.200672) (xy 136.195308 -121.286016) (xy 136.201658 -121.303034)
			(xy 136.207754 -121.310146) (xy 136.225439 -121.331043) (xy 136.255163 -121.377017) (xy 136.278007 -121.426769)
			(xy 136.293501 -121.479276) (xy 136.301326 -121.53346) (xy 136.301321 -121.588206) (xy 136.293487 -121.642388)
			(xy 136.277984 -121.694893) (xy 136.255131 -121.744641) (xy 136.225399 -121.79061) (xy 136.207754 -121.811542)
			(xy 136.201658 -121.818654) (xy 136.195308 -121.835672) (xy 136.195308 -121.921016) (xy 136.201658 -121.938034)
			(xy 136.207754 -121.945146) (xy 136.225374 -121.966094) (xy 136.25509 -122.012061) (xy 136.277931 -122.061805)
			(xy 136.293426 -122.114302) (xy 136.301258 -122.168476) (xy 136.301734 -122.195844) (xy 136.301301 -122.221391)
			(xy 136.294498 -122.272029) (xy 136.280995 -122.321306) (xy 136.261031 -122.368338) (xy 136.234966 -122.412282)
			(xy 136.219438 -122.432572) (xy 136.213342 -122.440192) (xy 136.207754 -122.458226) (xy 136.214866 -122.546618)
			(xy 136.222994 -122.563636) (xy 136.23036 -122.57024) (xy 136.253229 -122.59198) (xy 136.293327 -122.640698)
			(xy 136.326349 -122.694466) (xy 136.351668 -122.752261) (xy 136.368803 -122.812989) (xy 136.377428 -122.875494)
			(xy 136.377934 -122.907044) (xy 136.377444 -122.937012) (xy 136.369621 -122.996434) (xy 136.354108 -123.054327)
			(xy 136.331172 -123.1097) (xy 136.301205 -123.161606) (xy 136.264718 -123.209156) (xy 136.222338 -123.251536)
			(xy 136.174788 -123.288023) (xy 136.122882 -123.31799) (xy 136.067509 -123.340926) (xy 136.009616 -123.356439)
			(xy 135.950194 -123.364262) (xy 135.890258 -123.364262) (xy 135.830836 -123.356439) (xy 135.772943 -123.340926)
			(xy 135.71757 -123.31799) (xy 135.665664 -123.288023) (xy 135.618114 -123.251536) (xy 135.575734 -123.209156)
			(xy 135.539247 -123.161606) (xy 135.50928 -123.1097) (xy 135.486344 -123.054327) (xy 135.470831 -122.996434)
			(xy 135.463008 -122.937012) (xy 135.462518 -122.907044) (xy 133.288931 -122.907044) (xy 133.292944 -122.913252)
			(xy 133.315783 -122.962996) (xy 133.331277 -123.015494) (xy 133.33911 -123.069668) (xy 133.339586 -123.097036)
			(xy 133.3391 -123.124287) (xy 133.331344 -123.178235) (xy 133.315989 -123.23053) (xy 133.293347 -123.280107)
			(xy 133.263881 -123.325957) (xy 133.22819 -123.367148) (xy 133.186999 -123.402839) (xy 133.141149 -123.432305)
			(xy 133.091572 -123.454947) (xy 133.039277 -123.470302) (xy 132.985329 -123.478058) (xy 132.930827 -123.478058)
			(xy 132.876879 -123.470302) (xy 132.824584 -123.454947) (xy 132.775007 -123.432305) (xy 132.729157 -123.402839)
			(xy 132.687966 -123.367148) (xy 132.652275 -123.325957) (xy 132.622809 -123.280107) (xy 132.600167 -123.23053)
			(xy 132.584812 -123.178235) (xy 132.577056 -123.124287) (xy 132.57657 -123.097036) (xy 130.74369 -123.097036)
			(xy 130.756807 -123.139036) (xy 130.765523 -123.19616) (xy 130.766058 -123.225052) (xy 130.7656 -123.252306)
			(xy 130.757848 -123.30626) (xy 130.742496 -123.358561) (xy 130.719855 -123.408144) (xy 130.690387 -123.454)
			(xy 130.654693 -123.495194) (xy 130.613498 -123.530889) (xy 130.567642 -123.560356) (xy 130.518059 -123.582996)
			(xy 130.465758 -123.598349) (xy 130.411804 -123.6061) (xy 130.38455 -123.60656) (xy 130.35718 -123.606074)
			(xy 130.303002 -123.598263) (xy 130.250498 -123.582779) (xy 130.200751 -123.559941) (xy 130.154784 -123.53022)
			(xy 130.133852 -123.51258) (xy 130.12674 -123.506484) (xy 130.109722 -123.500134) (xy 130.024378 -123.500134)
			(xy 130.00736 -123.506484) (xy 130.000248 -123.51258) (xy 129.979315 -123.530221) (xy 129.933347 -123.559945)
			(xy 129.883601 -123.582791) (xy 129.831099 -123.598287) (xy 129.776921 -123.606116) (xy 129.722179 -123.606116)
			(xy 129.668001 -123.598287) (xy 129.615499 -123.582791) (xy 129.565753 -123.559945) (xy 129.519785 -123.530221)
			(xy 129.498852 -123.51258) (xy 129.49174 -123.506484) (xy 129.474722 -123.500134) (xy 129.389378 -123.500134)
			(xy 129.37236 -123.506484) (xy 129.365248 -123.51258) (xy 129.344306 -123.530207) (xy 129.298336 -123.559921)
			(xy 129.248591 -123.58276) (xy 129.196093 -123.598254) (xy 129.141919 -123.606085) (xy 129.11455 -123.60656)
			(xy 129.08752 -123.606077) (xy 129.034003 -123.598433) (xy 128.982102 -123.583307) (xy 128.932859 -123.561)
			(xy 128.88726 -123.531961) (xy 128.846221 -123.496772) (xy 128.828038 -123.476766) (xy 128.820672 -123.468638)
			(xy 128.80086 -123.459494) (xy 128.702816 -123.45924) (xy 128.683004 -123.46813) (xy 128.675638 -123.476258)
			(xy 128.657465 -123.495969) (xy 128.616566 -123.530632) (xy 128.571212 -123.559221) (xy 128.522299 -123.581171)
			(xy 128.470793 -123.59605) (xy 128.41771 -123.603564) (xy 128.390904 -123.60402) (xy 128.363652 -123.603533)
			(xy 128.309702 -123.595777) (xy 128.257405 -123.580421) (xy 128.207826 -123.55778) (xy 128.161974 -123.528313)
			(xy 128.120782 -123.49262) (xy 128.085089 -123.451429) (xy 128.055622 -123.405577) (xy 128.03298 -123.355998)
			(xy 128.017624 -123.303702) (xy 128.009867 -123.249752) (xy 125.364377 -123.249752) (xy 125.338011 -123.266698)
			(xy 125.288435 -123.289342) (xy 125.236142 -123.304701) (xy 125.182195 -123.312463) (xy 125.154944 -123.312936)
			(xy 125.15469 -123.312936) (xy 125.1259 -123.3124) (xy 125.068977 -123.303715) (xy 125.014011 -123.28656)
			(xy 124.962254 -123.261325) (xy 124.938282 -123.245372) (xy 124.938028 -123.245372) (xy 124.930194 -123.240422)
			(xy 124.912226 -123.235947) (xy 124.893839 -123.238134) (xy 124.88545 -123.24207) (xy 124.805948 -123.28398)
			(xy 124.79796 -123.288626) (xy 124.785713 -123.302445) (xy 124.779154 -123.319706) (xy 124.77877 -123.328938)
			(xy 124.77877 -123.549918) (xy 124.779173 -123.559146) (xy 124.785727 -123.5764) (xy 124.797976 -123.590206)
			(xy 124.805948 -123.594876) (xy 124.88545 -123.636786) (xy 124.893836 -123.640734) (xy 124.912225 -123.642936)
			(xy 124.930189 -123.638432) (xy 124.938028 -123.633484) (xy 124.938282 -123.633484) (xy 124.962297 -123.617541)
			(xy 125.014115 -123.592298) (xy 125.069142 -123.575139) (xy 125.126124 -123.566457) (xy 125.154944 -123.56592)
			(xy 125.162056 -123.56592) (xy 125.188975 -123.566882) (xy 125.242154 -123.575445) (xy 125.2936 -123.591404)
			(xy 125.34229 -123.614441) (xy 125.387254 -123.6441) (xy 125.427598 -123.679788) (xy 125.462521 -123.720798)
			(xy 125.491327 -123.766313) (xy 125.513444 -123.815427) (xy 125.528431 -123.867164) (xy 125.535991 -123.920496)
			(xy 125.536452 -123.947428) (xy 125.535964 -123.974679) (xy 125.528205 -124.028626) (xy 125.512848 -124.08092)
			(xy 125.490206 -124.130497) (xy 125.460739 -124.176347) (xy 125.425048 -124.217537) (xy 125.383859 -124.25323)
			(xy 125.338011 -124.282698) (xy 125.288435 -124.305342) (xy 125.236142 -124.320701) (xy 125.182195 -124.328463)
			(xy 125.154944 -124.328936) (xy 125.15469 -124.328936) (xy 125.1259 -124.3284) (xy 125.068977 -124.319715)
			(xy 125.014011 -124.30256) (xy 124.962254 -124.277325) (xy 124.938282 -124.261372) (xy 124.938028 -124.261372)
			(xy 124.930194 -124.256422) (xy 124.912226 -124.251947) (xy 124.893839 -124.254134) (xy 124.88545 -124.25807)
			(xy 124.805948 -124.29998) (xy 124.79796 -124.304626) (xy 124.785713 -124.318445) (xy 124.779154 -124.335706)
			(xy 124.77877 -124.344938) (xy 124.77877 -124.476002) (xy 124.779159 -124.484852) (xy 124.785183 -124.501497)
			(xy 124.796485 -124.515121) (xy 124.803916 -124.519944) (xy 124.891292 -124.571252) (xy 124.918216 -124.571506)
			(xy 124.930154 -124.564648) (xy 124.955969 -124.550607) (xy 125.010432 -124.528535) (xy 125.067275 -124.51363)
			(xy 125.125561 -124.506137) (xy 125.154944 -124.50572) (xy 125.16104 -124.50572) (xy 125.190749 -124.506586)
			(xy 125.249579 -124.515056) (xy 125.306817 -124.531071) (xy 125.361501 -124.554359) (xy 125.412711 -124.58453)
			(xy 125.459584 -124.621076) (xy 125.501332 -124.663381) (xy 125.537253 -124.710735) (xy 125.566743 -124.76234)
			(xy 125.589304 -124.817327) (xy 125.604558 -124.874773) (xy 125.612248 -124.93371) (xy 125.612652 -124.963428)
			(xy 125.61216 -124.993395) (xy 125.609885 -125.010668) (xy 126.853678 -125.010668) (xy 126.853678 -124.950732)
			(xy 126.861501 -124.89131) (xy 126.877014 -124.833417) (xy 126.89995 -124.778044) (xy 126.929917 -124.726138)
			(xy 126.966404 -124.678588) (xy 127.008784 -124.636208) (xy 127.056334 -124.599721) (xy 127.10824 -124.569754)
			(xy 127.163613 -124.546818) (xy 127.221506 -124.531305) (xy 127.280928 -124.523482) (xy 127.340864 -124.523482)
			(xy 127.400286 -124.531305) (xy 127.458179 -124.546818) (xy 127.513552 -124.569754) (xy 127.565458 -124.599721)
			(xy 127.613008 -124.636208) (xy 127.655388 -124.678588) (xy 127.691875 -124.726138) (xy 127.721842 -124.778044)
			(xy 127.744778 -124.833417) (xy 127.760291 -124.89131) (xy 127.768114 -124.950732) (xy 127.768604 -124.9807)
			(xy 127.768114 -125.010668) (xy 127.760291 -125.07009) (xy 127.744778 -125.127983) (xy 127.721842 -125.183356)
			(xy 127.691875 -125.235262) (xy 127.655388 -125.282812) (xy 127.613008 -125.325192) (xy 127.565458 -125.361679)
			(xy 127.513552 -125.391646) (xy 127.458179 -125.414582) (xy 127.400286 -125.430095) (xy 127.340864 -125.437918)
			(xy 127.280928 -125.437918) (xy 127.221506 -125.430095) (xy 127.163613 -125.414582) (xy 127.10824 -125.391646)
			(xy 127.056334 -125.361679) (xy 127.008784 -125.325192) (xy 126.966404 -125.282812) (xy 126.929917 -125.235262)
			(xy 126.89995 -125.183356) (xy 126.877014 -125.127983) (xy 126.861501 -125.07009) (xy 126.853678 -125.010668)
			(xy 125.609885 -125.010668) (xy 125.604334 -125.052817) (xy 125.58882 -125.11071) (xy 125.565883 -125.166082)
			(xy 125.535915 -125.217987) (xy 125.499429 -125.265537) (xy 125.457049 -125.307918) (xy 125.4095 -125.344406)
			(xy 125.357596 -125.374375) (xy 125.302225 -125.397315) (xy 125.244333 -125.412831) (xy 125.184911 -125.420659)
			(xy 125.154944 -125.421136) (xy 125.125566 -125.420657) (xy 125.067294 -125.413135) (xy 125.010459 -125.398234)
			(xy 124.955992 -125.376197) (xy 124.930154 -125.362208) (xy 124.918216 -125.35535) (xy 124.891292 -125.355604)
			(xy 124.803916 -125.406912) (xy 124.796418 -125.411662) (xy 124.785065 -125.42529) (xy 124.779069 -125.441983)
			(xy 124.77877 -125.450854) (xy 124.77877 -125.992886) (xy 127.176004 -125.992886) (xy 127.176004 -125.93295)
			(xy 127.183827 -125.873528) (xy 127.19934 -125.815635) (xy 127.222276 -125.760262) (xy 127.252243 -125.708356)
			(xy 127.28873 -125.660806) (xy 127.33111 -125.618426) (xy 127.37866 -125.581939) (xy 127.430566 -125.551972)
			(xy 127.485939 -125.529036) (xy 127.543832 -125.513523) (xy 127.603254 -125.5057) (xy 127.66319 -125.5057)
			(xy 127.722612 -125.513523) (xy 127.780505 -125.529036) (xy 127.835878 -125.551972) (xy 127.887784 -125.581939)
			(xy 127.935334 -125.618426) (xy 127.977714 -125.660806) (xy 128.014201 -125.708356) (xy 128.044168 -125.760262)
			(xy 128.067104 -125.815635) (xy 128.082617 -125.873528) (xy 128.09044 -125.93295) (xy 128.09093 -125.962918)
			(xy 128.09044 -125.992886) (xy 128.082617 -126.052308) (xy 128.067104 -126.110201) (xy 128.044168 -126.165574)
			(xy 128.014201 -126.21748) (xy 127.977714 -126.26503) (xy 127.935334 -126.30741) (xy 127.887784 -126.343897)
			(xy 127.835878 -126.373864) (xy 127.780505 -126.3968) (xy 127.722612 -126.412313) (xy 127.66319 -126.420136)
			(xy 127.603254 -126.420136) (xy 127.543832 -126.412313) (xy 127.485939 -126.3968) (xy 127.430566 -126.373864)
			(xy 127.37866 -126.343897) (xy 127.33111 -126.30741) (xy 127.28873 -126.26503) (xy 127.252243 -126.21748)
			(xy 127.222276 -126.165574) (xy 127.19934 -126.110201) (xy 127.183827 -126.052308) (xy 127.176004 -125.992886)
			(xy 124.77877 -125.992886) (xy 124.77877 -126.597918) (xy 124.779173 -126.607146) (xy 124.785727 -126.6244)
			(xy 124.797976 -126.638206) (xy 124.805948 -126.642876) (xy 124.88545 -126.684786) (xy 124.893836 -126.688734)
			(xy 124.912225 -126.690936) (xy 124.930189 -126.686432) (xy 124.938028 -126.681484) (xy 124.938282 -126.681484)
			(xy 124.962297 -126.665541) (xy 125.014115 -126.640298) (xy 125.069142 -126.623139) (xy 125.126124 -126.614457)
			(xy 125.154944 -126.61392) (xy 125.162056 -126.61392) (xy 125.188975 -126.614882) (xy 125.242154 -126.623445)
			(xy 125.2936 -126.639404) (xy 125.34229 -126.662441) (xy 125.387254 -126.6921) (xy 125.427598 -126.727788)
			(xy 125.462521 -126.768798) (xy 125.491327 -126.814313) (xy 125.513444 -126.863427) (xy 125.528431 -126.915164)
			(xy 125.535991 -126.968496) (xy 125.536452 -126.995428) (xy 125.535964 -127.022679) (xy 125.528205 -127.076626)
			(xy 125.526839 -127.081276) (xy 126.768842 -127.081276) (xy 126.768842 -127.02134) (xy 126.776665 -126.961918)
			(xy 126.792178 -126.904025) (xy 126.815114 -126.848652) (xy 126.845081 -126.796746) (xy 126.881568 -126.749196)
			(xy 126.923948 -126.706816) (xy 126.971498 -126.670329) (xy 127.023404 -126.640362) (xy 127.078777 -126.617426)
			(xy 127.13667 -126.601913) (xy 127.196092 -126.59409) (xy 127.256028 -126.59409) (xy 127.31545 -126.601913)
			(xy 127.373343 -126.617426) (xy 127.428716 -126.640362) (xy 127.480622 -126.670329) (xy 127.528172 -126.706816)
			(xy 127.570552 -126.749196) (xy 127.607039 -126.796746) (xy 127.637006 -126.848652) (xy 127.659942 -126.904025)
			(xy 127.675455 -126.961918) (xy 127.683278 -127.02134) (xy 127.683286 -127.021844) (xy 130.874006 -127.021844)
			(xy 130.878077 -126.966222) (xy 130.890203 -126.911785) (xy 130.910126 -126.859694) (xy 130.937422 -126.811059)
			(xy 130.971508 -126.766916) (xy 131.011657 -126.728207) (xy 131.057015 -126.695756) (xy 131.106615 -126.670255)
			(xy 131.159399 -126.652248) (xy 131.214242 -126.642118) (xy 131.269976 -126.640081) (xy 131.325413 -126.646181)
			(xy 131.37937 -126.660287) (xy 131.430699 -126.682099) (xy 131.478305 -126.711153) (xy 131.521173 -126.746828)
			(xy 131.55839 -126.788365) (xy 131.589163 -126.834878) (xy 131.612835 -126.885375) (xy 131.628903 -126.938782)
			(xy 131.637023 -126.993958) (xy 131.637532 -127.021844) (xy 131.637023 -127.04973) (xy 131.628903 -127.104906)
			(xy 131.612835 -127.158313) (xy 131.589163 -127.20881) (xy 131.55839 -127.255323) (xy 131.521173 -127.29686)
			(xy 131.478305 -127.332535) (xy 131.430699 -127.361589) (xy 131.37937 -127.383401) (xy 131.325413 -127.397507)
			(xy 131.269976 -127.403607) (xy 131.214242 -127.40157) (xy 131.159399 -127.39144) (xy 131.106615 -127.373433)
			(xy 131.057015 -127.347932) (xy 131.011657 -127.315481) (xy 130.971508 -127.276772) (xy 130.937422 -127.232629)
			(xy 130.910126 -127.183994) (xy 130.890203 -127.131903) (xy 130.878077 -127.077466) (xy 130.874006 -127.021844)
			(xy 127.683286 -127.021844) (xy 127.683768 -127.051308) (xy 127.683278 -127.081276) (xy 127.675455 -127.140698)
			(xy 127.659942 -127.198591) (xy 127.637006 -127.253964) (xy 127.607039 -127.30587) (xy 127.570552 -127.35342)
			(xy 127.528172 -127.3958) (xy 127.480622 -127.432287) (xy 127.428716 -127.462254) (xy 127.373343 -127.48519)
			(xy 127.31545 -127.500703) (xy 127.256028 -127.508526) (xy 127.196092 -127.508526) (xy 127.13667 -127.500703)
			(xy 127.078777 -127.48519) (xy 127.023404 -127.462254) (xy 126.971498 -127.432287) (xy 126.923948 -127.3958)
			(xy 126.881568 -127.35342) (xy 126.845081 -127.30587) (xy 126.815114 -127.253964) (xy 126.792178 -127.198591)
			(xy 126.776665 -127.140698) (xy 126.768842 -127.081276) (xy 125.526839 -127.081276) (xy 125.512848 -127.12892)
			(xy 125.490206 -127.178497) (xy 125.460739 -127.224347) (xy 125.425048 -127.265537) (xy 125.383859 -127.30123)
			(xy 125.338011 -127.330698) (xy 125.288435 -127.353342) (xy 125.236142 -127.368701) (xy 125.182195 -127.376463)
			(xy 125.154944 -127.376936) (xy 125.15342 -127.376936) (xy 125.143473 -127.377479) (xy 125.125111 -127.385152)
			(xy 125.111022 -127.399208) (xy 125.106684 -127.408178) (xy 125.070616 -127.495046) (xy 125.067141 -127.504458)
			(xy 125.067094 -127.524507) (xy 125.074739 -127.543041) (xy 125.081538 -127.550418) (xy 125.132338 -127.601218)
			(xy 125.139735 -127.608067) (xy 125.158334 -127.615801) (xy 125.168406 -127.616204) (xy 137.186924 -127.616204)
			(xy 137.196992 -127.616632) (xy 137.21559 -127.624353) (xy 137.222992 -127.63119) (xy 137.523982 -127.93218)
			(xy 137.530818 -127.939582) (xy 137.538526 -127.95818) (xy 137.538968 -127.968248) (xy 137.538968 -134.193534)
			(xy 137.539397 -134.203602) (xy 137.547116 -134.222201) (xy 137.553954 -134.229602) (xy 143.305784 -139.981432)
			(xy 143.313184 -139.988273) (xy 143.331783 -139.995987) (xy 143.341852 -139.996418) (xy 151.969216 -139.996418)
			(xy 151.97551 -139.996228) (xy 151.987715 -139.993142) (xy 151.993346 -139.990322) (xy 152.017248 -139.978)
			(xy 152.067721 -139.959448) (xy 152.120299 -139.948167) (xy 152.17394 -139.944382) (xy 152.227581 -139.948167)
			(xy 152.280159 -139.959448) (xy 152.330632 -139.978) (xy 152.354534 -139.990322) (xy 152.360162 -139.99315)
			(xy 152.372368 -139.996241) (xy 152.378664 -139.996418) (xy 156.889958 -139.996418) (xy 156.900023 -139.996852)
			(xy 156.918611 -140.004583) (xy 156.926026 -140.011404) (xy 159.005778 -142.091156) (xy 159.013179 -142.097995)
			(xy 159.031777 -142.105708) (xy 159.041846 -142.106142)
		)
		(stroke
			(width 0)
			(type solid)
		)
		(fill yes)
		(layer "B.Cu")
		(net "P3V3_NIC2")
	)
	(gr_poly
		(pts
			(xy 45.868844 -142.106142) (xy 45.878809 -142.105661) (xy 45.897243 -142.098084) (xy 45.904658 -142.09141)
			(xy 45.964094 -142.032228) (xy 45.968666 -142.026894) (xy 45.973746 -142.020544) (xy 45.97908 -142.004542)
			(xy 45.97908 -139.559284) (xy 45.978653 -139.549216) (xy 45.970933 -139.530617) (xy 45.964094 -139.523216)
			(xy 45.924978 -139.4841) (xy 45.917866 -139.476734) (xy 45.89907 -139.469114) (xy 44.426886 -139.469114)
			(xy 44.416817 -139.468689) (xy 44.398214 -139.460972) (xy 44.390818 -139.454128) (xy 42.372788 -137.436098)
			(xy 42.365676 -137.428732) (xy 42.34688 -137.421112) (xy 34.760916 -137.421112) (xy 34.750852 -137.420674)
			(xy 34.732269 -137.41294) (xy 34.724848 -137.406126) (xy 31.279592 -133.96087) (xy 31.272751 -133.953469)
			(xy 31.265029 -133.934871) (xy 31.264606 -133.924802) (xy 31.264606 -120.604534) (xy 31.264171 -120.594469)
			(xy 31.256441 -120.575881) (xy 31.24962 -120.568466) (xy 26.005028 -115.323874) (xy 25.997916 -115.316508)
			(xy 25.994868 -115.315238) (xy 18.318734 -115.315238) (xy 17.319244 -116.314728) (xy 17.319244 -117.483128)
			(xy 17.2847 -117.517926) (xy 17.282705 -117.526201) (xy 17.283604 -117.543188) (xy 17.286478 -117.5512)
			(xy 17.311878 -117.612414) (xy 17.327626 -117.6274) (xy 17.33804 -117.630956) (xy 17.367637 -117.641755)
			(xy 17.423786 -117.67033) (xy 17.475487 -117.706334) (xy 17.521762 -117.749087) (xy 17.561738 -117.797782)
			(xy 17.594659 -117.851498) (xy 17.619904 -117.909221) (xy 17.636996 -117.969861) (xy 17.645611 -118.032271)
			(xy 17.646142 -118.063772) (xy 17.645675 -118.093758) (xy 17.63785 -118.153218) (xy 17.62233 -118.211148)
			(xy 17.599382 -118.266557) (xy 17.569397 -118.318495) (xy 17.532888 -118.366076) (xy 17.490482 -118.408483)
			(xy 17.442902 -118.444992) (xy 17.390964 -118.474978) (xy 17.335556 -118.497928) (xy 17.277626 -118.513448)
			(xy 17.218166 -118.521274) (xy 17.18818 -118.521734) (xy 17.15777 -118.521235) (xy 17.097487 -118.513182)
			(xy 17.0388 -118.49722) (xy 16.982742 -118.473629) (xy 16.9303 -118.442826) (xy 16.882397 -118.405352)
			(xy 16.839876 -118.361867) (xy 16.803486 -118.313136) (xy 16.773866 -118.260017) (xy 16.762222 -118.23192)
			(xy 16.757396 -118.219728) (xy 16.737838 -118.203472) (xy 16.642588 -118.18366) (xy 16.641826 -118.18366)
			(xy 16.635806 -118.182652) (xy 16.623613 -118.183173) (xy 16.617696 -118.184676) (xy 16.12519 -118.677182)
			(xy 16.12519 -119.946166) (xy 16.126714 -119.948452) (xy 16.140826 -119.971472) (xy 16.163122 -120.020647)
			(xy 16.178253 -120.072478) (xy 16.185915 -120.125925) (xy 16.186404 -120.152922) (xy 16.186404 -120.15343)
			(xy 16.438878 -120.15343) (xy 16.442949 -120.097808) (xy 16.455075 -120.043371) (xy 16.474998 -119.99128)
			(xy 16.502294 -119.942645) (xy 16.53638 -119.898502) (xy 16.576529 -119.859793) (xy 16.621887 -119.827342)
			(xy 16.671487 -119.801841) (xy 16.724271 -119.783834) (xy 16.779114 -119.773704) (xy 16.834848 -119.771667)
			(xy 16.890285 -119.777767) (xy 16.944242 -119.791873) (xy 16.995571 -119.813685) (xy 17.043177 -119.842739)
			(xy 17.086045 -119.878414) (xy 17.123262 -119.919951) (xy 17.154035 -119.966464) (xy 17.177707 -120.016961)
			(xy 17.193775 -120.070368) (xy 17.201895 -120.125544) (xy 17.202404 -120.15343) (xy 17.201895 -120.181316)
			(xy 17.193775 -120.236492) (xy 17.177707 -120.289899) (xy 17.154035 -120.340396) (xy 17.123262 -120.386909)
			(xy 17.086045 -120.428446) (xy 17.043177 -120.464121) (xy 16.995571 -120.493175) (xy 16.944242 -120.514987)
			(xy 16.890285 -120.529093) (xy 16.834848 -120.535193) (xy 16.779114 -120.533156) (xy 16.724271 -120.523026)
			(xy 16.671487 -120.505019) (xy 16.621887 -120.479518) (xy 16.576529 -120.447067) (xy 16.53638 -120.408358)
			(xy 16.502294 -120.364215) (xy 16.474998 -120.31558) (xy 16.455075 -120.263489) (xy 16.442949 -120.209052)
			(xy 16.438878 -120.15343) (xy 16.186404 -120.15343) (xy 16.185918 -120.180681) (xy 16.178162 -120.234629)
			(xy 16.162807 -120.286924) (xy 16.140165 -120.336501) (xy 16.110699 -120.382351) (xy 16.075008 -120.423542)
			(xy 16.033817 -120.459233) (xy 15.987967 -120.488699) (xy 15.93839 -120.511341) (xy 15.886095 -120.526696)
			(xy 15.832147 -120.534452) (xy 15.777645 -120.534452) (xy 15.723697 -120.526696) (xy 15.671402 -120.511341)
			(xy 15.621825 -120.488699) (xy 15.575975 -120.459233) (xy 15.534784 -120.423542) (xy 15.499093 -120.382351)
			(xy 15.469627 -120.336501) (xy 15.446985 -120.286924) (xy 15.43163 -120.234629) (xy 15.423874 -120.180681)
			(xy 15.423388 -120.15343) (xy 15.423388 -120.152922) (xy 15.423894 -120.125927) (xy 15.431575 -120.072486)
			(xy 15.446702 -120.020657) (xy 15.468974 -119.971474) (xy 15.483078 -119.948452) (xy 15.484602 -119.946166)
			(xy 15.484602 -118.412006) (xy 15.894812 -118.001542) (xy 15.896295 -117.995885) (xy 15.896947 -117.984211)
			(xy 15.896082 -117.978428) (xy 15.87881 -117.884194) (xy 15.86357 -117.864636) (xy 15.85214 -117.859302)
			(xy 15.825767 -117.846872) (xy 15.776127 -117.816291) (xy 15.730773 -117.779652) (xy 15.690442 -117.737548)
			(xy 15.655786 -117.690663) (xy 15.627366 -117.639754) (xy 15.605644 -117.585648) (xy 15.590972 -117.52922)
			(xy 15.583586 -117.471386) (xy 15.583154 -117.442234) (xy 15.583621 -117.412247) (xy 15.591445 -117.352786)
			(xy 15.606964 -117.294856) (xy 15.629912 -117.239446) (xy 15.659897 -117.187507) (xy 15.696405 -117.139926)
			(xy 15.738812 -117.097517) (xy 15.786392 -117.061007) (xy 15.83833 -117.03102) (xy 15.893739 -117.00807)
			(xy 15.951669 -116.992549) (xy 16.011129 -116.984722) (xy 16.041116 -116.984272) (xy 16.070263 -116.984735)
			(xy 16.128083 -116.992148) (xy 16.184495 -117.006839) (xy 16.238587 -117.02857) (xy 16.289483 -117.05699)
			(xy 16.336361 -117.09164) (xy 16.378462 -117.131959) (xy 16.415106 -117.177295) (xy 16.445701 -117.226915)
			(xy 16.458184 -117.253258) (xy 16.463518 -117.264688) (xy 16.483076 -117.279928) (xy 16.576548 -117.2972)
			(xy 16.582582 -117.298151) (xy 16.594778 -117.297513) (xy 16.600678 -117.29593) (xy 16.678656 -117.217952)
			(xy 16.678656 -116.049552) (xy 17.275048 -115.45316) (xy 17.280786 -115.439734) (xy 17.285142 -115.410874)
			(xy 17.281167 -115.381959) (xy 17.269184 -115.355346) (xy 17.25017 -115.333202) (xy 17.225674 -115.317333)
			(xy 17.197693 -115.309032) (xy 17.1831 -115.308634) (xy 9.845802 -115.308634) (xy 9.835732 -115.309057)
			(xy 9.81713 -115.316775) (xy 9.809734 -115.32362) (xy 8.693912 -116.439442) (xy 8.686546 -116.446554)
			(xy 8.685001 -116.450364) (xy 11.961366 -116.450364) (xy 11.965437 -116.394742) (xy 11.977563 -116.340305)
			(xy 11.997486 -116.288214) (xy 12.024782 -116.239579) (xy 12.058868 -116.195436) (xy 12.099017 -116.156727)
			(xy 12.144375 -116.124276) (xy 12.193975 -116.098775) (xy 12.246759 -116.080768) (xy 12.301602 -116.070638)
			(xy 12.357336 -116.068601) (xy 12.412773 -116.074701) (xy 12.46673 -116.088807) (xy 12.518059 -116.110619)
			(xy 12.565665 -116.139673) (xy 12.608533 -116.175348) (xy 12.64575 -116.216885) (xy 12.676523 -116.263398)
			(xy 12.700195 -116.313895) (xy 12.716263 -116.367302) (xy 12.724383 -116.422478) (xy 12.724892 -116.450364)
			(xy 12.724383 -116.47825) (xy 12.716263 -116.533426) (xy 12.700195 -116.586833) (xy 12.676523 -116.63733)
			(xy 12.64575 -116.683843) (xy 12.608533 -116.72538) (xy 12.565665 -116.761055) (xy 12.518059 -116.790109)
			(xy 12.46673 -116.811921) (xy 12.412773 -116.826027) (xy 12.357336 -116.832127) (xy 12.301602 -116.83009)
			(xy 12.246759 -116.81996) (xy 12.193975 -116.801953) (xy 12.144375 -116.776452) (xy 12.099017 -116.744001)
			(xy 12.058868 -116.705292) (xy 12.024782 -116.661149) (xy 11.997486 -116.612514) (xy 11.977563 -116.560423)
			(xy 11.965437 -116.505986) (xy 11.961366 -116.450364) (xy 8.685001 -116.450364) (xy 8.678926 -116.46535)
			(xy 8.678926 -117.434106) (xy 13.37691 -117.434106) (xy 13.377412 -117.406773) (xy 13.385213 -117.352668)
			(xy 13.400655 -117.300229) (xy 13.423422 -117.250531) (xy 13.453049 -117.20459) (xy 13.470636 -117.183662)
			(xy 13.471144 -117.183154) (xy 13.476719 -117.17606) (xy 13.482972 -117.159149) (xy 13.483336 -117.150134)
			(xy 13.483336 -117.083078) (xy 13.482982 -117.074061) (xy 13.476732 -117.057144) (xy 13.471144 -117.050058)
			(xy 13.470636 -117.04955) (xy 13.453043 -117.028623) (xy 13.423392 -116.98269) (xy 13.400605 -116.932993)
			(xy 13.385149 -116.880552) (xy 13.37734 -116.82644) (xy 13.37734 -116.771769) (xy 13.385147 -116.717657)
			(xy 13.400602 -116.665215) (xy 13.423388 -116.615518) (xy 13.453037 -116.569585) (xy 13.470636 -116.548662)
			(xy 13.471144 -116.548154) (xy 13.476719 -116.54106) (xy 13.482972 -116.524149) (xy 13.483336 -116.515134)
			(xy 13.483336 -116.448078) (xy 13.482982 -116.439061) (xy 13.476732 -116.422144) (xy 13.471144 -116.415058)
			(xy 13.470636 -116.41455) (xy 13.453059 -116.393612) (xy 13.423417 -116.347679) (xy 13.400637 -116.297984)
			(xy 13.385186 -116.245546) (xy 13.37738 -116.191439) (xy 13.37691 -116.164106) (xy 13.377361 -116.136852)
			(xy 13.385118 -116.0829) (xy 13.400474 -116.030601) (xy 13.423117 -115.98102) (xy 13.452586 -115.935166)
			(xy 13.488281 -115.893972) (xy 13.529475 -115.858279) (xy 13.57533 -115.828811) (xy 13.624912 -115.80617)
			(xy 13.677212 -115.790815) (xy 13.731164 -115.78306) (xy 13.758418 -115.782598) (xy 13.785789 -115.783054)
			(xy 13.839968 -115.790874) (xy 13.892471 -115.806366) (xy 13.942218 -115.82921) (xy 13.988184 -115.858936)
			(xy 14.009116 -115.876578) (xy 14.00937 -115.876832) (xy 14.016458 -115.882416) (xy 14.033374 -115.888663)
			(xy 14.04239 -115.889024) (xy 14.109446 -115.889024) (xy 14.11846 -115.888636) (xy 14.135377 -115.882409)
			(xy 14.142466 -115.876832) (xy 14.142974 -115.876324) (xy 14.163902 -115.858734) (xy 14.209838 -115.829094)
			(xy 14.259535 -115.806317) (xy 14.311975 -115.790869) (xy 14.366084 -115.783066) (xy 14.393418 -115.782598)
			(xy 14.42067 -115.783061) (xy 14.474619 -115.79082) (xy 14.526914 -115.806178) (xy 14.576492 -115.828822)
			(xy 14.622343 -115.85829) (xy 14.663533 -115.893984) (xy 14.699224 -115.935177) (xy 14.72869 -115.981029)
			(xy 14.75133 -116.030608) (xy 14.766685 -116.082905) (xy 14.774441 -116.136854) (xy 14.774926 -116.164106)
			(xy 14.774446 -116.19144) (xy 14.766642 -116.245547) (xy 14.751196 -116.297986) (xy 14.728423 -116.347684)
			(xy 14.69879 -116.393623) (xy 14.6812 -116.41455) (xy 14.680692 -116.415058) (xy 14.675116 -116.422152)
			(xy 14.668863 -116.439063) (xy 14.6685 -116.448078) (xy 14.6685 -116.515134) (xy 14.668841 -116.524152)
			(xy 14.6751 -116.541069) (xy 14.680692 -116.548154) (xy 14.6812 -116.548662) (xy 14.698808 -116.569579)
			(xy 14.728463 -116.615512) (xy 14.751253 -116.66521) (xy 14.766711 -116.717654) (xy 14.77452 -116.771767)
			(xy 14.774519 -116.826442) (xy 14.766709 -116.880555) (xy 14.75125 -116.932999) (xy 14.728458 -116.982696)
			(xy 14.698802 -117.028629) (xy 14.6812 -117.04955) (xy 14.680692 -117.050058) (xy 14.675116 -117.057152)
			(xy 14.668863 -117.074063) (xy 14.6685 -117.083078) (xy 14.6685 -117.150134) (xy 14.668841 -117.159152)
			(xy 14.6751 -117.176069) (xy 14.680692 -117.183154) (xy 14.6812 -117.183662) (xy 14.698788 -117.204591)
			(xy 14.728427 -117.250527) (xy 14.751204 -117.300224) (xy 14.766653 -117.352664) (xy 14.774457 -117.406772)
			(xy 14.774926 -117.434106) (xy 14.774489 -117.458319) (xy 14.768243 -117.506343) (xy 14.76248 -117.529864)
			(xy 14.759686 -117.540532) (xy 14.763496 -117.561868) (xy 14.81836 -117.644164) (xy 14.836902 -117.655594)
			(xy 14.847824 -117.657118) (xy 14.877522 -117.661436) (xy 14.935516 -117.676874) (xy 14.990995 -117.699759)
			(xy 15.043008 -117.729698) (xy 15.090661 -117.766178) (xy 15.133138 -117.808573) (xy 15.16971 -117.856156)
			(xy 15.19975 -117.908111) (xy 15.222742 -117.963546) (xy 15.238292 -118.02151) (xy 15.246133 -118.081009)
			(xy 15.246604 -118.111016) (xy 15.246114 -118.140984) (xy 15.238291 -118.200406) (xy 15.222778 -118.258299)
			(xy 15.199842 -118.313672) (xy 15.169875 -118.365578) (xy 15.133388 -118.413128) (xy 15.091008 -118.455508)
			(xy 15.043458 -118.491995) (xy 14.991552 -118.521962) (xy 14.936179 -118.544898) (xy 14.878286 -118.560411)
			(xy 14.818864 -118.568234) (xy 14.758928 -118.568234) (xy 14.699506 -118.560411) (xy 14.641613 -118.544898)
			(xy 14.58624 -118.521962) (xy 14.534334 -118.491995) (xy 14.486784 -118.455508) (xy 14.444404 -118.413128)
			(xy 14.407917 -118.365578) (xy 14.37795 -118.313672) (xy 14.355014 -118.258299) (xy 14.339501 -118.200406)
			(xy 14.331678 -118.140984) (xy 14.331188 -118.111016) (xy 14.331188 -118.110254) (xy 14.331636 -118.081538)
			(xy 14.338895 -118.024565) (xy 14.353244 -117.968953) (xy 14.363446 -117.942106) (xy 14.363954 -117.940836)
			(xy 14.365478 -117.936264) (xy 14.368273 -117.926605) (xy 14.366825 -117.906565) (xy 14.362684 -117.897402)
			(xy 14.324076 -117.819932) (xy 14.315694 -117.813328) (xy 14.315186 -117.81282) (xy 14.306296 -117.805454)
			(xy 14.295374 -117.80266) (xy 14.267417 -117.794675) (xy 14.214144 -117.771387) (xy 14.165009 -117.740305)
			(xy 14.14272 -117.721634) (xy 14.142466 -117.72138) (xy 14.135366 -117.715813) (xy 14.11846 -117.709555)
			(xy 14.109446 -117.709188) (xy 14.04239 -117.709188) (xy 14.033373 -117.709543) (xy 14.016456 -117.715792)
			(xy 14.00937 -117.72138) (xy 14.008862 -117.721888) (xy 13.987922 -117.739463) (xy 13.941989 -117.769104)
			(xy 13.892295 -117.791884) (xy 13.839858 -117.807336) (xy 13.785751 -117.815143) (xy 13.758418 -117.815614)
			(xy 13.731166 -117.815128) (xy 13.677216 -117.807374) (xy 13.624919 -117.79202) (xy 13.575339 -117.76938)
			(xy 13.529486 -117.739915) (xy 13.488294 -117.704223) (xy 13.4526 -117.663033) (xy 13.423131 -117.617182)
			(xy 13.400488 -117.567604) (xy 13.385132 -117.515307) (xy 13.377374 -117.461358) (xy 13.37691 -117.434106)
			(xy 8.678926 -117.434106) (xy 8.678926 -118.119394) (xy 10.120104 -118.119394) (xy 10.120104 -118.059458)
			(xy 10.127927 -118.000036) (xy 10.14344 -117.942143) (xy 10.166376 -117.88677) (xy 10.196343 -117.834864)
			(xy 10.23283 -117.787314) (xy 10.27521 -117.744934) (xy 10.32276 -117.708447) (xy 10.374666 -117.67848)
			(xy 10.430039 -117.655544) (xy 10.487932 -117.640031) (xy 10.547354 -117.632208) (xy 10.60729 -117.632208)
			(xy 10.666712 -117.640031) (xy 10.724605 -117.655544) (xy 10.779978 -117.67848) (xy 10.831884 -117.708447)
			(xy 10.879434 -117.744934) (xy 10.921814 -117.787314) (xy 10.958301 -117.834864) (xy 10.988268 -117.88677)
			(xy 11.011204 -117.942143) (xy 11.024669 -117.992394) (xy 12.152104 -117.992394) (xy 12.152104 -117.932458)
			(xy 12.159927 -117.873036) (xy 12.17544 -117.815143) (xy 12.198376 -117.75977) (xy 12.228343 -117.707864)
			(xy 12.26483 -117.660314) (xy 12.30721 -117.617934) (xy 12.35476 -117.581447) (xy 12.406666 -117.55148)
			(xy 12.462039 -117.528544) (xy 12.519932 -117.513031) (xy 12.579354 -117.505208) (xy 12.63929 -117.505208)
			(xy 12.698712 -117.513031) (xy 12.756605 -117.528544) (xy 12.811978 -117.55148) (xy 12.863884 -117.581447)
			(xy 12.911434 -117.617934) (xy 12.953814 -117.660314) (xy 12.990301 -117.707864) (xy 13.020268 -117.75977)
			(xy 13.043204 -117.815143) (xy 13.058717 -117.873036) (xy 13.06654 -117.932458) (xy 13.06703 -117.962426)
			(xy 13.06654 -117.992394) (xy 13.058717 -118.051816) (xy 13.043204 -118.109709) (xy 13.020268 -118.165082)
			(xy 12.990301 -118.216988) (xy 12.953814 -118.264538) (xy 12.911434 -118.306918) (xy 12.863884 -118.343405)
			(xy 12.811978 -118.373372) (xy 12.756605 -118.396308) (xy 12.698712 -118.411821) (xy 12.63929 -118.419644)
			(xy 12.579354 -118.419644) (xy 12.519932 -118.411821) (xy 12.462039 -118.396308) (xy 12.406666 -118.373372)
			(xy 12.35476 -118.343405) (xy 12.30721 -118.306918) (xy 12.26483 -118.264538) (xy 12.228343 -118.216988)
			(xy 12.198376 -118.165082) (xy 12.17544 -118.109709) (xy 12.159927 -118.051816) (xy 12.152104 -117.992394)
			(xy 11.024669 -117.992394) (xy 11.026717 -118.000036) (xy 11.03454 -118.059458) (xy 11.03503 -118.089426)
			(xy 11.03454 -118.119394) (xy 11.026717 -118.178816) (xy 11.011204 -118.236709) (xy 10.988268 -118.292082)
			(xy 10.958301 -118.343988) (xy 10.921814 -118.391538) (xy 10.879434 -118.433918) (xy 10.831884 -118.470405)
			(xy 10.779978 -118.500372) (xy 10.724605 -118.523308) (xy 10.666712 -118.538821) (xy 10.60729 -118.546644)
			(xy 10.547354 -118.546644) (xy 10.487932 -118.538821) (xy 10.430039 -118.523308) (xy 10.374666 -118.500372)
			(xy 10.32276 -118.470405) (xy 10.27521 -118.433918) (xy 10.23283 -118.391538) (xy 10.196343 -118.343988)
			(xy 10.166376 -118.292082) (xy 10.14344 -118.236709) (xy 10.127927 -118.178816) (xy 10.120104 -118.119394)
			(xy 8.678926 -118.119394) (xy 8.678926 -120.248426) (xy 10.195304 -120.248426) (xy 10.199375 -120.192804)
			(xy 10.211501 -120.138367) (xy 10.231424 -120.086276) (xy 10.25872 -120.037641) (xy 10.292806 -119.993498)
			(xy 10.332955 -119.954789) (xy 10.378313 -119.922338) (xy 10.427913 -119.896837) (xy 10.480697 -119.87883)
			(xy 10.53554 -119.8687) (xy 10.591274 -119.866663) (xy 10.646711 -119.872763) (xy 10.700668 -119.886869)
			(xy 10.751997 -119.908681) (xy 10.799603 -119.937735) (xy 10.842471 -119.97341) (xy 10.879688 -120.014947)
			(xy 10.910461 -120.06146) (xy 10.934133 -120.111957) (xy 10.935912 -120.11787) (xy 11.211304 -120.11787)
			(xy 11.215375 -120.062248) (xy 11.227501 -120.007811) (xy 11.247424 -119.95572) (xy 11.27472 -119.907085)
			(xy 11.308806 -119.862942) (xy 11.348955 -119.824233) (xy 11.394313 -119.791782) (xy 11.443913 -119.766281)
			(xy 11.496697 -119.748274) (xy 11.55154 -119.738144) (xy 11.607274 -119.736107) (xy 11.662711 -119.742207)
			(xy 11.716668 -119.756313) (xy 11.767997 -119.778125) (xy 11.815603 -119.807179) (xy 11.858471 -119.842854)
			(xy 11.895688 -119.884391) (xy 11.926461 -119.930904) (xy 11.950133 -119.981401) (xy 11.966201 -120.034808)
			(xy 11.974321 -120.089984) (xy 11.97483 -120.11787) (xy 13.243814 -120.11787) (xy 13.2443 -120.090619)
			(xy 13.252056 -120.036671) (xy 13.267411 -119.984376) (xy 13.290053 -119.934799) (xy 13.319519 -119.888949)
			(xy 13.35521 -119.847758) (xy 13.396401 -119.812067) (xy 13.442251 -119.782601) (xy 13.491828 -119.759959)
			(xy 13.544123 -119.744604) (xy 13.598071 -119.736848) (xy 13.652573 -119.736848) (xy 13.706521 -119.744604)
			(xy 13.758816 -119.759959) (xy 13.808393 -119.782601) (xy 13.854243 -119.812067) (xy 13.895434 -119.847758)
			(xy 13.931125 -119.888949) (xy 13.960591 -119.934799) (xy 13.983233 -119.984376) (xy 13.998588 -120.036671)
			(xy 14.006344 -120.090619) (xy 14.00683 -120.11787) (xy 14.006355 -120.144929) (xy 14.005143 -120.15343)
			(xy 14.406878 -120.15343) (xy 14.410949 -120.097808) (xy 14.423075 -120.043371) (xy 14.442998 -119.99128)
			(xy 14.470294 -119.942645) (xy 14.50438 -119.898502) (xy 14.544529 -119.859793) (xy 14.589887 -119.827342)
			(xy 14.639487 -119.801841) (xy 14.692271 -119.783834) (xy 14.747114 -119.773704) (xy 14.802848 -119.771667)
			(xy 14.858285 -119.777767) (xy 14.912242 -119.791873) (xy 14.963571 -119.813685) (xy 15.011177 -119.842739)
			(xy 15.054045 -119.878414) (xy 15.091262 -119.919951) (xy 15.122035 -119.966464) (xy 15.145707 -120.016961)
			(xy 15.161775 -120.070368) (xy 15.169895 -120.125544) (xy 15.170404 -120.15343) (xy 15.169895 -120.181316)
			(xy 15.161775 -120.236492) (xy 15.145707 -120.289899) (xy 15.122035 -120.340396) (xy 15.091262 -120.386909)
			(xy 15.054045 -120.428446) (xy 15.011177 -120.464121) (xy 14.963571 -120.493175) (xy 14.912242 -120.514987)
			(xy 14.858285 -120.529093) (xy 14.802848 -120.535193) (xy 14.747114 -120.533156) (xy 14.692271 -120.523026)
			(xy 14.639487 -120.505019) (xy 14.589887 -120.479518) (xy 14.544529 -120.447067) (xy 14.50438 -120.408358)
			(xy 14.470294 -120.364215) (xy 14.442998 -120.31558) (xy 14.423075 -120.263489) (xy 14.410949 -120.209052)
			(xy 14.406878 -120.15343) (xy 14.005143 -120.15343) (xy 13.998716 -120.198505) (xy 13.983586 -120.250465)
			(xy 13.96127 -120.299767) (xy 13.94714 -120.322848) (xy 13.939774 -120.334278) (xy 13.938504 -120.361202)
			(xy 13.990574 -120.46331) (xy 14.012672 -120.477788) (xy 14.026388 -120.478804) (xy 14.055025 -120.481216)
			(xy 14.111156 -120.493534) (xy 14.164805 -120.514131) (xy 14.21476 -120.542538) (xy 14.25989 -120.578115)
			(xy 14.299175 -120.620057) (xy 14.331727 -120.667416) (xy 14.356809 -120.71912) (xy 14.373856 -120.774001)
			(xy 14.38248 -120.830817) (xy 14.383004 -120.85955) (xy 14.383004 -120.859804) (xy 14.382547 -120.886099)
			(xy 14.375301 -120.938188) (xy 14.360975 -120.988789) (xy 14.339839 -121.036945) (xy 14.312294 -121.081745)
			(xy 14.278861 -121.12234) (xy 14.259814 -121.140474) (xy 14.252424 -121.148005) (xy 14.243892 -121.167278)
			(xy 14.243304 -121.177812) (xy 14.243304 -121.252488) (xy 14.243825 -121.263039) (xy 14.252366 -121.282334)
			(xy 14.259814 -121.289826) (xy 14.278894 -121.30793) (xy 14.312348 -121.348518) (xy 14.339904 -121.393319)
			(xy 14.361038 -121.441484) (xy 14.375351 -121.492097) (xy 14.379949 -121.525284) (xy 17.351756 -121.525284)
			(xy 17.352234 -121.49795) (xy 17.360039 -121.443843) (xy 17.375486 -121.391404) (xy 17.398259 -121.341706)
			(xy 17.427892 -121.295767) (xy 17.445482 -121.27484) (xy 17.44599 -121.274332) (xy 17.451568 -121.26724)
			(xy 17.45782 -121.250327) (xy 17.458182 -121.241312) (xy 17.458182 -121.174256) (xy 17.457802 -121.165241)
			(xy 17.451571 -121.148324) (xy 17.44599 -121.141236) (xy 17.445482 -121.140728) (xy 17.427886 -121.119805)
			(xy 17.398249 -121.073867) (xy 17.375474 -121.024168) (xy 17.360027 -120.971727) (xy 17.352224 -120.917618)
			(xy 17.351756 -120.890284) (xy 17.352242 -120.863033) (xy 17.359998 -120.809085) (xy 17.375353 -120.75679)
			(xy 17.397995 -120.707213) (xy 17.427461 -120.661363) (xy 17.463152 -120.620172) (xy 17.504343 -120.584481)
			(xy 17.550193 -120.555015) (xy 17.59977 -120.532373) (xy 17.652065 -120.517018) (xy 17.706013 -120.509262)
			(xy 17.760515 -120.509262) (xy 17.814463 -120.517018) (xy 17.866758 -120.532373) (xy 17.916335 -120.555015)
			(xy 17.962185 -120.584481) (xy 18.003376 -120.620172) (xy 18.039067 -120.661363) (xy 18.068533 -120.707213)
			(xy 18.091175 -120.75679) (xy 18.10653 -120.809085) (xy 18.114286 -120.863033) (xy 18.114772 -120.890284)
			(xy 18.114327 -120.917619) (xy 18.106513 -120.971727) (xy 18.091058 -121.024167) (xy 18.068278 -121.073864)
			(xy 18.038638 -121.119802) (xy 18.021046 -121.140728) (xy 18.020538 -121.141236) (xy 18.014965 -121.148331)
			(xy 18.008712 -121.165242) (xy 18.008346 -121.174256) (xy 18.008346 -121.241312) (xy 18.008687 -121.250331)
			(xy 18.014944 -121.267248) (xy 18.020538 -121.274332) (xy 18.021046 -121.27484) (xy 18.038631 -121.295772)
			(xy 18.068269 -121.341708) (xy 18.091046 -121.391404) (xy 18.106496 -121.443843) (xy 18.114302 -121.49795)
			(xy 18.114772 -121.525284) (xy 18.114502 -121.54221) (xy 18.111321 -121.575916) (xy 18.108422 -121.592594)
			(xy 18.10766 -121.597166) (xy 18.10766 -121.597928) (xy 18.105628 -121.609612) (xy 18.108676 -121.620788)
			(xy 18.111724 -121.632218) (xy 18.173192 -121.70156) (xy 18.178018 -121.706386) (xy 18.181289 -121.709133)
			(xy 18.188568 -121.713599) (xy 18.192496 -121.715276) (xy 18.203164 -121.71934) (xy 18.215102 -121.718578)
			(xy 18.215356 -121.718578) (xy 18.243804 -121.717562) (xy 18.271175 -121.718011) (xy 18.325355 -121.72583)
			(xy 18.377859 -121.741323) (xy 18.427606 -121.764169) (xy 18.473571 -121.793898) (xy 18.494502 -121.811542)
			(xy 18.494756 -121.811796) (xy 18.501851 -121.81737) (xy 18.518761 -121.823624) (xy 18.527776 -121.823988)
			(xy 18.594832 -121.823988) (xy 18.603851 -121.823649) (xy 18.620768 -121.817389) (xy 18.627852 -121.811796)
			(xy 18.62836 -121.811288) (xy 18.649288 -121.793699) (xy 18.695225 -121.764061) (xy 18.744922 -121.741284)
			(xy 18.797362 -121.725835) (xy 18.85147 -121.718031) (xy 18.878804 -121.717562) (xy 18.906053 -121.718108)
			(xy 18.959996 -121.725865) (xy 19.012286 -121.741219) (xy 19.061859 -121.763859) (xy 19.107705 -121.793323)
			(xy 19.148891 -121.829011) (xy 19.18458 -121.870198) (xy 19.214043 -121.916045) (xy 19.236682 -121.965618)
			(xy 19.252036 -122.017908) (xy 19.259792 -122.071851) (xy 19.259792 -122.126349) (xy 19.252036 -122.180292)
			(xy 19.236682 -122.232582) (xy 19.214043 -122.282155) (xy 19.18458 -122.328002) (xy 19.148891 -122.369189)
			(xy 19.107705 -122.404877) (xy 19.061859 -122.434341) (xy 19.012286 -122.456981) (xy 18.959996 -122.472335)
			(xy 18.906053 -122.480092) (xy 18.878804 -122.480578) (xy 18.851434 -122.480115) (xy 18.797254 -122.472297)
			(xy 18.744751 -122.456808) (xy 18.695004 -122.433965) (xy 18.649037 -122.40424) (xy 18.628106 -122.386598)
			(xy 18.627852 -122.386344) (xy 18.62076 -122.380766) (xy 18.603847 -122.374516) (xy 18.594832 -122.374152)
			(xy 18.527776 -122.374152) (xy 18.518757 -122.374486) (xy 18.501839 -122.380748) (xy 18.494756 -122.386344)
			(xy 18.494248 -122.386852) (xy 18.473309 -122.404428) (xy 18.427376 -122.43407) (xy 18.377682 -122.456851)
			(xy 18.325244 -122.472302) (xy 18.271137 -122.480108) (xy 18.243804 -122.480578) (xy 18.21655 -122.480141)
			(xy 18.162596 -122.472384) (xy 18.110296 -122.457027) (xy 18.060714 -122.434382) (xy 18.01486 -122.404912)
			(xy 17.973666 -122.369215) (xy 17.937972 -122.32802) (xy 17.908505 -122.282163) (xy 17.885864 -122.232579)
			(xy 17.870511 -122.180278) (xy 17.862757 -122.126324) (xy 17.862296 -122.09907) (xy 17.862572 -122.082144)
			(xy 17.865749 -122.048439) (xy 17.868646 -122.03176) (xy 17.869408 -122.027188) (xy 17.869408 -122.026426)
			(xy 17.87144 -122.014742) (xy 17.868392 -122.003566) (xy 17.865344 -121.992136) (xy 17.803876 -121.922794)
			(xy 17.79905 -121.917968) (xy 17.795779 -121.915221) (xy 17.7885 -121.910755) (xy 17.784572 -121.909078)
			(xy 17.773904 -121.905014) (xy 17.761966 -121.905776) (xy 17.761712 -121.905776) (xy 17.733264 -121.906792)
			(xy 17.706011 -121.906356) (xy 17.652061 -121.898594) (xy 17.599764 -121.883233) (xy 17.550186 -121.860587)
			(xy 17.504335 -121.831115) (xy 17.463145 -121.795419) (xy 17.427454 -121.754224) (xy 17.397988 -121.708369)
			(xy 17.375349 -121.658787) (xy 17.359995 -121.606488) (xy 17.352241 -121.552537) (xy 17.351756 -121.525284)
			(xy 14.379949 -121.525284) (xy 14.382569 -121.544197) (xy 14.383004 -121.570496) (xy 14.383004 -121.57075)
			(xy 14.382518 -121.598001) (xy 14.374762 -121.651949) (xy 14.359407 -121.704244) (xy 14.336765 -121.753821)
			(xy 14.307299 -121.799671) (xy 14.271608 -121.840862) (xy 14.230417 -121.876553) (xy 14.184567 -121.906019)
			(xy 14.13499 -121.928661) (xy 14.082695 -121.944016) (xy 14.028747 -121.951772) (xy 13.974245 -121.951772)
			(xy 13.920297 -121.944016) (xy 13.868002 -121.928661) (xy 13.818425 -121.906019) (xy 13.772575 -121.876553)
			(xy 13.731384 -121.840862) (xy 13.695693 -121.799671) (xy 13.666227 -121.753821) (xy 13.643585 -121.704244)
			(xy 13.62823 -121.651949) (xy 13.620474 -121.598001) (xy 13.619988 -121.57075) (xy 13.619988 -121.570496)
			(xy 13.620448 -121.544201) (xy 13.627694 -121.492113) (xy 13.64202 -121.441512) (xy 13.663155 -121.393356)
			(xy 13.690699 -121.348556) (xy 13.724132 -121.307961) (xy 13.743178 -121.289826) (xy 13.750567 -121.282294)
			(xy 13.759099 -121.263022) (xy 13.759688 -121.252488) (xy 13.759688 -121.177812) (xy 13.759169 -121.167261)
			(xy 13.750627 -121.147966) (xy 13.743178 -121.140474) (xy 13.724096 -121.122372) (xy 13.690643 -121.081783)
			(xy 13.663088 -121.036981) (xy 13.641953 -120.988816) (xy 13.627641 -120.938203) (xy 13.620423 -120.886103)
			(xy 13.619988 -120.859804) (xy 13.619988 -120.85955) (xy 13.62047 -120.832491) (xy 13.628106 -120.778916)
			(xy 13.643234 -120.726956) (xy 13.665548 -120.677653) (xy 13.679678 -120.654572) (xy 13.687044 -120.643142)
			(xy 13.688314 -120.616218) (xy 13.636244 -120.51411) (xy 13.614146 -120.499632) (xy 13.60043 -120.498616)
			(xy 13.571797 -120.496169) (xy 13.515668 -120.483854) (xy 13.46202 -120.463262) (xy 13.412067 -120.434858)
			(xy 13.366937 -120.399285) (xy 13.327652 -120.357347) (xy 13.295099 -120.309992) (xy 13.270015 -120.258292)
			(xy 13.252966 -120.203415) (xy 13.244339 -120.146602) (xy 13.243814 -120.11787) (xy 11.97483 -120.11787)
			(xy 11.974321 -120.145756) (xy 11.966201 -120.200932) (xy 11.950133 -120.254339) (xy 11.926461 -120.304836)
			(xy 11.895688 -120.351349) (xy 11.858471 -120.392886) (xy 11.815603 -120.428561) (xy 11.767997 -120.457615)
			(xy 11.716668 -120.479427) (xy 11.662711 -120.493533) (xy 11.607274 -120.499633) (xy 11.55154 -120.497596)
			(xy 11.496697 -120.487466) (xy 11.443913 -120.469459) (xy 11.394313 -120.443958) (xy 11.348955 -120.411507)
			(xy 11.308806 -120.372798) (xy 11.27472 -120.328655) (xy 11.247424 -120.28002) (xy 11.227501 -120.227929)
			(xy 11.215375 -120.173492) (xy 11.211304 -120.11787) (xy 10.935912 -120.11787) (xy 10.950201 -120.165364)
			(xy 10.958321 -120.22054) (xy 10.95883 -120.248426) (xy 10.958321 -120.276312) (xy 10.950201 -120.331488)
			(xy 10.934133 -120.384895) (xy 10.910461 -120.435392) (xy 10.879688 -120.481905) (xy 10.842471 -120.523442)
			(xy 10.799603 -120.559117) (xy 10.751997 -120.588171) (xy 10.700668 -120.609983) (xy 10.646711 -120.624089)
			(xy 10.591274 -120.630189) (xy 10.53554 -120.628152) (xy 10.480697 -120.618022) (xy 10.427913 -120.600015)
			(xy 10.378313 -120.574514) (xy 10.332955 -120.542063) (xy 10.292806 -120.503354) (xy 10.25872 -120.459211)
			(xy 10.231424 -120.410576) (xy 10.211501 -120.358485) (xy 10.199375 -120.304048) (xy 10.195304 -120.248426)
			(xy 8.678926 -120.248426) (xy 8.678926 -121.263918) (xy 8.679328 -121.273148) (xy 8.685879 -121.290406)
			(xy 8.698123 -121.304221) (xy 8.706104 -121.308876) (xy 8.798306 -121.35739) (xy 8.8265 -121.355612)
			(xy 8.838184 -121.347484) (xy 8.862205 -121.331555) (xy 8.914028 -121.30633) (xy 8.969052 -121.289175)
			(xy 9.026028 -121.28048) (xy 9.054846 -121.27992) (xy 9.0551 -121.27992) (xy 9.082351 -121.280406)
			(xy 9.136299 -121.288162) (xy 9.188594 -121.303518) (xy 9.238172 -121.326159) (xy 9.284023 -121.355625)
			(xy 9.325213 -121.391317) (xy 9.360905 -121.432507) (xy 9.390371 -121.478358) (xy 9.413012 -121.527936)
			(xy 9.428368 -121.580231) (xy 9.436124 -121.634179) (xy 9.436124 -121.688681) (xy 9.428368 -121.742629)
			(xy 9.413012 -121.794924) (xy 9.390371 -121.844502) (xy 9.360905 -121.890353) (xy 9.325213 -121.931543)
			(xy 9.284023 -121.967235) (xy 9.238172 -121.996701) (xy 9.188594 -122.019342) (xy 9.136299 -122.034698)
			(xy 9.082351 -122.042454) (xy 9.0551 -122.042936) (xy 9.054846 -122.042936) (xy 9.026023 -122.042417)
			(xy 8.969034 -122.033751) (xy 8.914001 -122.016596) (xy 8.862183 -121.991342) (xy 8.838184 -121.975372)
			(xy 8.8265 -121.967244) (xy 8.798306 -121.965466) (xy 8.706104 -122.01398) (xy 8.698121 -122.01863)
			(xy 8.685885 -122.032451) (xy 8.679332 -122.049709) (xy 8.678926 -122.058938) (xy 8.678926 -122.292618)
			(xy 9.780268 -122.292618) (xy 9.784339 -122.236996) (xy 9.796465 -122.182559) (xy 9.816388 -122.130468)
			(xy 9.843684 -122.081833) (xy 9.87777 -122.03769) (xy 9.917919 -121.998981) (xy 9.963277 -121.96653)
			(xy 10.012877 -121.941029) (xy 10.065661 -121.923022) (xy 10.120504 -121.912892) (xy 10.176238 -121.910855)
			(xy 10.231675 -121.916955) (xy 10.285632 -121.931061) (xy 10.336961 -121.952873) (xy 10.384567 -121.981927)
			(xy 10.427435 -122.017602) (xy 10.464652 -122.059139) (xy 10.495425 -122.105652) (xy 10.519097 -122.156149)
			(xy 10.535165 -122.209556) (xy 10.543285 -122.264732) (xy 10.543794 -122.292618) (xy 10.543285 -122.320504)
			(xy 10.535165 -122.37568) (xy 10.519097 -122.429087) (xy 10.495425 -122.479584) (xy 10.481998 -122.499878)
			(xy 10.861784 -122.499878) (xy 10.861784 -122.439942) (xy 10.869607 -122.38052) (xy 10.88512 -122.322627)
			(xy 10.908056 -122.267254) (xy 10.938023 -122.215348) (xy 10.97451 -122.167798) (xy 11.01689 -122.125418)
			(xy 11.06444 -122.088931) (xy 11.116346 -122.058964) (xy 11.171719 -122.036028) (xy 11.229612 -122.020515)
			(xy 11.289034 -122.012692) (xy 11.34897 -122.012692) (xy 11.408392 -122.020515) (xy 11.466285 -122.036028)
			(xy 11.521658 -122.058964) (xy 11.573564 -122.088931) (xy 11.621114 -122.125418) (xy 11.663494 -122.167798)
			(xy 11.699981 -122.215348) (xy 11.729948 -122.267254) (xy 11.752884 -122.322627) (xy 11.768397 -122.38052)
			(xy 11.77622 -122.439942) (xy 11.77671 -122.46991) (xy 11.77622 -122.499878) (xy 11.768397 -122.5593)
			(xy 11.752884 -122.617193) (xy 11.729948 -122.672566) (xy 11.699981 -122.724472) (xy 11.663494 -122.772022)
			(xy 11.621114 -122.814402) (xy 11.573564 -122.850889) (xy 11.521658 -122.880856) (xy 11.466285 -122.903792)
			(xy 11.408392 -122.919305) (xy 11.34897 -122.927128) (xy 11.289034 -122.927128) (xy 11.229612 -122.919305)
			(xy 11.171719 -122.903792) (xy 11.116346 -122.880856) (xy 11.06444 -122.850889) (xy 11.01689 -122.814402)
			(xy 10.97451 -122.772022) (xy 10.938023 -122.724472) (xy 10.908056 -122.672566) (xy 10.88512 -122.617193)
			(xy 10.869607 -122.5593) (xy 10.861784 -122.499878) (xy 10.481998 -122.499878) (xy 10.464652 -122.526097)
			(xy 10.427435 -122.567634) (xy 10.384567 -122.603309) (xy 10.336961 -122.632363) (xy 10.285632 -122.654175)
			(xy 10.231675 -122.668281) (xy 10.176238 -122.674381) (xy 10.120504 -122.672344) (xy 10.065661 -122.662214)
			(xy 10.012877 -122.644207) (xy 9.963277 -122.618706) (xy 9.917919 -122.586255) (xy 9.87777 -122.547546)
			(xy 9.843684 -122.503403) (xy 9.816388 -122.454768) (xy 9.796465 -122.402677) (xy 9.784339 -122.34824)
			(xy 9.780268 -122.292618) (xy 8.678926 -122.292618) (xy 8.678926 -122.533918) (xy 8.679328 -122.543148)
			(xy 8.685879 -122.560406) (xy 8.698123 -122.574221) (xy 8.706104 -122.578876) (xy 8.798306 -122.62739)
			(xy 8.8265 -122.625612) (xy 8.838184 -122.617484) (xy 8.862205 -122.601555) (xy 8.914028 -122.57633)
			(xy 8.969052 -122.559175) (xy 9.026028 -122.55048) (xy 9.054846 -122.54992) (xy 9.0551 -122.54992)
			(xy 9.082351 -122.550406) (xy 9.136299 -122.558162) (xy 9.188594 -122.573518) (xy 9.238172 -122.596159)
			(xy 9.284023 -122.625625) (xy 9.325213 -122.661317) (xy 9.360905 -122.702507) (xy 9.390371 -122.748358)
			(xy 9.413012 -122.797936) (xy 9.428368 -122.850231) (xy 9.436124 -122.904179) (xy 9.436124 -122.958681)
			(xy 9.428368 -123.012629) (xy 9.413012 -123.064924) (xy 9.390371 -123.114502) (xy 9.360905 -123.160353)
			(xy 9.325213 -123.201543) (xy 9.301014 -123.222512) (xy 11.909552 -123.222512) (xy 11.910089 -123.195263)
			(xy 11.917843 -123.141319) (xy 11.933195 -123.089028) (xy 11.955832 -123.039453) (xy 11.985293 -122.993605)
			(xy 12.020979 -122.952416) (xy 12.062163 -122.916724) (xy 12.108008 -122.887256) (xy 12.157579 -122.864613)
			(xy 12.209868 -122.849254) (xy 12.263811 -122.841493) (xy 12.29106 -122.841004) (xy 12.317814 -122.841465)
			(xy 12.370788 -122.849005) (xy 12.422189 -122.863874) (xy 12.471008 -122.885779) (xy 12.516287 -122.91429)
			(xy 12.557139 -122.948848) (xy 12.575286 -122.968512) (xy 12.576302 -122.969528) (xy 12.577572 -122.970798)
			(xy 12.578334 -122.97156) (xy 12.585847 -122.978973) (xy 12.605133 -122.987492) (xy 12.615672 -122.98807)
			(xy 12.61618 -122.98807) (xy 12.691618 -122.988324) (xy 12.702486 -122.987878) (xy 12.722352 -122.979068)
			(xy 12.729972 -122.971306) (xy 12.748153 -122.951603) (xy 12.78905 -122.916937) (xy 12.834401 -122.888346)
			(xy 12.883312 -122.866393) (xy 12.934818 -122.851514) (xy 12.9879 -122.844) (xy 13.014706 -122.843544)
			(xy 13.042077 -122.843996) (xy 13.096257 -122.851815) (xy 13.148761 -122.867307) (xy 13.198507 -122.890152)
			(xy 13.244473 -122.919881) (xy 13.265404 -122.937524) (xy 13.265658 -122.937778) (xy 13.272746 -122.943362)
			(xy 13.289662 -122.949608) (xy 13.298678 -122.94997) (xy 13.365734 -122.94997) (xy 13.374753 -122.949636)
			(xy 13.39167 -122.943373) (xy 13.398754 -122.937778) (xy 13.399262 -122.93727) (xy 13.420208 -122.919673)
			(xy 13.466172 -122.890006) (xy 13.515904 -122.867214) (xy 13.568382 -122.851763) (xy 13.622531 -122.843971)
			(xy 13.677236 -122.843997) (xy 13.731377 -122.851842) (xy 13.783841 -122.867343) (xy 13.83355 -122.890184)
			(xy 13.879486 -122.919894) (xy 13.900404 -122.937524) (xy 13.900658 -122.937778) (xy 13.907746 -122.943362)
			(xy 13.924662 -122.949608) (xy 13.933678 -122.94997) (xy 14.000734 -122.94997) (xy 14.009753 -122.949636)
			(xy 14.02667 -122.943373) (xy 14.033754 -122.937778) (xy 14.034262 -122.93727) (xy 14.047858 -122.925681)
			(xy 14.076861 -122.904817) (xy 14.092174 -122.895614) (xy 14.099474 -122.889717) (xy 14.109643 -122.873966)
			(xy 14.111986 -122.86488) (xy 14.129766 -122.78233) (xy 14.125702 -122.761756) (xy 14.119606 -122.75312)
			(xy 14.103613 -122.729052) (xy 14.078269 -122.677122) (xy 14.061041 -122.621965) (xy 14.052324 -122.564842)
			(xy 14.051788 -122.53595) (xy 14.052274 -122.508699) (xy 14.06003 -122.454751) (xy 14.075385 -122.402456)
			(xy 14.098027 -122.352879) (xy 14.127493 -122.307029) (xy 14.163184 -122.265838) (xy 14.204375 -122.230147)
			(xy 14.250225 -122.200681) (xy 14.299802 -122.178039) (xy 14.352097 -122.162684) (xy 14.406045 -122.154928)
			(xy 14.460547 -122.154928) (xy 14.514495 -122.162684) (xy 14.56679 -122.178039) (xy 14.616367 -122.200681)
			(xy 14.662217 -122.230147) (xy 14.703408 -122.265838) (xy 14.739099 -122.307029) (xy 14.768565 -122.352879)
			(xy 14.791207 -122.402456) (xy 14.806562 -122.454751) (xy 14.814318 -122.508699) (xy 14.814804 -122.53595)
			(xy 14.814253 -122.564342) (xy 14.805829 -122.620499) (xy 14.789188 -122.674791) (xy 14.764697 -122.726024)
			(xy 14.732895 -122.773068) (xy 14.694483 -122.81489) (xy 14.650305 -122.850567) (xy 14.626082 -122.865388)
			(xy 14.618699 -122.871243) (xy 14.608408 -122.887008) (xy 14.606016 -122.896122) (xy 14.588236 -122.978672)
			(xy 14.5923 -122.999246) (xy 14.598396 -123.007882) (xy 14.61439 -123.03195) (xy 14.639734 -123.08388)
			(xy 14.643843 -123.097036) (xy 16.476726 -123.097036) (xy 16.477183 -123.069702) (xy 16.484994 -123.015594)
			(xy 16.500446 -122.963155) (xy 16.523224 -122.913457) (xy 16.552861 -122.867519) (xy 16.570452 -122.846592)
			(xy 16.570706 -122.846338) (xy 16.57096 -122.846084) (xy 16.576567 -122.839011) (xy 16.5828 -122.822084)
			(xy 16.583152 -122.813064) (xy 16.583152 -122.746008) (xy 16.582801 -122.73699) (xy 16.57655 -122.720073)
			(xy 16.57096 -122.712988) (xy 16.570706 -122.712734) (xy 16.570452 -122.71248) (xy 16.552829 -122.691579)
			(xy 16.523197 -122.645634) (xy 16.500427 -122.59593) (xy 16.484986 -122.543485) (xy 16.477191 -122.489372)
			(xy 16.476726 -122.462036) (xy 16.477212 -122.434785) (xy 16.484968 -122.380837) (xy 16.500323 -122.328542)
			(xy 16.522965 -122.278965) (xy 16.552431 -122.233115) (xy 16.588122 -122.191924) (xy 16.629313 -122.156233)
			(xy 16.675163 -122.126767) (xy 16.72474 -122.104125) (xy 16.777035 -122.08877) (xy 16.830983 -122.081014)
			(xy 16.885485 -122.081014) (xy 16.939433 -122.08877) (xy 16.991728 -122.104125) (xy 17.041305 -122.126767)
			(xy 17.087155 -122.156233) (xy 17.128346 -122.191924) (xy 17.164037 -122.233115) (xy 17.193503 -122.278965)
			(xy 17.216145 -122.328542) (xy 17.2315 -122.380837) (xy 17.239256 -122.434785) (xy 17.239742 -122.462036)
			(xy 17.239276 -122.48937) (xy 17.231469 -122.543478) (xy 17.216019 -122.595917) (xy 17.193243 -122.645615)
			(xy 17.163607 -122.691553) (xy 17.146016 -122.71248) (xy 17.145762 -122.712734) (xy 17.145508 -122.712988)
			(xy 17.139921 -122.720074) (xy 17.133674 -122.736991) (xy 17.133316 -122.746008) (xy 17.133316 -122.813064)
			(xy 17.133687 -122.82208) (xy 17.136919 -122.830844) (xy 19.438874 -122.830844) (xy 19.439324 -122.803509)
			(xy 19.447135 -122.749401) (xy 19.462588 -122.696961) (xy 19.485368 -122.647264) (xy 19.515007 -122.601326)
			(xy 19.5326 -122.5804) (xy 19.533108 -122.579892) (xy 19.538705 -122.572813) (xy 19.544945 -122.55589)
			(xy 19.5453 -122.546872) (xy 19.5453 -122.479816) (xy 19.544935 -122.4708) (xy 19.538693 -122.453883)
			(xy 19.533108 -122.446796) (xy 19.5326 -122.446288) (xy 19.515003 -122.425363) (xy 19.48535 -122.37943)
			(xy 19.462561 -122.329734) (xy 19.447104 -122.277292) (xy 19.439295 -122.223179) (xy 19.439294 -122.168507)
			(xy 19.447103 -122.114394) (xy 19.462559 -122.061952) (xy 19.485347 -122.012255) (xy 19.515 -121.966322)
			(xy 19.5326 -121.9454) (xy 19.533108 -121.944892) (xy 19.538705 -121.937813) (xy 19.544945 -121.92089)
			(xy 19.5453 -121.911872) (xy 19.5453 -121.844816) (xy 19.544935 -121.8358) (xy 19.538693 -121.818883)
			(xy 19.533108 -121.811796) (xy 19.5326 -121.811288) (xy 19.515003 -121.790363) (xy 19.48535 -121.74443)
			(xy 19.462561 -121.694734) (xy 19.447104 -121.642292) (xy 19.439295 -121.588179) (xy 19.439294 -121.533507)
			(xy 19.447103 -121.479394) (xy 19.462559 -121.426952) (xy 19.485347 -121.377255) (xy 19.515 -121.331322)
			(xy 19.5326 -121.3104) (xy 19.533108 -121.309892) (xy 19.538705 -121.302813) (xy 19.544945 -121.28589)
			(xy 19.5453 -121.276872) (xy 19.5453 -121.209816) (xy 19.544935 -121.2008) (xy 19.538693 -121.183883)
			(xy 19.533108 -121.176796) (xy 19.5326 -121.176288) (xy 19.514988 -121.155378) (xy 19.485353 -121.109436)
			(xy 19.46258 -121.059735) (xy 19.447137 -121.007291) (xy 19.439339 -120.953179) (xy 19.438874 -120.925844)
			(xy 19.43936 -120.898593) (xy 19.447116 -120.844645) (xy 19.462471 -120.79235) (xy 19.485113 -120.742773)
			(xy 19.514579 -120.696923) (xy 19.55027 -120.655732) (xy 19.591461 -120.620041) (xy 19.637311 -120.590575)
			(xy 19.686888 -120.567933) (xy 19.739183 -120.552578) (xy 19.793131 -120.544822) (xy 19.847633 -120.544822)
			(xy 19.901581 -120.552578) (xy 19.953876 -120.567933) (xy 20.003453 -120.590575) (xy 20.049303 -120.620041)
			(xy 20.090494 -120.655732) (xy 20.126185 -120.696923) (xy 20.155651 -120.742773) (xy 20.178293 -120.79235)
			(xy 20.193648 -120.844645) (xy 20.201404 -120.898593) (xy 20.20189 -120.925844) (xy 20.201417 -120.953178)
			(xy 20.19361 -121.007285) (xy 20.178161 -121.059724) (xy 20.155387 -121.109421) (xy 20.125753 -121.15536)
			(xy 20.108164 -121.176288) (xy 20.107656 -121.176796) (xy 20.10206 -121.183876) (xy 20.09582 -121.200798)
			(xy 20.095464 -121.209816) (xy 20.095464 -121.276872) (xy 20.095842 -121.285887) (xy 20.102076 -121.302803)
			(xy 20.107656 -121.309892) (xy 20.108164 -121.3104) (xy 20.125768 -121.331319) (xy 20.155421 -121.377253)
			(xy 20.178209 -121.42695) (xy 20.193666 -121.479393) (xy 20.201474 -121.533506) (xy 20.201473 -121.58818)
			(xy 20.193664 -121.642292) (xy 20.178207 -121.694735) (xy 20.155418 -121.744433) (xy 20.125765 -121.790366)
			(xy 20.108164 -121.811288) (xy 20.107656 -121.811796) (xy 20.10206 -121.818876) (xy 20.09582 -121.835798)
			(xy 20.095464 -121.844816) (xy 20.095464 -121.911872) (xy 20.095842 -121.920887) (xy 20.102076 -121.937803)
			(xy 20.107656 -121.944892) (xy 20.108164 -121.9454) (xy 20.125768 -121.966319) (xy 20.155421 -122.012253)
			(xy 20.178209 -122.06195) (xy 20.193666 -122.114393) (xy 20.201474 -122.168506) (xy 20.201473 -122.22318)
			(xy 20.193664 -122.277292) (xy 20.178207 -122.329735) (xy 20.155418 -122.379433) (xy 20.125765 -122.425366)
			(xy 20.108164 -122.446288) (xy 20.107656 -122.446796) (xy 20.10206 -122.453876) (xy 20.09582 -122.470798)
			(xy 20.095464 -122.479816) (xy 20.095464 -122.546872) (xy 20.095842 -122.555887) (xy 20.102076 -122.572803)
			(xy 20.107656 -122.579892) (xy 20.108164 -122.5804) (xy 20.125764 -122.60132) (xy 20.155403 -122.647258)
			(xy 20.178178 -122.696957) (xy 20.193624 -122.749399) (xy 20.201424 -122.803509) (xy 20.20189 -122.830844)
			(xy 20.201404 -122.858095) (xy 20.193648 -122.912043) (xy 20.178293 -122.964338) (xy 20.155651 -123.013915)
			(xy 20.126185 -123.059765) (xy 20.090494 -123.100956) (xy 20.049303 -123.136647) (xy 20.003453 -123.166113)
			(xy 19.953876 -123.188755) (xy 19.901581 -123.20411) (xy 19.847633 -123.211866) (xy 19.793131 -123.211866)
			(xy 19.739183 -123.20411) (xy 19.686888 -123.188755) (xy 19.637311 -123.166113) (xy 19.591461 -123.136647)
			(xy 19.55027 -123.100956) (xy 19.514579 -123.059765) (xy 19.485113 -123.013915) (xy 19.462471 -122.964338)
			(xy 19.447116 -122.912043) (xy 19.43936 -122.858095) (xy 19.438874 -122.830844) (xy 17.136919 -122.830844)
			(xy 17.139925 -122.838997) (xy 17.145508 -122.846084) (xy 17.145762 -122.846338) (xy 17.146016 -122.846592)
			(xy 17.163621 -122.867508) (xy 17.193257 -122.913448) (xy 17.21603 -122.963148) (xy 17.231475 -123.015591)
			(xy 17.239275 -123.069701) (xy 17.239742 -123.097036) (xy 17.239256 -123.124287) (xy 17.2315 -123.178235)
			(xy 17.216145 -123.23053) (xy 17.193503 -123.280107) (xy 17.164037 -123.325957) (xy 17.128346 -123.367148)
			(xy 17.087155 -123.402839) (xy 17.041305 -123.432305) (xy 16.991728 -123.454947) (xy 16.939433 -123.470302)
			(xy 16.885485 -123.478058) (xy 16.830983 -123.478058) (xy 16.777035 -123.470302) (xy 16.72474 -123.454947)
			(xy 16.675163 -123.432305) (xy 16.629313 -123.402839) (xy 16.588122 -123.367148) (xy 16.552431 -123.325957)
			(xy 16.522965 -123.280107) (xy 16.500323 -123.23053) (xy 16.484968 -123.178235) (xy 16.477212 -123.124287)
			(xy 16.476726 -123.097036) (xy 14.643843 -123.097036) (xy 14.656962 -123.139036) (xy 14.665678 -123.19616)
			(xy 14.666214 -123.225052) (xy 14.6657 -123.252303) (xy 14.65795 -123.306252) (xy 14.6426 -123.358549)
			(xy 14.619964 -123.408128) (xy 14.590501 -123.453981) (xy 14.554813 -123.495174) (xy 14.513625 -123.530869)
			(xy 14.467776 -123.560338) (xy 14.418199 -123.582981) (xy 14.365905 -123.598338) (xy 14.311957 -123.606096)
			(xy 14.284706 -123.60656) (xy 14.257335 -123.6061) (xy 14.203156 -123.598282) (xy 14.150652 -123.582792)
			(xy 14.100905 -123.559949) (xy 14.054939 -123.530222) (xy 14.034008 -123.51258) (xy 14.033754 -123.512326)
			(xy 14.026662 -123.506747) (xy 14.009749 -123.500498) (xy 14.000734 -123.500134) (xy 13.933678 -123.500134)
			(xy 13.924659 -123.500473) (xy 13.907742 -123.506732) (xy 13.900658 -123.512326) (xy 13.90015 -123.512834)
			(xy 13.879194 -123.53042) (xy 13.833232 -123.560086) (xy 13.783502 -123.582879) (xy 13.731025 -123.59833)
			(xy 13.676878 -123.606124) (xy 13.622173 -123.606099) (xy 13.568034 -123.598256) (xy 13.515571 -123.582756)
			(xy 13.465862 -123.559917) (xy 13.419927 -123.530209) (xy 13.399008 -123.51258) (xy 13.398754 -123.512326)
			(xy 13.391662 -123.506747) (xy 13.374749 -123.500498) (xy 13.365734 -123.500134) (xy 13.298678 -123.500134)
			(xy 13.289659 -123.500473) (xy 13.272742 -123.506732) (xy 13.265658 -123.512326) (xy 13.26515 -123.512834)
			(xy 13.244221 -123.530422) (xy 13.198284 -123.56006) (xy 13.148587 -123.582836) (xy 13.096148 -123.598285)
			(xy 13.04204 -123.60609) (xy 13.014706 -123.60656) (xy 12.987954 -123.606066) (xy 12.93498 -123.598534)
			(xy 12.88358 -123.583673) (xy 12.83476 -123.561774) (xy 12.78948 -123.533268) (xy 12.748628 -123.498714)
			(xy 12.73048 -123.479052) (xy 12.729464 -123.478036) (xy 12.728194 -123.476766) (xy 12.727432 -123.476004)
			(xy 12.7199 -123.468615) (xy 12.700628 -123.460083) (xy 12.690094 -123.459494) (xy 12.689586 -123.459494)
			(xy 12.614148 -123.45924) (xy 12.603279 -123.459678) (xy 12.583414 -123.468494) (xy 12.575794 -123.476258)
			(xy 12.557643 -123.495991) (xy 12.516739 -123.530651) (xy 12.471381 -123.559237) (xy 12.422464 -123.581184)
			(xy 12.370954 -123.596059) (xy 12.317867 -123.603567) (xy 12.29106 -123.60402) (xy 12.263808 -123.603559)
			(xy 12.20986 -123.595798) (xy 12.157566 -123.580438) (xy 12.107989 -123.557793) (xy 12.06214 -123.528324)
			(xy 12.02095 -123.49263) (xy 11.985259 -123.451438) (xy 11.955793 -123.405586) (xy 11.933152 -123.356008)
			(xy 11.917796 -123.303712) (xy 11.910039 -123.249764) (xy 11.909552 -123.222512) (xy 9.301014 -123.222512)
			(xy 9.284023 -123.237235) (xy 9.238172 -123.266701) (xy 9.188594 -123.289342) (xy 9.136299 -123.304698)
			(xy 9.082351 -123.312454) (xy 9.0551 -123.312936) (xy 9.054846 -123.312936) (xy 9.026023 -123.312417)
			(xy 8.969034 -123.303751) (xy 8.914001 -123.286596) (xy 8.862183 -123.261342) (xy 8.838184 -123.245372)
			(xy 8.8265 -123.237244) (xy 8.798306 -123.235466) (xy 8.706104 -123.28398) (xy 8.698121 -123.28863)
			(xy 8.685885 -123.302451) (xy 8.679332 -123.319709) (xy 8.678926 -123.328938) (xy 8.678926 -123.549918)
			(xy 8.679328 -123.559148) (xy 8.685879 -123.576406) (xy 8.698123 -123.590221) (xy 8.706104 -123.594876)
			(xy 8.798306 -123.64339) (xy 8.8265 -123.641612) (xy 8.838184 -123.633484) (xy 8.862205 -123.617555)
			(xy 8.914028 -123.59233) (xy 8.969052 -123.575175) (xy 9.026028 -123.56648) (xy 9.054846 -123.56592)
			(xy 9.0551 -123.56592) (xy 9.082351 -123.566406) (xy 9.136299 -123.574162) (xy 9.188594 -123.589518)
			(xy 9.238172 -123.612159) (xy 9.284023 -123.641625) (xy 9.325213 -123.677317) (xy 9.360905 -123.718507)
			(xy 9.390371 -123.764358) (xy 9.413012 -123.813936) (xy 9.428368 -123.866231) (xy 9.436124 -123.920179)
			(xy 9.436124 -123.974681) (xy 9.428368 -124.028629) (xy 9.413012 -124.080924) (xy 9.390371 -124.130502)
			(xy 9.360905 -124.176353) (xy 9.325213 -124.217543) (xy 9.284023 -124.253235) (xy 9.238172 -124.282701)
			(xy 9.188594 -124.305342) (xy 9.136299 -124.320698) (xy 9.082351 -124.328454) (xy 9.0551 -124.328936)
			(xy 9.054846 -124.328936) (xy 9.026023 -124.328417) (xy 8.969034 -124.319751) (xy 8.914001 -124.302596)
			(xy 8.862183 -124.277342) (xy 8.838184 -124.261372) (xy 8.8265 -124.253244) (xy 8.798306 -124.251466)
			(xy 8.706104 -124.29998) (xy 8.698121 -124.30463) (xy 8.685885 -124.318451) (xy 8.679332 -124.335709)
			(xy 8.678926 -124.344938) (xy 8.678926 -124.565918) (xy 8.679328 -124.575148) (xy 8.685879 -124.592406)
			(xy 8.698123 -124.606221) (xy 8.706104 -124.610876) (xy 8.798306 -124.65939) (xy 8.8265 -124.657612)
			(xy 8.838184 -124.649484) (xy 8.862205 -124.633555) (xy 8.914028 -124.60833) (xy 8.969052 -124.591175)
			(xy 9.026028 -124.58248) (xy 9.054846 -124.58192) (xy 9.0551 -124.58192) (xy 9.082351 -124.582406)
			(xy 9.136299 -124.590162) (xy 9.188594 -124.605518) (xy 9.238172 -124.628159) (xy 9.284023 -124.657625)
			(xy 9.325213 -124.693317) (xy 9.360905 -124.734507) (xy 9.390371 -124.780358) (xy 9.413012 -124.829936)
			(xy 9.428368 -124.882231) (xy 9.436124 -124.936179) (xy 9.436124 -124.990681) (xy 9.43113 -125.025416)
			(xy 10.70532 -125.025416) (xy 10.70532 -124.965448) (xy 10.713148 -124.905992) (xy 10.728669 -124.848067)
			(xy 10.751618 -124.792663) (xy 10.781602 -124.740729) (xy 10.818108 -124.693153) (xy 10.860513 -124.650748)
			(xy 10.908089 -124.614242) (xy 10.960023 -124.584258) (xy 11.015427 -124.561309) (xy 11.073352 -124.545788)
			(xy 11.132808 -124.53796) (xy 11.192776 -124.53796) (xy 11.252232 -124.545788) (xy 11.310157 -124.561309)
			(xy 11.365561 -124.584258) (xy 11.417495 -124.614242) (xy 11.465071 -124.650748) (xy 11.507476 -124.693153)
			(xy 11.543982 -124.740729) (xy 11.573966 -124.792663) (xy 11.596915 -124.848067) (xy 11.612436 -124.905992)
			(xy 11.620264 -124.965448) (xy 11.620754 -124.995432) (xy 11.620264 -125.025416) (xy 11.612436 -125.084872)
			(xy 11.596915 -125.142797) (xy 11.573966 -125.198201) (xy 11.543982 -125.250135) (xy 11.507476 -125.297711)
			(xy 11.465071 -125.340116) (xy 11.417495 -125.376622) (xy 11.365561 -125.406606) (xy 11.310157 -125.429555)
			(xy 11.252232 -125.445076) (xy 11.192776 -125.452904) (xy 11.132808 -125.452904) (xy 11.073352 -125.445076)
			(xy 11.015427 -125.429555) (xy 10.960023 -125.406606) (xy 10.908089 -125.376622) (xy 10.860513 -125.340116)
			(xy 10.818108 -125.297711) (xy 10.781602 -125.250135) (xy 10.751618 -125.198201) (xy 10.728669 -125.142797)
			(xy 10.713148 -125.084872) (xy 10.70532 -125.025416) (xy 9.43113 -125.025416) (xy 9.428368 -125.044629)
			(xy 9.413012 -125.096924) (xy 9.390371 -125.146502) (xy 9.360905 -125.192353) (xy 9.325213 -125.233543)
			(xy 9.284023 -125.269235) (xy 9.238172 -125.298701) (xy 9.188594 -125.321342) (xy 9.136299 -125.336698)
			(xy 9.082351 -125.344454) (xy 9.0551 -125.344936) (xy 9.054846 -125.344936) (xy 9.026023 -125.344417)
			(xy 8.969034 -125.335751) (xy 8.914001 -125.318596) (xy 8.862183 -125.293342) (xy 8.838184 -125.277372)
			(xy 8.8265 -125.269244) (xy 8.798306 -125.267466) (xy 8.706104 -125.31598) (xy 8.698121 -125.32063)
			(xy 8.685885 -125.334451) (xy 8.679332 -125.351709) (xy 8.678926 -125.360938) (xy 8.678926 -126.012206)
			(xy 11.037552 -126.012206) (xy 11.037552 -125.952238) (xy 11.04538 -125.892782) (xy 11.060901 -125.834857)
			(xy 11.08385 -125.779453) (xy 11.113834 -125.727519) (xy 11.15034 -125.679943) (xy 11.192745 -125.637538)
			(xy 11.240321 -125.601032) (xy 11.292255 -125.571048) (xy 11.347659 -125.548099) (xy 11.405584 -125.532578)
			(xy 11.46504 -125.52475) (xy 11.525008 -125.52475) (xy 11.584464 -125.532578) (xy 11.642389 -125.548099)
			(xy 11.697793 -125.571048) (xy 11.749727 -125.601032) (xy 11.797303 -125.637538) (xy 11.839708 -125.679943)
			(xy 11.876214 -125.727519) (xy 11.906198 -125.779453) (xy 11.929147 -125.834857) (xy 11.944668 -125.892782)
			(xy 11.952496 -125.952238) (xy 11.952986 -125.982222) (xy 11.952496 -126.012206) (xy 11.944668 -126.071662)
			(xy 11.929147 -126.129587) (xy 11.906198 -126.184991) (xy 11.876214 -126.236925) (xy 11.839708 -126.284501)
			(xy 11.797303 -126.326906) (xy 11.749727 -126.363412) (xy 11.697793 -126.393396) (xy 11.642389 -126.416345)
			(xy 11.584464 -126.431866) (xy 11.525008 -126.439694) (xy 11.46504 -126.439694) (xy 11.405584 -126.431866)
			(xy 11.347659 -126.416345) (xy 11.292255 -126.393396) (xy 11.240321 -126.363412) (xy 11.192745 -126.326906)
			(xy 11.15034 -126.284501) (xy 11.113834 -126.236925) (xy 11.08385 -126.184991) (xy 11.060901 -126.129587)
			(xy 11.04538 -126.071662) (xy 11.037552 -126.012206) (xy 8.678926 -126.012206) (xy 8.678926 -126.597918)
			(xy 8.679328 -126.607148) (xy 8.685879 -126.624406) (xy 8.698123 -126.638221) (xy 8.706104 -126.642876)
			(xy 8.798306 -126.69139) (xy 8.8265 -126.689612) (xy 8.838184 -126.681484) (xy 8.862205 -126.665555)
			(xy 8.914028 -126.64033) (xy 8.969052 -126.623175) (xy 9.026028 -126.61448) (xy 9.054846 -126.61392)
			(xy 9.0551 -126.61392) (xy 9.082351 -126.614406) (xy 9.136299 -126.622162) (xy 9.188594 -126.637518)
			(xy 9.238172 -126.660159) (xy 9.284023 -126.689625) (xy 9.325213 -126.725317) (xy 9.360905 -126.766507)
			(xy 9.390371 -126.812358) (xy 9.413012 -126.861936) (xy 9.428368 -126.914231) (xy 9.436124 -126.968179)
			(xy 9.436124 -127.022681) (xy 9.428368 -127.076629) (xy 9.427003 -127.081276) (xy 10.668998 -127.081276)
			(xy 10.668998 -127.02134) (xy 10.676821 -126.961918) (xy 10.692334 -126.904025) (xy 10.71527 -126.848652)
			(xy 10.745237 -126.796746) (xy 10.781724 -126.749196) (xy 10.824104 -126.706816) (xy 10.871654 -126.670329)
			(xy 10.92356 -126.640362) (xy 10.978933 -126.617426) (xy 11.036826 -126.601913) (xy 11.096248 -126.59409)
			(xy 11.156184 -126.59409) (xy 11.215606 -126.601913) (xy 11.273499 -126.617426) (xy 11.328872 -126.640362)
			(xy 11.380778 -126.670329) (xy 11.428328 -126.706816) (xy 11.470708 -126.749196) (xy 11.507195 -126.796746)
			(xy 11.537162 -126.848652) (xy 11.560098 -126.904025) (xy 11.575611 -126.961918) (xy 11.583434 -127.02134)
			(xy 11.583442 -127.021844) (xy 14.774162 -127.021844) (xy 14.778233 -126.966222) (xy 14.790359 -126.911785)
			(xy 14.810282 -126.859694) (xy 14.837578 -126.811059) (xy 14.871664 -126.766916) (xy 14.911813 -126.728207)
			(xy 14.957171 -126.695756) (xy 15.006771 -126.670255) (xy 15.059555 -126.652248) (xy 15.114398 -126.642118)
			(xy 15.170132 -126.640081) (xy 15.225569 -126.646181) (xy 15.279526 -126.660287) (xy 15.330855 -126.682099)
			(xy 15.378461 -126.711153) (xy 15.421329 -126.746828) (xy 15.458546 -126.788365) (xy 15.489319 -126.834878)
			(xy 15.512991 -126.885375) (xy 15.529059 -126.938782) (xy 15.537179 -126.993958) (xy 15.537688 -127.021844)
			(xy 15.537179 -127.04973) (xy 15.529059 -127.104906) (xy 15.512991 -127.158313) (xy 15.489319 -127.20881)
			(xy 15.458546 -127.255323) (xy 15.421329 -127.29686) (xy 15.378461 -127.332535) (xy 15.330855 -127.361589)
			(xy 15.279526 -127.383401) (xy 15.225569 -127.397507) (xy 15.170132 -127.403607) (xy 15.114398 -127.40157)
			(xy 15.059555 -127.39144) (xy 15.006771 -127.373433) (xy 14.957171 -127.347932) (xy 14.911813 -127.315481)
			(xy 14.871664 -127.276772) (xy 14.837578 -127.232629) (xy 14.810282 -127.183994) (xy 14.790359 -127.131903)
			(xy 14.778233 -127.077466) (xy 14.774162 -127.021844) (xy 11.583442 -127.021844) (xy 11.583924 -127.051308)
			(xy 11.583434 -127.081276) (xy 11.575611 -127.140698) (xy 11.560098 -127.198591) (xy 11.537162 -127.253964)
			(xy 11.507195 -127.30587) (xy 11.470708 -127.35342) (xy 11.428328 -127.3958) (xy 11.380778 -127.432287)
			(xy 11.328872 -127.462254) (xy 11.273499 -127.48519) (xy 11.215606 -127.500703) (xy 11.156184 -127.508526)
			(xy 11.096248 -127.508526) (xy 11.036826 -127.500703) (xy 10.978933 -127.48519) (xy 10.92356 -127.462254)
			(xy 10.871654 -127.432287) (xy 10.824104 -127.3958) (xy 10.781724 -127.35342) (xy 10.745237 -127.30587)
			(xy 10.71527 -127.253964) (xy 10.692334 -127.198591) (xy 10.676821 -127.140698) (xy 10.668998 -127.081276)
			(xy 9.427003 -127.081276) (xy 9.413012 -127.128924) (xy 9.390371 -127.178502) (xy 9.360905 -127.224353)
			(xy 9.325213 -127.265543) (xy 9.284023 -127.301235) (xy 9.238172 -127.330701) (xy 9.188594 -127.353342)
			(xy 9.136299 -127.368698) (xy 9.082351 -127.376454) (xy 9.0551 -127.376936) (xy 9.05383 -127.376936)
			(xy 9.043833 -127.377428) (xy 9.025351 -127.385061) (xy 9.011162 -127.39915) (xy 9.00684 -127.408178)
			(xy 8.970772 -127.495046) (xy 8.967294 -127.504457) (xy 8.967247 -127.524506) (xy 8.974899 -127.543037)
			(xy 8.981694 -127.550418) (xy 9.032494 -127.601218) (xy 9.039888 -127.608074) (xy 9.058487 -127.615824)
			(xy 9.068562 -127.616204) (xy 21.08708 -127.616204) (xy 21.097144 -127.616642) (xy 21.115727 -127.624377)
			(xy 21.123148 -127.63119) (xy 21.424138 -127.93218) (xy 21.430978 -127.93958) (xy 21.438693 -127.958179)
			(xy 21.439124 -127.968248) (xy 21.439124 -134.193534) (xy 21.439554 -134.203601) (xy 21.44728 -134.222194)
			(xy 21.45411 -134.229602) (xy 27.20594 -139.981432) (xy 27.213337 -139.98828) (xy 27.231936 -139.99601)
			(xy 27.242008 -139.996418) (xy 35.869372 -139.996418) (xy 35.875668 -139.996234) (xy 35.887878 -139.993156)
			(xy 35.893502 -139.990322) (xy 35.917404 -139.978) (xy 35.967877 -139.959448) (xy 36.020455 -139.948167)
			(xy 36.074096 -139.944382) (xy 36.127737 -139.948167) (xy 36.180315 -139.959448) (xy 36.230788 -139.978)
			(xy 36.25469 -139.990322) (xy 36.260319 -139.993144) (xy 36.272526 -139.996222) (xy 36.27882 -139.996418)
			(xy 40.790114 -139.996418) (xy 40.800183 -139.996844) (xy 40.818782 -140.004564) (xy 40.826182 -140.011404)
			(xy 42.905934 -142.091156) (xy 42.913332 -142.098002) (xy 42.931931 -142.105731) (xy 42.942002 -142.106142)
		)
		(stroke
			(width 0)
			(type solid)
		)
		(fill yes)
		(layer "B.Cu")
		(net "P3V3_NIC0")
	)
	(gr_poly
		(pts
			(xy 278.068786 -142.106142) (xy 278.078747 -142.105653) (xy 278.097171 -142.098065) (xy 278.1046 -142.09141)
			(xy 278.164036 -142.032228) (xy 278.170814 -142.024803) (xy 278.178412 -142.006207) (xy 278.178768 -141.99616)
			(xy 278.178768 -139.55903) (xy 278.178331 -139.548966) (xy 278.170596 -139.530383) (xy 278.163782 -139.522962)
			(xy 278.12492 -139.4841) (xy 278.117517 -139.477266) (xy 278.098919 -139.469561) (xy 278.088852 -139.469114)
			(xy 276.626828 -139.469114) (xy 276.616763 -139.468678) (xy 276.598176 -139.460947) (xy 276.59076 -139.454128)
			(xy 274.57273 -137.436098) (xy 274.565328 -137.429263) (xy 274.546729 -137.421554) (xy 274.536662 -137.421112)
			(xy 266.960858 -137.421112) (xy 266.950791 -137.420682) (xy 266.932196 -137.412958) (xy 266.92479 -137.406126)
			(xy 263.479534 -133.96087) (xy 263.472688 -133.953472) (xy 263.46496 -133.934873) (xy 263.464548 -133.924802)
			(xy 263.464548 -120.594374) (xy 263.456928 -120.575578) (xy 263.449562 -120.568466) (xy 258.204716 -115.32362)
			(xy 258.197314 -115.316785) (xy 258.178715 -115.309078) (xy 258.168648 -115.308634) (xy 242.046252 -115.308634)
			(xy 242.036186 -115.309067) (xy 242.017598 -115.316797) (xy 242.010184 -115.32362) (xy 240.894108 -116.439696)
			(xy 240.887422 -116.447105) (xy 240.886081 -116.450364) (xy 244.161308 -116.450364) (xy 244.165379 -116.394742)
			(xy 244.177505 -116.340305) (xy 244.197428 -116.288214) (xy 244.224724 -116.239579) (xy 244.25881 -116.195436)
			(xy 244.298959 -116.156727) (xy 244.344317 -116.124276) (xy 244.393917 -116.098775) (xy 244.446701 -116.080768)
			(xy 244.501544 -116.070638) (xy 244.557278 -116.068601) (xy 244.612715 -116.074701) (xy 244.666672 -116.088807)
			(xy 244.718001 -116.110619) (xy 244.765607 -116.139673) (xy 244.808475 -116.175348) (xy 244.845692 -116.216885)
			(xy 244.876465 -116.263398) (xy 244.900137 -116.313895) (xy 244.916205 -116.367302) (xy 244.924325 -116.422478)
			(xy 244.924834 -116.450364) (xy 244.924325 -116.47825) (xy 244.916205 -116.533426) (xy 244.900137 -116.586833)
			(xy 244.876465 -116.63733) (xy 244.845692 -116.683843) (xy 244.808475 -116.72538) (xy 244.765607 -116.761055)
			(xy 244.718001 -116.790109) (xy 244.666672 -116.811921) (xy 244.612715 -116.826027) (xy 244.557278 -116.832127)
			(xy 244.501544 -116.83009) (xy 244.446701 -116.81996) (xy 244.393917 -116.801953) (xy 244.344317 -116.776452)
			(xy 244.298959 -116.744001) (xy 244.25881 -116.705292) (xy 244.224724 -116.661149) (xy 244.197428 -116.612514)
			(xy 244.177505 -116.560423) (xy 244.165379 -116.505986) (xy 244.161308 -116.450364) (xy 240.886081 -116.450364)
			(xy 240.879837 -116.465541) (xy 240.879376 -116.47551) (xy 240.879376 -117.434106) (xy 245.576852 -117.434106)
			(xy 245.577309 -117.406735) (xy 245.585127 -117.352555) (xy 245.600618 -117.300052) (xy 245.623462 -117.250305)
			(xy 245.653189 -117.204339) (xy 245.670832 -117.183408) (xy 245.676928 -117.176296) (xy 245.683278 -117.159532)
			(xy 245.683278 -117.07368) (xy 245.676928 -117.056916) (xy 245.670832 -117.049804) (xy 245.653197 -117.028867)
			(xy 245.623472 -116.9829) (xy 245.600626 -116.933154) (xy 245.585129 -116.880653) (xy 245.577299 -116.826475)
			(xy 245.577299 -116.771734) (xy 245.585127 -116.717556) (xy 245.600622 -116.665054) (xy 245.623467 -116.615308)
			(xy 245.653192 -116.569341) (xy 245.670832 -116.548408) (xy 245.676928 -116.541296) (xy 245.683278 -116.524532)
			(xy 245.683278 -116.43868) (xy 245.676928 -116.421916) (xy 245.670832 -116.414804) (xy 245.653186 -116.393877)
			(xy 245.623474 -116.347903) (xy 245.600639 -116.298155) (xy 245.58515 -116.245653) (xy 245.577324 -116.191476)
			(xy 245.576852 -116.164106) (xy 245.577383 -116.136857) (xy 245.585138 -116.082913) (xy 245.60049 -116.030621)
			(xy 245.623128 -115.981047) (xy 245.65259 -115.935198) (xy 245.688276 -115.894009) (xy 245.729461 -115.858317)
			(xy 245.775306 -115.82885) (xy 245.824878 -115.806206) (xy 245.877168 -115.790848) (xy 245.931111 -115.783087)
			(xy 245.95836 -115.782598) (xy 245.985729 -115.783088) (xy 246.039907 -115.7909) (xy 246.09241 -115.806384)
			(xy 246.142157 -115.82922) (xy 246.188125 -115.858939) (xy 246.209058 -115.876578) (xy 246.21617 -115.882674)
			(xy 246.232934 -115.889024) (xy 246.318786 -115.889024) (xy 246.33555 -115.882674) (xy 246.342662 -115.876578)
			(xy 246.363595 -115.85894) (xy 246.409568 -115.829229) (xy 246.459315 -115.806393) (xy 246.511815 -115.790901)
			(xy 246.565991 -115.783073) (xy 246.59336 -115.782598) (xy 246.620612 -115.783093) (xy 246.674562 -115.790844)
			(xy 246.72686 -115.806195) (xy 246.77644 -115.828834) (xy 246.822294 -115.858298) (xy 246.863487 -115.893989)
			(xy 246.899181 -115.935179) (xy 246.92865 -115.98103) (xy 246.951293 -116.030608) (xy 246.966649 -116.082904)
			(xy 246.974405 -116.136854) (xy 246.974868 -116.164106) (xy 246.974413 -116.191477) (xy 246.966594 -116.245657)
			(xy 246.951103 -116.29816) (xy 246.928258 -116.347907) (xy 246.898531 -116.393873) (xy 246.880888 -116.414804)
			(xy 246.874792 -116.421916) (xy 246.868442 -116.43868) (xy 246.868442 -116.524532) (xy 246.874792 -116.541296)
			(xy 246.880888 -116.548408) (xy 246.898534 -116.569336) (xy 246.928257 -116.615305) (xy 246.951101 -116.665052)
			(xy 246.966597 -116.717555) (xy 246.974424 -116.771734) (xy 246.974424 -116.826475) (xy 246.966595 -116.880654)
			(xy 246.951098 -116.933156) (xy 246.928253 -116.982903) (xy 246.898528 -117.028871) (xy 246.880888 -117.049804)
			(xy 246.874792 -117.056916) (xy 246.868442 -117.07368) (xy 246.868442 -117.159532) (xy 246.874792 -117.176296)
			(xy 246.880888 -117.183408) (xy 246.898542 -117.204328) (xy 246.928252 -117.250304) (xy 246.951086 -117.300054)
			(xy 246.966573 -117.352558) (xy 246.974397 -117.406736) (xy 246.974868 -117.434106) (xy 246.974437 -117.458382)
			(xy 246.972645 -117.472202) (xy 247.78384 -117.472202) (xy 247.78384 -117.412266) (xy 247.791663 -117.352844)
			(xy 247.807176 -117.294951) (xy 247.830112 -117.239578) (xy 247.860079 -117.187672) (xy 247.896566 -117.140122)
			(xy 247.938946 -117.097742) (xy 247.986496 -117.061255) (xy 248.038402 -117.031288) (xy 248.093775 -117.008352)
			(xy 248.151668 -116.992839) (xy 248.21109 -116.985016) (xy 248.271026 -116.985016) (xy 248.330448 -116.992839)
			(xy 248.388341 -117.008352) (xy 248.443714 -117.031288) (xy 248.49562 -117.061255) (xy 248.54317 -117.097742)
			(xy 248.58555 -117.140122) (xy 248.622037 -117.187672) (xy 248.652004 -117.239578) (xy 248.67494 -117.294951)
			(xy 248.690453 -117.352844) (xy 248.698276 -117.412266) (xy 248.698766 -117.442234) (xy 248.698276 -117.472202)
			(xy 248.690453 -117.531624) (xy 248.67494 -117.589517) (xy 248.652004 -117.64489) (xy 248.622037 -117.696796)
			(xy 248.58555 -117.744346) (xy 248.54317 -117.786726) (xy 248.49562 -117.823213) (xy 248.443714 -117.85318)
			(xy 248.388341 -117.876116) (xy 248.330448 -117.891629) (xy 248.271026 -117.899452) (xy 248.21109 -117.899452)
			(xy 248.151668 -117.891629) (xy 248.093775 -117.876116) (xy 248.038402 -117.85318) (xy 247.986496 -117.823213)
			(xy 247.938946 -117.786726) (xy 247.896566 -117.744346) (xy 247.860079 -117.696796) (xy 247.830112 -117.64489)
			(xy 247.807176 -117.589517) (xy 247.791663 -117.531624) (xy 247.78384 -117.472202) (xy 246.972645 -117.472202)
			(xy 246.968195 -117.506534) (xy 246.962422 -117.530118) (xy 246.959628 -117.540786) (xy 246.963438 -117.562122)
			(xy 247.012206 -117.63502) (xy 247.018593 -117.64373) (xy 247.036887 -117.655176) (xy 247.047512 -117.657118)
			(xy 247.04802 -117.657118) (xy 247.077705 -117.661449) (xy 247.13567 -117.676915) (xy 247.191118 -117.699821)
			(xy 247.243098 -117.729774) (xy 247.29072 -117.766261) (xy 247.333167 -117.808656) (xy 247.369712 -117.856233)
			(xy 247.399729 -117.908176) (xy 247.422704 -117.963595) (xy 247.438241 -118.021541) (xy 247.446076 -118.08102)
			(xy 247.446275 -118.09374) (xy 248.930904 -118.09374) (xy 248.930904 -118.033804) (xy 248.938727 -117.974382)
			(xy 248.95424 -117.916489) (xy 248.977176 -117.861116) (xy 249.007143 -117.80921) (xy 249.04363 -117.76166)
			(xy 249.08601 -117.71928) (xy 249.13356 -117.682793) (xy 249.185466 -117.652826) (xy 249.240839 -117.62989)
			(xy 249.298732 -117.614377) (xy 249.358154 -117.606554) (xy 249.41809 -117.606554) (xy 249.477512 -117.614377)
			(xy 249.535405 -117.62989) (xy 249.590778 -117.652826) (xy 249.642684 -117.682793) (xy 249.690234 -117.71928)
			(xy 249.732614 -117.76166) (xy 249.769101 -117.80921) (xy 249.799068 -117.861116) (xy 249.822004 -117.916489)
			(xy 249.837517 -117.974382) (xy 249.84534 -118.033804) (xy 249.84583 -118.063772) (xy 249.84534 -118.09374)
			(xy 249.837517 -118.153162) (xy 249.822004 -118.211055) (xy 249.799068 -118.266428) (xy 249.769101 -118.318334)
			(xy 249.732614 -118.365884) (xy 249.690234 -118.408264) (xy 249.642684 -118.444751) (xy 249.590778 -118.474718)
			(xy 249.535405 -118.497654) (xy 249.477512 -118.513167) (xy 249.41809 -118.52099) (xy 249.358154 -118.52099)
			(xy 249.298732 -118.513167) (xy 249.240839 -118.497654) (xy 249.185466 -118.474718) (xy 249.13356 -118.444751)
			(xy 249.08601 -118.408264) (xy 249.04363 -118.365884) (xy 249.007143 -118.318334) (xy 248.977176 -118.266428)
			(xy 248.95424 -118.211055) (xy 248.938727 -118.153162) (xy 248.930904 -118.09374) (xy 247.446275 -118.09374)
			(xy 247.446546 -118.111016) (xy 247.446056 -118.140984) (xy 247.438233 -118.200406) (xy 247.42272 -118.258299)
			(xy 247.399784 -118.313672) (xy 247.369817 -118.365578) (xy 247.33333 -118.413128) (xy 247.29095 -118.455508)
			(xy 247.2434 -118.491995) (xy 247.191494 -118.521962) (xy 247.136121 -118.544898) (xy 247.078228 -118.560411)
			(xy 247.018806 -118.568234) (xy 246.95887 -118.568234) (xy 246.899448 -118.560411) (xy 246.841555 -118.544898)
			(xy 246.786182 -118.521962) (xy 246.734276 -118.491995) (xy 246.686726 -118.455508) (xy 246.644346 -118.413128)
			(xy 246.607859 -118.365578) (xy 246.577892 -118.313672) (xy 246.554956 -118.258299) (xy 246.539443 -118.200406)
			(xy 246.53162 -118.140984) (xy 246.53113 -118.111016) (xy 246.53113 -118.110254) (xy 246.531602 -118.081082)
			(xy 246.539093 -118.02322) (xy 246.553896 -117.966784) (xy 246.564404 -117.939566) (xy 246.564404 -117.939312)
			(xy 246.564658 -117.93855) (xy 246.56801 -117.928428) (xy 246.566944 -117.907154) (xy 246.562626 -117.897402)
			(xy 246.52859 -117.82933) (xy 246.526061 -117.824692) (xy 246.51941 -117.81649) (xy 246.515382 -117.813074)
			(xy 246.506238 -117.805454) (xy 246.49557 -117.80266) (xy 246.467567 -117.79469) (xy 246.414196 -117.771431)
			(xy 246.364981 -117.74033) (xy 246.342662 -117.721634) (xy 246.33555 -117.715538) (xy 246.318786 -117.709188)
			(xy 246.232934 -117.709188) (xy 246.21617 -117.715538) (xy 246.209058 -117.721634) (xy 246.188119 -117.739265)
			(xy 246.142148 -117.768977) (xy 246.092402 -117.791814) (xy 246.039903 -117.807307) (xy 245.985729 -117.815138)
			(xy 245.95836 -117.815614) (xy 245.931108 -117.815159) (xy 245.87716 -117.807398) (xy 245.824865 -117.792038)
			(xy 245.775288 -117.769392) (xy 245.729438 -117.739922) (xy 245.688248 -117.704228) (xy 245.652557 -117.663035)
			(xy 245.623091 -117.617183) (xy 245.60045 -117.567604) (xy 245.585095 -117.515307) (xy 245.577338 -117.461358)
			(xy 245.576852 -117.434106) (xy 240.879376 -117.434106) (xy 240.879376 -118.072154) (xy 240.997992 -118.072154)
			(xy 241.002063 -118.016532) (xy 241.014189 -117.962095) (xy 241.034112 -117.910004) (xy 241.061408 -117.861369)
			(xy 241.095494 -117.817226) (xy 241.135643 -117.778517) (xy 241.181001 -117.746066) (xy 241.230601 -117.720565)
			(xy 241.283385 -117.702558) (xy 241.338228 -117.692428) (xy 241.393962 -117.690391) (xy 241.449399 -117.696491)
			(xy 241.503356 -117.710597) (xy 241.554685 -117.732409) (xy 241.602291 -117.761463) (xy 241.645159 -117.797138)
			(xy 241.682376 -117.838675) (xy 241.713149 -117.885188) (xy 241.736821 -117.935685) (xy 241.752889 -117.989092)
			(xy 241.761009 -118.044268) (xy 241.761518 -118.072154) (xy 241.761009 -118.10004) (xy 241.758161 -118.119394)
			(xy 242.320046 -118.119394) (xy 242.320046 -118.059458) (xy 242.327869 -118.000036) (xy 242.343382 -117.942143)
			(xy 242.366318 -117.88677) (xy 242.396285 -117.834864) (xy 242.432772 -117.787314) (xy 242.475152 -117.744934)
			(xy 242.522702 -117.708447) (xy 242.574608 -117.67848) (xy 242.629981 -117.655544) (xy 242.687874 -117.640031)
			(xy 242.747296 -117.632208) (xy 242.807232 -117.632208) (xy 242.866654 -117.640031) (xy 242.924547 -117.655544)
			(xy 242.97992 -117.67848) (xy 243.031826 -117.708447) (xy 243.079376 -117.744934) (xy 243.121756 -117.787314)
			(xy 243.158243 -117.834864) (xy 243.18821 -117.88677) (xy 243.211146 -117.942143) (xy 243.224611 -117.992394)
			(xy 244.352046 -117.992394) (xy 244.352046 -117.932458) (xy 244.359869 -117.873036) (xy 244.375382 -117.815143)
			(xy 244.398318 -117.75977) (xy 244.428285 -117.707864) (xy 244.464772 -117.660314) (xy 244.507152 -117.617934)
			(xy 244.554702 -117.581447) (xy 244.606608 -117.55148) (xy 244.661981 -117.528544) (xy 244.719874 -117.513031)
			(xy 244.779296 -117.505208) (xy 244.839232 -117.505208) (xy 244.898654 -117.513031) (xy 244.956547 -117.528544)
			(xy 245.01192 -117.55148) (xy 245.063826 -117.581447) (xy 245.111376 -117.617934) (xy 245.153756 -117.660314)
			(xy 245.190243 -117.707864) (xy 245.22021 -117.75977) (xy 245.243146 -117.815143) (xy 245.258659 -117.873036)
			(xy 245.266482 -117.932458) (xy 245.266972 -117.962426) (xy 245.266482 -117.992394) (xy 245.258659 -118.051816)
			(xy 245.243146 -118.109709) (xy 245.22021 -118.165082) (xy 245.190243 -118.216988) (xy 245.153756 -118.264538)
			(xy 245.111376 -118.306918) (xy 245.063826 -118.343405) (xy 245.01192 -118.373372) (xy 244.956547 -118.396308)
			(xy 244.898654 -118.411821) (xy 244.839232 -118.419644) (xy 244.779296 -118.419644) (xy 244.719874 -118.411821)
			(xy 244.661981 -118.396308) (xy 244.606608 -118.373372) (xy 244.554702 -118.343405) (xy 244.507152 -118.306918)
			(xy 244.464772 -118.264538) (xy 244.428285 -118.216988) (xy 244.398318 -118.165082) (xy 244.375382 -118.109709)
			(xy 244.359869 -118.051816) (xy 244.352046 -117.992394) (xy 243.224611 -117.992394) (xy 243.226659 -118.000036)
			(xy 243.234482 -118.059458) (xy 243.234972 -118.089426) (xy 243.234482 -118.119394) (xy 243.226659 -118.178816)
			(xy 243.211146 -118.236709) (xy 243.18821 -118.292082) (xy 243.158243 -118.343988) (xy 243.121756 -118.391538)
			(xy 243.079376 -118.433918) (xy 243.031826 -118.470405) (xy 242.97992 -118.500372) (xy 242.924547 -118.523308)
			(xy 242.866654 -118.538821) (xy 242.807232 -118.546644) (xy 242.747296 -118.546644) (xy 242.687874 -118.538821)
			(xy 242.629981 -118.523308) (xy 242.574608 -118.500372) (xy 242.522702 -118.470405) (xy 242.475152 -118.433918)
			(xy 242.432772 -118.391538) (xy 242.396285 -118.343988) (xy 242.366318 -118.292082) (xy 242.343382 -118.236709)
			(xy 242.327869 -118.178816) (xy 242.320046 -118.119394) (xy 241.758161 -118.119394) (xy 241.752889 -118.155216)
			(xy 241.736821 -118.208623) (xy 241.713149 -118.25912) (xy 241.682376 -118.305633) (xy 241.645159 -118.34717)
			(xy 241.602291 -118.382845) (xy 241.554685 -118.411899) (xy 241.503356 -118.433711) (xy 241.449399 -118.447817)
			(xy 241.393962 -118.453917) (xy 241.338228 -118.45188) (xy 241.283385 -118.44175) (xy 241.230601 -118.423743)
			(xy 241.181001 -118.398242) (xy 241.135643 -118.365791) (xy 241.095494 -118.327082) (xy 241.061408 -118.282939)
			(xy 241.034112 -118.234304) (xy 241.014189 -118.182213) (xy 241.002063 -118.127776) (xy 240.997992 -118.072154)
			(xy 240.879376 -118.072154) (xy 240.879376 -120.212104) (xy 240.878868 -120.230138) (xy 240.878868 -120.231154)
			(xy 240.878868 -120.248426) (xy 242.395246 -120.248426) (xy 242.399317 -120.192804) (xy 242.411443 -120.138367)
			(xy 242.431366 -120.086276) (xy 242.458662 -120.037641) (xy 242.492748 -119.993498) (xy 242.532897 -119.954789)
			(xy 242.578255 -119.922338) (xy 242.627855 -119.896837) (xy 242.680639 -119.87883) (xy 242.735482 -119.8687)
			(xy 242.791216 -119.866663) (xy 242.846653 -119.872763) (xy 242.90061 -119.886869) (xy 242.951939 -119.908681)
			(xy 242.999545 -119.937735) (xy 243.042413 -119.97341) (xy 243.07963 -120.014947) (xy 243.110403 -120.06146)
			(xy 243.134075 -120.111957) (xy 243.135854 -120.11787) (xy 243.411246 -120.11787) (xy 243.415317 -120.062248)
			(xy 243.427443 -120.007811) (xy 243.447366 -119.95572) (xy 243.474662 -119.907085) (xy 243.508748 -119.862942)
			(xy 243.548897 -119.824233) (xy 243.594255 -119.791782) (xy 243.643855 -119.766281) (xy 243.696639 -119.748274)
			(xy 243.751482 -119.738144) (xy 243.807216 -119.736107) (xy 243.862653 -119.742207) (xy 243.91661 -119.756313)
			(xy 243.967939 -119.778125) (xy 244.015545 -119.807179) (xy 244.058413 -119.842854) (xy 244.09563 -119.884391)
			(xy 244.126403 -119.930904) (xy 244.150075 -119.981401) (xy 244.166143 -120.034808) (xy 244.174263 -120.089984)
			(xy 244.174772 -120.11787) (xy 245.443502 -120.11787) (xy 245.443988 -120.090601) (xy 245.45175 -120.036617)
			(xy 245.467115 -119.984287) (xy 245.489772 -119.934677) (xy 245.519258 -119.888796) (xy 245.554973 -119.847579)
			(xy 245.59619 -119.811864) (xy 245.642071 -119.782378) (xy 245.691681 -119.759721) (xy 245.744011 -119.744356)
			(xy 245.797995 -119.736594) (xy 245.852533 -119.736594) (xy 245.906517 -119.744356) (xy 245.958847 -119.759721)
			(xy 246.008457 -119.782378) (xy 246.054338 -119.811864) (xy 246.095555 -119.847579) (xy 246.13127 -119.888796)
			(xy 246.160756 -119.934677) (xy 246.183413 -119.984287) (xy 246.198778 -120.036617) (xy 246.20654 -120.090601)
			(xy 246.207026 -120.11787) (xy 246.206808 -120.130316) (xy 246.607076 -120.130316) (xy 246.607516 -120.103044)
			(xy 246.615277 -120.049054) (xy 246.630644 -119.996719) (xy 246.653302 -119.947103) (xy 246.682792 -119.901217)
			(xy 246.718512 -119.859996) (xy 246.759735 -119.824278) (xy 246.805622 -119.794792) (xy 246.855239 -119.772136)
			(xy 246.907576 -119.756773) (xy 246.961566 -119.749015) (xy 246.988838 -119.748554) (xy 247.016109 -119.748989)
			(xy 247.070095 -119.756756) (xy 247.122427 -119.772127) (xy 247.172038 -119.794789) (xy 247.21792 -119.82428)
			(xy 247.259137 -119.860001) (xy 247.294852 -119.901224) (xy 247.324337 -119.947109) (xy 247.346992 -119.996724)
			(xy 247.362355 -120.049058) (xy 247.370115 -120.103045) (xy 247.3706 -120.130316) (xy 247.370346 -120.144286)
			(xy 247.370346 -120.146572) (xy 247.370346 -120.153176) (xy 247.370346 -120.15343) (xy 247.622566 -120.15343)
			(xy 247.626639 -120.097771) (xy 247.638774 -120.043298) (xy 247.65871 -119.991172) (xy 247.686024 -119.942504)
			(xy 247.720132 -119.898332) (xy 247.760309 -119.859597) (xy 247.805697 -119.827125) (xy 247.855329 -119.801607)
			(xy 247.908149 -119.783588) (xy 247.963028 -119.773451) (xy 248.018799 -119.771413) (xy 248.074273 -119.777516)
			(xy 248.128266 -119.791632) (xy 248.179629 -119.813459) (xy 248.227267 -119.842532) (xy 248.270163 -119.878231)
			(xy 248.307405 -119.919795) (xy 248.338199 -119.966339) (xy 248.361887 -120.01687) (xy 248.377965 -120.070312)
			(xy 248.386091 -120.125526) (xy 248.3866 -120.15343) (xy 248.638566 -120.15343) (xy 248.642639 -120.097771)
			(xy 248.654774 -120.043298) (xy 248.67471 -119.991172) (xy 248.702024 -119.942504) (xy 248.736132 -119.898332)
			(xy 248.776309 -119.859597) (xy 248.821697 -119.827125) (xy 248.871329 -119.801607) (xy 248.924149 -119.783588)
			(xy 248.979028 -119.773451) (xy 249.034799 -119.771413) (xy 249.090273 -119.777516) (xy 249.144266 -119.791632)
			(xy 249.195629 -119.813459) (xy 249.243267 -119.842532) (xy 249.286163 -119.878231) (xy 249.323405 -119.919795)
			(xy 249.354199 -119.966339) (xy 249.377887 -120.01687) (xy 249.393965 -120.070312) (xy 249.402091 -120.125526)
			(xy 249.4026 -120.15343) (xy 249.402091 -120.181334) (xy 249.393965 -120.236548) (xy 249.377887 -120.28999)
			(xy 249.354199 -120.340521) (xy 249.323405 -120.387065) (xy 249.286163 -120.428629) (xy 249.243267 -120.464328)
			(xy 249.195629 -120.493401) (xy 249.144266 -120.515228) (xy 249.090273 -120.529344) (xy 249.034799 -120.535447)
			(xy 248.979028 -120.533409) (xy 248.924149 -120.523272) (xy 248.871329 -120.505253) (xy 248.821697 -120.479735)
			(xy 248.776309 -120.447263) (xy 248.736132 -120.408528) (xy 248.702024 -120.364356) (xy 248.67471 -120.315688)
			(xy 248.654774 -120.263562) (xy 248.642639 -120.209089) (xy 248.638566 -120.15343) (xy 248.3866 -120.15343)
			(xy 248.386091 -120.181334) (xy 248.377965 -120.236548) (xy 248.361887 -120.28999) (xy 248.338199 -120.340521)
			(xy 248.307405 -120.387065) (xy 248.270163 -120.428629) (xy 248.227267 -120.464328) (xy 248.179629 -120.493401)
			(xy 248.128266 -120.515228) (xy 248.074273 -120.529344) (xy 248.018799 -120.535447) (xy 247.963028 -120.533409)
			(xy 247.908149 -120.523272) (xy 247.855329 -120.505253) (xy 247.805697 -120.479735) (xy 247.760309 -120.447263)
			(xy 247.720132 -120.408528) (xy 247.686024 -120.364356) (xy 247.65871 -120.315688) (xy 247.638774 -120.263562)
			(xy 247.626639 -120.209089) (xy 247.622566 -120.15343) (xy 247.370346 -120.15343) (xy 247.370346 -120.153684)
			(xy 247.369833 -120.180922) (xy 247.362044 -120.23484) (xy 247.346665 -120.287102) (xy 247.324009 -120.336645)
			(xy 247.294536 -120.382461) (xy 247.258846 -120.42362) (xy 247.217664 -120.459283) (xy 247.171829 -120.488727)
			(xy 247.122271 -120.511351) (xy 247.07 -120.526696) (xy 247.016077 -120.53445) (xy 246.988838 -120.534938)
			(xy 246.961601 -120.534387) (xy 246.907679 -120.526643) (xy 246.855408 -120.511307) (xy 246.80585 -120.488692)
			(xy 246.760013 -120.459256) (xy 246.71883 -120.423598) (xy 246.683138 -120.382445) (xy 246.653663 -120.336633)
			(xy 246.631005 -120.287094) (xy 246.615625 -120.234836) (xy 246.607836 -120.180921) (xy 246.60733 -120.153684)
			(xy 246.60733 -120.153176) (xy 246.60733 -120.146572) (xy 246.60733 -120.144286) (xy 246.607076 -120.130316)
			(xy 246.206808 -120.130316) (xy 246.206552 -120.144929) (xy 246.198912 -120.198505) (xy 246.183783 -120.250465)
			(xy 246.161466 -120.299767) (xy 246.147336 -120.322848) (xy 246.147082 -120.323102) (xy 246.13997 -120.334532)
			(xy 246.139208 -120.34774) (xy 246.139049 -120.354458) (xy 246.141888 -120.367589) (xy 246.144796 -120.373648)
			(xy 246.151654 -120.38711) (xy 246.176038 -120.401842) (xy 246.19077 -120.401588) (xy 246.201184 -120.401588)
			(xy 246.201692 -120.401588) (xy 246.231664 -120.402108) (xy 246.291092 -120.409967) (xy 246.348986 -120.425512)
			(xy 246.404358 -120.448477) (xy 246.456261 -120.478469) (xy 246.503806 -120.514977) (xy 246.546183 -120.557376)
			(xy 246.582665 -120.604941) (xy 246.612631 -120.656859) (xy 246.635566 -120.712243) (xy 246.65108 -120.770146)
			(xy 246.658907 -120.829578) (xy 246.6594 -120.85955) (xy 246.658886 -120.891095) (xy 246.650214 -120.953585)
			(xy 246.633055 -121.014296) (xy 246.607732 -121.072081) (xy 246.574724 -121.125847) (xy 246.534656 -121.174579)
			(xy 246.511826 -121.196354) (xy 246.500988 -121.207058) (xy 246.485639 -121.233352) (xy 246.478726 -121.263003)
			(xy 246.480864 -121.293374) (xy 246.491863 -121.321764) (xy 246.500904 -121.334022) (xy 246.516418 -121.354323)
			(xy 246.542481 -121.398268) (xy 246.562449 -121.445296) (xy 246.575965 -121.494569) (xy 246.580104 -121.525284)
			(xy 249.551444 -121.525284) (xy 249.55188 -121.497913) (xy 249.55971 -121.443734) (xy 249.575209 -121.391232)
			(xy 249.598056 -121.341486) (xy 249.627783 -121.295519) (xy 249.645424 -121.274586) (xy 249.645678 -121.274332)
			(xy 249.645932 -121.274078) (xy 249.651537 -121.267005) (xy 249.657772 -121.250078) (xy 249.658124 -121.241058)
			(xy 249.658124 -121.17451) (xy 249.657757 -121.165494) (xy 249.651516 -121.148578) (xy 249.645932 -121.14149)
			(xy 249.645678 -121.141236) (xy 249.645424 -121.140982) (xy 249.627813 -121.12003) (xy 249.598126 -121.074049)
			(xy 249.575299 -121.024305) (xy 249.559798 -120.971814) (xy 249.551939 -120.917649) (xy 249.551444 -120.890284)
			(xy 249.55193 -120.863015) (xy 249.559692 -120.809031) (xy 249.575057 -120.756701) (xy 249.597714 -120.707091)
			(xy 249.6272 -120.66121) (xy 249.662915 -120.619993) (xy 249.704132 -120.584278) (xy 249.750013 -120.554792)
			(xy 249.799623 -120.532135) (xy 249.851953 -120.51677) (xy 249.905937 -120.509008) (xy 249.960475 -120.509008)
			(xy 250.014459 -120.51677) (xy 250.066789 -120.532135) (xy 250.116399 -120.554792) (xy 250.16228 -120.584278)
			(xy 250.203497 -120.619993) (xy 250.239212 -120.66121) (xy 250.268698 -120.707091) (xy 250.291355 -120.756701)
			(xy 250.30672 -120.809031) (xy 250.314482 -120.863015) (xy 250.314968 -120.890284) (xy 250.314511 -120.917654)
			(xy 250.306685 -120.971832) (xy 250.291191 -121.024334) (xy 250.268349 -121.07408) (xy 250.238627 -121.120049)
			(xy 250.220988 -121.140982) (xy 250.220734 -121.141236) (xy 250.22048 -121.14149) (xy 250.214889 -121.148574)
			(xy 250.208646 -121.165493) (xy 250.208288 -121.17451) (xy 250.208288 -121.241058) (xy 250.208668 -121.250073)
			(xy 250.2149 -121.26699) (xy 250.22048 -121.274078) (xy 250.220734 -121.274332) (xy 250.220988 -121.274586)
			(xy 250.238617 -121.295524) (xy 250.268304 -121.341507) (xy 250.291129 -121.391255) (xy 250.306626 -121.443749)
			(xy 250.314477 -121.497917) (xy 250.314968 -121.525284) (xy 250.314714 -121.538238) (xy 250.314714 -121.538492)
			(xy 250.31446 -121.548398) (xy 250.317762 -121.557542) (xy 250.319482 -121.562039) (xy 250.324333 -121.570353)
			(xy 250.327414 -121.574052) (xy 250.380246 -121.633488) (xy 250.397518 -121.642378) (xy 250.407424 -121.64314)
			(xy 250.4355 -121.645969) (xy 250.490691 -121.657732) (xy 250.544017 -121.676191) (xy 250.594668 -121.701067)
			(xy 250.641876 -121.731982) (xy 250.684925 -121.768468) (xy 250.70435 -121.788936) (xy 250.704604 -121.78919)
			(xy 250.71129 -121.795845) (xy 250.728257 -121.804065) (xy 250.737624 -121.805192) (xy 250.806204 -121.81078)
			(xy 250.815657 -121.811213) (xy 250.833795 -121.805848) (xy 250.84151 -121.800366) (xy 250.842018 -121.799858)
			(xy 250.842272 -121.799604) (xy 250.862581 -121.78416) (xy 250.906487 -121.758174) (xy 250.953463 -121.738266)
			(xy 251.002671 -121.724792) (xy 251.053236 -121.71799) (xy 251.078746 -121.717562) (xy 251.105993 -121.718111)
			(xy 251.159931 -121.725873) (xy 251.212216 -121.74123) (xy 251.261784 -121.763872) (xy 251.307625 -121.793338)
			(xy 251.348806 -121.829026) (xy 251.38449 -121.870212) (xy 251.41395 -121.916057) (xy 251.436586 -121.965627)
			(xy 251.451937 -122.017914) (xy 251.459692 -122.071853) (xy 251.459692 -122.126347) (xy 251.451937 -122.180286)
			(xy 251.436586 -122.232573) (xy 251.41395 -122.282143) (xy 251.38449 -122.327988) (xy 251.348806 -122.369174)
			(xy 251.307625 -122.404862) (xy 251.261784 -122.434328) (xy 251.212216 -122.45697) (xy 251.159931 -122.472327)
			(xy 251.105993 -122.480089) (xy 251.078746 -122.480578) (xy 251.053234 -122.480158) (xy 251.002666 -122.473366)
			(xy 250.953452 -122.459897) (xy 250.906472 -122.439992) (xy 250.862563 -122.414005) (xy 250.842272 -122.398536)
			(xy 250.842018 -122.398282) (xy 250.84151 -122.397774) (xy 250.833787 -122.392307) (xy 250.815656 -122.386943)
			(xy 250.806204 -122.38736) (xy 250.737624 -122.392948) (xy 250.728282 -122.394168) (xy 250.711341 -122.402366)
			(xy 250.704604 -122.40895) (xy 250.70435 -122.409204) (xy 250.682619 -122.432052) (xy 250.63394 -122.472131)
			(xy 250.580216 -122.505143) (xy 250.522467 -122.530462) (xy 250.461788 -122.547609) (xy 250.399328 -122.556257)
			(xy 250.3678 -122.556778) (xy 250.367546 -122.556778) (xy 250.337577 -122.556296) (xy 250.278151 -122.548477)
			(xy 250.220253 -122.532968) (xy 250.164876 -122.510034) (xy 250.112967 -122.480067) (xy 250.065413 -122.443581)
			(xy 250.02303 -122.401199) (xy 249.986541 -122.353647) (xy 249.956573 -122.301738) (xy 249.933637 -122.246362)
			(xy 249.918126 -122.188465) (xy 249.910305 -122.129039) (xy 249.909838 -122.09907) (xy 249.910098 -122.0787)
			(xy 249.913784 -122.038126) (xy 249.917204 -122.018044) (xy 249.917966 -122.013726) (xy 249.917966 -122.002296)
			(xy 249.917729 -121.995027) (xy 249.913602 -121.981087) (xy 249.909838 -121.974864) (xy 249.867928 -121.90984)
			(xy 249.85218 -121.89841) (xy 249.842782 -121.896124) (xy 249.815453 -121.888933) (xy 249.76312 -121.867611)
			(xy 249.714503 -121.838805) (xy 249.670666 -121.803146) (xy 249.632565 -121.761412) (xy 249.601035 -121.714516)
			(xy 249.576764 -121.663484) (xy 249.560284 -121.609431) (xy 249.551954 -121.553539) (xy 249.551444 -121.525284)
			(xy 246.580104 -121.525284) (xy 246.582788 -121.545204) (xy 246.5832 -121.57075) (xy 246.582714 -121.598019)
			(xy 246.574952 -121.652003) (xy 246.559587 -121.704333) (xy 246.53693 -121.753943) (xy 246.507444 -121.799824)
			(xy 246.471729 -121.841041) (xy 246.430512 -121.876756) (xy 246.384631 -121.906242) (xy 246.335021 -121.928899)
			(xy 246.282691 -121.944264) (xy 246.228707 -121.952026) (xy 246.174169 -121.952026) (xy 246.120185 -121.944264)
			(xy 246.067855 -121.928899) (xy 246.018245 -121.906242) (xy 245.972364 -121.876756) (xy 245.931147 -121.841041)
			(xy 245.895432 -121.799824) (xy 245.865946 -121.753943) (xy 245.843289 -121.704333) (xy 245.827924 -121.652003)
			(xy 245.820162 -121.598019) (xy 245.819676 -121.57075) (xy 245.820104 -121.545203) (xy 245.826907 -121.494564)
			(xy 245.840412 -121.445288) (xy 245.860377 -121.398256) (xy 245.886443 -121.354311) (xy 245.901972 -121.334022)
			(xy 245.910952 -121.321732) (xy 245.921915 -121.293354) (xy 245.924045 -121.263006) (xy 245.917153 -121.233374)
			(xy 245.901849 -121.207082) (xy 245.89105 -121.196354) (xy 245.868211 -121.174587) (xy 245.828132 -121.125861)
			(xy 245.795121 -121.072095) (xy 245.769801 -121.014307) (xy 245.752653 -120.953591) (xy 245.744 -120.891096)
			(xy 245.743476 -120.85955) (xy 245.743973 -120.829586) (xy 245.751775 -120.770167) (xy 245.767264 -120.712276)
			(xy 245.790177 -120.656901) (xy 245.820121 -120.60499) (xy 245.837964 -120.580912) (xy 245.843465 -120.573103)
			(xy 245.848674 -120.554737) (xy 245.84679 -120.53574) (xy 245.84279 -120.527064) (xy 245.83644 -120.514364)
			(xy 245.814342 -120.499632) (xy 245.800626 -120.49887) (xy 245.771961 -120.496421) (xy 245.715761 -120.484134)
			(xy 245.662041 -120.463554) (xy 245.612016 -120.435147) (xy 245.56682 -120.399557) (xy 245.527474 -120.357589)
			(xy 245.49487 -120.310193) (xy 245.469746 -120.258443) (xy 245.45267 -120.203508) (xy 245.444029 -120.146634)
			(xy 245.443502 -120.11787) (xy 244.174772 -120.11787) (xy 244.174263 -120.145756) (xy 244.166143 -120.200932)
			(xy 244.150075 -120.254339) (xy 244.126403 -120.304836) (xy 244.09563 -120.351349) (xy 244.058413 -120.392886)
			(xy 244.015545 -120.428561) (xy 243.967939 -120.457615) (xy 243.91661 -120.479427) (xy 243.862653 -120.493533)
			(xy 243.807216 -120.499633) (xy 243.751482 -120.497596) (xy 243.696639 -120.487466) (xy 243.643855 -120.469459)
			(xy 243.594255 -120.443958) (xy 243.548897 -120.411507) (xy 243.508748 -120.372798) (xy 243.474662 -120.328655)
			(xy 243.447366 -120.28002) (xy 243.427443 -120.227929) (xy 243.415317 -120.173492) (xy 243.411246 -120.11787)
			(xy 243.135854 -120.11787) (xy 243.150143 -120.165364) (xy 243.158263 -120.22054) (xy 243.158772 -120.248426)
			(xy 243.158263 -120.276312) (xy 243.150143 -120.331488) (xy 243.134075 -120.384895) (xy 243.110403 -120.435392)
			(xy 243.07963 -120.481905) (xy 243.042413 -120.523442) (xy 242.999545 -120.559117) (xy 242.951939 -120.588171)
			(xy 242.90061 -120.609983) (xy 242.846653 -120.624089) (xy 242.791216 -120.630189) (xy 242.735482 -120.628152)
			(xy 242.680639 -120.618022) (xy 242.627855 -120.600015) (xy 242.578255 -120.574514) (xy 242.532897 -120.542063)
			(xy 242.492748 -120.503354) (xy 242.458662 -120.459211) (xy 242.431366 -120.410576) (xy 242.411443 -120.358485)
			(xy 242.399317 -120.304048) (xy 242.395246 -120.248426) (xy 240.878868 -120.248426) (xy 240.878868 -121.147586)
			(xy 240.879302 -121.156973) (xy 240.886052 -121.174492) (xy 240.898625 -121.188434) (xy 240.906808 -121.193052)
			(xy 240.987834 -121.233692) (xy 240.9964 -121.237538) (xy 241.015068 -121.239389) (xy 241.03315 -121.234389)
			(xy 241.04092 -121.22912) (xy 241.065736 -121.211444) (xy 241.119804 -121.183366) (xy 241.177644 -121.164229)
			(xy 241.237789 -121.154517) (xy 241.26825 -121.153936) (xy 241.268504 -121.153936) (xy 241.295752 -121.154422)
			(xy 241.349693 -121.162179) (xy 241.401981 -121.177532) (xy 241.451552 -121.200171) (xy 241.497397 -121.229634)
			(xy 241.538582 -121.265321) (xy 241.574269 -121.306507) (xy 241.603731 -121.352351) (xy 241.626369 -121.401923)
			(xy 241.641722 -121.454211) (xy 241.649478 -121.508152) (xy 241.649478 -121.562648) (xy 241.641722 -121.616589)
			(xy 241.626369 -121.668877) (xy 241.603731 -121.718449) (xy 241.574269 -121.764293) (xy 241.538582 -121.805479)
			(xy 241.497397 -121.841166) (xy 241.451552 -121.870629) (xy 241.401981 -121.893268) (xy 241.349693 -121.908621)
			(xy 241.295752 -121.916378) (xy 241.268504 -121.916952) (xy 241.26825 -121.916952) (xy 241.237788 -121.916358)
			(xy 241.177638 -121.906672) (xy 241.119796 -121.887539) (xy 241.065736 -121.859446) (xy 241.04092 -121.841768)
			(xy 241.03313 -121.836533) (xy 241.015055 -121.831532) (xy 240.996389 -121.83334) (xy 240.987834 -121.837196)
			(xy 240.906808 -121.877836) (xy 240.898568 -121.882388) (xy 240.885939 -121.896329) (xy 240.879206 -121.913895)
			(xy 240.878868 -121.923302) (xy 240.878868 -122.292618) (xy 241.98021 -122.292618) (xy 241.984281 -122.236996)
			(xy 241.996407 -122.182559) (xy 242.01633 -122.130468) (xy 242.043626 -122.081833) (xy 242.077712 -122.03769)
			(xy 242.117861 -121.998981) (xy 242.163219 -121.96653) (xy 242.212819 -121.941029) (xy 242.265603 -121.923022)
			(xy 242.320446 -121.912892) (xy 242.37618 -121.910855) (xy 242.431617 -121.916955) (xy 242.485574 -121.931061)
			(xy 242.536903 -121.952873) (xy 242.584509 -121.981927) (xy 242.627377 -122.017602) (xy 242.664594 -122.059139)
			(xy 242.695367 -122.105652) (xy 242.719039 -122.156149) (xy 242.735107 -122.209556) (xy 242.743227 -122.264732)
			(xy 242.743736 -122.292618) (xy 242.743227 -122.320504) (xy 242.735107 -122.37568) (xy 242.719039 -122.429087)
			(xy 242.695367 -122.479584) (xy 242.68194 -122.499878) (xy 243.061726 -122.499878) (xy 243.061726 -122.439942)
			(xy 243.069549 -122.38052) (xy 243.085062 -122.322627) (xy 243.107998 -122.267254) (xy 243.137965 -122.215348)
			(xy 243.174452 -122.167798) (xy 243.216832 -122.125418) (xy 243.264382 -122.088931) (xy 243.316288 -122.058964)
			(xy 243.371661 -122.036028) (xy 243.429554 -122.020515) (xy 243.488976 -122.012692) (xy 243.548912 -122.012692)
			(xy 243.608334 -122.020515) (xy 243.666227 -122.036028) (xy 243.7216 -122.058964) (xy 243.773506 -122.088931)
			(xy 243.821056 -122.125418) (xy 243.863436 -122.167798) (xy 243.899923 -122.215348) (xy 243.92989 -122.267254)
			(xy 243.952826 -122.322627) (xy 243.968339 -122.38052) (xy 243.976162 -122.439942) (xy 243.976652 -122.46991)
			(xy 243.976162 -122.499878) (xy 243.968339 -122.5593) (xy 243.952826 -122.617193) (xy 243.92989 -122.672566)
			(xy 243.899923 -122.724472) (xy 243.863436 -122.772022) (xy 243.821056 -122.814402) (xy 243.773506 -122.850889)
			(xy 243.7216 -122.880856) (xy 243.666227 -122.903792) (xy 243.608334 -122.919305) (xy 243.548912 -122.927128)
			(xy 243.488976 -122.927128) (xy 243.429554 -122.919305) (xy 243.371661 -122.903792) (xy 243.316288 -122.880856)
			(xy 243.264382 -122.850889) (xy 243.216832 -122.814402) (xy 243.174452 -122.772022) (xy 243.137965 -122.724472)
			(xy 243.107998 -122.672566) (xy 243.085062 -122.617193) (xy 243.069549 -122.5593) (xy 243.061726 -122.499878)
			(xy 242.68194 -122.499878) (xy 242.664594 -122.526097) (xy 242.627377 -122.567634) (xy 242.584509 -122.603309)
			(xy 242.536903 -122.632363) (xy 242.485574 -122.654175) (xy 242.431617 -122.668281) (xy 242.37618 -122.674381)
			(xy 242.320446 -122.672344) (xy 242.265603 -122.662214) (xy 242.212819 -122.644207) (xy 242.163219 -122.618706)
			(xy 242.117861 -122.586255) (xy 242.077712 -122.547546) (xy 242.043626 -122.503403) (xy 242.01633 -122.454768)
			(xy 241.996407 -122.402677) (xy 241.984281 -122.34824) (xy 241.98021 -122.292618) (xy 240.878868 -122.292618)
			(xy 240.878868 -122.533918) (xy 240.879271 -122.543146) (xy 240.885825 -122.5604) (xy 240.898074 -122.574207)
			(xy 240.906046 -122.578876) (xy 240.985294 -122.620786) (xy 240.991898 -122.62358) (xy 241.003587 -122.627054)
			(xy 241.027725 -122.623854) (xy 241.038126 -122.617484) (xy 241.062146 -122.601551) (xy 241.113968 -122.576318)
			(xy 241.168992 -122.559155) (xy 241.225969 -122.550452) (xy 241.254788 -122.54992) (xy 241.255042 -122.54992)
			(xy 241.282289 -122.550409) (xy 241.336228 -122.55817) (xy 241.388514 -122.573527) (xy 241.438082 -122.596169)
			(xy 241.483924 -122.625635) (xy 241.525106 -122.661323) (xy 241.560791 -122.702509) (xy 241.590251 -122.748354)
			(xy 241.612887 -122.797925) (xy 241.628239 -122.850213) (xy 241.635994 -122.904153) (xy 241.635994 -122.958647)
			(xy 241.628239 -123.012587) (xy 241.612887 -123.064875) (xy 241.590251 -123.114446) (xy 241.560791 -123.160291)
			(xy 241.525106 -123.201477) (xy 241.500833 -123.222512) (xy 244.109494 -123.222512) (xy 244.109966 -123.195259)
			(xy 244.117722 -123.141309) (xy 244.133076 -123.089011) (xy 244.155718 -123.039431) (xy 244.185185 -122.993577)
			(xy 244.220877 -122.952385) (xy 244.262069 -122.916691) (xy 244.307922 -122.887223) (xy 244.357501 -122.86458)
			(xy 244.409799 -122.849224) (xy 244.463749 -122.841467) (xy 244.491002 -122.841004) (xy 244.517875 -122.841529)
			(xy 244.571082 -122.849123) (xy 244.622698 -122.864106) (xy 244.671703 -122.886179) (xy 244.717127 -122.914908)
			(xy 244.758072 -122.949725) (xy 244.776244 -122.969528) (xy 244.77726 -122.970544) (xy 244.777514 -122.970798)
			(xy 244.785388 -122.979434) (xy 244.804946 -122.98807) (xy 244.815614 -122.98807) (xy 244.816122 -122.98807)
			(xy 244.891814 -122.988324) (xy 244.901887 -122.987926) (xy 244.920485 -122.980188) (xy 244.927882 -122.973338)
			(xy 244.930168 -122.971052) (xy 244.93093 -122.970036) (xy 244.949081 -122.950485) (xy 244.989918 -122.916157)
			(xy 245.035141 -122.887856) (xy 245.083867 -122.866134) (xy 245.135145 -122.851415) (xy 245.187974 -122.843986)
			(xy 245.214648 -122.843544) (xy 245.242018 -122.84403) (xy 245.296196 -122.851841) (xy 245.3487 -122.867325)
			(xy 245.398447 -122.890163) (xy 245.444414 -122.919884) (xy 245.465346 -122.937524) (xy 245.472458 -122.94362)
			(xy 245.489222 -122.94997) (xy 245.575074 -122.94997) (xy 245.591838 -122.94362) (xy 245.59895 -122.937524)
			(xy 245.619883 -122.919883) (xy 245.665851 -122.890159) (xy 245.715597 -122.867313) (xy 245.768099 -122.851817)
			(xy 245.822277 -122.843988) (xy 245.877019 -122.843988) (xy 245.931197 -122.851817) (xy 245.983699 -122.867313)
			(xy 246.033445 -122.890159) (xy 246.079413 -122.919883) (xy 246.100346 -122.937524) (xy 246.107458 -122.94362)
			(xy 246.124222 -122.94997) (xy 246.210074 -122.94997) (xy 246.226838 -122.94362) (xy 246.23395 -122.937524)
			(xy 246.246692 -122.92659) (xy 246.273784 -122.906751) (xy 246.288052 -122.8979) (xy 246.288306 -122.8979)
			(xy 246.29745 -122.892312) (xy 246.303546 -122.88393) (xy 246.306519 -122.879604) (xy 246.31074 -122.869994)
			(xy 246.311928 -122.86488) (xy 246.329708 -122.78233) (xy 246.325644 -122.761756) (xy 246.319548 -122.75312)
			(xy 246.303548 -122.729056) (xy 246.278207 -122.677124) (xy 246.260982 -122.621966) (xy 246.252266 -122.564842)
			(xy 246.25173 -122.53595) (xy 246.252216 -122.508699) (xy 246.259972 -122.454751) (xy 246.275327 -122.402456)
			(xy 246.297969 -122.352879) (xy 246.327435 -122.307029) (xy 246.363126 -122.265838) (xy 246.404317 -122.230147)
			(xy 246.450167 -122.200681) (xy 246.499744 -122.178039) (xy 246.552039 -122.162684) (xy 246.605987 -122.154928)
			(xy 246.660489 -122.154928) (xy 246.714437 -122.162684) (xy 246.766732 -122.178039) (xy 246.816309 -122.200681)
			(xy 246.862159 -122.230147) (xy 246.90335 -122.265838) (xy 246.939041 -122.307029) (xy 246.968507 -122.352879)
			(xy 246.991149 -122.402456) (xy 247.006504 -122.454751) (xy 247.01426 -122.508699) (xy 247.014746 -122.53595)
			(xy 247.014234 -122.564029) (xy 247.006026 -122.619583) (xy 246.989765 -122.673335) (xy 246.965802 -122.724123)
			(xy 246.934654 -122.770851) (xy 246.896995 -122.81251) (xy 246.853637 -122.8482) (xy 246.829834 -122.863102)
			(xy 246.82958 -122.863102) (xy 246.820436 -122.86869) (xy 246.81434 -122.877072) (xy 246.811375 -122.881403)
			(xy 246.807148 -122.89101) (xy 246.805958 -122.896122) (xy 246.788178 -122.978672) (xy 246.792242 -122.999246)
			(xy 246.798338 -123.007882) (xy 246.814337 -123.031946) (xy 246.839679 -123.083878) (xy 246.843788 -123.097036)
			(xy 248.676668 -123.097036) (xy 248.677139 -123.069666) (xy 248.684953 -123.015486) (xy 248.70044 -122.962982)
			(xy 248.723281 -122.913235) (xy 248.753006 -122.867269) (xy 248.770648 -122.846338) (xy 248.776744 -122.839226)
			(xy 248.783094 -122.822462) (xy 248.783094 -122.73661) (xy 248.776744 -122.719846) (xy 248.770648 -122.712734)
			(xy 248.753019 -122.691794) (xy 248.723304 -122.645824) (xy 248.700465 -122.596079) (xy 248.684972 -122.543579)
			(xy 248.677142 -122.489405) (xy 248.676668 -122.462036) (xy 248.677154 -122.434785) (xy 248.68491 -122.380837)
			(xy 248.700265 -122.328542) (xy 248.722907 -122.278965) (xy 248.752373 -122.233115) (xy 248.788064 -122.191924)
			(xy 248.829255 -122.156233) (xy 248.875105 -122.126767) (xy 248.924682 -122.104125) (xy 248.976977 -122.08877)
			(xy 249.030925 -122.081014) (xy 249.085427 -122.081014) (xy 249.139375 -122.08877) (xy 249.19167 -122.104125)
			(xy 249.241247 -122.126767) (xy 249.287097 -122.156233) (xy 249.328288 -122.191924) (xy 249.363979 -122.233115)
			(xy 249.393445 -122.278965) (xy 249.416087 -122.328542) (xy 249.431442 -122.380837) (xy 249.439198 -122.434785)
			(xy 249.439684 -122.462036) (xy 249.439243 -122.489407) (xy 249.43142 -122.543587) (xy 249.415925 -122.596091)
			(xy 249.393078 -122.645837) (xy 249.363348 -122.691803) (xy 249.345704 -122.712734) (xy 249.339608 -122.719846)
			(xy 249.333258 -122.73661) (xy 249.333258 -122.822462) (xy 249.339608 -122.839226) (xy 249.345704 -122.846338)
			(xy 249.363328 -122.867282) (xy 249.389029 -122.907044) (xy 251.562616 -122.907044) (xy 251.562616 -122.90679)
			(xy 251.563143 -122.875265) (xy 251.57182 -122.812815) (xy 251.588982 -122.752146) (xy 251.614304 -122.694404)
			(xy 251.647306 -122.640681) (xy 251.687366 -122.591993) (xy 251.71019 -122.57024) (xy 251.710444 -122.569986)
			(xy 251.717111 -122.56331) (xy 251.725322 -122.546335) (xy 251.726446 -122.536966) (xy 251.732034 -122.468386)
			(xy 251.732461 -122.458933) (xy 251.727099 -122.440797) (xy 251.72162 -122.43308) (xy 251.721112 -122.432572)
			(xy 251.720858 -122.432318) (xy 251.705403 -122.412017) (xy 251.67942 -122.368108) (xy 251.659515 -122.32113)
			(xy 251.646043 -122.27192) (xy 251.639244 -122.221354) (xy 251.638816 -122.195844) (xy 251.639304 -122.168475)
			(xy 251.647116 -122.114296) (xy 251.6626 -122.061793) (xy 251.685437 -122.012046) (xy 251.715157 -121.966078)
			(xy 251.732796 -121.945146) (xy 251.738892 -121.938034) (xy 251.745242 -121.92127) (xy 251.745242 -121.835418)
			(xy 251.738892 -121.818654) (xy 251.732796 -121.811542) (xy 251.7152 -121.790574) (xy 251.685475 -121.744611)
			(xy 251.662629 -121.694871) (xy 251.647131 -121.642374) (xy 251.639299 -121.588201) (xy 251.639294 -121.533465)
			(xy 251.647117 -121.47929) (xy 251.662606 -121.426791) (xy 251.685444 -121.377047) (xy 251.71516 -121.331079)
			(xy 251.732796 -121.310146) (xy 251.738892 -121.303034) (xy 251.745242 -121.28627) (xy 251.745242 -121.200418)
			(xy 251.738892 -121.183654) (xy 251.732796 -121.176542) (xy 251.715163 -121.155605) (xy 251.68545 -121.109634)
			(xy 251.662613 -121.059887) (xy 251.647121 -121.007388) (xy 251.639291 -120.953213) (xy 251.638816 -120.925844)
			(xy 251.639302 -120.898593) (xy 251.647058 -120.844645) (xy 251.662413 -120.79235) (xy 251.685055 -120.742773)
			(xy 251.714521 -120.696923) (xy 251.750212 -120.655732) (xy 251.791403 -120.620041) (xy 251.837253 -120.590575)
			(xy 251.88683 -120.567933) (xy 251.939125 -120.552578) (xy 251.993073 -120.544822) (xy 252.047575 -120.544822)
			(xy 252.101523 -120.552578) (xy 252.153818 -120.567933) (xy 252.203395 -120.590575) (xy 252.249245 -120.620041)
			(xy 252.290436 -120.655732) (xy 252.326127 -120.696923) (xy 252.355593 -120.742773) (xy 252.378235 -120.79235)
			(xy 252.39359 -120.844645) (xy 252.401346 -120.898593) (xy 252.401832 -120.925844) (xy 252.40135 -120.953214)
			(xy 252.393538 -121.007393) (xy 252.378054 -121.059896) (xy 252.355215 -121.109644) (xy 252.325493 -121.155611)
			(xy 252.307852 -121.176542) (xy 252.301756 -121.183654) (xy 252.295406 -121.200418) (xy 252.295406 -121.28627)
			(xy 252.301756 -121.303034) (xy 252.307852 -121.310146) (xy 252.325537 -121.331043) (xy 252.355261 -121.377017)
			(xy 252.378105 -121.426769) (xy 252.393599 -121.479276) (xy 252.401424 -121.53346) (xy 252.401419 -121.588206)
			(xy 252.393585 -121.642388) (xy 252.378082 -121.694893) (xy 252.355229 -121.744641) (xy 252.325497 -121.79061)
			(xy 252.307852 -121.811542) (xy 252.301756 -121.818654) (xy 252.295406 -121.835418) (xy 252.295406 -121.92127)
			(xy 252.301756 -121.938034) (xy 252.307852 -121.945146) (xy 252.325472 -121.966094) (xy 252.355188 -122.012062)
			(xy 252.378029 -122.061805) (xy 252.393524 -122.114302) (xy 252.401356 -122.168476) (xy 252.401832 -122.195844)
			(xy 252.401416 -122.221356) (xy 252.394625 -122.271925) (xy 252.381156 -122.321139) (xy 252.361249 -122.368119)
			(xy 252.33526 -122.412027) (xy 252.31979 -122.432318) (xy 252.319536 -122.432572) (xy 252.319028 -122.43308)
			(xy 252.313514 -122.440775) (xy 252.30818 -122.458928) (xy 252.308614 -122.468386) (xy 252.314202 -122.536966)
			(xy 252.315412 -122.54631) (xy 252.323616 -122.563251) (xy 252.330204 -122.569986) (xy 252.330458 -122.57024)
			(xy 252.353312 -122.591965) (xy 252.393388 -122.640647) (xy 252.426398 -122.694372) (xy 252.451716 -122.752122)
			(xy 252.468862 -122.812802) (xy 252.47751 -122.875262) (xy 252.478032 -122.90679) (xy 252.478032 -122.907044)
			(xy 252.477542 -122.937012) (xy 252.469719 -122.996434) (xy 252.454206 -123.054327) (xy 252.43127 -123.1097)
			(xy 252.401303 -123.161606) (xy 252.364816 -123.209156) (xy 252.322436 -123.251536) (xy 252.274886 -123.288023)
			(xy 252.22298 -123.31799) (xy 252.167607 -123.340926) (xy 252.109714 -123.356439) (xy 252.050292 -123.364262)
			(xy 251.990356 -123.364262) (xy 251.930934 -123.356439) (xy 251.873041 -123.340926) (xy 251.817668 -123.31799)
			(xy 251.765762 -123.288023) (xy 251.718212 -123.251536) (xy 251.675832 -123.209156) (xy 251.639345 -123.161606)
			(xy 251.609378 -123.1097) (xy 251.586442 -123.054327) (xy 251.570929 -122.996434) (xy 251.563106 -122.937012)
			(xy 251.562616 -122.907044) (xy 249.389029 -122.907044) (xy 249.393042 -122.913252) (xy 249.415881 -122.962996)
			(xy 249.431375 -123.015494) (xy 249.439208 -123.069668) (xy 249.439684 -123.097036) (xy 249.439198 -123.124287)
			(xy 249.431442 -123.178235) (xy 249.416087 -123.23053) (xy 249.393445 -123.280107) (xy 249.363979 -123.325957)
			(xy 249.328288 -123.367148) (xy 249.287097 -123.402839) (xy 249.241247 -123.432305) (xy 249.19167 -123.454947)
			(xy 249.139375 -123.470302) (xy 249.085427 -123.478058) (xy 249.030925 -123.478058) (xy 248.976977 -123.470302)
			(xy 248.924682 -123.454947) (xy 248.875105 -123.432305) (xy 248.829255 -123.402839) (xy 248.788064 -123.367148)
			(xy 248.752373 -123.325957) (xy 248.722907 -123.280107) (xy 248.700265 -123.23053) (xy 248.68491 -123.178235)
			(xy 248.677154 -123.124287) (xy 248.676668 -123.097036) (xy 246.843788 -123.097036) (xy 246.856905 -123.139036)
			(xy 246.865621 -123.19616) (xy 246.866156 -123.225052) (xy 246.865577 -123.2523) (xy 246.857829 -123.306242)
			(xy 246.842482 -123.358532) (xy 246.81985 -123.408106) (xy 246.790393 -123.453954) (xy 246.754711 -123.495143)
			(xy 246.713531 -123.530836) (xy 246.66769 -123.560304) (xy 246.618122 -123.582948) (xy 246.565836 -123.598308)
			(xy 246.511896 -123.60607) (xy 246.484648 -123.60656) (xy 246.457278 -123.606076) (xy 246.4031 -123.598264)
			(xy 246.350596 -123.582779) (xy 246.300849 -123.559942) (xy 246.254882 -123.53022) (xy 246.23395 -123.51258)
			(xy 246.226838 -123.506484) (xy 246.210074 -123.500134) (xy 246.124222 -123.500134) (xy 246.107458 -123.506484)
			(xy 246.100346 -123.51258) (xy 246.079413 -123.530221) (xy 246.033445 -123.559945) (xy 245.983699 -123.582791)
			(xy 245.931197 -123.598287) (xy 245.877019 -123.606116) (xy 245.822277 -123.606116) (xy 245.768099 -123.598287)
			(xy 245.715597 -123.582791) (xy 245.665851 -123.559945) (xy 245.619883 -123.530221) (xy 245.59895 -123.51258)
			(xy 245.591838 -123.506484) (xy 245.575074 -123.500134) (xy 245.489222 -123.500134) (xy 245.472458 -123.506484)
			(xy 245.465346 -123.51258) (xy 245.444405 -123.530208) (xy 245.398435 -123.559922) (xy 245.34869 -123.582761)
			(xy 245.296191 -123.598254) (xy 245.242017 -123.606085) (xy 245.214648 -123.60656) (xy 245.187773 -123.606081)
			(xy 245.134564 -123.598479) (xy 245.082946 -123.583488) (xy 245.033941 -123.561406) (xy 244.988519 -123.532668)
			(xy 244.947576 -123.497844) (xy 244.929406 -123.478036) (xy 244.92839 -123.47702) (xy 244.928136 -123.476766)
			(xy 244.920262 -123.46813) (xy 244.900704 -123.459494) (xy 244.890036 -123.459494) (xy 244.889528 -123.459494)
			(xy 244.813836 -123.45924) (xy 244.803767 -123.459674) (xy 244.785169 -123.467388) (xy 244.777768 -123.474226)
			(xy 244.775482 -123.476512) (xy 244.77472 -123.477528) (xy 244.756537 -123.497048) (xy 244.715707 -123.53138)
			(xy 244.670491 -123.559686) (xy 244.621772 -123.581413) (xy 244.570499 -123.596139) (xy 244.517675 -123.603574)
			(xy 244.491002 -123.60402) (xy 244.463751 -123.60352) (xy 244.409805 -123.595764) (xy 244.357511 -123.58041)
			(xy 244.307935 -123.55777) (xy 244.262085 -123.528305) (xy 244.220895 -123.492615) (xy 244.185203 -123.451427)
			(xy 244.155737 -123.405578) (xy 244.133095 -123.356002) (xy 244.117739 -123.303709) (xy 244.109981 -123.249763)
			(xy 244.109494 -123.222512) (xy 241.500833 -123.222512) (xy 241.483924 -123.237165) (xy 241.438082 -123.266631)
			(xy 241.388514 -123.289273) (xy 241.336228 -123.30463) (xy 241.282289 -123.312391) (xy 241.255042 -123.312936)
			(xy 241.254788 -123.312936) (xy 241.225967 -123.312413) (xy 241.168981 -123.303739) (xy 241.113953 -123.286577)
			(xy 241.06214 -123.261317) (xy 241.038126 -123.245372) (xy 241.02773 -123.239001) (xy 241.003591 -123.23582)
			(xy 240.991898 -123.239276) (xy 240.985294 -123.24207) (xy 240.906046 -123.28398) (xy 240.8936 -123.290584)
			(xy 240.878868 -123.314714) (xy 240.878868 -123.549918) (xy 240.879271 -123.559146) (xy 240.885825 -123.5764)
			(xy 240.898074 -123.590207) (xy 240.906046 -123.594876) (xy 240.985294 -123.636786) (xy 240.991898 -123.63958)
			(xy 241.003587 -123.643054) (xy 241.027725 -123.639854) (xy 241.038126 -123.633484) (xy 241.062146 -123.617551)
			(xy 241.113968 -123.592318) (xy 241.168992 -123.575155) (xy 241.225969 -123.566452) (xy 241.254788 -123.56592)
			(xy 241.255042 -123.56592) (xy 241.282289 -123.566409) (xy 241.336228 -123.57417) (xy 241.388514 -123.589527)
			(xy 241.438082 -123.612169) (xy 241.483924 -123.641635) (xy 241.525106 -123.677323) (xy 241.560791 -123.718509)
			(xy 241.590251 -123.764354) (xy 241.612887 -123.813925) (xy 241.628239 -123.866213) (xy 241.635994 -123.920153)
			(xy 241.635994 -123.974647) (xy 241.628239 -124.028587) (xy 241.612887 -124.080875) (xy 241.590251 -124.130446)
			(xy 241.560791 -124.176291) (xy 241.525106 -124.217477) (xy 241.483924 -124.253165) (xy 241.438082 -124.282631)
			(xy 241.388514 -124.305273) (xy 241.336228 -124.32063) (xy 241.282289 -124.328391) (xy 241.255042 -124.328936)
			(xy 241.254788 -124.328936) (xy 241.225967 -124.328413) (xy 241.168981 -124.319739) (xy 241.113953 -124.302577)
			(xy 241.06214 -124.277317) (xy 241.038126 -124.261372) (xy 241.02773 -124.255001) (xy 241.003591 -124.25182)
			(xy 240.991898 -124.255276) (xy 240.985294 -124.25807) (xy 240.906046 -124.29998) (xy 240.8936 -124.306584)
			(xy 240.878868 -124.330714) (xy 240.878868 -124.565918) (xy 240.879271 -124.575146) (xy 240.885825 -124.5924)
			(xy 240.898074 -124.606207) (xy 240.906046 -124.610876) (xy 240.985294 -124.652786) (xy 240.991898 -124.65558)
			(xy 241.003587 -124.659054) (xy 241.027725 -124.655854) (xy 241.038126 -124.649484) (xy 241.062146 -124.633551)
			(xy 241.113968 -124.608318) (xy 241.168992 -124.591155) (xy 241.225969 -124.582452) (xy 241.254788 -124.58192)
			(xy 241.255042 -124.58192) (xy 241.282289 -124.582409) (xy 241.336228 -124.59017) (xy 241.388514 -124.605527)
			(xy 241.438082 -124.628169) (xy 241.483924 -124.657635) (xy 241.525106 -124.693323) (xy 241.560791 -124.734509)
			(xy 241.590251 -124.780354) (xy 241.612887 -124.829925) (xy 241.628239 -124.882213) (xy 241.635994 -124.936153)
			(xy 241.635994 -124.990647) (xy 241.628239 -125.044587) (xy 241.615522 -125.0879) (xy 242.906024 -125.0879)
			(xy 242.906024 -125.027932) (xy 242.913852 -124.968476) (xy 242.929373 -124.910551) (xy 242.952322 -124.855147)
			(xy 242.982306 -124.803213) (xy 243.018812 -124.755637) (xy 243.061217 -124.713232) (xy 243.108793 -124.676726)
			(xy 243.160727 -124.646742) (xy 243.216131 -124.623793) (xy 243.274056 -124.608272) (xy 243.333512 -124.600444)
			(xy 243.39348 -124.600444) (xy 243.452936 -124.608272) (xy 243.510861 -124.623793) (xy 243.566265 -124.646742)
			(xy 243.618199 -124.676726) (xy 243.665775 -124.713232) (xy 243.70818 -124.755637) (xy 243.744686 -124.803213)
			(xy 243.77467 -124.855147) (xy 243.797619 -124.910551) (xy 243.81314 -124.968476) (xy 243.820968 -125.027932)
			(xy 243.821458 -125.057916) (xy 243.820968 -125.0879) (xy 243.81314 -125.147356) (xy 243.797619 -125.205281)
			(xy 243.77467 -125.260685) (xy 243.744686 -125.312619) (xy 243.70818 -125.360195) (xy 243.665775 -125.4026)
			(xy 243.618199 -125.439106) (xy 243.566265 -125.46909) (xy 243.510861 -125.492039) (xy 243.452936 -125.50756)
			(xy 243.39348 -125.515388) (xy 243.333512 -125.515388) (xy 243.274056 -125.50756) (xy 243.216131 -125.492039)
			(xy 243.160727 -125.46909) (xy 243.108793 -125.439106) (xy 243.061217 -125.4026) (xy 243.018812 -125.360195)
			(xy 242.982306 -125.312619) (xy 242.952322 -125.260685) (xy 242.929373 -125.205281) (xy 242.913852 -125.147356)
			(xy 242.906024 -125.0879) (xy 241.615522 -125.0879) (xy 241.612887 -125.096875) (xy 241.590251 -125.146446)
			(xy 241.560791 -125.192291) (xy 241.525106 -125.233477) (xy 241.483924 -125.269165) (xy 241.438082 -125.298631)
			(xy 241.388514 -125.321273) (xy 241.336228 -125.33663) (xy 241.282289 -125.344391) (xy 241.255042 -125.344936)
			(xy 241.254788 -125.344936) (xy 241.225967 -125.344413) (xy 241.168981 -125.335739) (xy 241.113953 -125.318577)
			(xy 241.06214 -125.293317) (xy 241.038126 -125.277372) (xy 241.02773 -125.271001) (xy 241.003591 -125.26782)
			(xy 240.991898 -125.271276) (xy 240.985294 -125.27407) (xy 240.906046 -125.31598) (xy 240.8936 -125.322584)
			(xy 240.878868 -125.346714) (xy 240.878868 -126.137428) (xy 243.280928 -126.137428) (xy 243.280928 -126.07746)
			(xy 243.288756 -126.018004) (xy 243.304277 -125.960079) (xy 243.327226 -125.904675) (xy 243.35721 -125.852741)
			(xy 243.393716 -125.805165) (xy 243.436121 -125.76276) (xy 243.483697 -125.726254) (xy 243.535631 -125.69627)
			(xy 243.591035 -125.673321) (xy 243.64896 -125.6578) (xy 243.708416 -125.649972) (xy 243.768384 -125.649972)
			(xy 243.82784 -125.6578) (xy 243.885765 -125.673321) (xy 243.941169 -125.69627) (xy 243.993103 -125.726254)
			(xy 244.040679 -125.76276) (xy 244.083084 -125.805165) (xy 244.11959 -125.852741) (xy 244.149574 -125.904675)
			(xy 244.172523 -125.960079) (xy 244.188044 -126.018004) (xy 244.195872 -126.07746) (xy 244.196362 -126.107444)
			(xy 244.195872 -126.137428) (xy 244.188044 -126.196884) (xy 244.172523 -126.254809) (xy 244.149574 -126.310213)
			(xy 244.11959 -126.362147) (xy 244.083084 -126.409723) (xy 244.040679 -126.452128) (xy 243.993103 -126.488634)
			(xy 243.941169 -126.518618) (xy 243.885765 -126.541567) (xy 243.82784 -126.557088) (xy 243.768384 -126.564916)
			(xy 243.708416 -126.564916) (xy 243.64896 -126.557088) (xy 243.591035 -126.541567) (xy 243.535631 -126.518618)
			(xy 243.483697 -126.488634) (xy 243.436121 -126.452128) (xy 243.393716 -126.409723) (xy 243.35721 -126.362147)
			(xy 243.327226 -126.310213) (xy 243.304277 -126.254809) (xy 243.288756 -126.196884) (xy 243.280928 -126.137428)
			(xy 240.878868 -126.137428) (xy 240.878868 -126.597918) (xy 240.879271 -126.607146) (xy 240.885825 -126.6244)
			(xy 240.898074 -126.638207) (xy 240.906046 -126.642876) (xy 240.985294 -126.684786) (xy 240.991898 -126.68758)
			(xy 241.003587 -126.691054) (xy 241.027725 -126.687854) (xy 241.038126 -126.681484) (xy 241.062146 -126.665551)
			(xy 241.113968 -126.640318) (xy 241.168992 -126.623155) (xy 241.225969 -126.614452) (xy 241.254788 -126.61392)
			(xy 241.255042 -126.61392) (xy 241.282289 -126.614409) (xy 241.336228 -126.62217) (xy 241.388514 -126.637527)
			(xy 241.438082 -126.660169) (xy 241.483924 -126.689635) (xy 241.525106 -126.725323) (xy 241.560791 -126.766509)
			(xy 241.590251 -126.812354) (xy 241.612887 -126.861925) (xy 241.628239 -126.914213) (xy 241.635994 -126.968153)
			(xy 241.635994 -127.022647) (xy 241.628239 -127.076587) (xy 241.626862 -127.081276) (xy 242.86894 -127.081276)
			(xy 242.86894 -127.02134) (xy 242.876763 -126.961918) (xy 242.892276 -126.904025) (xy 242.915212 -126.848652)
			(xy 242.945179 -126.796746) (xy 242.981666 -126.749196) (xy 243.024046 -126.706816) (xy 243.071596 -126.670329)
			(xy 243.123502 -126.640362) (xy 243.178875 -126.617426) (xy 243.236768 -126.601913) (xy 243.29619 -126.59409)
			(xy 243.356126 -126.59409) (xy 243.415548 -126.601913) (xy 243.473441 -126.617426) (xy 243.528814 -126.640362)
			(xy 243.58072 -126.670329) (xy 243.62827 -126.706816) (xy 243.67065 -126.749196) (xy 243.707137 -126.796746)
			(xy 243.737104 -126.848652) (xy 243.76004 -126.904025) (xy 243.775553 -126.961918) (xy 243.783376 -127.02134)
			(xy 243.783384 -127.021844) (xy 246.974104 -127.021844) (xy 246.978175 -126.966222) (xy 246.990301 -126.911785)
			(xy 247.010224 -126.859694) (xy 247.03752 -126.811059) (xy 247.071606 -126.766916) (xy 247.111755 -126.728207)
			(xy 247.157113 -126.695756) (xy 247.206713 -126.670255) (xy 247.259497 -126.652248) (xy 247.31434 -126.642118)
			(xy 247.370074 -126.640081) (xy 247.425511 -126.646181) (xy 247.479468 -126.660287) (xy 247.530797 -126.682099)
			(xy 247.578403 -126.711153) (xy 247.621271 -126.746828) (xy 247.658488 -126.788365) (xy 247.689261 -126.834878)
			(xy 247.712933 -126.885375) (xy 247.729001 -126.938782) (xy 247.737121 -126.993958) (xy 247.73763 -127.021844)
			(xy 247.737121 -127.04973) (xy 247.729001 -127.104906) (xy 247.712933 -127.158313) (xy 247.689261 -127.20881)
			(xy 247.658488 -127.255323) (xy 247.621271 -127.29686) (xy 247.578403 -127.332535) (xy 247.530797 -127.361589)
			(xy 247.479468 -127.383401) (xy 247.425511 -127.397507) (xy 247.370074 -127.403607) (xy 247.31434 -127.40157)
			(xy 247.259497 -127.39144) (xy 247.206713 -127.373433) (xy 247.157113 -127.347932) (xy 247.111755 -127.315481)
			(xy 247.071606 -127.276772) (xy 247.03752 -127.232629) (xy 247.010224 -127.183994) (xy 246.990301 -127.131903)
			(xy 246.978175 -127.077466) (xy 246.974104 -127.021844) (xy 243.783384 -127.021844) (xy 243.783866 -127.051308)
			(xy 243.783376 -127.081276) (xy 243.775553 -127.140698) (xy 243.76004 -127.198591) (xy 243.737104 -127.253964)
			(xy 243.707137 -127.30587) (xy 243.67065 -127.35342) (xy 243.62827 -127.3958) (xy 243.58072 -127.432287)
			(xy 243.528814 -127.462254) (xy 243.473441 -127.48519) (xy 243.415548 -127.500703) (xy 243.356126 -127.508526)
			(xy 243.29619 -127.508526) (xy 243.236768 -127.500703) (xy 243.178875 -127.48519) (xy 243.123502 -127.462254)
			(xy 243.071596 -127.432287) (xy 243.024046 -127.3958) (xy 242.981666 -127.35342) (xy 242.945179 -127.30587)
			(xy 242.915212 -127.253964) (xy 242.892276 -127.198591) (xy 242.876763 -127.140698) (xy 242.86894 -127.081276)
			(xy 241.626862 -127.081276) (xy 241.612887 -127.128875) (xy 241.590251 -127.178446) (xy 241.560791 -127.224291)
			(xy 241.525106 -127.265477) (xy 241.483924 -127.301165) (xy 241.438082 -127.330631) (xy 241.388514 -127.353273)
			(xy 241.336228 -127.36863) (xy 241.282289 -127.376391) (xy 241.255042 -127.376936) (xy 241.253772 -127.376936)
			(xy 241.243781 -127.377438) (xy 241.225317 -127.385083) (xy 241.211146 -127.399174) (xy 241.206782 -127.408178)
			(xy 241.170714 -127.495046) (xy 241.167239 -127.504458) (xy 241.167192 -127.524507) (xy 241.174837 -127.543041)
			(xy 241.181636 -127.550418) (xy 241.232436 -127.601218) (xy 241.239832 -127.608068) (xy 241.258432 -127.615802)
			(xy 241.268504 -127.616204) (xy 253.287022 -127.616204) (xy 253.29709 -127.616631) (xy 253.315689 -127.624352)
			(xy 253.32309 -127.63119) (xy 253.62408 -127.93218) (xy 253.630916 -127.939582) (xy 253.638624 -127.95818)
			(xy 253.639066 -127.968248) (xy 253.639066 -134.203694) (xy 253.646686 -134.22249) (xy 253.654052 -134.229602)
			(xy 259.405882 -139.981432) (xy 259.413282 -139.988273) (xy 259.431881 -139.995988) (xy 259.44195 -139.996418)
			(xy 272.990056 -139.996418) (xy 273.000121 -139.996852) (xy 273.018709 -140.004583) (xy 273.026124 -140.011404)
			(xy 275.105876 -142.091156) (xy 275.112988 -142.098522) (xy 275.131784 -142.106142)
		)
		(stroke
			(width 0)
			(type solid)
		)
		(fill yes)
		(layer "B.Cu")
		(net "P3V3_NIC4")
	)
	(gr_poly
		(pts
			(xy 394.168884 -142.106142) (xy 394.178846 -142.105654) (xy 394.197269 -142.098066) (xy 394.204698 -142.09141)
			(xy 394.231114 -142.065248) (xy 394.266674 -142.029688) (xy 394.27168 -142.023562) (xy 394.278014 -142.009074)
			(xy 394.27912 -142.00124) (xy 394.27912 -139.559284) (xy 394.278736 -139.550453) (xy 394.272754 -139.533833)
			(xy 394.267436 -139.526772) (xy 394.265912 -139.524994) (xy 394.225018 -139.4841) (xy 394.217906 -139.476734)
			(xy 394.19911 -139.469114) (xy 392.726926 -139.469114) (xy 392.716861 -139.468678) (xy 392.698275 -139.460946)
			(xy 392.690858 -139.454128) (xy 390.672828 -137.436098) (xy 390.665716 -137.428732) (xy 390.64692 -137.421112)
			(xy 383.060956 -137.421112) (xy 383.050889 -137.420681) (xy 383.032295 -137.412957) (xy 383.024888 -137.406126)
			(xy 379.579632 -133.96087) (xy 379.572787 -133.953471) (xy 379.565058 -133.934873) (xy 379.564646 -133.924802)
			(xy 379.564646 -120.604534) (xy 379.564209 -120.59447) (xy 379.556472 -120.575888) (xy 379.54966 -120.568466)
			(xy 374.304814 -115.32362) (xy 374.297702 -115.316254) (xy 374.278906 -115.308634) (xy 362.668312 -115.308634)
			(xy 362.663143 -115.30882) (xy 362.653035 -115.310998) (xy 362.648246 -115.312952) (xy 362.639356 -115.316762)
			(xy 362.57484 -115.380262) (xy 362.56722 -115.398296) (xy 362.566966 -115.408456) (xy 362.566079 -115.435146)
			(xy 362.557755 -115.487896) (xy 362.542146 -115.538966) (xy 362.51956 -115.587357) (xy 362.490438 -115.632119)
			(xy 362.47324 -115.65255) (xy 362.472986 -115.652804) (xy 362.472732 -115.653058) (xy 362.467138 -115.660142)
			(xy 362.460878 -115.677059) (xy 362.46054 -115.686078) (xy 362.46054 -115.753134) (xy 362.460904 -115.762149)
			(xy 362.467154 -115.779062) (xy 362.472732 -115.786154) (xy 362.472986 -115.786408) (xy 362.47324 -115.786662)
			(xy 362.49084 -115.807584) (xy 362.520491 -115.853517) (xy 362.543278 -115.903214) (xy 362.558734 -115.955656)
			(xy 362.566542 -116.009768) (xy 362.566541 -116.064441) (xy 362.558732 -116.118552) (xy 362.543275 -116.170994)
			(xy 362.520487 -116.220691) (xy 362.490834 -116.266623) (xy 362.47324 -116.28755) (xy 362.472986 -116.287804)
			(xy 362.472732 -116.288058) (xy 362.467138 -116.295142) (xy 362.460878 -116.312059) (xy 362.46054 -116.321078)
			(xy 362.46054 -116.388134) (xy 362.460904 -116.397149) (xy 362.467154 -116.414062) (xy 362.472732 -116.421154)
			(xy 362.472986 -116.421408) (xy 362.47324 -116.421662) (xy 362.490828 -116.44259) (xy 362.520456 -116.48853)
			(xy 362.543226 -116.538228) (xy 362.558669 -116.590667) (xy 362.56647 -116.644773) (xy 362.566966 -116.672106)
			(xy 362.566585 -116.696449) (xy 362.564808 -116.710202) (xy 363.375938 -116.710202) (xy 363.375938 -116.650266)
			(xy 363.383761 -116.590844) (xy 363.399274 -116.532951) (xy 363.42221 -116.477578) (xy 363.452177 -116.425672)
			(xy 363.488664 -116.378122) (xy 363.531044 -116.335742) (xy 363.578594 -116.299255) (xy 363.6305 -116.269288)
			(xy 363.685873 -116.246352) (xy 363.743766 -116.230839) (xy 363.803188 -116.223016) (xy 363.863124 -116.223016)
			(xy 363.922546 -116.230839) (xy 363.980439 -116.246352) (xy 364.035812 -116.269288) (xy 364.087718 -116.299255)
			(xy 364.135268 -116.335742) (xy 364.177648 -116.378122) (xy 364.214135 -116.425672) (xy 364.244102 -116.477578)
			(xy 364.267038 -116.532951) (xy 364.282551 -116.590844) (xy 364.290374 -116.650266) (xy 364.290864 -116.680234)
			(xy 364.290374 -116.710202) (xy 364.282551 -116.769624) (xy 364.267038 -116.827517) (xy 364.244102 -116.88289)
			(xy 364.214135 -116.934796) (xy 364.177648 -116.982346) (xy 364.135268 -117.024726) (xy 364.087718 -117.061213)
			(xy 364.035812 -117.09118) (xy 363.980439 -117.114116) (xy 363.922546 -117.129629) (xy 363.863124 -117.137452)
			(xy 363.803188 -117.137452) (xy 363.743766 -117.129629) (xy 363.685873 -117.114116) (xy 363.6305 -117.09118)
			(xy 363.578594 -117.061213) (xy 363.531044 -117.024726) (xy 363.488664 -116.982346) (xy 363.452177 -116.934796)
			(xy 363.42221 -116.88289) (xy 363.399274 -116.827517) (xy 363.383761 -116.769624) (xy 363.375938 -116.710202)
			(xy 362.564808 -116.710202) (xy 362.560345 -116.744733) (xy 362.55452 -116.768372) (xy 362.552291 -116.77897)
			(xy 362.555961 -116.800295) (xy 362.561632 -116.80952) (xy 362.604304 -116.87302) (xy 362.610709 -116.881712)
			(xy 362.628993 -116.893157) (xy 362.63961 -116.895118) (xy 362.639864 -116.895118) (xy 362.669558 -116.899451)
			(xy 362.727546 -116.914892) (xy 362.783019 -116.937779) (xy 362.835026 -116.96772) (xy 362.882674 -117.0042)
			(xy 362.925145 -117.046594) (xy 362.961713 -117.094174) (xy 362.991749 -117.146126) (xy 363.014738 -117.201557)
			(xy 363.030285 -117.259517) (xy 363.038126 -117.319011) (xy 363.038346 -117.33174) (xy 364.523002 -117.33174)
			(xy 364.523002 -117.271804) (xy 364.530825 -117.212382) (xy 364.546338 -117.154489) (xy 364.569274 -117.099116)
			(xy 364.599241 -117.04721) (xy 364.635728 -116.99966) (xy 364.678108 -116.95728) (xy 364.725658 -116.920793)
			(xy 364.777564 -116.890826) (xy 364.832937 -116.86789) (xy 364.89083 -116.852377) (xy 364.950252 -116.844554)
			(xy 365.010188 -116.844554) (xy 365.06961 -116.852377) (xy 365.127503 -116.86789) (xy 365.182876 -116.890826)
			(xy 365.234782 -116.920793) (xy 365.282332 -116.95728) (xy 365.324712 -116.99966) (xy 365.361199 -117.04721)
			(xy 365.391166 -117.099116) (xy 365.414102 -117.154489) (xy 365.429615 -117.212382) (xy 365.437438 -117.271804)
			(xy 365.437928 -117.301772) (xy 365.437438 -117.33174) (xy 365.429615 -117.391162) (xy 365.414102 -117.449055)
			(xy 365.391166 -117.504428) (xy 365.361199 -117.556334) (xy 365.324712 -117.603884) (xy 365.282332 -117.646264)
			(xy 365.234782 -117.682751) (xy 365.182876 -117.712718) (xy 365.127503 -117.735654) (xy 365.06961 -117.751167)
			(xy 365.010188 -117.75899) (xy 364.950252 -117.75899) (xy 364.89083 -117.751167) (xy 364.832937 -117.735654)
			(xy 364.777564 -117.712718) (xy 364.725658 -117.682751) (xy 364.678108 -117.646264) (xy 364.635728 -117.603884)
			(xy 364.599241 -117.556334) (xy 364.569274 -117.504428) (xy 364.546338 -117.449055) (xy 364.530825 -117.391162)
			(xy 364.523002 -117.33174) (xy 363.038346 -117.33174) (xy 363.038644 -117.349016) (xy 363.038154 -117.378984)
			(xy 363.030331 -117.438406) (xy 363.014818 -117.496299) (xy 362.991882 -117.551672) (xy 362.961915 -117.603578)
			(xy 362.925428 -117.651128) (xy 362.883048 -117.693508) (xy 362.835498 -117.729995) (xy 362.783592 -117.759962)
			(xy 362.728219 -117.782898) (xy 362.670326 -117.798411) (xy 362.610904 -117.806234) (xy 362.550968 -117.806234)
			(xy 362.491546 -117.798411) (xy 362.433653 -117.782898) (xy 362.37828 -117.759962) (xy 362.326374 -117.729995)
			(xy 362.278824 -117.693508) (xy 362.236444 -117.651128) (xy 362.199957 -117.603578) (xy 362.16999 -117.551672)
			(xy 362.147054 -117.496299) (xy 362.131541 -117.438406) (xy 362.123718 -117.378984) (xy 362.123228 -117.349016)
			(xy 362.123228 -117.348254) (xy 362.123736 -117.319084) (xy 362.131236 -117.261227) (xy 362.146008 -117.204787)
			(xy 362.156502 -117.177566) (xy 362.156502 -117.177312) (xy 362.156756 -117.17655) (xy 362.160076 -117.166422)
			(xy 362.15901 -117.145162) (xy 362.154724 -117.135402) (xy 362.120688 -117.06733) (xy 362.118144 -117.062704)
			(xy 362.111488 -117.054511) (xy 362.10748 -117.051074) (xy 362.09859 -117.043708) (xy 362.087668 -117.040914)
			(xy 362.0597 -117.032889) (xy 362.006409 -117.009535) (xy 361.957281 -116.978363) (xy 361.935014 -116.959634)
			(xy 361.934506 -116.95938) (xy 361.927419 -116.953796) (xy 361.910502 -116.947554) (xy 361.901486 -116.947188)
			(xy 361.83443 -116.947188) (xy 361.825411 -116.947542) (xy 361.808488 -116.953781) (xy 361.80141 -116.95938)
			(xy 361.801156 -116.959634) (xy 361.780223 -116.977272) (xy 361.734255 -117.00699) (xy 361.684508 -117.029826)
			(xy 361.632005 -117.045308) (xy 361.577827 -117.05312) (xy 361.550458 -117.053614) (xy 361.523209 -117.053125)
			(xy 361.469265 -117.045364) (xy 361.416975 -117.030005) (xy 361.367403 -117.007362) (xy 361.321557 -116.977895)
			(xy 361.280371 -116.942203) (xy 361.244684 -116.901014) (xy 361.215221 -116.855166) (xy 361.192582 -116.805591)
			(xy 361.177228 -116.7533) (xy 361.169472 -116.699355) (xy 361.16895 -116.672106) (xy 361.169419 -116.644772)
			(xy 361.177222 -116.590663) (xy 361.19267 -116.538223) (xy 361.215447 -116.488525) (xy 361.245084 -116.442588)
			(xy 361.262676 -116.421662) (xy 361.26293 -116.421408) (xy 361.263184 -116.421154) (xy 361.268779 -116.41407)
			(xy 361.27504 -116.397153) (xy 361.275376 -116.388134) (xy 361.275376 -116.321078) (xy 361.275012 -116.312063)
			(xy 361.268757 -116.295154) (xy 361.263184 -116.288058) (xy 361.26293 -116.287804) (xy 361.262676 -116.28755)
			(xy 361.245075 -116.266628) (xy 361.215421 -116.220695) (xy 361.192631 -116.170998) (xy 361.177172 -116.118555)
			(xy 361.169363 -116.064441) (xy 361.169362 -116.009768) (xy 361.17717 -115.955654) (xy 361.192627 -115.903211)
			(xy 361.215416 -115.853513) (xy 361.245069 -115.807579) (xy 361.262676 -115.786662) (xy 361.26293 -115.786408)
			(xy 361.263184 -115.786154) (xy 361.268779 -115.77907) (xy 361.27504 -115.762153) (xy 361.275376 -115.753134)
			(xy 361.275376 -115.686078) (xy 361.275012 -115.677063) (xy 361.268757 -115.660154) (xy 361.263184 -115.653058)
			(xy 361.26293 -115.652804) (xy 361.262676 -115.65255) (xy 361.245487 -115.632115) (xy 361.21639 -115.587339)
			(xy 361.193812 -115.538949) (xy 361.178192 -115.487885) (xy 361.169836 -115.435144) (xy 361.16895 -115.408456)
			(xy 361.168696 -115.398296) (xy 361.161076 -115.380262) (xy 361.103418 -115.323366) (xy 361.099985 -115.32016)
			(xy 361.092188 -115.314923) (xy 361.087924 -115.312952) (xy 361.078018 -115.308634) (xy 361.06735 -115.308634)
			(xy 360.51617 -115.308634) (xy 360.49204 -115.323366) (xy 360.485436 -115.336066) (xy 360.437176 -115.428776)
			(xy 360.438954 -115.45697) (xy 360.447336 -115.468654) (xy 360.463765 -115.4929) (xy 360.489782 -115.54537)
			(xy 360.50747 -115.601202) (xy 360.516415 -115.659081) (xy 360.516932 -115.688364) (xy 360.516446 -115.715615)
			(xy 360.50869 -115.769563) (xy 360.493335 -115.821858) (xy 360.470693 -115.871435) (xy 360.441227 -115.917285)
			(xy 360.405536 -115.958476) (xy 360.364345 -115.994167) (xy 360.318495 -116.023633) (xy 360.268918 -116.046275)
			(xy 360.216623 -116.06163) (xy 360.162675 -116.069386) (xy 360.108173 -116.069386) (xy 360.054225 -116.06163)
			(xy 360.00193 -116.046275) (xy 359.952353 -116.023633) (xy 359.906503 -115.994167) (xy 359.865312 -115.958476)
			(xy 359.829621 -115.917285) (xy 359.800155 -115.871435) (xy 359.777513 -115.821858) (xy 359.762158 -115.769563)
			(xy 359.754402 -115.715615) (xy 359.753916 -115.688364) (xy 359.754452 -115.659082) (xy 359.763403 -115.601207)
			(xy 359.781089 -115.545379) (xy 359.807095 -115.492906) (xy 359.823512 -115.468654) (xy 359.828481 -115.461042)
			(xy 359.833195 -115.443499) (xy 359.831484 -115.425414) (xy 359.82783 -115.417092) (xy 359.827068 -115.415822)
			(xy 359.785412 -115.336066) (xy 359.778808 -115.323366) (xy 359.754678 -115.308634) (xy 358.145842 -115.308634)
			(xy 358.135777 -115.309068) (xy 358.117191 -115.316801) (xy 358.109774 -115.32362) (xy 356.993952 -116.439442)
			(xy 356.986586 -116.446554) (xy 356.978966 -116.46535) (xy 356.978966 -117.357394) (xy 357.912144 -117.357394)
			(xy 357.912144 -117.297458) (xy 357.919967 -117.238036) (xy 357.93548 -117.180143) (xy 357.958416 -117.12477)
			(xy 357.988383 -117.072864) (xy 358.02487 -117.025314) (xy 358.06725 -116.982934) (xy 358.1148 -116.946447)
			(xy 358.166706 -116.91648) (xy 358.222079 -116.893544) (xy 358.279972 -116.878031) (xy 358.339394 -116.870208)
			(xy 358.39933 -116.870208) (xy 358.458752 -116.878031) (xy 358.516645 -116.893544) (xy 358.572018 -116.91648)
			(xy 358.623924 -116.946447) (xy 358.671474 -116.982934) (xy 358.713854 -117.025314) (xy 358.750341 -117.072864)
			(xy 358.780308 -117.12477) (xy 358.803244 -117.180143) (xy 358.816709 -117.230394) (xy 359.944144 -117.230394)
			(xy 359.944144 -117.170458) (xy 359.951967 -117.111036) (xy 359.96748 -117.053143) (xy 359.990416 -116.99777)
			(xy 360.020383 -116.945864) (xy 360.05687 -116.898314) (xy 360.09925 -116.855934) (xy 360.1468 -116.819447)
			(xy 360.198706 -116.78948) (xy 360.254079 -116.766544) (xy 360.311972 -116.751031) (xy 360.371394 -116.743208)
			(xy 360.43133 -116.743208) (xy 360.490752 -116.751031) (xy 360.548645 -116.766544) (xy 360.604018 -116.78948)
			(xy 360.655924 -116.819447) (xy 360.703474 -116.855934) (xy 360.745854 -116.898314) (xy 360.782341 -116.945864)
			(xy 360.812308 -116.99777) (xy 360.835244 -117.053143) (xy 360.850757 -117.111036) (xy 360.85858 -117.170458)
			(xy 360.85907 -117.200426) (xy 360.85858 -117.230394) (xy 360.850757 -117.289816) (xy 360.835244 -117.347709)
			(xy 360.812308 -117.403082) (xy 360.782341 -117.454988) (xy 360.745854 -117.502538) (xy 360.703474 -117.544918)
			(xy 360.655924 -117.581405) (xy 360.604018 -117.611372) (xy 360.548645 -117.634308) (xy 360.490752 -117.649821)
			(xy 360.43133 -117.657644) (xy 360.371394 -117.657644) (xy 360.311972 -117.649821) (xy 360.254079 -117.634308)
			(xy 360.198706 -117.611372) (xy 360.1468 -117.581405) (xy 360.09925 -117.544918) (xy 360.05687 -117.502538)
			(xy 360.020383 -117.454988) (xy 359.990416 -117.403082) (xy 359.96748 -117.347709) (xy 359.951967 -117.289816)
			(xy 359.944144 -117.230394) (xy 358.816709 -117.230394) (xy 358.818757 -117.238036) (xy 358.82658 -117.297458)
			(xy 358.82707 -117.327426) (xy 358.82658 -117.357394) (xy 358.818757 -117.416816) (xy 358.803244 -117.474709)
			(xy 358.780308 -117.530082) (xy 358.750341 -117.581988) (xy 358.713854 -117.629538) (xy 358.671474 -117.671918)
			(xy 358.623924 -117.708405) (xy 358.572018 -117.738372) (xy 358.516645 -117.761308) (xy 358.458752 -117.776821)
			(xy 358.39933 -117.784644) (xy 358.339394 -117.784644) (xy 358.279972 -117.776821) (xy 358.222079 -117.761308)
			(xy 358.166706 -117.738372) (xy 358.1148 -117.708405) (xy 358.06725 -117.671918) (xy 358.02487 -117.629538)
			(xy 357.988383 -117.581988) (xy 357.958416 -117.530082) (xy 357.93548 -117.474709) (xy 357.919967 -117.416816)
			(xy 357.912144 -117.357394) (xy 356.978966 -117.357394) (xy 356.978966 -119.516394) (xy 357.912144 -119.516394)
			(xy 357.912144 -119.456458) (xy 357.919967 -119.397036) (xy 357.93548 -119.339143) (xy 357.958416 -119.28377)
			(xy 357.988383 -119.231864) (xy 358.02487 -119.184314) (xy 358.06725 -119.141934) (xy 358.1148 -119.105447)
			(xy 358.166706 -119.07548) (xy 358.222079 -119.052544) (xy 358.279972 -119.037031) (xy 358.339394 -119.029208)
			(xy 358.39933 -119.029208) (xy 358.458752 -119.037031) (xy 358.516645 -119.052544) (xy 358.572018 -119.07548)
			(xy 358.623924 -119.105447) (xy 358.671474 -119.141934) (xy 358.713854 -119.184314) (xy 358.750341 -119.231864)
			(xy 358.780308 -119.28377) (xy 358.803244 -119.339143) (xy 358.807726 -119.35587) (xy 359.003344 -119.35587)
			(xy 359.007415 -119.300248) (xy 359.019541 -119.245811) (xy 359.039464 -119.19372) (xy 359.06676 -119.145085)
			(xy 359.100846 -119.100942) (xy 359.140995 -119.062233) (xy 359.186353 -119.029782) (xy 359.235953 -119.004281)
			(xy 359.288737 -118.986274) (xy 359.34358 -118.976144) (xy 359.399314 -118.974107) (xy 359.454751 -118.980207)
			(xy 359.508708 -118.994313) (xy 359.560037 -119.016125) (xy 359.607643 -119.045179) (xy 359.650511 -119.080854)
			(xy 359.687728 -119.122391) (xy 359.718501 -119.168904) (xy 359.742173 -119.219401) (xy 359.758241 -119.272808)
			(xy 359.766361 -119.327984) (xy 359.76687 -119.35587) (xy 361.035344 -119.35587) (xy 361.039415 -119.300248)
			(xy 361.051541 -119.245811) (xy 361.071464 -119.19372) (xy 361.09876 -119.145085) (xy 361.132846 -119.100942)
			(xy 361.172995 -119.062233) (xy 361.218353 -119.029782) (xy 361.267953 -119.004281) (xy 361.320737 -118.986274)
			(xy 361.37558 -118.976144) (xy 361.431314 -118.974107) (xy 361.486751 -118.980207) (xy 361.540708 -118.994313)
			(xy 361.592037 -119.016125) (xy 361.639643 -119.045179) (xy 361.682511 -119.080854) (xy 361.719728 -119.122391)
			(xy 361.750501 -119.168904) (xy 361.774173 -119.219401) (xy 361.790241 -119.272808) (xy 361.798361 -119.327984)
			(xy 361.79887 -119.35587) (xy 361.798361 -119.383756) (xy 361.797232 -119.39143) (xy 362.198918 -119.39143)
			(xy 362.202989 -119.335808) (xy 362.215115 -119.281371) (xy 362.235038 -119.22928) (xy 362.262334 -119.180645)
			(xy 362.29642 -119.136502) (xy 362.336569 -119.097793) (xy 362.381927 -119.065342) (xy 362.431527 -119.039841)
			(xy 362.484311 -119.021834) (xy 362.539154 -119.011704) (xy 362.594888 -119.009667) (xy 362.650325 -119.015767)
			(xy 362.704282 -119.029873) (xy 362.755611 -119.051685) (xy 362.803217 -119.080739) (xy 362.846085 -119.116414)
			(xy 362.883302 -119.157951) (xy 362.914075 -119.204464) (xy 362.937747 -119.254961) (xy 362.953815 -119.308368)
			(xy 362.961935 -119.363544) (xy 362.962444 -119.39143) (xy 363.214918 -119.39143) (xy 363.218989 -119.335808)
			(xy 363.231115 -119.281371) (xy 363.251038 -119.22928) (xy 363.278334 -119.180645) (xy 363.31242 -119.136502)
			(xy 363.352569 -119.097793) (xy 363.397927 -119.065342) (xy 363.447527 -119.039841) (xy 363.500311 -119.021834)
			(xy 363.555154 -119.011704) (xy 363.610888 -119.009667) (xy 363.666325 -119.015767) (xy 363.720282 -119.029873)
			(xy 363.771611 -119.051685) (xy 363.819217 -119.080739) (xy 363.862085 -119.116414) (xy 363.899302 -119.157951)
			(xy 363.930075 -119.204464) (xy 363.953747 -119.254961) (xy 363.969815 -119.308368) (xy 363.977935 -119.363544)
			(xy 363.978444 -119.39143) (xy 364.230918 -119.39143) (xy 364.234989 -119.335808) (xy 364.247115 -119.281371)
			(xy 364.267038 -119.22928) (xy 364.294334 -119.180645) (xy 364.32842 -119.136502) (xy 364.368569 -119.097793)
			(xy 364.413927 -119.065342) (xy 364.463527 -119.039841) (xy 364.516311 -119.021834) (xy 364.571154 -119.011704)
			(xy 364.626888 -119.009667) (xy 364.682325 -119.015767) (xy 364.736282 -119.029873) (xy 364.787611 -119.051685)
			(xy 364.835217 -119.080739) (xy 364.878085 -119.116414) (xy 364.915302 -119.157951) (xy 364.946075 -119.204464)
			(xy 364.969747 -119.254961) (xy 364.985815 -119.308368) (xy 364.993935 -119.363544) (xy 364.994444 -119.39143)
			(xy 364.993935 -119.419316) (xy 364.985815 -119.474492) (xy 364.969747 -119.527899) (xy 364.946075 -119.578396)
			(xy 364.915302 -119.624909) (xy 364.878085 -119.666446) (xy 364.835217 -119.702121) (xy 364.787611 -119.731175)
			(xy 364.736282 -119.752987) (xy 364.682325 -119.767093) (xy 364.626888 -119.773193) (xy 364.571154 -119.771156)
			(xy 364.516311 -119.761026) (xy 364.463527 -119.743019) (xy 364.413927 -119.717518) (xy 364.368569 -119.685067)
			(xy 364.32842 -119.646358) (xy 364.294334 -119.602215) (xy 364.267038 -119.55358) (xy 364.247115 -119.501489)
			(xy 364.234989 -119.447052) (xy 364.230918 -119.39143) (xy 363.978444 -119.39143) (xy 363.977935 -119.419316)
			(xy 363.969815 -119.474492) (xy 363.953747 -119.527899) (xy 363.930075 -119.578396) (xy 363.899302 -119.624909)
			(xy 363.862085 -119.666446) (xy 363.819217 -119.702121) (xy 363.771611 -119.731175) (xy 363.720282 -119.752987)
			(xy 363.666325 -119.767093) (xy 363.610888 -119.773193) (xy 363.555154 -119.771156) (xy 363.500311 -119.761026)
			(xy 363.447527 -119.743019) (xy 363.397927 -119.717518) (xy 363.352569 -119.685067) (xy 363.31242 -119.646358)
			(xy 363.278334 -119.602215) (xy 363.251038 -119.55358) (xy 363.231115 -119.501489) (xy 363.218989 -119.447052)
			(xy 363.214918 -119.39143) (xy 362.962444 -119.39143) (xy 362.961935 -119.419316) (xy 362.953815 -119.474492)
			(xy 362.937747 -119.527899) (xy 362.914075 -119.578396) (xy 362.883302 -119.624909) (xy 362.846085 -119.666446)
			(xy 362.803217 -119.702121) (xy 362.755611 -119.731175) (xy 362.704282 -119.752987) (xy 362.650325 -119.767093)
			(xy 362.594888 -119.773193) (xy 362.539154 -119.771156) (xy 362.484311 -119.761026) (xy 362.431527 -119.743019)
			(xy 362.381927 -119.717518) (xy 362.336569 -119.685067) (xy 362.29642 -119.646358) (xy 362.262334 -119.602215)
			(xy 362.235038 -119.55358) (xy 362.215115 -119.501489) (xy 362.202989 -119.447052) (xy 362.198918 -119.39143)
			(xy 361.797232 -119.39143) (xy 361.790241 -119.438932) (xy 361.774173 -119.492339) (xy 361.750501 -119.542836)
			(xy 361.719728 -119.589349) (xy 361.682511 -119.630886) (xy 361.639643 -119.666561) (xy 361.592037 -119.695615)
			(xy 361.540708 -119.717427) (xy 361.486751 -119.731533) (xy 361.431314 -119.737633) (xy 361.37558 -119.735596)
			(xy 361.320737 -119.725466) (xy 361.267953 -119.707459) (xy 361.218353 -119.681958) (xy 361.172995 -119.649507)
			(xy 361.132846 -119.610798) (xy 361.09876 -119.566655) (xy 361.071464 -119.51802) (xy 361.051541 -119.465929)
			(xy 361.039415 -119.411492) (xy 361.035344 -119.35587) (xy 359.76687 -119.35587) (xy 359.766361 -119.383756)
			(xy 359.758241 -119.438932) (xy 359.742173 -119.492339) (xy 359.718501 -119.542836) (xy 359.687728 -119.589349)
			(xy 359.650511 -119.630886) (xy 359.607643 -119.666561) (xy 359.560037 -119.695615) (xy 359.508708 -119.717427)
			(xy 359.454751 -119.731533) (xy 359.399314 -119.737633) (xy 359.34358 -119.735596) (xy 359.288737 -119.725466)
			(xy 359.235953 -119.707459) (xy 359.186353 -119.681958) (xy 359.140995 -119.649507) (xy 359.100846 -119.610798)
			(xy 359.06676 -119.566655) (xy 359.039464 -119.51802) (xy 359.019541 -119.465929) (xy 359.007415 -119.411492)
			(xy 359.003344 -119.35587) (xy 358.807726 -119.35587) (xy 358.818757 -119.397036) (xy 358.82658 -119.456458)
			(xy 358.82707 -119.486426) (xy 358.82658 -119.516394) (xy 358.818757 -119.575816) (xy 358.803244 -119.633709)
			(xy 358.780308 -119.689082) (xy 358.750341 -119.740988) (xy 358.713854 -119.788538) (xy 358.671474 -119.830918)
			(xy 358.623924 -119.867405) (xy 358.572018 -119.897372) (xy 358.516645 -119.920308) (xy 358.458752 -119.935821)
			(xy 358.39933 -119.943644) (xy 358.339394 -119.943644) (xy 358.279972 -119.935821) (xy 358.222079 -119.920308)
			(xy 358.166706 -119.897372) (xy 358.1148 -119.867405) (xy 358.06725 -119.830918) (xy 358.02487 -119.788538)
			(xy 357.988383 -119.740988) (xy 357.958416 -119.689082) (xy 357.93548 -119.633709) (xy 357.919967 -119.575816)
			(xy 357.912144 -119.516394) (xy 356.978966 -119.516394) (xy 356.978966 -121.263918) (xy 356.979339 -121.272706)
			(xy 356.985296 -121.289241) (xy 356.996502 -121.302781) (xy 357.003858 -121.307606) (xy 357.004874 -121.308368)
			(xy 357.098346 -121.35739) (xy 357.126286 -121.355612) (xy 357.138224 -121.347484) (xy 357.142034 -121.344944)
			(xy 357.150416 -121.33961) (xy 357.173463 -121.32548) (xy 357.222699 -121.30316) (xy 357.274595 -121.288023)
			(xy 357.328111 -121.280373) (xy 357.35514 -121.27992) (xy 357.362252 -121.27992) (xy 357.389171 -121.280882)
			(xy 357.442351 -121.289444) (xy 357.493797 -121.305403) (xy 357.542487 -121.32844) (xy 357.587452 -121.358098)
			(xy 357.627797 -121.393787) (xy 357.66272 -121.434797) (xy 357.691526 -121.480311) (xy 357.713643 -121.529426)
			(xy 357.725614 -121.57075) (xy 361.920028 -121.57075) (xy 361.920493 -121.543416) (xy 361.928302 -121.489309)
			(xy 361.943752 -121.436869) (xy 361.966528 -121.387172) (xy 361.996164 -121.341233) (xy 362.013754 -121.320306)
			(xy 362.014008 -121.320052) (xy 362.014262 -121.319798) (xy 362.019863 -121.312722) (xy 362.026099 -121.295797)
			(xy 362.026454 -121.286778) (xy 362.026454 -121.219722) (xy 362.026096 -121.210705) (xy 362.01985 -121.193788)
			(xy 362.014262 -121.186702) (xy 362.014008 -121.186448) (xy 362.013754 -121.186194) (xy 361.996138 -121.165287)
			(xy 361.966505 -121.119344) (xy 361.943734 -121.069642) (xy 361.928291 -121.017197) (xy 361.920494 -120.963085)
			(xy 361.920028 -120.93575) (xy 361.920514 -120.908499) (xy 361.92827 -120.854551) (xy 361.943625 -120.802256)
			(xy 361.966267 -120.752679) (xy 361.995733 -120.706829) (xy 362.031424 -120.665638) (xy 362.072615 -120.629947)
			(xy 362.118465 -120.600481) (xy 362.168042 -120.577839) (xy 362.220337 -120.562484) (xy 362.274285 -120.554728)
			(xy 362.328787 -120.554728) (xy 362.382735 -120.562484) (xy 362.43503 -120.577839) (xy 362.484607 -120.600481)
			(xy 362.530457 -120.629947) (xy 362.571648 -120.665638) (xy 362.607339 -120.706829) (xy 362.636805 -120.752679)
			(xy 362.659447 -120.802256) (xy 362.674802 -120.854551) (xy 362.682558 -120.908499) (xy 362.683044 -120.93575)
			(xy 362.682586 -120.963084) (xy 362.674776 -121.017192) (xy 362.659325 -121.069632) (xy 362.636547 -121.119329)
			(xy 362.60691 -121.165267) (xy 362.589318 -121.186194) (xy 362.589064 -121.186448) (xy 362.58881 -121.186702)
			(xy 362.583218 -121.193785) (xy 362.576974 -121.210704) (xy 362.576618 -121.219722) (xy 362.576618 -121.286778)
			(xy 362.576982 -121.295794) (xy 362.583224 -121.312711) (xy 362.58881 -121.319798) (xy 362.589064 -121.320052)
			(xy 362.589318 -121.320306) (xy 362.60693 -121.341216) (xy 362.636564 -121.387158) (xy 362.659337 -121.43686)
			(xy 362.67478 -121.489303) (xy 362.679965 -121.525284) (xy 365.651796 -121.525284) (xy 365.652289 -121.497951)
			(xy 365.660092 -121.443845) (xy 365.675536 -121.391406) (xy 365.698306 -121.341708) (xy 365.727935 -121.295768)
			(xy 365.745522 -121.27484) (xy 365.745776 -121.274586) (xy 365.74603 -121.274332) (xy 365.751613 -121.267243)
			(xy 365.757861 -121.250328) (xy 365.758222 -121.241312) (xy 365.758222 -121.174256) (xy 365.757834 -121.165242)
			(xy 365.751607 -121.148325) (xy 365.74603 -121.141236) (xy 365.745776 -121.140982) (xy 365.745522 -121.140728)
			(xy 365.727933 -121.1198) (xy 365.698293 -121.073864) (xy 365.675516 -121.024167) (xy 365.660067 -120.971727)
			(xy 365.652264 -120.917618) (xy 365.651796 -120.890284) (xy 365.652282 -120.863033) (xy 365.660038 -120.809085)
			(xy 365.675393 -120.75679) (xy 365.698035 -120.707213) (xy 365.727501 -120.661363) (xy 365.763192 -120.620172)
			(xy 365.804383 -120.584481) (xy 365.850233 -120.555015) (xy 365.89981 -120.532373) (xy 365.952105 -120.517018)
			(xy 366.006053 -120.509262) (xy 366.060555 -120.509262) (xy 366.114503 -120.517018) (xy 366.166798 -120.532373)
			(xy 366.216375 -120.555015) (xy 366.262225 -120.584481) (xy 366.303416 -120.620172) (xy 366.339107 -120.661363)
			(xy 366.368573 -120.707213) (xy 366.391215 -120.75679) (xy 366.40657 -120.809085) (xy 366.414326 -120.863033)
			(xy 366.414812 -120.890284) (xy 366.414357 -120.917618) (xy 366.406544 -120.971726) (xy 366.391091 -121.024165)
			(xy 366.368313 -121.073862) (xy 366.338677 -121.119801) (xy 366.321086 -121.140728) (xy 366.320832 -121.140982)
			(xy 366.320578 -121.141236) (xy 366.31501 -121.148335) (xy 366.308753 -121.165242) (xy 366.308386 -121.174256)
			(xy 366.308386 -121.241312) (xy 366.30874 -121.250329) (xy 366.31499 -121.267246) (xy 366.320578 -121.274332)
			(xy 366.320832 -121.274586) (xy 366.321086 -121.27484) (xy 366.338662 -121.295779) (xy 366.368303 -121.341712)
			(xy 366.391083 -121.391407) (xy 366.406535 -121.443844) (xy 366.414342 -121.497951) (xy 366.414812 -121.525284)
			(xy 366.414565 -121.543563) (xy 366.411006 -121.579949) (xy 366.4077 -121.597928) (xy 366.4077 -121.598182)
			(xy 366.4077 -121.598436) (xy 366.406316 -121.60894) (xy 366.411161 -121.62954) (xy 366.417098 -121.638314)
			(xy 366.469422 -121.707656) (xy 366.488218 -121.717816) (xy 366.49914 -121.718832) (xy 366.527426 -121.721712)
			(xy 366.582763 -121.734753) (xy 366.635557 -121.755853) (xy 366.684639 -121.784545) (xy 366.728927 -121.820195)
			(xy 366.748568 -121.840752) (xy 366.756159 -121.848171) (xy 366.775562 -121.85671) (xy 366.78616 -121.857262)
			(xy 366.860328 -121.857262) (xy 366.870962 -121.856871) (xy 366.890427 -121.84831) (xy 366.89792 -121.840752)
			(xy 366.91604 -121.821688) (xy 366.956623 -121.78823) (xy 367.001421 -121.76067) (xy 367.049582 -121.739532)
			(xy 367.100193 -121.725217) (xy 367.152292 -121.717998) (xy 367.17859 -121.717562) (xy 367.178844 -121.717562)
			(xy 367.206091 -121.718111) (xy 367.26003 -121.725872) (xy 367.312315 -121.74123) (xy 367.361883 -121.763872)
			(xy 367.407724 -121.793337) (xy 367.448906 -121.829026) (xy 367.48459 -121.870211) (xy 367.514049 -121.916056)
			(xy 367.536686 -121.965626) (xy 367.552037 -122.017913) (xy 367.559792 -122.071853) (xy 367.559792 -122.126347)
			(xy 367.552037 -122.180287) (xy 367.536686 -122.232574) (xy 367.514049 -122.282144) (xy 367.48459 -122.327989)
			(xy 367.448906 -122.369174) (xy 367.407724 -122.404863) (xy 367.361883 -122.434328) (xy 367.312315 -122.45697)
			(xy 367.26003 -122.472328) (xy 367.206091 -122.480089) (xy 367.178844 -122.480578) (xy 367.17859 -122.480578)
			(xy 367.152295 -122.480133) (xy 367.100205 -122.472886) (xy 367.049603 -122.458558) (xy 367.001447 -122.43742)
			(xy 366.956648 -122.409872) (xy 366.916054 -122.376436) (xy 366.89792 -122.357388) (xy 366.890342 -122.349955)
			(xy 366.870929 -122.341425) (xy 366.860328 -122.340878) (xy 366.78616 -122.340878) (xy 366.775527 -122.341281)
			(xy 366.756064 -122.349835) (xy 366.748568 -122.357388) (xy 366.730462 -122.376466) (xy 366.689875 -122.409921)
			(xy 366.645074 -122.437478) (xy 366.59691 -122.458613) (xy 366.546297 -122.472926) (xy 366.494197 -122.480143)
			(xy 366.467898 -122.480578) (xy 366.467644 -122.480578) (xy 366.440391 -122.480104) (xy 366.386439 -122.472352)
			(xy 366.334139 -122.457) (xy 366.284557 -122.43436) (xy 366.238703 -122.404894) (xy 366.197509 -122.369201)
			(xy 366.161814 -122.328009) (xy 366.132346 -122.282155) (xy 366.109705 -122.232574) (xy 366.094351 -122.180275)
			(xy 366.086597 -122.126323) (xy 366.086136 -122.09907) (xy 366.086377 -122.080791) (xy 366.089941 -122.044405)
			(xy 366.093248 -122.026426) (xy 366.093248 -122.026172) (xy 366.093248 -122.025918) (xy 366.09465 -122.015415)
			(xy 366.089791 -121.994814) (xy 366.08385 -121.98604) (xy 366.031526 -121.916698) (xy 366.01273 -121.906538)
			(xy 366.001808 -121.905522) (xy 365.973539 -121.902721) (xy 365.918249 -121.889677) (xy 365.865504 -121.86858)
			(xy 365.81647 -121.839897) (xy 365.772229 -121.804262) (xy 365.73376 -121.762463) (xy 365.701913 -121.715422)
			(xy 365.677391 -121.664179) (xy 365.660736 -121.609868) (xy 365.652317 -121.553688) (xy 365.651796 -121.525284)
			(xy 362.679965 -121.525284) (xy 362.682578 -121.543415) (xy 362.683044 -121.57075) (xy 362.682558 -121.598001)
			(xy 362.674802 -121.651949) (xy 362.659447 -121.704244) (xy 362.636805 -121.753821) (xy 362.607339 -121.799671)
			(xy 362.571648 -121.840862) (xy 362.530457 -121.876553) (xy 362.484607 -121.906019) (xy 362.43503 -121.928661)
			(xy 362.382735 -121.944016) (xy 362.328787 -121.951772) (xy 362.274285 -121.951772) (xy 362.220337 -121.944016)
			(xy 362.168042 -121.928661) (xy 362.118465 -121.906019) (xy 362.072615 -121.876553) (xy 362.031424 -121.840862)
			(xy 361.995733 -121.799671) (xy 361.966267 -121.753821) (xy 361.943625 -121.704244) (xy 361.92827 -121.651949)
			(xy 361.920514 -121.598001) (xy 361.920028 -121.57075) (xy 357.725614 -121.57075) (xy 357.728631 -121.581164)
			(xy 357.73619 -121.634495) (xy 357.736648 -121.661428) (xy 357.73616 -121.688679) (xy 357.728401 -121.742626)
			(xy 357.713044 -121.794919) (xy 357.690401 -121.844496) (xy 357.660935 -121.890345) (xy 357.625244 -121.931536)
			(xy 357.584055 -121.967228) (xy 357.538206 -121.996696) (xy 357.488631 -122.019339) (xy 357.436338 -122.034698)
			(xy 357.382391 -122.042459) (xy 357.35514 -122.042936) (xy 357.328114 -122.042443) (xy 357.274609 -122.034773)
			(xy 357.222719 -122.019639) (xy 357.17348 -121.997342) (xy 357.150416 -121.983246) (xy 357.142034 -121.977912)
			(xy 357.138224 -121.975372) (xy 357.126286 -121.967244) (xy 357.098346 -121.965466) (xy 357.006144 -122.01398)
			(xy 356.996746 -122.02033) (xy 356.988734 -122.027907) (xy 356.979536 -122.047923) (xy 356.978966 -122.058938)
			(xy 356.978966 -122.292618) (xy 358.080308 -122.292618) (xy 358.084379 -122.236996) (xy 358.096505 -122.182559)
			(xy 358.116428 -122.130468) (xy 358.143724 -122.081833) (xy 358.17781 -122.03769) (xy 358.217959 -121.998981)
			(xy 358.263317 -121.96653) (xy 358.312917 -121.941029) (xy 358.365701 -121.923022) (xy 358.420544 -121.912892)
			(xy 358.476278 -121.910855) (xy 358.531715 -121.916955) (xy 358.585672 -121.931061) (xy 358.637001 -121.952873)
			(xy 358.684607 -121.981927) (xy 358.727475 -122.017602) (xy 358.764692 -122.059139) (xy 358.795465 -122.105652)
			(xy 358.819137 -122.156149) (xy 358.835205 -122.209556) (xy 358.843325 -122.264732) (xy 358.843834 -122.292618)
			(xy 358.843325 -122.320504) (xy 358.835205 -122.37568) (xy 358.819137 -122.429087) (xy 358.795465 -122.479584)
			(xy 358.782038 -122.499878) (xy 359.161824 -122.499878) (xy 359.161824 -122.439942) (xy 359.169647 -122.38052)
			(xy 359.18516 -122.322627) (xy 359.208096 -122.267254) (xy 359.238063 -122.215348) (xy 359.27455 -122.167798)
			(xy 359.31693 -122.125418) (xy 359.36448 -122.088931) (xy 359.416386 -122.058964) (xy 359.471759 -122.036028)
			(xy 359.529652 -122.020515) (xy 359.589074 -122.012692) (xy 359.64901 -122.012692) (xy 359.708432 -122.020515)
			(xy 359.766325 -122.036028) (xy 359.821698 -122.058964) (xy 359.873604 -122.088931) (xy 359.921154 -122.125418)
			(xy 359.963534 -122.167798) (xy 360.000021 -122.215348) (xy 360.029988 -122.267254) (xy 360.052924 -122.322627)
			(xy 360.068437 -122.38052) (xy 360.07626 -122.439942) (xy 360.07675 -122.46991) (xy 360.07626 -122.499878)
			(xy 360.068437 -122.5593) (xy 360.052924 -122.617193) (xy 360.029988 -122.672566) (xy 360.000021 -122.724472)
			(xy 359.963534 -122.772022) (xy 359.921154 -122.814402) (xy 359.873604 -122.850889) (xy 359.821698 -122.880856)
			(xy 359.766325 -122.903792) (xy 359.708432 -122.919305) (xy 359.64901 -122.927128) (xy 359.589074 -122.927128)
			(xy 359.529652 -122.919305) (xy 359.471759 -122.903792) (xy 359.416386 -122.880856) (xy 359.36448 -122.850889)
			(xy 359.31693 -122.814402) (xy 359.27455 -122.772022) (xy 359.238063 -122.724472) (xy 359.208096 -122.672566)
			(xy 359.18516 -122.617193) (xy 359.169647 -122.5593) (xy 359.161824 -122.499878) (xy 358.782038 -122.499878)
			(xy 358.764692 -122.526097) (xy 358.727475 -122.567634) (xy 358.684607 -122.603309) (xy 358.637001 -122.632363)
			(xy 358.585672 -122.654175) (xy 358.531715 -122.668281) (xy 358.476278 -122.674381) (xy 358.420544 -122.672344)
			(xy 358.365701 -122.662214) (xy 358.312917 -122.644207) (xy 358.263317 -122.618706) (xy 358.217959 -122.586255)
			(xy 358.17781 -122.547546) (xy 358.143724 -122.503403) (xy 358.116428 -122.454768) (xy 358.096505 -122.402677)
			(xy 358.084379 -122.34824) (xy 358.080308 -122.292618) (xy 356.978966 -122.292618) (xy 356.978966 -122.533918)
			(xy 356.979339 -122.542706) (xy 356.985296 -122.559241) (xy 356.996502 -122.572781) (xy 357.003858 -122.577606)
			(xy 357.004874 -122.578368) (xy 357.098346 -122.62739) (xy 357.126286 -122.625612) (xy 357.138224 -122.617484)
			(xy 357.142034 -122.614944) (xy 357.150416 -122.60961) (xy 357.173463 -122.59548) (xy 357.222699 -122.57316)
			(xy 357.274595 -122.558023) (xy 357.328111 -122.550373) (xy 357.35514 -122.54992) (xy 357.362252 -122.54992)
			(xy 357.389171 -122.550882) (xy 357.442351 -122.559444) (xy 357.493797 -122.575403) (xy 357.542487 -122.59844)
			(xy 357.587452 -122.628098) (xy 357.627797 -122.663787) (xy 357.66272 -122.704797) (xy 357.691526 -122.750311)
			(xy 357.713643 -122.799426) (xy 357.728631 -122.851164) (xy 357.73619 -122.904495) (xy 357.736648 -122.931428)
			(xy 357.73616 -122.958679) (xy 357.728401 -123.012626) (xy 357.713044 -123.064919) (xy 357.690401 -123.114496)
			(xy 357.660935 -123.160345) (xy 357.625244 -123.201536) (xy 357.584055 -123.237228) (xy 357.564572 -123.24975)
			(xy 360.21009 -123.24975) (xy 360.21009 -123.19525) (xy 360.217847 -123.141304) (xy 360.233201 -123.089011)
			(xy 360.255842 -123.039435) (xy 360.285307 -122.993586) (xy 360.320997 -122.952397) (xy 360.362186 -122.916707)
			(xy 360.408035 -122.887242) (xy 360.457611 -122.864601) (xy 360.509904 -122.849247) (xy 360.56385 -122.84149)
			(xy 360.5911 -122.841004) (xy 360.618099 -122.841486) (xy 360.671556 -122.849119) (xy 360.723401 -122.864217)
			(xy 360.772597 -122.886478) (xy 360.81816 -122.915458) (xy 360.859179 -122.950576) (xy 360.877358 -122.970544)
			(xy 360.877612 -122.970798) (xy 360.884978 -122.978926) (xy 360.89463 -122.983498) (xy 360.899697 -122.985652)
			(xy 360.910461 -122.987952) (xy 360.915966 -122.98807) (xy 361.002834 -122.988324) (xy 361.012994 -122.983752)
			(xy 361.017708 -122.981496) (xy 361.026157 -122.975348) (xy 361.029758 -122.97156) (xy 361.030012 -122.971306)
			(xy 361.030266 -122.971052) (xy 361.048438 -122.951382) (xy 361.089316 -122.91679) (xy 361.134634 -122.88826)
			(xy 361.183499 -122.866355) (xy 361.234949 -122.851504) (xy 361.287971 -122.844001) (xy 361.314746 -122.843544)
			(xy 361.342116 -122.844031) (xy 361.396294 -122.851842) (xy 361.448798 -122.867326) (xy 361.498545 -122.890163)
			(xy 361.544512 -122.919884) (xy 361.565444 -122.937524) (xy 361.565698 -122.937778) (xy 361.572774 -122.943379)
			(xy 361.589699 -122.949615) (xy 361.598718 -122.94997) (xy 361.665774 -122.94997) (xy 361.67479 -122.949607)
			(xy 361.691708 -122.943364) (xy 361.698794 -122.937778) (xy 361.699302 -122.93727) (xy 361.720217 -122.919633)
			(xy 361.766186 -122.889969) (xy 361.815923 -122.867179) (xy 361.868406 -122.851731) (xy 361.922559 -122.843942)
			(xy 361.977268 -122.843973) (xy 362.031412 -122.851822) (xy 362.083878 -122.867329) (xy 362.13359 -122.890175)
			(xy 362.179525 -122.919891) (xy 362.200444 -122.937524) (xy 362.200698 -122.937778) (xy 362.207774 -122.943379)
			(xy 362.224699 -122.949615) (xy 362.233718 -122.94997) (xy 362.300774 -122.94997) (xy 362.30979 -122.949607)
			(xy 362.326708 -122.943364) (xy 362.333794 -122.937778) (xy 362.334302 -122.93727) (xy 362.347048 -122.926398)
			(xy 362.374141 -122.906687) (xy 362.388404 -122.8979) (xy 362.397548 -122.892312) (xy 362.40974 -122.875294)
			(xy 362.429806 -122.78233) (xy 362.425742 -122.761756) (xy 362.419646 -122.75312) (xy 362.403646 -122.729056)
			(xy 362.378305 -122.677124) (xy 362.36108 -122.621966) (xy 362.352364 -122.564842) (xy 362.351828 -122.53595)
			(xy 362.352314 -122.508699) (xy 362.36007 -122.454751) (xy 362.375425 -122.402456) (xy 362.398067 -122.352879)
			(xy 362.427533 -122.307029) (xy 362.463224 -122.265838) (xy 362.504415 -122.230147) (xy 362.550265 -122.200681)
			(xy 362.599842 -122.178039) (xy 362.652137 -122.162684) (xy 362.706085 -122.154928) (xy 362.760587 -122.154928)
			(xy 362.814535 -122.162684) (xy 362.86683 -122.178039) (xy 362.916407 -122.200681) (xy 362.962257 -122.230147)
			(xy 363.003448 -122.265838) (xy 363.039139 -122.307029) (xy 363.068605 -122.352879) (xy 363.091247 -122.402456)
			(xy 363.106602 -122.454751) (xy 363.114358 -122.508699) (xy 363.114844 -122.53595) (xy 363.114297 -122.56404)
			(xy 363.106078 -122.619614) (xy 363.089795 -122.673381) (xy 363.065801 -122.724178) (xy 363.034614 -122.770905)
			(xy 362.99691 -122.812552) (xy 362.953505 -122.848217) (xy 362.929678 -122.863102) (xy 362.920534 -122.86869)
			(xy 362.908342 -122.885708) (xy 362.888276 -122.978672) (xy 362.89234 -122.999246) (xy 362.898436 -123.007882)
			(xy 362.914435 -123.031947) (xy 362.939777 -123.083878) (xy 362.943886 -123.097036) (xy 364.776766 -123.097036)
			(xy 364.777214 -123.069701) (xy 364.785025 -123.015593) (xy 364.800479 -122.963153) (xy 364.823259 -122.913455)
			(xy 364.852899 -122.867518) (xy 364.870492 -122.846592) (xy 364.870746 -122.846338) (xy 364.871 -122.846084)
			(xy 364.876599 -122.839006) (xy 364.882838 -122.822083) (xy 364.883192 -122.813064) (xy 364.883192 -122.746008)
			(xy 364.882833 -122.736991) (xy 364.876587 -122.720074) (xy 364.871 -122.712988) (xy 364.870746 -122.712734)
			(xy 364.870492 -122.71248) (xy 364.852875 -122.691574) (xy 364.823241 -122.645631) (xy 364.800469 -122.595928)
			(xy 364.785027 -122.543484) (xy 364.777231 -122.489372) (xy 364.776766 -122.462036) (xy 364.777252 -122.434785)
			(xy 364.785008 -122.380837) (xy 364.800363 -122.328542) (xy 364.823005 -122.278965) (xy 364.852471 -122.233115)
			(xy 364.888162 -122.191924) (xy 364.929353 -122.156233) (xy 364.975203 -122.126767) (xy 365.02478 -122.104125)
			(xy 365.077075 -122.08877) (xy 365.131023 -122.081014) (xy 365.185525 -122.081014) (xy 365.239473 -122.08877)
			(xy 365.291768 -122.104125) (xy 365.341345 -122.126767) (xy 365.387195 -122.156233) (xy 365.428386 -122.191924)
			(xy 365.464077 -122.233115) (xy 365.493543 -122.278965) (xy 365.516185 -122.328542) (xy 365.53154 -122.380837)
			(xy 365.539296 -122.434785) (xy 365.539782 -122.462036) (xy 365.539306 -122.48937) (xy 365.5315 -122.543476)
			(xy 365.516052 -122.595916) (xy 365.493278 -122.645613) (xy 365.463645 -122.691552) (xy 365.446056 -122.71248)
			(xy 365.445802 -122.712734) (xy 365.445548 -122.712988) (xy 365.439954 -122.720069) (xy 365.433713 -122.73699)
			(xy 365.433356 -122.746008) (xy 365.433356 -122.813064) (xy 365.433718 -122.822081) (xy 365.439961 -122.838998)
			(xy 365.445548 -122.846084) (xy 365.445802 -122.846338) (xy 365.446056 -122.846592) (xy 365.463651 -122.867516)
			(xy 365.489156 -122.907044) (xy 367.738914 -122.907044) (xy 367.738914 -122.90679) (xy 367.739362 -122.880495)
			(xy 367.746609 -122.828405) (xy 367.760936 -122.777804) (xy 367.782074 -122.729647) (xy 367.809621 -122.684848)
			(xy 367.843056 -122.644254) (xy 367.862104 -122.62612) (xy 367.869536 -122.61854) (xy 367.878066 -122.599128)
			(xy 367.878614 -122.588528) (xy 367.878614 -122.51436) (xy 367.878214 -122.503727) (xy 367.869658 -122.484263)
			(xy 367.862104 -122.476768) (xy 367.843025 -122.458663) (xy 367.80957 -122.418076) (xy 367.782014 -122.373275)
			(xy 367.760879 -122.32511) (xy 367.746566 -122.274497) (xy 367.739349 -122.222397) (xy 367.738914 -122.196098)
			(xy 367.738914 -122.195844) (xy 367.739379 -122.16851) (xy 367.747188 -122.114403) (xy 367.762639 -122.061964)
			(xy 367.785415 -122.012266) (xy 367.81505 -121.966327) (xy 367.83264 -121.9454) (xy 367.832894 -121.945146)
			(xy 367.833148 -121.944892) (xy 367.83875 -121.937816) (xy 367.844986 -121.920891) (xy 367.84534 -121.911872)
			(xy 367.84534 -121.844816) (xy 367.844988 -121.835798) (xy 367.838738 -121.818881) (xy 367.833148 -121.811796)
			(xy 367.832894 -121.811542) (xy 367.83264 -121.811288) (xy 367.815084 -121.790331) (xy 367.785431 -121.744403)
			(xy 367.762642 -121.694711) (xy 367.747183 -121.642274) (xy 367.73937 -121.588167) (xy 367.739366 -121.533499)
			(xy 367.747168 -121.47939) (xy 367.762619 -121.426951) (xy 367.785399 -121.377255) (xy 367.815044 -121.331323)
			(xy 367.83264 -121.3104) (xy 367.832894 -121.310146) (xy 367.833148 -121.309892) (xy 367.83875 -121.302816)
			(xy 367.844986 -121.285891) (xy 367.84534 -121.276872) (xy 367.84534 -121.209816) (xy 367.844988 -121.200798)
			(xy 367.838738 -121.183881) (xy 367.833148 -121.176796) (xy 367.832894 -121.176542) (xy 367.83264 -121.176288)
			(xy 367.815035 -121.155373) (xy 367.785397 -121.109433) (xy 367.762622 -121.059733) (xy 367.747178 -121.00729)
			(xy 367.73938 -120.953179) (xy 367.738914 -120.925844) (xy 367.7394 -120.898593) (xy 367.747156 -120.844645)
			(xy 367.762511 -120.79235) (xy 367.785153 -120.742773) (xy 367.814619 -120.696923) (xy 367.85031 -120.655732)
			(xy 367.891501 -120.620041) (xy 367.937351 -120.590575) (xy 367.986928 -120.567933) (xy 368.039223 -120.552578)
			(xy 368.093171 -120.544822) (xy 368.147673 -120.544822) (xy 368.201621 -120.552578) (xy 368.253916 -120.567933)
			(xy 368.303493 -120.590575) (xy 368.349343 -120.620041) (xy 368.390534 -120.655732) (xy 368.426225 -120.696923)
			(xy 368.455691 -120.742773) (xy 368.478333 -120.79235) (xy 368.493688 -120.844645) (xy 368.501444 -120.898593)
			(xy 368.50193 -120.925844) (xy 368.501472 -120.953178) (xy 368.493663 -121.007287) (xy 368.478211 -121.059726)
			(xy 368.455434 -121.109424) (xy 368.425796 -121.155362) (xy 368.408204 -121.176288) (xy 368.40795 -121.176542)
			(xy 368.407696 -121.176796) (xy 368.402105 -121.183879) (xy 368.395861 -121.200799) (xy 368.395504 -121.209816)
			(xy 368.395504 -121.276872) (xy 368.395873 -121.285888) (xy 368.402112 -121.302805) (xy 368.407696 -121.309892)
			(xy 368.40795 -121.310146) (xy 368.408204 -121.3104) (xy 368.425849 -121.331287) (xy 368.455502 -121.377225)
			(xy 368.47829 -121.426928) (xy 368.493744 -121.479376) (xy 368.50155 -121.533494) (xy 368.501545 -121.588172)
			(xy 368.49373 -121.642289) (xy 368.478266 -121.694734) (xy 368.45547 -121.744433) (xy 368.425809 -121.790366)
			(xy 368.408204 -121.811288) (xy 368.40795 -121.811542) (xy 368.407696 -121.811796) (xy 368.402105 -121.818879)
			(xy 368.395861 -121.835799) (xy 368.395504 -121.844816) (xy 368.395504 -121.911872) (xy 368.395873 -121.920888)
			(xy 368.402112 -121.937805) (xy 368.407696 -121.944892) (xy 368.40795 -121.945146) (xy 368.408204 -121.9454)
			(xy 368.425811 -121.966314) (xy 368.455447 -122.012255) (xy 368.47822 -122.061955) (xy 368.493665 -122.114398)
			(xy 368.501464 -122.168509) (xy 368.50193 -122.195844) (xy 368.50193 -122.196098) (xy 368.50146 -122.222392)
			(xy 368.494216 -122.27448) (xy 368.479891 -122.325081) (xy 368.458758 -122.373237) (xy 368.431215 -122.418037)
			(xy 368.397785 -122.458633) (xy 368.37874 -122.476768) (xy 368.37132 -122.484358) (xy 368.362782 -122.503762)
			(xy 368.36223 -122.51436) (xy 368.36223 -122.588528) (xy 368.362624 -122.599162) (xy 368.371183 -122.618627)
			(xy 368.37874 -122.62612) (xy 368.397803 -122.644241) (xy 368.431261 -122.684824) (xy 368.458821 -122.729621)
			(xy 368.479959 -122.777783) (xy 368.494275 -122.828393) (xy 368.501494 -122.880492) (xy 368.50193 -122.90679)
			(xy 368.50193 -122.907044) (xy 368.501444 -122.934295) (xy 368.493688 -122.988243) (xy 368.478333 -123.040538)
			(xy 368.455691 -123.090115) (xy 368.426225 -123.135965) (xy 368.390534 -123.177156) (xy 368.349343 -123.212847)
			(xy 368.303493 -123.242313) (xy 368.253916 -123.264955) (xy 368.201621 -123.28031) (xy 368.147673 -123.288066)
			(xy 368.093171 -123.288066) (xy 368.039223 -123.28031) (xy 367.986928 -123.264955) (xy 367.937351 -123.242313)
			(xy 367.891501 -123.212847) (xy 367.85031 -123.177156) (xy 367.814619 -123.135965) (xy 367.785153 -123.090115)
			(xy 367.762511 -123.040538) (xy 367.747156 -122.988243) (xy 367.7394 -122.934295) (xy 367.738914 -122.907044)
			(xy 365.489156 -122.907044) (xy 365.493291 -122.913452) (xy 365.516067 -122.963151) (xy 365.531514 -123.015592)
			(xy 365.539315 -123.069701) (xy 365.539782 -123.097036) (xy 365.539296 -123.124287) (xy 365.53154 -123.178235)
			(xy 365.516185 -123.23053) (xy 365.493543 -123.280107) (xy 365.464077 -123.325957) (xy 365.428386 -123.367148)
			(xy 365.387195 -123.402839) (xy 365.341345 -123.432305) (xy 365.291768 -123.454947) (xy 365.239473 -123.470302)
			(xy 365.185525 -123.478058) (xy 365.131023 -123.478058) (xy 365.077075 -123.470302) (xy 365.02478 -123.454947)
			(xy 364.975203 -123.432305) (xy 364.929353 -123.402839) (xy 364.888162 -123.367148) (xy 364.852471 -123.325957)
			(xy 364.823005 -123.280107) (xy 364.800363 -123.23053) (xy 364.785008 -123.178235) (xy 364.777252 -123.124287)
			(xy 364.776766 -123.097036) (xy 362.943886 -123.097036) (xy 362.957002 -123.139036) (xy 362.965719 -123.19616)
			(xy 362.966254 -123.225052) (xy 362.9657 -123.252302) (xy 362.957951 -123.306247) (xy 362.942603 -123.35854)
			(xy 362.91997 -123.408117) (xy 362.890511 -123.453968) (xy 362.854827 -123.49516) (xy 362.813644 -123.530855)
			(xy 362.7678 -123.560325) (xy 362.718228 -123.58297) (xy 362.665939 -123.598331) (xy 362.611995 -123.606093)
			(xy 362.584746 -123.60656) (xy 362.557376 -123.606077) (xy 362.503198 -123.598265) (xy 362.450694 -123.58278)
			(xy 362.400947 -123.559942) (xy 362.35498 -123.53022) (xy 362.334048 -123.51258) (xy 362.333794 -123.512326)
			(xy 362.32672 -123.506722) (xy 362.309793 -123.500488) (xy 362.300774 -123.500134) (xy 362.233718 -123.500134)
			(xy 362.224701 -123.500492) (xy 362.207784 -123.506738) (xy 362.200698 -123.512326) (xy 362.20019 -123.512834)
			(xy 362.179282 -123.530478) (xy 362.133311 -123.560142) (xy 362.083573 -123.582932) (xy 362.031089 -123.598379)
			(xy 361.976936 -123.606166) (xy 361.922225 -123.606135) (xy 361.868081 -123.598285) (xy 361.815614 -123.582777)
			(xy 361.765903 -123.55993) (xy 361.719967 -123.530213) (xy 361.699048 -123.51258) (xy 361.698794 -123.512326)
			(xy 361.69172 -123.506722) (xy 361.674793 -123.500488) (xy 361.665774 -123.500134) (xy 361.598718 -123.500134)
			(xy 361.589701 -123.500492) (xy 361.572784 -123.506738) (xy 361.565698 -123.512326) (xy 361.56519 -123.512834)
			(xy 361.544283 -123.53045) (xy 361.49834 -123.560084) (xy 361.448638 -123.582855) (xy 361.396193 -123.598297)
			(xy 361.342081 -123.606094) (xy 361.314746 -123.60656) (xy 361.287747 -123.606093) (xy 361.23429 -123.598454)
			(xy 361.182446 -123.583352) (xy 361.13325 -123.561087) (xy 361.087687 -123.532106) (xy 361.046668 -123.496987)
			(xy 361.028488 -123.47702) (xy 361.028234 -123.476766) (xy 361.020868 -123.468638) (xy 361.011216 -123.464066)
			(xy 361.006145 -123.461924) (xy 360.995384 -123.459617) (xy 360.98988 -123.459494) (xy 360.903012 -123.45924)
			(xy 360.892852 -123.463812) (xy 360.888135 -123.466063) (xy 360.879688 -123.472215) (xy 360.876088 -123.476004)
			(xy 360.875834 -123.476258) (xy 360.87558 -123.476512) (xy 360.857448 -123.496221) (xy 360.81656 -123.530807)
			(xy 360.771233 -123.55933) (xy 360.722361 -123.581228) (xy 360.670904 -123.596071) (xy 360.617877 -123.603567)
			(xy 360.5911 -123.60402) (xy 360.56385 -123.60351) (xy 360.509904 -123.595753) (xy 360.457611 -123.580399)
			(xy 360.408035 -123.557758) (xy 360.362186 -123.528293) (xy 360.320997 -123.492603) (xy 360.285307 -123.451414)
			(xy 360.255842 -123.405565) (xy 360.233201 -123.355989) (xy 360.217847 -123.303696) (xy 360.21009 -123.24975)
			(xy 357.564572 -123.24975) (xy 357.538206 -123.266696) (xy 357.488631 -123.289339) (xy 357.436338 -123.304698)
			(xy 357.382391 -123.312459) (xy 357.35514 -123.312936) (xy 357.328114 -123.312443) (xy 357.274609 -123.304773)
			(xy 357.222719 -123.289639) (xy 357.17348 -123.267342) (xy 357.150416 -123.253246) (xy 357.142034 -123.247912)
			(xy 357.138224 -123.245372) (xy 357.126286 -123.237244) (xy 357.098346 -123.235466) (xy 357.006144 -123.28398)
			(xy 356.996746 -123.29033) (xy 356.988734 -123.297907) (xy 356.979536 -123.317923) (xy 356.978966 -123.328938)
			(xy 356.978966 -123.549918) (xy 356.979339 -123.558706) (xy 356.985296 -123.575241) (xy 356.996502 -123.588781)
			(xy 357.003858 -123.593606) (xy 357.004874 -123.594368) (xy 357.098346 -123.64339) (xy 357.126286 -123.641612)
			(xy 357.138224 -123.633484) (xy 357.142034 -123.630944) (xy 357.150416 -123.62561) (xy 357.173463 -123.61148)
			(xy 357.222699 -123.58916) (xy 357.274595 -123.574023) (xy 357.328111 -123.566373) (xy 357.35514 -123.56592)
			(xy 357.362252 -123.56592) (xy 357.389171 -123.566882) (xy 357.442351 -123.575444) (xy 357.493797 -123.591403)
			(xy 357.542487 -123.61444) (xy 357.587452 -123.644098) (xy 357.627797 -123.679787) (xy 357.66272 -123.720797)
			(xy 357.691526 -123.766311) (xy 357.713643 -123.815426) (xy 357.728631 -123.867164) (xy 357.73619 -123.920495)
			(xy 357.736648 -123.947428) (xy 357.73616 -123.974679) (xy 357.728401 -124.028626) (xy 357.713044 -124.080919)
			(xy 357.690401 -124.130496) (xy 357.660935 -124.176345) (xy 357.625244 -124.217536) (xy 357.584055 -124.253228)
			(xy 357.538206 -124.282696) (xy 357.488631 -124.305339) (xy 357.436338 -124.320698) (xy 357.382391 -124.328459)
			(xy 357.35514 -124.328936) (xy 357.328114 -124.328443) (xy 357.274609 -124.320773) (xy 357.222719 -124.305639)
			(xy 357.17348 -124.283342) (xy 357.150416 -124.269246) (xy 357.142034 -124.263912) (xy 357.138224 -124.261372)
			(xy 357.126286 -124.253244) (xy 357.098346 -124.251466) (xy 357.006144 -124.29998) (xy 356.996746 -124.30633)
			(xy 356.988734 -124.313907) (xy 356.979536 -124.333923) (xy 356.978966 -124.344938) (xy 356.978966 -124.565918)
			(xy 356.979339 -124.574706) (xy 356.985296 -124.591241) (xy 356.996502 -124.604781) (xy 357.003858 -124.609606)
			(xy 357.004874 -124.610368) (xy 357.098346 -124.65939) (xy 357.126286 -124.657612) (xy 357.138224 -124.649484)
			(xy 357.142034 -124.646944) (xy 357.150416 -124.64161) (xy 357.173463 -124.62748) (xy 357.222699 -124.60516)
			(xy 357.274595 -124.590023) (xy 357.328111 -124.582373) (xy 357.35514 -124.58192) (xy 357.362252 -124.58192)
			(xy 357.389171 -124.582882) (xy 357.442351 -124.591444) (xy 357.493797 -124.607403) (xy 357.542487 -124.63044)
			(xy 357.587452 -124.660098) (xy 357.627797 -124.695787) (xy 357.66272 -124.736797) (xy 357.691526 -124.782311)
			(xy 357.713643 -124.831426) (xy 357.728631 -124.883164) (xy 357.73619 -124.936495) (xy 357.736648 -124.963428)
			(xy 357.73616 -124.990679) (xy 357.729631 -125.036072) (xy 359.11028 -125.036072) (xy 359.11077 -125.006088)
			(xy 359.118598 -124.946632) (xy 359.134119 -124.888707) (xy 359.157068 -124.833303) (xy 359.187052 -124.781369)
			(xy 359.223558 -124.733793) (xy 359.265963 -124.691388) (xy 359.313539 -124.654882) (xy 359.365473 -124.624898)
			(xy 359.420877 -124.601949) (xy 359.478802 -124.586428) (xy 359.538258 -124.5786) (xy 359.598226 -124.5786)
			(xy 359.657682 -124.586428) (xy 359.715607 -124.601949) (xy 359.771011 -124.624898) (xy 359.822945 -124.654882)
			(xy 359.870521 -124.691388) (xy 359.912926 -124.733793) (xy 359.949432 -124.781369) (xy 359.979416 -124.833303)
			(xy 360.002365 -124.888707) (xy 360.017886 -124.946632) (xy 360.025714 -125.006088) (xy 360.026204 -125.036072)
			(xy 360.025683 -125.06714) (xy 360.01729 -125.128705) (xy 360.000643 -125.188569) (xy 359.976046 -125.245628)
			(xy 359.943952 -125.298833) (xy 359.924858 -125.323346) (xy 359.915626 -125.335691) (xy 359.90437 -125.364375)
			(xy 359.90216 -125.39511) (xy 359.909196 -125.425109) (xy 359.924842 -125.451655) (xy 359.947678 -125.472342)
			(xy 359.961434 -125.479302) (xy 359.987498 -125.491879) (xy 360.03652 -125.522635) (xy 360.081277 -125.559322)
			(xy 360.121058 -125.601354) (xy 360.155227 -125.648062) (xy 360.18324 -125.698701) (xy 360.204653 -125.752466)
			(xy 360.219122 -125.8085) (xy 360.226418 -125.86591) (xy 360.226864 -125.894846) (xy 360.226374 -125.92483)
			(xy 360.218546 -125.984286) (xy 360.203025 -126.042211) (xy 360.180076 -126.097615) (xy 360.150092 -126.149549)
			(xy 360.113586 -126.197125) (xy 360.071181 -126.23953) (xy 360.023605 -126.276036) (xy 359.971671 -126.30602)
			(xy 359.916267 -126.328969) (xy 359.858342 -126.34449) (xy 359.798886 -126.352318) (xy 359.738918 -126.352318)
			(xy 359.679462 -126.34449) (xy 359.621537 -126.328969) (xy 359.566133 -126.30602) (xy 359.514199 -126.276036)
			(xy 359.466623 -126.23953) (xy 359.424218 -126.197125) (xy 359.387712 -126.149549) (xy 359.357728 -126.097615)
			(xy 359.334779 -126.042211) (xy 359.319258 -125.984286) (xy 359.31143 -125.92483) (xy 359.31094 -125.894846)
			(xy 359.311461 -125.863778) (xy 359.319852 -125.802212) (xy 359.3365 -125.742348) (xy 359.361097 -125.685289)
			(xy 359.393191 -125.632084) (xy 359.412286 -125.607572) (xy 359.42148 -125.595202) (xy 359.432732 -125.566527)
			(xy 359.434943 -125.535802) (xy 359.427914 -125.505811) (xy 359.41228 -125.479269) (xy 359.389458 -125.458579)
			(xy 359.37571 -125.451616) (xy 359.349624 -125.439083) (xy 359.300598 -125.408323) (xy 359.255839 -125.371633)
			(xy 359.216058 -125.329596) (xy 359.18189 -125.282882) (xy 359.153879 -125.232236) (xy 359.132471 -125.178465)
			(xy 359.118009 -125.122425) (xy 359.110721 -125.06501) (xy 359.11028 -125.036072) (xy 357.729631 -125.036072)
			(xy 357.728401 -125.044626) (xy 357.713044 -125.096919) (xy 357.690401 -125.146496) (xy 357.660935 -125.192345)
			(xy 357.625244 -125.233536) (xy 357.584055 -125.269228) (xy 357.538206 -125.298696) (xy 357.488631 -125.321339)
			(xy 357.436338 -125.336698) (xy 357.382391 -125.344459) (xy 357.35514 -125.344936) (xy 357.328114 -125.344443)
			(xy 357.274609 -125.336773) (xy 357.222719 -125.321639) (xy 357.17348 -125.299342) (xy 357.150416 -125.285246)
			(xy 357.142034 -125.279912) (xy 357.138224 -125.277372) (xy 357.126286 -125.269244) (xy 357.098346 -125.267466)
			(xy 357.006144 -125.31598) (xy 356.996746 -125.32233) (xy 356.988734 -125.329907) (xy 356.979536 -125.349923)
			(xy 356.978966 -125.360938) (xy 356.978966 -126.597918) (xy 356.979339 -126.606706) (xy 356.985296 -126.623241)
			(xy 356.996502 -126.636781) (xy 357.003858 -126.641606) (xy 357.004874 -126.642368) (xy 357.098346 -126.69139)
			(xy 357.126286 -126.689612) (xy 357.138224 -126.681484) (xy 357.142034 -126.678944) (xy 357.150416 -126.67361)
			(xy 357.173463 -126.65948) (xy 357.222699 -126.63716) (xy 357.274595 -126.622023) (xy 357.328111 -126.614373)
			(xy 357.35514 -126.61392) (xy 357.362252 -126.61392) (xy 357.389171 -126.614882) (xy 357.442351 -126.623444)
			(xy 357.493797 -126.639403) (xy 357.542487 -126.66244) (xy 357.587452 -126.692098) (xy 357.627797 -126.727787)
			(xy 357.66272 -126.768797) (xy 357.691526 -126.814311) (xy 357.713643 -126.863426) (xy 357.728631 -126.915164)
			(xy 357.73619 -126.968495) (xy 357.736648 -126.995428) (xy 357.73616 -127.022679) (xy 357.728401 -127.076626)
			(xy 357.727035 -127.081276) (xy 358.969038 -127.081276) (xy 358.969038 -127.02134) (xy 358.976861 -126.961918)
			(xy 358.992374 -126.904025) (xy 359.01531 -126.848652) (xy 359.045277 -126.796746) (xy 359.081764 -126.749196)
			(xy 359.124144 -126.706816) (xy 359.171694 -126.670329) (xy 359.2236 -126.640362) (xy 359.278973 -126.617426)
			(xy 359.336866 -126.601913) (xy 359.396288 -126.59409) (xy 359.456224 -126.59409) (xy 359.515646 -126.601913)
			(xy 359.573539 -126.617426) (xy 359.628912 -126.640362) (xy 359.680818 -126.670329) (xy 359.728368 -126.706816)
			(xy 359.770748 -126.749196) (xy 359.807235 -126.796746) (xy 359.837202 -126.848652) (xy 359.860138 -126.904025)
			(xy 359.875651 -126.961918) (xy 359.883474 -127.02134) (xy 359.883482 -127.021844) (xy 363.074202 -127.021844)
			(xy 363.078273 -126.966222) (xy 363.090399 -126.911785) (xy 363.110322 -126.859694) (xy 363.137618 -126.811059)
			(xy 363.171704 -126.766916) (xy 363.211853 -126.728207) (xy 363.257211 -126.695756) (xy 363.306811 -126.670255)
			(xy 363.359595 -126.652248) (xy 363.414438 -126.642118) (xy 363.470172 -126.640081) (xy 363.525609 -126.646181)
			(xy 363.579566 -126.660287) (xy 363.630895 -126.682099) (xy 363.678501 -126.711153) (xy 363.721369 -126.746828)
			(xy 363.758586 -126.788365) (xy 363.789359 -126.834878) (xy 363.813031 -126.885375) (xy 363.829099 -126.938782)
			(xy 363.837219 -126.993958) (xy 363.837728 -127.021844) (xy 363.837219 -127.04973) (xy 363.829099 -127.104906)
			(xy 363.813031 -127.158313) (xy 363.789359 -127.20881) (xy 363.758586 -127.255323) (xy 363.721369 -127.29686)
			(xy 363.678501 -127.332535) (xy 363.630895 -127.361589) (xy 363.579566 -127.383401) (xy 363.525609 -127.397507)
			(xy 363.470172 -127.403607) (xy 363.414438 -127.40157) (xy 363.359595 -127.39144) (xy 363.306811 -127.373433)
			(xy 363.257211 -127.347932) (xy 363.211853 -127.315481) (xy 363.171704 -127.276772) (xy 363.137618 -127.232629)
			(xy 363.110322 -127.183994) (xy 363.090399 -127.131903) (xy 363.078273 -127.077466) (xy 363.074202 -127.021844)
			(xy 359.883482 -127.021844) (xy 359.883964 -127.051308) (xy 359.883474 -127.081276) (xy 359.875651 -127.140698)
			(xy 359.860138 -127.198591) (xy 359.837202 -127.253964) (xy 359.807235 -127.30587) (xy 359.770748 -127.35342)
			(xy 359.728368 -127.3958) (xy 359.680818 -127.432287) (xy 359.628912 -127.462254) (xy 359.573539 -127.48519)
			(xy 359.515646 -127.500703) (xy 359.456224 -127.508526) (xy 359.396288 -127.508526) (xy 359.336866 -127.500703)
			(xy 359.278973 -127.48519) (xy 359.2236 -127.462254) (xy 359.171694 -127.432287) (xy 359.124144 -127.3958)
			(xy 359.081764 -127.35342) (xy 359.045277 -127.30587) (xy 359.01531 -127.253964) (xy 358.992374 -127.198591)
			(xy 358.976861 -127.140698) (xy 358.969038 -127.081276) (xy 357.727035 -127.081276) (xy 357.713044 -127.128919)
			(xy 357.690401 -127.178496) (xy 357.660935 -127.224345) (xy 357.625244 -127.265536) (xy 357.584055 -127.301228)
			(xy 357.538206 -127.330696) (xy 357.488631 -127.353339) (xy 357.436338 -127.368698) (xy 357.382391 -127.376459)
			(xy 357.35514 -127.376936) (xy 357.35387 -127.376936) (xy 357.343879 -127.377439) (xy 357.325416 -127.385084)
			(xy 357.311245 -127.399174) (xy 357.30688 -127.408178) (xy 357.270812 -127.495046) (xy 357.267337 -127.504458)
			(xy 357.26729 -127.524507) (xy 357.274934 -127.543041) (xy 357.281734 -127.550418) (xy 357.332534 -127.601218)
			(xy 357.333042 -127.601726) (xy 357.340421 -127.608313) (xy 357.358721 -127.615772) (xy 357.368602 -127.616204)
			(xy 369.38712 -127.616204) (xy 369.397188 -127.616631) (xy 369.415787 -127.624351) (xy 369.423188 -127.63119)
			(xy 369.724178 -127.93218) (xy 369.731014 -127.939582) (xy 369.738723 -127.95818) (xy 369.739164 -127.968248)
			(xy 369.739164 -134.193534) (xy 369.739595 -134.2036) (xy 369.747325 -134.22219) (xy 369.75415 -134.229602)
			(xy 375.50598 -139.981432) (xy 375.506488 -139.98194) (xy 375.51387 -139.988518) (xy 375.53217 -139.995958)
			(xy 375.542048 -139.996418) (xy 384.169412 -139.996418) (xy 384.175707 -139.996229) (xy 384.187912 -139.993143)
			(xy 384.193542 -139.990322) (xy 384.217444 -139.978) (xy 384.267917 -139.959448) (xy 384.320495 -139.948167)
			(xy 384.374136 -139.944382) (xy 384.427777 -139.948167) (xy 384.480355 -139.959448) (xy 384.530828 -139.978)
			(xy 384.55473 -139.990322) (xy 384.560358 -139.99315) (xy 384.572564 -139.996243) (xy 384.57886 -139.996418)
			(xy 389.090154 -139.996418) (xy 389.100219 -139.996851) (xy 389.118808 -140.004582) (xy 389.126222 -140.011404)
			(xy 391.205974 -142.091156) (xy 391.206482 -142.091664) (xy 391.213865 -142.098241) (xy 391.232164 -142.105679)
			(xy 391.242042 -142.106142)
		)
		(stroke
			(width 0)
			(type solid)
		)
		(fill yes)
		(layer "B.Cu")
		(net "P3V3_NIC6")
	)
	(gr_poly
		(pts
			(xy 326.095614 -228.9556) (xy 326.102861 -228.953978) (xy 326.11604 -228.947147) (xy 326.121522 -228.942138)
			(xy 326.467724 -228.59619) (xy 326.475119 -228.589337) (xy 326.493719 -228.581598) (xy 326.503792 -228.581204)
			(xy 326.766682 -228.581204) (xy 326.778366 -228.57968) (xy 326.780906 -228.578918) (xy 326.790595 -228.575794)
			(xy 326.806579 -228.563216) (xy 326.811894 -228.554534) (xy 326.8218 -228.5365) (xy 326.821546 -228.535992)
			(xy 326.8363 -228.511551) (xy 326.871929 -228.466944) (xy 326.913805 -228.428143) (xy 326.960993 -228.396012)
			(xy 327.012441 -228.371269) (xy 327.067001 -228.354465) (xy 327.123455 -228.345976) (xy 327.152 -228.345492)
			(xy 327.152762 -228.345492) (xy 327.164031 -228.345602) (xy 327.186525 -228.346999) (xy 327.19772 -228.348286)
			(xy 327.209912 -228.348286) (xy 327.227115 -228.346292) (xy 327.261683 -228.344134) (xy 327.279 -228.343968)
			(xy 327.310572 -228.344457) (xy 327.373325 -228.351489) (xy 327.434931 -228.365349) (xy 327.464928 -228.37521)
			(xy 327.471843 -228.377352) (xy 327.486299 -228.378001) (xy 327.493376 -228.37648) (xy 327.495154 -228.375972)
			(xy 327.562718 -228.308408) (xy 327.56792 -228.30266) (xy 327.574907 -228.28883) (xy 327.576434 -228.28123)
			(xy 327.577196 -228.272848) (xy 327.577196 -226.929696) (xy 327.57711 -226.925752) (xy 327.575837 -226.917966)
			(xy 327.574656 -226.914202) (xy 327.568052 -226.893374) (xy 327.566528 -226.890834) (xy 327.564242 -226.887278)
			(xy 327.546452 -226.859133) (xy 327.518327 -226.798785) (xy 327.499258 -226.734993) (xy 327.48965 -226.669109)
			(xy 327.489058 -226.635818) (xy 327.489659 -226.602529) (xy 327.499299 -226.536653) (xy 327.518365 -226.472864)
			(xy 327.546455 -226.412502) (xy 327.564242 -226.384358) (xy 327.566528 -226.380802) (xy 327.568052 -226.378262)
			(xy 327.574656 -226.357434) (xy 327.575804 -226.353662) (xy 327.577083 -226.345881) (xy 327.577196 -226.34194)
			(xy 327.577196 -225.3234) (xy 327.576776 -225.313379) (xy 327.569106 -225.294863) (xy 327.554934 -225.280691)
			(xy 327.536417 -225.273023) (xy 327.526396 -225.2726) (xy 327.49998 -225.2726) (xy 327.480676 -225.280982)
			(xy 327.473564 -225.288602) (xy 327.450684 -225.311828) (xy 327.399756 -225.352534) (xy 327.343811 -225.386012)
			(xy 327.283867 -225.411651) (xy 327.221017 -225.428985) (xy 327.156405 -225.437698) (xy 327.123806 -225.438208)
			(xy 327.09289 -225.437729) (xy 327.031562 -225.429862) (xy 326.97174 -225.414232) (xy 326.914402 -225.391094)
			(xy 326.860486 -225.360826) (xy 326.810875 -225.323924) (xy 326.788272 -225.302826) (xy 326.78155 -225.29689)
			(xy 326.765179 -225.289603) (xy 326.756268 -225.288602) (xy 326.725788 -225.286824) (xy 326.716922 -225.28663)
			(xy 326.699904 -225.291572) (xy 326.692514 -225.296476) (xy 326.667842 -225.313885) (xy 326.614152 -225.341508)
			(xy 326.556776 -225.360315) (xy 326.497152 -225.369834) (xy 326.466962 -225.37039) (xy 326.466708 -225.37039)
			(xy 326.439456 -225.369927) (xy 326.385507 -225.362172) (xy 326.33321 -225.346817) (xy 326.283632 -225.324176)
			(xy 326.23778 -225.29471) (xy 326.196588 -225.259018) (xy 326.160895 -225.217827) (xy 326.131428 -225.171975)
			(xy 326.108786 -225.122397) (xy 326.09343 -225.070101) (xy 326.085673 -225.016152) (xy 326.085673 -224.961648)
			(xy 326.09343 -224.907699) (xy 326.108786 -224.855403) (xy 326.131428 -224.805825) (xy 326.160895 -224.759973)
			(xy 326.196588 -224.718782) (xy 326.23778 -224.68309) (xy 326.283632 -224.653624) (xy 326.33321 -224.630983)
			(xy 326.385507 -224.615628) (xy 326.439456 -224.607873) (xy 326.466708 -224.607374) (xy 326.481052 -224.607506)
			(xy 326.509658 -224.609666) (xy 326.523858 -224.611692) (xy 326.534841 -224.612879) (xy 326.556061 -224.606826)
			(xy 326.564752 -224.600008) (xy 326.623172 -224.549716) (xy 326.631202 -224.542147) (xy 326.640434 -224.52213)
			(xy 326.640952 -224.511108) (xy 326.640952 -224.450656) (xy 326.640405 -224.43964) (xy 326.631181 -224.419632)
			(xy 326.623172 -224.412048) (xy 326.556116 -224.35439) (xy 326.535034 -224.348294) (xy 326.527922 -224.34931)
			(xy 326.500626 -224.353255) (xy 326.445484 -224.354175) (xy 326.390784 -224.347146) (xy 326.337666 -224.332315)
			(xy 326.287236 -224.309992) (xy 326.240546 -224.28064) (xy 326.198567 -224.244873) (xy 326.162176 -224.203434)
			(xy 326.13213 -224.157188) (xy 326.109054 -224.107097) (xy 326.093431 -224.054207) (xy 326.08901 -224.026984)
			(xy 326.088756 -224.024952) (xy 326.08615 -224.013726) (xy 326.072557 -223.995144) (xy 326.05223 -223.984334)
			(xy 326.04075 -223.983296) (xy 324.738238 -223.983296) (xy 324.728173 -223.982861) (xy 324.709585 -223.975131)
			(xy 324.70217 -223.96831) (xy 324.595236 -223.861376) (xy 324.588389 -223.853978) (xy 324.580658 -223.835379)
			(xy 324.58025 -223.825308) (xy 324.58025 -223.626426) (xy 324.578726 -223.61398) (xy 324.574662 -223.597724)
			(xy 324.57263 -223.593152) (xy 324.572122 -223.592136) (xy 324.571868 -223.591882) (xy 324.557629 -223.56154)
			(xy 324.537193 -223.497708) (xy 324.526289 -223.431577) (xy 324.525132 -223.39808) (xy 324.524624 -223.384618)
			(xy 324.201028 -223.061022) (xy 324.183536 -223.042894) (xy 324.153902 -223.002161) (xy 324.131009 -222.957291)
			(xy 324.115423 -222.90939) (xy 324.107529 -222.85964) (xy 324.107048 -222.834454) (xy 324.107048 -221.881446)
			(xy 324.107568 -221.856266) (xy 324.115491 -221.806531) (xy 324.131088 -221.758645) (xy 324.153974 -221.713784)
			(xy 324.183589 -221.67305) (xy 324.201028 -221.654878) (xy 324.52564 -221.330266) (xy 324.542807 -221.313754)
			(xy 324.58113 -221.285467) (xy 324.62321 -221.263151) (xy 324.645528 -221.254828) (xy 324.657212 -221.25051)
			(xy 324.67423 -221.232476) (xy 324.69963 -221.139766) (xy 324.702178 -221.127817) (xy 324.697139 -221.103945)
			(xy 324.689978 -221.094046) (xy 324.689724 -221.093792) (xy 324.673107 -221.073143) (xy 324.645141 -221.02812)
			(xy 324.62368 -220.979658) (xy 324.609139 -220.92869) (xy 324.601798 -220.876199) (xy 324.601332 -220.849698)
			(xy 324.601818 -220.822447) (xy 324.609574 -220.768499) (xy 324.624929 -220.716204) (xy 324.647571 -220.666627)
			(xy 324.677037 -220.620777) (xy 324.712728 -220.579586) (xy 324.753919 -220.543895) (xy 324.799769 -220.514429)
			(xy 324.849346 -220.491787) (xy 324.901641 -220.476432) (xy 324.955589 -220.468676) (xy 325.010091 -220.468676)
			(xy 325.064039 -220.476432) (xy 325.116334 -220.491787) (xy 325.165911 -220.514429) (xy 325.211761 -220.543895)
			(xy 325.252952 -220.579586) (xy 325.288643 -220.620777) (xy 325.318109 -220.666627) (xy 325.340751 -220.716204)
			(xy 325.356106 -220.768499) (xy 325.363862 -220.822447) (xy 325.364348 -220.849698) (xy 325.363781 -220.8798)
			(xy 325.354327 -220.939258) (xy 325.335652 -220.996493) (xy 325.30822 -221.050085) (xy 325.290942 -221.074742)
			(xy 325.290688 -221.074996) (xy 325.285577 -221.082794) (xy 325.280807 -221.100803) (xy 325.282791 -221.119326)
			(xy 325.286624 -221.127828) (xy 325.327518 -221.208854) (xy 325.332158 -221.217002) (xy 325.346107 -221.229507)
			(xy 325.363616 -221.23617) (xy 325.372984 -221.23654) (xy 325.554086 -221.23654) (xy 325.564148 -221.2361)
			(xy 325.582724 -221.228356) (xy 325.590154 -221.221554) (xy 326.192388 -220.61932) (xy 326.192896 -220.618812)
			(xy 326.198992 -220.612716) (xy 326.206104 -220.596968) (xy 326.206866 -220.588332) (xy 326.207348 -220.579711)
			(xy 326.203196 -220.562961) (xy 326.198738 -220.555566) (xy 326.183791 -220.532015) (xy 326.160149 -220.481496)
			(xy 326.144108 -220.428075) (xy 326.136008 -220.372889) (xy 326.135492 -220.345) (xy 326.135492 -220.338142)
			(xy 326.136441 -220.311213) (xy 326.144981 -220.258011) (xy 326.160923 -220.20654) (xy 326.183949 -220.157824)
			(xy 326.213602 -220.112834) (xy 326.24929 -220.072464) (xy 326.290305 -220.037518) (xy 326.335828 -220.008691)
			(xy 326.384956 -219.986557) (xy 326.436709 -219.971556) (xy 326.490058 -219.963988) (xy 326.517 -219.963492)
			(xy 326.517508 -219.963492) (xy 326.544463 -219.963972) (xy 326.597833 -219.971595) (xy 326.649597 -219.986659)
			(xy 326.698723 -220.008864) (xy 326.721724 -220.022928) (xy 326.723756 -220.024198) (xy 326.727566 -220.026738)
			(xy 326.75576 -220.03512) (xy 326.765303 -220.034666) (xy 326.783045 -220.027615) (xy 326.790304 -220.021404)
			(xy 326.884538 -219.92717) (xy 326.891935 -219.920322) (xy 326.910534 -219.91259) (xy 326.920606 -219.912184)
			(xy 327.045828 -219.912184) (xy 327.055831 -219.911691) (xy 327.07431 -219.904026) (xy 327.088451 -219.889873)
			(xy 327.0961 -219.871387) (xy 327.096628 -219.861384) (xy 327.096628 -219.8497) (xy 327.097048 -219.839681)
			(xy 327.104719 -219.821169) (xy 327.118892 -219.807003) (xy 327.137409 -219.799343) (xy 327.147428 -219.7989)
			(xy 327.70191 -219.7989) (xy 327.731628 -219.828618) (xy 327.731628 -219.830396) (xy 328.371454 -219.830396)
			(xy 328.382183 -219.829939) (xy 328.401776 -219.821195) (xy 328.416058 -219.805185) (xy 328.419714 -219.79509)
			(xy 328.431652 -219.758006) (xy 328.433454 -219.750657) (xy 328.43306 -219.735537) (xy 328.43089 -219.728288)
			(xy 328.429874 -219.725494) (xy 328.427006 -219.718866) (xy 328.418104 -219.707503) (xy 328.412348 -219.703142)
			(xy 328.412094 -219.702888) (xy 328.386827 -219.684451) (xy 328.341092 -219.64178) (xy 328.3016 -219.593275)
			(xy 328.269087 -219.539839) (xy 328.244159 -219.482472) (xy 328.227283 -219.422242) (xy 328.218772 -219.360275)
			(xy 328.218292 -219.329) (xy 328.218782 -219.299032) (xy 328.226605 -219.23961) (xy 328.242118 -219.181717)
			(xy 328.265054 -219.126344) (xy 328.295021 -219.074438) (xy 328.331508 -219.026888) (xy 328.373888 -218.984508)
			(xy 328.421438 -218.948021) (xy 328.473344 -218.918054) (xy 328.528717 -218.895118) (xy 328.58661 -218.879605)
			(xy 328.646032 -218.871782) (xy 328.705968 -218.871782) (xy 328.76539 -218.879605) (xy 328.823283 -218.895118)
			(xy 328.878656 -218.918054) (xy 328.930562 -218.948021) (xy 328.978112 -218.984508) (xy 329.020492 -219.026888)
			(xy 329.056979 -219.074438) (xy 329.086946 -219.126344) (xy 329.109882 -219.181717) (xy 329.125395 -219.23961)
			(xy 329.133218 -219.299032) (xy 329.133708 -219.329) (xy 329.133175 -219.360287) (xy 329.124657 -219.422278)
			(xy 329.107782 -219.482533) (xy 329.082861 -219.53993) (xy 329.050361 -219.593401) (xy 329.010884 -219.641951)
			(xy 328.965166 -219.684675) (xy 328.939906 -219.703142) (xy 328.936858 -219.705174) (xy 328.931613 -219.709869)
			(xy 328.92364 -219.721464) (xy 328.92111 -219.728034) (xy 328.92111 -219.728288) (xy 328.918794 -219.736052)
			(xy 328.918649 -219.752244) (xy 328.920856 -219.760038) (xy 328.921872 -219.76334) (xy 328.932032 -219.79509)
			(xy 328.935751 -219.805204) (xy 328.950104 -219.821251) (xy 328.969779 -219.829992) (xy 328.980546 -219.830396)
			(xy 330.428854 -219.830396) (xy 330.434696 -219.824554) (xy 330.435204 -219.824046) (xy 330.4404 -219.818295)
			(xy 330.447373 -219.804463) (xy 330.44892 -219.796868) (xy 330.449682 -219.788486) (xy 330.449682 -219.054426)
			(xy 330.449584 -219.049549) (xy 330.447793 -219.039961) (xy 330.446126 -219.035376) (xy 330.442316 -219.026232)
			(xy 330.331826 -218.915742) (xy 330.32442 -218.909049) (xy 330.305983 -218.901451) (xy 330.296012 -218.90101)
			(xy 330.292964 -218.90101) (xy 330.265786 -218.889834) (xy 330.262992 -218.888818) (xy 330.259046 -218.88755)
			(xy 330.250879 -218.886138) (xy 330.246736 -218.886024) (xy 329.357482 -218.886024) (xy 329.347413 -218.885598)
			(xy 329.328811 -218.877882) (xy 329.321414 -218.871038) (xy 329.146154 -218.695778) (xy 329.139305 -218.688381)
			(xy 329.13157 -218.669782) (xy 329.131168 -218.65971) (xy 329.131168 -215.759538) (xy 329.13167 -215.749486)
			(xy 329.139386 -215.73092) (xy 329.146154 -215.72347) (xy 329.40371 -215.465914) (xy 329.411109 -215.459068)
			(xy 329.429707 -215.451335) (xy 329.439778 -215.450928) (xy 330.831952 -215.450928) (xy 330.841982 -215.450517)
			(xy 330.86052 -215.442857) (xy 330.874714 -215.428684) (xy 330.882402 -215.410157) (xy 330.882752 -215.400128)
			(xy 330.882752 -214.33663) (xy 330.882583 -214.330621) (xy 330.879758 -214.318939) (xy 330.877164 -214.313516)
			(xy 330.875325 -214.310041) (xy 330.870732 -214.303662) (xy 330.86802 -214.300816) (xy 330.096622 -213.529418)
			(xy 330.089786 -213.522016) (xy 330.082078 -213.503418) (xy 330.081636 -213.49335) (xy 330.081636 -212.796628)
			(xy 330.080366 -212.785452) (xy 330.075794 -212.773006) (xy 330.073508 -212.768688) (xy 330.064618 -212.751924)
			(xy 330.058014 -212.742526) (xy 330.054712 -212.738716) (xy 330.049378 -212.734906) (xy 330.024489 -212.716744)
			(xy 329.979079 -212.6751) (xy 329.939331 -212.62802) (xy 329.905892 -212.576269) (xy 329.879304 -212.520687)
			(xy 329.859998 -212.462175) (xy 329.848288 -212.401684) (xy 329.844364 -212.340194) (xy 329.848289 -212.278705)
			(xy 329.860001 -212.218214) (xy 329.879308 -212.159702) (xy 329.905897 -212.104121) (xy 329.939338 -212.05237)
			(xy 329.979087 -212.005292) (xy 330.024498 -211.963649) (xy 330.049378 -211.945474) (xy 330.054712 -211.941664)
			(xy 330.058014 -211.938108) (xy 330.064618 -211.928202) (xy 330.07681 -211.905088) (xy 330.079 -211.900091)
			(xy 330.081437 -211.889458) (xy 330.081636 -211.884006) (xy 330.081636 -211.844128) (xy 330.080874 -211.83473)
			(xy 330.080061 -211.830878) (xy 330.07738 -211.823478) (xy 330.07554 -211.819998) (xy 330.067666 -211.805774)
			(xy 330.067412 -211.80552) (xy 330.061316 -211.79663) (xy 330.061062 -211.796376) (xy 330.05014 -211.78393)
			(xy 330.04887 -211.782914) (xy 330.045568 -211.780628) (xy 330.032224 -211.770682) (xy 330.0068 -211.749201)
			(xy 329.994768 -211.737702) (xy 329.988418 -211.731606) (xy 329.95616 -211.71662) (xy 329.946254 -211.716112)
			(xy 329.931522 -211.71535) (xy 329.927206 -211.715293) (xy 329.918653 -211.716447) (xy 329.914504 -211.717636)
			(xy 329.890882 -211.725764) (xy 329.884532 -211.73059) (xy 329.860547 -211.748184) (xy 329.808901 -211.777698)
			(xy 329.753875 -211.800293) (xy 329.696392 -211.815591) (xy 329.637414 -211.823336) (xy 329.607672 -211.823808)
			(xy 329.607418 -211.823808) (xy 329.577448 -211.82334) (xy 329.518021 -211.815519) (xy 329.460124 -211.800007)
			(xy 329.404746 -211.777071) (xy 329.352836 -211.747102) (xy 329.305282 -211.710614) (xy 329.262897 -211.668232)
			(xy 329.226408 -211.620679) (xy 329.196437 -211.56877) (xy 329.173499 -211.513394) (xy 329.157985 -211.455496)
			(xy 329.150161 -211.39607) (xy 329.14971 -211.3661) (xy 329.150221 -211.335504) (xy 329.158377 -211.274857)
			(xy 329.174542 -211.215839) (xy 329.19843 -211.159502) (xy 329.229613 -211.106851) (xy 329.267536 -211.058826)
			(xy 329.289156 -211.03717) (xy 329.293728 -211.032598) (xy 329.300586 -211.021676) (xy 329.302364 -211.01558)
			(xy 329.304063 -211.009304) (xy 329.304578 -210.996316) (xy 329.30338 -210.989926) (xy 329.298046 -210.965542)
			(xy 329.298046 -210.965034) (xy 329.284584 -210.904836) (xy 329.283025 -210.898768) (xy 329.27737 -210.887592)
			(xy 329.273408 -210.882738) (xy 329.268836 -210.877404) (xy 329.240716 -210.868395) (xy 329.187425 -210.842966)
			(xy 329.138647 -210.809692) (xy 329.095526 -210.769355) (xy 329.059076 -210.722902) (xy 329.030152 -210.671424)
			(xy 329.009434 -210.616132) (xy 329.002898 -210.587336) (xy 329.001372 -210.580741) (xy 328.995323 -210.568636)
			(xy 328.99096 -210.56346) (xy 328.986642 -210.558888) (xy 328.888852 -210.526122) (xy 328.877315 -210.523592)
			(xy 328.854158 -210.528099) (xy 328.844402 -210.534758) (xy 328.842878 -210.536028) (xy 328.832972 -210.543902)
			(xy 328.825098 -210.550506) (xy 328.818748 -210.554824) (xy 328.795199 -210.571464) (xy 328.744715 -210.599327)
			(xy 328.691128 -210.620621) (xy 328.63529 -210.635011) (xy 328.578085 -210.642266) (xy 328.549254 -210.642708)
			(xy 328.54011 -210.642708) (xy 328.51052 -210.641673) (xy 328.451962 -210.632911) (xy 328.395022 -210.616671)
			(xy 328.340653 -210.593224) (xy 328.289761 -210.562961) (xy 328.243197 -210.526388) (xy 328.201738 -210.484116)
			(xy 328.166077 -210.43685) (xy 328.136808 -210.38538) (xy 328.114421 -210.330566) (xy 328.09929 -210.273322)
			(xy 328.091668 -210.214605) (xy 328.091292 -210.185) (xy 328.091782 -210.155032) (xy 328.099605 -210.09561)
			(xy 328.115118 -210.037717) (xy 328.138054 -209.982344) (xy 328.168021 -209.930438) (xy 328.204508 -209.882888)
			(xy 328.246888 -209.840508) (xy 328.294438 -209.804021) (xy 328.346344 -209.774054) (xy 328.401717 -209.751118)
			(xy 328.45961 -209.735605) (xy 328.519032 -209.727782) (xy 328.549 -209.727292) (xy 328.549508 -209.727292)
			(xy 328.562107 -209.727386) (xy 328.587268 -209.728785) (xy 328.5998 -209.730086) (xy 328.629979 -209.733963)
			(xy 328.68902 -209.748678) (xy 328.745592 -209.771083) (xy 328.798697 -209.800783) (xy 328.847401 -209.837256)
			(xy 328.890845 -209.879859) (xy 328.928262 -209.927841) (xy 328.958995 -209.980356) (xy 328.982501 -210.036479)
			(xy 328.998366 -210.095221) (xy 329.002898 -210.12531) (xy 329.002898 -210.125564) (xy 329.004676 -210.138772)
			(xy 329.012804 -210.14944) (xy 329.01686 -210.154517) (xy 329.027019 -210.162615) (xy 329.03287 -210.165442)
			(xy 329.112118 -210.200494) (xy 329.113896 -210.201256) (xy 329.121606 -210.203993) (xy 329.137931 -210.204889)
			(xy 329.1459 -210.203034) (xy 329.166112 -210.188114) (xy 329.209668 -210.163082) (xy 329.25611 -210.143928)
			(xy 329.30465 -210.130979) (xy 329.354461 -210.124454) (xy 329.37958 -210.12404) (xy 329.407068 -210.124506)
			(xy 329.461486 -210.132328) (xy 329.514236 -210.147816) (xy 329.564244 -210.170654) (xy 329.610493 -210.200377)
			(xy 329.652041 -210.23638) (xy 329.688041 -210.277931) (xy 329.717761 -210.324182) (xy 329.740595 -210.374192)
			(xy 329.756078 -210.426944) (xy 329.763896 -210.481362) (xy 329.76439 -210.50885) (xy 329.763896 -210.536771)
			(xy 329.755838 -210.592028) (xy 329.739883 -210.645542) (xy 329.716366 -210.69619) (xy 329.68578 -210.742911)
			(xy 329.667616 -210.76412) (xy 329.663409 -210.769227) (xy 329.657498 -210.781059) (xy 329.655932 -210.787488)
			(xy 329.654662 -210.793076) (xy 329.68057 -210.876134) (xy 329.682719 -210.882247) (xy 329.689664 -210.893182)
			(xy 329.694286 -210.897724) (xy 329.715622 -210.918044) (xy 329.72629 -210.92414) (xy 329.732132 -210.925664)
			(xy 329.757391 -210.933218) (xy 329.806122 -210.953346) (xy 329.852217 -210.97894) (xy 329.873864 -210.99399)
			(xy 329.882579 -211.00031) (xy 329.899476 -211.013651) (xy 329.907646 -211.02066) (xy 329.9079 -211.020914)
			(xy 329.914758 -211.026756) (xy 329.941174 -211.036916) (xy 329.954636 -211.03971) (xy 329.963272 -211.039964)
			(xy 329.969876 -211.039964) (xy 329.981052 -211.038948) (xy 329.988672 -211.036662) (xy 330.012802 -211.027264)
			(xy 330.01966 -211.021676) (xy 330.049886 -210.9978) (xy 330.054966 -210.994244) (xy 330.062332 -210.985862)
			(xy 330.063856 -210.983068) (xy 330.07554 -210.96097) (xy 330.077064 -210.958176) (xy 330.078953 -210.953823)
			(xy 330.081244 -210.944617) (xy 330.081636 -210.939888) (xy 330.081636 -210.86699) (xy 330.082062 -210.856921)
			(xy 330.089783 -210.838323) (xy 330.096622 -210.830922) (xy 330.817728 -210.109816) (xy 330.824064 -210.102946)
			(xy 330.831699 -210.085908) (xy 330.832666 -210.067262) (xy 330.830174 -210.058254) (xy 330.802488 -209.972148)
			(xy 330.800964 -209.96783) (xy 330.797267 -209.960072) (xy 330.78566 -209.947412) (xy 330.770531 -209.939282)
			(xy 330.762102 -209.937604) (xy 330.733195 -209.932471) (xy 330.676913 -209.915759) (xy 330.62323 -209.891988)
			(xy 330.573027 -209.861546) (xy 330.52713 -209.824935) (xy 330.486291 -209.782755) (xy 330.451181 -209.735699)
			(xy 330.422377 -209.684539) (xy 330.400352 -209.630116) (xy 330.385467 -209.573323) (xy 330.377967 -209.515094)
			(xy 330.377546 -209.485738) (xy 330.378034 -209.455768) (xy 330.385852 -209.396339) (xy 330.401361 -209.33844)
			(xy 330.424295 -209.28306) (xy 330.45426 -209.231147) (xy 330.490746 -209.183589) (xy 330.533126 -209.141201)
			(xy 330.580677 -209.104707) (xy 330.632584 -209.074732) (xy 330.68796 -209.051788) (xy 330.745857 -209.036269)
			(xy 330.805284 -209.028439) (xy 330.835254 -209.02803) (xy 330.835762 -209.02803) (xy 330.848362 -209.028123)
			(xy 330.873522 -209.029519) (xy 330.886054 -209.030824) (xy 330.914948 -209.034516) (xy 330.971547 -209.048283)
			(xy 331.025944 -209.069116) (xy 331.07726 -209.096678) (xy 331.124668 -209.130523) (xy 331.167402 -209.170106)
			(xy 331.204773 -209.214788) (xy 331.236176 -209.263848) (xy 331.261106 -209.316493) (xy 331.27916 -209.371875)
			(xy 331.285088 -209.400394) (xy 331.286573 -209.406967) (xy 331.292488 -209.41907) (xy 331.296772 -209.42427)
			(xy 331.312266 -209.442304) (xy 331.317002 -209.447368) (xy 331.328593 -209.454966) (xy 331.335126 -209.45729)
			(xy 331.40777 -209.480658) (xy 331.416778 -209.483101) (xy 331.435398 -209.482077) (xy 331.452439 -209.474503)
			(xy 331.459332 -209.468212) (xy 331.592682 -209.334862) (xy 331.600082 -209.328022) (xy 331.618681 -209.320308)
			(xy 331.62875 -209.319876) (xy 333.16037 -209.319876) (xy 333.170022 -209.31886) (xy 333.177268 -209.317236)
			(xy 333.190442 -209.310399) (xy 333.19593 -209.305398) (xy 333.317342 -209.183986) (xy 333.322547 -209.17824)
			(xy 333.32954 -209.16441) (xy 333.331058 -209.156808) (xy 333.33182 -209.148426) (xy 333.33182 -207.534764)
			(xy 333.331654 -207.528754) (xy 333.328835 -207.51707) (xy 333.326232 -207.51165) (xy 333.324392 -207.508176)
			(xy 333.319797 -207.501798) (xy 333.317088 -207.49895) (xy 333.168498 -207.35036) (xy 333.164767 -207.346839)
			(xy 333.156193 -207.34121) (xy 333.15148 -207.339184) (xy 333.142844 -207.335628) (xy 329.169776 -207.335628)
			(xy 329.159707 -207.335201) (xy 329.141106 -207.327484) (xy 329.133708 -207.320642) (xy 328.078846 -206.26578)
			(xy 328.071998 -206.258383) (xy 328.064263 -206.239784) (xy 328.06386 -206.229712) (xy 328.06386 -204.66812)
			(xy 328.063606 -204.664056) (xy 328.0631 -204.658954) (xy 328.060278 -204.6491) (xy 328.058018 -204.644498)
			(xy 328.054301 -204.63805) (xy 328.043845 -204.627467) (xy 328.037444 -204.62367) (xy 327.948798 -204.578458)
			(xy 327.942448 -204.57541) (xy 327.928478 -204.576426) (xy 327.921428 -204.577268) (xy 327.908154 -204.582291)
			(xy 327.902316 -204.586332) (xy 327.878783 -204.602899) (xy 327.82776 -204.629517) (xy 327.773316 -204.648167)
			(xy 327.716689 -204.658426) (xy 327.68794 -204.659738) (xy 327.687432 -204.659738) (xy 327.67905 -204.659992)
			(xy 327.672192 -204.659992) (xy 327.645157 -204.659195) (xy 327.591709 -204.65091) (xy 327.539967 -204.63516)
			(xy 327.490968 -204.612261) (xy 327.445695 -204.582671) (xy 327.405054 -204.546984) (xy 327.36986 -204.505915)
			(xy 327.340819 -204.460287) (xy 327.318513 -204.411015) (xy 327.303389 -204.359086) (xy 327.295751 -204.305543)
			(xy 327.295751 -204.251457) (xy 327.30339 -204.197913) (xy 327.318513 -204.145985) (xy 327.340819 -204.096713)
			(xy 327.36986 -204.051085) (xy 327.405054 -204.010016) (xy 327.445695 -203.974329) (xy 327.490969 -203.944739)
			(xy 327.539968 -203.92184) (xy 327.59171 -203.90609) (xy 327.645157 -203.897805) (xy 327.672192 -203.896976)
			(xy 327.677272 -203.896976) (xy 327.707387 -203.897559) (xy 327.766864 -203.907057) (xy 327.824107 -203.925789)
			(xy 327.877693 -203.953289) (xy 327.902316 -203.970636) (xy 327.908134 -203.974718) (xy 327.921415 -203.979759)
			(xy 327.928478 -203.980542) (xy 327.942448 -203.981558) (xy 327.948798 -203.97851) (xy 328.037444 -203.933298)
			(xy 328.043852 -203.929511) (xy 328.054305 -203.918922) (xy 328.058018 -203.91247) (xy 328.060708 -203.906937)
			(xy 328.06365 -203.894997) (xy 328.06386 -203.888848) (xy 328.06386 -203.817474) (xy 328.064289 -203.807407)
			(xy 328.072017 -203.788815) (xy 328.078846 -203.781406) (xy 328.569066 -203.291186) (xy 328.576464 -203.284341)
			(xy 328.595063 -203.276617) (xy 328.605134 -203.2762) (xy 329.125326 -203.2762) (xy 329.134702 -203.275829)
			(xy 329.152174 -203.269026) (xy 329.159362 -203.262992) (xy 329.259692 -203.162662) (xy 329.265648 -203.155433)
			(xy 329.272408 -203.137981) (xy 329.2729 -203.128626) (xy 329.2729 -196.446394) (xy 329.272799 -196.441518)
			(xy 329.270999 -196.431933) (xy 329.269344 -196.427344) (xy 329.265534 -196.4182) (xy 328.698098 -195.850764)
			(xy 328.695349 -195.848157) (xy 328.689227 -195.843697) (xy 328.685906 -195.841874) (xy 328.685906 -195.84162)
			(xy 328.676762 -195.83781) (xy 328.668034 -195.835584) (xy 328.650071 -195.836748) (xy 328.64171 -195.840096)
			(xy 328.553064 -195.879212) (xy 328.546634 -195.882682) (xy 328.535934 -195.892624) (xy 328.531982 -195.89877)
			(xy 328.529696 -195.902834) (xy 328.527271 -195.908425) (xy 328.524832 -195.920362) (xy 328.52487 -195.926456)
			(xy 328.525124 -195.944236) (xy 328.525124 -195.944744) (xy 328.524619 -195.974702) (xy 328.516769 -196.034101)
			(xy 328.501237 -196.091968) (xy 328.478286 -196.147314) (xy 328.44831 -196.199193) (xy 328.411822 -196.246716)
			(xy 328.369445 -196.289072) (xy 328.321903 -196.325537) (xy 328.27001 -196.355487) (xy 328.214652 -196.37841)
			(xy 328.156777 -196.393914) (xy 328.097374 -196.401734) (xy 328.067416 -196.402198) (xy 328.037447 -196.40173)
			(xy 327.97802 -196.393908) (xy 327.920123 -196.378396) (xy 327.864746 -196.35546) (xy 327.812837 -196.325491)
			(xy 327.765284 -196.289003) (xy 327.722901 -196.24662) (xy 327.686412 -196.199068) (xy 327.656443 -196.147159)
			(xy 327.633506 -196.091782) (xy 327.617993 -196.033886) (xy 327.61017 -195.974459) (xy 327.609708 -195.94449)
			(xy 327.610198 -195.914534) (xy 327.618017 -195.855134) (xy 327.633519 -195.797261) (xy 327.656441 -195.741907)
			(xy 327.686389 -195.690016) (xy 327.722851 -195.642477) (xy 327.765205 -195.600102) (xy 327.812726 -195.563615)
			(xy 327.864602 -195.533642) (xy 327.919945 -195.510693) (xy 327.97781 -195.495161) (xy 328.037206 -195.487313)
			(xy 328.067162 -195.486782) (xy 328.06767 -195.486782) (xy 328.08545 -195.487036) (xy 328.095191 -195.486954)
			(xy 328.1135 -195.48035) (xy 328.128017 -195.467386) (xy 328.132694 -195.458842) (xy 328.17181 -195.370196)
			(xy 328.175131 -195.361826) (xy 328.176317 -195.343869) (xy 328.174096 -195.335144) (xy 328.170286 -195.326)
			(xy 328.166476 -195.319142) (xy 327.782936 -194.935602) (xy 327.780085 -194.932896) (xy 327.773708 -194.928302)
			(xy 327.770236 -194.926458) (xy 327.764809 -194.923874) (xy 327.75313 -194.921052) (xy 327.747122 -194.92087)
			(xy 325.954644 -194.92087) (xy 325.949056 -194.92214) (xy 325.93407 -194.925442) (xy 325.928482 -194.927982)
			(xy 325.902796 -194.939607) (xy 325.848859 -194.956018) (xy 325.793095 -194.964321) (xy 325.764906 -194.964812)
			(xy 325.737743 -194.964337) (xy 325.683966 -194.956629) (xy 325.631832 -194.941355) (xy 325.606918 -194.930522)
			(xy 325.596758 -194.92595) (xy 325.546212 -194.92595) (xy 325.546212 -194.92087) (xy 323.064378 -194.92087)
			(xy 323.0595 -194.920963) (xy 323.049909 -194.922748) (xy 323.045328 -194.924426) (xy 323.036184 -194.928236)
			(xy 322.365624 -195.598796) (xy 322.362918 -195.601647) (xy 322.358326 -195.608026) (xy 322.35648 -195.611496)
			(xy 322.353903 -195.616924) (xy 322.351093 -195.628604) (xy 322.350892 -195.63461) (xy 322.350892 -196.234304)
			(xy 324.620888 -196.234304) (xy 324.624959 -196.178682) (xy 324.637085 -196.124245) (xy 324.657008 -196.072154)
			(xy 324.684304 -196.023519) (xy 324.71839 -195.979376) (xy 324.758539 -195.940667) (xy 324.803897 -195.908216)
			(xy 324.853497 -195.882715) (xy 324.906281 -195.864708) (xy 324.961124 -195.854578) (xy 325.016858 -195.852541)
			(xy 325.072295 -195.858641) (xy 325.126252 -195.872747) (xy 325.177581 -195.894559) (xy 325.225187 -195.923613)
			(xy 325.268055 -195.959288) (xy 325.305272 -196.000825) (xy 325.336045 -196.047338) (xy 325.359717 -196.097835)
			(xy 325.375785 -196.151242) (xy 325.383905 -196.206418) (xy 325.384414 -196.234304) (xy 325.383905 -196.26219)
			(xy 325.375785 -196.317366) (xy 325.359717 -196.370773) (xy 325.336045 -196.42127) (xy 325.305272 -196.467783)
			(xy 325.268055 -196.50932) (xy 325.225187 -196.544995) (xy 325.177581 -196.574049) (xy 325.126252 -196.595861)
			(xy 325.072295 -196.609967) (xy 325.016858 -196.616067) (xy 324.961124 -196.61403) (xy 324.906281 -196.6039)
			(xy 324.853497 -196.585893) (xy 324.803897 -196.560392) (xy 324.758539 -196.527941) (xy 324.71839 -196.489232)
			(xy 324.684304 -196.445089) (xy 324.657008 -196.396454) (xy 324.637085 -196.344363) (xy 324.624959 -196.289926)
			(xy 324.620888 -196.234304) (xy 322.350892 -196.234304) (xy 322.350892 -197.280272) (xy 324.545688 -197.280272)
			(xy 324.545688 -197.220336) (xy 324.553511 -197.160914) (xy 324.569024 -197.103021) (xy 324.59196 -197.047648)
			(xy 324.621927 -196.995742) (xy 324.658414 -196.948192) (xy 324.700794 -196.905812) (xy 324.748344 -196.869325)
			(xy 324.80025 -196.839358) (xy 324.855623 -196.816422) (xy 324.913516 -196.800909) (xy 324.972938 -196.793086)
			(xy 325.032874 -196.793086) (xy 325.092296 -196.800909) (xy 325.150189 -196.816422) (xy 325.205562 -196.839358)
			(xy 325.257468 -196.869325) (xy 325.305018 -196.905812) (xy 325.347398 -196.948192) (xy 325.383885 -196.995742)
			(xy 325.413852 -197.047648) (xy 325.436788 -197.103021) (xy 325.452301 -197.160914) (xy 325.460124 -197.220336)
			(xy 325.460614 -197.250304) (xy 325.460124 -197.280272) (xy 327.610198 -197.280272) (xy 327.610198 -197.220336)
			(xy 327.618021 -197.160914) (xy 327.633534 -197.103021) (xy 327.65647 -197.047648) (xy 327.686437 -196.995742)
			(xy 327.722924 -196.948192) (xy 327.765304 -196.905812) (xy 327.812854 -196.869325) (xy 327.86476 -196.839358)
			(xy 327.920133 -196.816422) (xy 327.978026 -196.800909) (xy 328.037448 -196.793086) (xy 328.097384 -196.793086)
			(xy 328.156806 -196.800909) (xy 328.214699 -196.816422) (xy 328.270072 -196.839358) (xy 328.321978 -196.869325)
			(xy 328.369528 -196.905812) (xy 328.411908 -196.948192) (xy 328.448395 -196.995742) (xy 328.478362 -197.047648)
			(xy 328.501298 -197.103021) (xy 328.516811 -197.160914) (xy 328.524634 -197.220336) (xy 328.525124 -197.250304)
			(xy 328.524634 -197.280272) (xy 328.516811 -197.339694) (xy 328.501298 -197.397587) (xy 328.478362 -197.45296)
			(xy 328.448395 -197.504866) (xy 328.411908 -197.552416) (xy 328.369528 -197.594796) (xy 328.321978 -197.631283)
			(xy 328.270072 -197.66125) (xy 328.214699 -197.684186) (xy 328.156806 -197.699699) (xy 328.097384 -197.707522)
			(xy 328.037448 -197.707522) (xy 327.978026 -197.699699) (xy 327.920133 -197.684186) (xy 327.86476 -197.66125)
			(xy 327.812854 -197.631283) (xy 327.765304 -197.594796) (xy 327.722924 -197.552416) (xy 327.686437 -197.504866)
			(xy 327.65647 -197.45296) (xy 327.633534 -197.397587) (xy 327.618021 -197.339694) (xy 327.610198 -197.280272)
			(xy 325.460124 -197.280272) (xy 325.452301 -197.339694) (xy 325.436788 -197.397587) (xy 325.413852 -197.45296)
			(xy 325.383885 -197.504866) (xy 325.347398 -197.552416) (xy 325.305018 -197.594796) (xy 325.257468 -197.631283)
			(xy 325.205562 -197.66125) (xy 325.150189 -197.684186) (xy 325.092296 -197.699699) (xy 325.032874 -197.707522)
			(xy 324.972938 -197.707522) (xy 324.913516 -197.699699) (xy 324.855623 -197.684186) (xy 324.80025 -197.66125)
			(xy 324.748344 -197.631283) (xy 324.700794 -197.594796) (xy 324.658414 -197.552416) (xy 324.621927 -197.504866)
			(xy 324.59196 -197.45296) (xy 324.569024 -197.397587) (xy 324.553511 -197.339694) (xy 324.545688 -197.280272)
			(xy 322.350892 -197.280272) (xy 322.350892 -198.550272) (xy 327.610198 -198.550272) (xy 327.610198 -198.490336)
			(xy 327.618021 -198.430914) (xy 327.633534 -198.373021) (xy 327.65647 -198.317648) (xy 327.686437 -198.265742)
			(xy 327.722924 -198.218192) (xy 327.765304 -198.175812) (xy 327.812854 -198.139325) (xy 327.86476 -198.109358)
			(xy 327.920133 -198.086422) (xy 327.978026 -198.070909) (xy 328.037448 -198.063086) (xy 328.097384 -198.063086)
			(xy 328.156806 -198.070909) (xy 328.214699 -198.086422) (xy 328.270072 -198.109358) (xy 328.321978 -198.139325)
			(xy 328.369528 -198.175812) (xy 328.411908 -198.218192) (xy 328.448395 -198.265742) (xy 328.478362 -198.317648)
			(xy 328.501298 -198.373021) (xy 328.516811 -198.430914) (xy 328.524634 -198.490336) (xy 328.525124 -198.520304)
			(xy 328.524634 -198.550272) (xy 328.516811 -198.609694) (xy 328.501298 -198.667587) (xy 328.478362 -198.72296)
			(xy 328.448395 -198.774866) (xy 328.411908 -198.822416) (xy 328.369528 -198.864796) (xy 328.321978 -198.901283)
			(xy 328.270072 -198.93125) (xy 328.214699 -198.954186) (xy 328.156806 -198.969699) (xy 328.097384 -198.977522)
			(xy 328.037448 -198.977522) (xy 327.978026 -198.969699) (xy 327.920133 -198.954186) (xy 327.86476 -198.93125)
			(xy 327.812854 -198.901283) (xy 327.765304 -198.864796) (xy 327.722924 -198.822416) (xy 327.686437 -198.774866)
			(xy 327.65647 -198.72296) (xy 327.633534 -198.667587) (xy 327.618021 -198.609694) (xy 327.610198 -198.550272)
			(xy 322.350892 -198.550272) (xy 322.350892 -208.962244) (xy 322.350675 -208.969259) (xy 322.346933 -208.982778)
			(xy 322.343526 -208.988914) (xy 322.34124 -208.992724) (xy 322.339716 -208.99501) (xy 322.337938 -209.00136)
			(xy 322.335906 -209.01533) (xy 322.335906 -209.198968) (xy 325.11414 -209.198968) (xy 325.11414 -209.139032)
			(xy 325.121963 -209.07961) (xy 325.137476 -209.021717) (xy 325.160412 -208.966344) (xy 325.190379 -208.914438)
			(xy 325.226866 -208.866888) (xy 325.269246 -208.824508) (xy 325.316796 -208.788021) (xy 325.368702 -208.758054)
			(xy 325.424075 -208.735118) (xy 325.481968 -208.719605) (xy 325.54139 -208.711782) (xy 325.601326 -208.711782)
			(xy 325.660748 -208.719605) (xy 325.718641 -208.735118) (xy 325.774014 -208.758054) (xy 325.82592 -208.788021)
			(xy 325.87347 -208.824508) (xy 325.91585 -208.866888) (xy 325.952337 -208.914438) (xy 325.982304 -208.966344)
			(xy 326.00524 -209.021717) (xy 326.020753 -209.07961) (xy 326.028576 -209.139032) (xy 326.029066 -209.169)
			(xy 326.028576 -209.198968) (xy 326.020753 -209.25839) (xy 326.00524 -209.316283) (xy 325.982304 -209.371656)
			(xy 325.952337 -209.423562) (xy 325.91585 -209.471112) (xy 325.87347 -209.513492) (xy 325.82592 -209.549979)
			(xy 325.774014 -209.579946) (xy 325.718641 -209.602882) (xy 325.660748 -209.618395) (xy 325.601326 -209.626218)
			(xy 325.54139 -209.626218) (xy 325.481968 -209.618395) (xy 325.424075 -209.602882) (xy 325.368702 -209.579946)
			(xy 325.316796 -209.549979) (xy 325.269246 -209.513492) (xy 325.226866 -209.471112) (xy 325.190379 -209.423562)
			(xy 325.160412 -209.371656) (xy 325.137476 -209.316283) (xy 325.121963 -209.25839) (xy 325.11414 -209.198968)
			(xy 322.335906 -209.198968) (xy 322.335906 -210.156552) (xy 325.090534 -210.156552) (xy 325.094605 -210.10093)
			(xy 325.106731 -210.046493) (xy 325.126654 -209.994402) (xy 325.15395 -209.945767) (xy 325.188036 -209.901624)
			(xy 325.228185 -209.862915) (xy 325.273543 -209.830464) (xy 325.323143 -209.804963) (xy 325.375927 -209.786956)
			(xy 325.43077 -209.776826) (xy 325.486504 -209.774789) (xy 325.541941 -209.780889) (xy 325.595898 -209.794995)
			(xy 325.647227 -209.816807) (xy 325.694833 -209.845861) (xy 325.737701 -209.881536) (xy 325.774918 -209.923073)
			(xy 325.805691 -209.969586) (xy 325.829363 -210.020083) (xy 325.845431 -210.07349) (xy 325.853551 -210.128666)
			(xy 325.85406 -210.156552) (xy 325.853551 -210.184438) (xy 325.853468 -210.185) (xy 326.134982 -210.185)
			(xy 326.139053 -210.129378) (xy 326.151179 -210.074941) (xy 326.171102 -210.02285) (xy 326.198398 -209.974215)
			(xy 326.232484 -209.930072) (xy 326.272633 -209.891363) (xy 326.317991 -209.858912) (xy 326.367591 -209.833411)
			(xy 326.420375 -209.815404) (xy 326.475218 -209.805274) (xy 326.530952 -209.803237) (xy 326.586389 -209.809337)
			(xy 326.640346 -209.823443) (xy 326.691675 -209.845255) (xy 326.739281 -209.874309) (xy 326.782149 -209.909984)
			(xy 326.819366 -209.951521) (xy 326.850139 -209.998034) (xy 326.873811 -210.048531) (xy 326.889879 -210.101938)
			(xy 326.897999 -210.157114) (xy 326.898508 -210.185) (xy 326.897999 -210.212886) (xy 326.889879 -210.268062)
			(xy 326.873811 -210.321469) (xy 326.850139 -210.371966) (xy 326.819366 -210.418479) (xy 326.782149 -210.460016)
			(xy 326.739281 -210.495691) (xy 326.691675 -210.524745) (xy 326.640346 -210.546557) (xy 326.586389 -210.560663)
			(xy 326.530952 -210.566763) (xy 326.475218 -210.564726) (xy 326.420375 -210.554596) (xy 326.367591 -210.536589)
			(xy 326.317991 -210.511088) (xy 326.272633 -210.478637) (xy 326.232484 -210.439928) (xy 326.198398 -210.395785)
			(xy 326.171102 -210.34715) (xy 326.151179 -210.295059) (xy 326.139053 -210.240622) (xy 326.134982 -210.185)
			(xy 325.853468 -210.185) (xy 325.845431 -210.239614) (xy 325.829363 -210.293021) (xy 325.805691 -210.343518)
			(xy 325.774918 -210.390031) (xy 325.737701 -210.431568) (xy 325.694833 -210.467243) (xy 325.647227 -210.496297)
			(xy 325.595898 -210.518109) (xy 325.541941 -210.532215) (xy 325.486504 -210.538315) (xy 325.43077 -210.536278)
			(xy 325.375927 -210.526148) (xy 325.323143 -210.508141) (xy 325.273543 -210.48264) (xy 325.228185 -210.450189)
			(xy 325.188036 -210.41148) (xy 325.15395 -210.367337) (xy 325.126654 -210.318702) (xy 325.106731 -210.266611)
			(xy 325.094605 -210.212174) (xy 325.090534 -210.156552) (xy 322.335906 -210.156552) (xy 322.335906 -212.244936)
			(xy 324.985108 -212.244936) (xy 324.985108 -212.185) (xy 324.992931 -212.125578) (xy 325.008444 -212.067685)
			(xy 325.03138 -212.012312) (xy 325.061347 -211.960406) (xy 325.097834 -211.912856) (xy 325.140214 -211.870476)
			(xy 325.187764 -211.833989) (xy 325.23967 -211.804022) (xy 325.295043 -211.781086) (xy 325.352936 -211.765573)
			(xy 325.412358 -211.75775) (xy 325.472294 -211.75775) (xy 325.531716 -211.765573) (xy 325.589609 -211.781086)
			(xy 325.644982 -211.804022) (xy 325.696888 -211.833989) (xy 325.744438 -211.870476) (xy 325.786818 -211.912856)
			(xy 325.823305 -211.960406) (xy 325.853272 -212.012312) (xy 325.876208 -212.067685) (xy 325.891721 -212.125578)
			(xy 325.899544 -212.185) (xy 325.900034 -212.214968) (xy 325.900001 -212.217) (xy 326.134982 -212.217)
			(xy 326.139053 -212.161378) (xy 326.151179 -212.106941) (xy 326.171102 -212.05485) (xy 326.198398 -212.006215)
			(xy 326.232484 -211.962072) (xy 326.272633 -211.923363) (xy 326.317991 -211.890912) (xy 326.367591 -211.865411)
			(xy 326.420375 -211.847404) (xy 326.475218 -211.837274) (xy 326.530952 -211.835237) (xy 326.586389 -211.841337)
			(xy 326.640346 -211.855443) (xy 326.691675 -211.877255) (xy 326.739281 -211.906309) (xy 326.782149 -211.941984)
			(xy 326.819366 -211.983521) (xy 326.850139 -212.030034) (xy 326.873811 -212.080531) (xy 326.889879 -212.133938)
			(xy 326.897999 -212.189114) (xy 326.898508 -212.217) (xy 326.897999 -212.244886) (xy 326.897693 -212.246968)
			(xy 328.091782 -212.246968) (xy 328.091782 -212.187032) (xy 328.099605 -212.12761) (xy 328.115118 -212.069717)
			(xy 328.138054 -212.014344) (xy 328.168021 -211.962438) (xy 328.204508 -211.914888) (xy 328.246888 -211.872508)
			(xy 328.294438 -211.836021) (xy 328.346344 -211.806054) (xy 328.401717 -211.783118) (xy 328.45961 -211.767605)
			(xy 328.519032 -211.759782) (xy 328.578968 -211.759782) (xy 328.63839 -211.767605) (xy 328.696283 -211.783118)
			(xy 328.751656 -211.806054) (xy 328.803562 -211.836021) (xy 328.851112 -211.872508) (xy 328.893492 -211.914888)
			(xy 328.929979 -211.962438) (xy 328.959946 -212.014344) (xy 328.982882 -212.069717) (xy 328.998395 -212.12761)
			(xy 329.006218 -212.187032) (xy 329.006708 -212.217) (xy 329.006218 -212.246968) (xy 328.998395 -212.30639)
			(xy 328.982882 -212.364283) (xy 328.959946 -212.419656) (xy 328.929979 -212.471562) (xy 328.893492 -212.519112)
			(xy 328.851112 -212.561492) (xy 328.803562 -212.597979) (xy 328.751656 -212.627946) (xy 328.696283 -212.650882)
			(xy 328.63839 -212.666395) (xy 328.578968 -212.674218) (xy 328.519032 -212.674218) (xy 328.45961 -212.666395)
			(xy 328.401717 -212.650882) (xy 328.346344 -212.627946) (xy 328.294438 -212.597979) (xy 328.246888 -212.561492)
			(xy 328.204508 -212.519112) (xy 328.168021 -212.471562) (xy 328.138054 -212.419656) (xy 328.115118 -212.364283)
			(xy 328.099605 -212.30639) (xy 328.091782 -212.246968) (xy 326.897693 -212.246968) (xy 326.889879 -212.300062)
			(xy 326.873811 -212.353469) (xy 326.850139 -212.403966) (xy 326.819366 -212.450479) (xy 326.782149 -212.492016)
			(xy 326.739281 -212.527691) (xy 326.691675 -212.556745) (xy 326.640346 -212.578557) (xy 326.586389 -212.592663)
			(xy 326.530952 -212.598763) (xy 326.475218 -212.596726) (xy 326.420375 -212.586596) (xy 326.367591 -212.568589)
			(xy 326.317991 -212.543088) (xy 326.272633 -212.510637) (xy 326.232484 -212.471928) (xy 326.198398 -212.427785)
			(xy 326.171102 -212.37915) (xy 326.151179 -212.327059) (xy 326.139053 -212.272622) (xy 326.134982 -212.217)
			(xy 325.900001 -212.217) (xy 325.899544 -212.244936) (xy 325.891721 -212.304358) (xy 325.876208 -212.362251)
			(xy 325.853272 -212.417624) (xy 325.823305 -212.46953) (xy 325.786818 -212.51708) (xy 325.744438 -212.55946)
			(xy 325.696888 -212.595947) (xy 325.644982 -212.625914) (xy 325.589609 -212.64885) (xy 325.531716 -212.664363)
			(xy 325.472294 -212.672186) (xy 325.412358 -212.672186) (xy 325.352936 -212.664363) (xy 325.295043 -212.64885)
			(xy 325.23967 -212.625914) (xy 325.187764 -212.595947) (xy 325.140214 -212.55946) (xy 325.097834 -212.51708)
			(xy 325.061347 -212.46953) (xy 325.03138 -212.417624) (xy 325.008444 -212.362251) (xy 324.992931 -212.304358)
			(xy 324.985108 -212.244936) (xy 322.335906 -212.244936) (xy 322.335906 -213.262968) (xy 328.90128 -213.262968)
			(xy 328.90128 -213.203032) (xy 328.909103 -213.14361) (xy 328.924616 -213.085717) (xy 328.947552 -213.030344)
			(xy 328.977519 -212.978438) (xy 329.014006 -212.930888) (xy 329.056386 -212.888508) (xy 329.103936 -212.852021)
			(xy 329.155842 -212.822054) (xy 329.211215 -212.799118) (xy 329.269108 -212.783605) (xy 329.32853 -212.775782)
			(xy 329.388466 -212.775782) (xy 329.447888 -212.783605) (xy 329.505781 -212.799118) (xy 329.561154 -212.822054)
			(xy 329.61306 -212.852021) (xy 329.66061 -212.888508) (xy 329.70299 -212.930888) (xy 329.739477 -212.978438)
			(xy 329.769444 -213.030344) (xy 329.79238 -213.085717) (xy 329.807893 -213.14361) (xy 329.815716 -213.203032)
			(xy 329.816206 -213.233) (xy 329.815716 -213.262968) (xy 329.807893 -213.32239) (xy 329.79238 -213.380283)
			(xy 329.769444 -213.435656) (xy 329.739477 -213.487562) (xy 329.70299 -213.535112) (xy 329.66061 -213.577492)
			(xy 329.61306 -213.613979) (xy 329.561154 -213.643946) (xy 329.505781 -213.666882) (xy 329.447888 -213.682395)
			(xy 329.388466 -213.690218) (xy 329.32853 -213.690218) (xy 329.269108 -213.682395) (xy 329.211215 -213.666882)
			(xy 329.155842 -213.643946) (xy 329.103936 -213.613979) (xy 329.056386 -213.577492) (xy 329.014006 -213.535112)
			(xy 328.977519 -213.487562) (xy 328.947552 -213.435656) (xy 328.924616 -213.380283) (xy 328.909103 -213.32239)
			(xy 328.90128 -213.262968) (xy 322.335906 -213.262968) (xy 322.335906 -214.206074) (xy 325.076056 -214.206074)
			(xy 325.080127 -214.150452) (xy 325.092253 -214.096015) (xy 325.112176 -214.043924) (xy 325.139472 -213.995289)
			(xy 325.173558 -213.951146) (xy 325.213707 -213.912437) (xy 325.259065 -213.879986) (xy 325.308665 -213.854485)
			(xy 325.361449 -213.836478) (xy 325.416292 -213.826348) (xy 325.472026 -213.824311) (xy 325.527463 -213.830411)
			(xy 325.58142 -213.844517) (xy 325.632749 -213.866329) (xy 325.680355 -213.895383) (xy 325.723223 -213.931058)
			(xy 325.76044 -213.972595) (xy 325.791213 -214.019108) (xy 325.814885 -214.069605) (xy 325.830953 -214.123012)
			(xy 325.839073 -214.178188) (xy 325.839582 -214.206074) (xy 325.839073 -214.23396) (xy 325.832449 -214.278968)
			(xy 326.059782 -214.278968) (xy 326.059782 -214.219032) (xy 326.067605 -214.15961) (xy 326.083118 -214.101717)
			(xy 326.106054 -214.046344) (xy 326.136021 -213.994438) (xy 326.172508 -213.946888) (xy 326.214888 -213.904508)
			(xy 326.262438 -213.868021) (xy 326.314344 -213.838054) (xy 326.369717 -213.815118) (xy 326.42761 -213.799605)
			(xy 326.487032 -213.791782) (xy 326.546968 -213.791782) (xy 326.60639 -213.799605) (xy 326.664283 -213.815118)
			(xy 326.719656 -213.838054) (xy 326.771562 -213.868021) (xy 326.819112 -213.904508) (xy 326.861492 -213.946888)
			(xy 326.897979 -213.994438) (xy 326.927946 -214.046344) (xy 326.950882 -214.101717) (xy 326.966395 -214.15961)
			(xy 326.974218 -214.219032) (xy 326.974708 -214.249) (xy 326.974218 -214.278968) (xy 328.091782 -214.278968)
			(xy 328.091782 -214.219032) (xy 328.099605 -214.15961) (xy 328.115118 -214.101717) (xy 328.138054 -214.046344)
			(xy 328.168021 -213.994438) (xy 328.204508 -213.946888) (xy 328.246888 -213.904508) (xy 328.294438 -213.868021)
			(xy 328.346344 -213.838054) (xy 328.401717 -213.815118) (xy 328.45961 -213.799605) (xy 328.519032 -213.791782)
			(xy 328.578968 -213.791782) (xy 328.63839 -213.799605) (xy 328.696283 -213.815118) (xy 328.751656 -213.838054)
			(xy 328.803562 -213.868021) (xy 328.851112 -213.904508) (xy 328.893492 -213.946888) (xy 328.929979 -213.994438)
			(xy 328.959946 -214.046344) (xy 328.982882 -214.101717) (xy 328.998395 -214.15961) (xy 329.006218 -214.219032)
			(xy 329.006708 -214.249) (xy 329.006218 -214.278968) (xy 328.998395 -214.33839) (xy 328.982882 -214.396283)
			(xy 328.959946 -214.451656) (xy 328.929979 -214.503562) (xy 328.893492 -214.551112) (xy 328.851112 -214.593492)
			(xy 328.803562 -214.629979) (xy 328.751656 -214.659946) (xy 328.696283 -214.682882) (xy 328.63839 -214.698395)
			(xy 328.578968 -214.706218) (xy 328.519032 -214.706218) (xy 328.45961 -214.698395) (xy 328.401717 -214.682882)
			(xy 328.346344 -214.659946) (xy 328.294438 -214.629979) (xy 328.246888 -214.593492) (xy 328.204508 -214.551112)
			(xy 328.168021 -214.503562) (xy 328.138054 -214.451656) (xy 328.115118 -214.396283) (xy 328.099605 -214.33839)
			(xy 328.091782 -214.278968) (xy 326.974218 -214.278968) (xy 326.966395 -214.33839) (xy 326.950882 -214.396283)
			(xy 326.927946 -214.451656) (xy 326.897979 -214.503562) (xy 326.861492 -214.551112) (xy 326.819112 -214.593492)
			(xy 326.771562 -214.629979) (xy 326.719656 -214.659946) (xy 326.664283 -214.682882) (xy 326.60639 -214.698395)
			(xy 326.546968 -214.706218) (xy 326.487032 -214.706218) (xy 326.42761 -214.698395) (xy 326.369717 -214.682882)
			(xy 326.314344 -214.659946) (xy 326.262438 -214.629979) (xy 326.214888 -214.593492) (xy 326.172508 -214.551112)
			(xy 326.136021 -214.503562) (xy 326.106054 -214.451656) (xy 326.083118 -214.396283) (xy 326.067605 -214.33839)
			(xy 326.059782 -214.278968) (xy 325.832449 -214.278968) (xy 325.830953 -214.289136) (xy 325.814885 -214.342543)
			(xy 325.791213 -214.39304) (xy 325.76044 -214.439553) (xy 325.723223 -214.48109) (xy 325.680355 -214.516765)
			(xy 325.632749 -214.545819) (xy 325.58142 -214.567631) (xy 325.527463 -214.581737) (xy 325.472026 -214.587837)
			(xy 325.416292 -214.5858) (xy 325.361449 -214.57567) (xy 325.308665 -214.557663) (xy 325.259065 -214.532162)
			(xy 325.213707 -214.499711) (xy 325.173558 -214.461002) (xy 325.139472 -214.416859) (xy 325.112176 -214.368224)
			(xy 325.092253 -214.316133) (xy 325.080127 -214.261696) (xy 325.076056 -214.206074) (xy 322.335906 -214.206074)
			(xy 322.335906 -214.942674) (xy 322.33646 -214.95337) (xy 322.345107 -214.972939) (xy 322.35267 -214.98052)
			(xy 322.408804 -215.031066) (xy 322.416949 -215.037744) (xy 322.43689 -215.044453) (xy 322.447412 -215.04402)
			(xy 322.447666 -215.04402) (xy 322.485766 -215.041988) (xy 322.513021 -215.042449) (xy 322.566976 -215.050202)
			(xy 322.619278 -215.065555) (xy 322.668863 -215.088196) (xy 322.714721 -215.117664) (xy 322.755918 -215.153358)
			(xy 322.791616 -215.194552) (xy 322.821087 -215.240407) (xy 322.843733 -215.28999) (xy 322.859091 -215.342291)
			(xy 322.866849 -215.396245) (xy 322.866849 -215.450755) (xy 322.864158 -215.46947) (xy 325.506332 -215.46947)
			(xy 325.510403 -215.413848) (xy 325.522529 -215.359411) (xy 325.542452 -215.30732) (xy 325.569748 -215.258685)
			(xy 325.603834 -215.214542) (xy 325.643983 -215.175833) (xy 325.689341 -215.143382) (xy 325.738941 -215.117881)
			(xy 325.791725 -215.099874) (xy 325.846568 -215.089744) (xy 325.902302 -215.087707) (xy 325.957739 -215.093807)
			(xy 326.011696 -215.107913) (xy 326.063025 -215.129725) (xy 326.110631 -215.158779) (xy 326.153499 -215.194454)
			(xy 326.190716 -215.235991) (xy 326.221489 -215.282504) (xy 326.245161 -215.333001) (xy 326.261229 -215.386408)
			(xy 326.269349 -215.441584) (xy 326.269858 -215.46947) (xy 326.269349 -215.497356) (xy 326.261229 -215.552532)
			(xy 326.245161 -215.605939) (xy 326.221489 -215.656436) (xy 326.190716 -215.702949) (xy 326.153499 -215.744486)
			(xy 326.110631 -215.780161) (xy 326.063025 -215.809215) (xy 326.011696 -215.831027) (xy 325.957739 -215.845133)
			(xy 325.902302 -215.851233) (xy 325.846568 -215.849196) (xy 325.791725 -215.839066) (xy 325.738941 -215.821059)
			(xy 325.689341 -215.795558) (xy 325.643983 -215.763107) (xy 325.603834 -215.724398) (xy 325.569748 -215.680255)
			(xy 325.542452 -215.63162) (xy 325.522529 -215.579529) (xy 325.510403 -215.525092) (xy 325.506332 -215.46947)
			(xy 322.864158 -215.46947) (xy 322.859091 -215.504709) (xy 322.843733 -215.55701) (xy 322.821087 -215.606593)
			(xy 322.791616 -215.652448) (xy 322.755918 -215.693642) (xy 322.714721 -215.729336) (xy 322.668863 -215.758804)
			(xy 322.619278 -215.781445) (xy 322.566976 -215.796798) (xy 322.513021 -215.804551) (xy 322.485766 -215.805004)
			(xy 322.44792 -215.802972) (xy 322.447412 -215.802972) (xy 322.436744 -215.801956) (xy 322.416932 -215.80856)
			(xy 322.35267 -215.866472) (xy 322.345002 -215.873986) (xy 322.336302 -215.893591) (xy 322.335906 -215.904318)
			(xy 322.335906 -216.310968) (xy 326.059782 -216.310968) (xy 326.059782 -216.251032) (xy 326.067605 -216.19161)
			(xy 326.083118 -216.133717) (xy 326.106054 -216.078344) (xy 326.136021 -216.026438) (xy 326.172508 -215.978888)
			(xy 326.214888 -215.936508) (xy 326.262438 -215.900021) (xy 326.314344 -215.870054) (xy 326.369717 -215.847118)
			(xy 326.42761 -215.831605) (xy 326.487032 -215.823782) (xy 326.546968 -215.823782) (xy 326.60639 -215.831605)
			(xy 326.664283 -215.847118) (xy 326.719656 -215.870054) (xy 326.771562 -215.900021) (xy 326.819112 -215.936508)
			(xy 326.861492 -215.978888) (xy 326.897979 -216.026438) (xy 326.927946 -216.078344) (xy 326.950882 -216.133717)
			(xy 326.966395 -216.19161) (xy 326.974218 -216.251032) (xy 326.974708 -216.281) (xy 326.974218 -216.310968)
			(xy 328.091782 -216.310968) (xy 328.091782 -216.251032) (xy 328.099605 -216.19161) (xy 328.115118 -216.133717)
			(xy 328.138054 -216.078344) (xy 328.168021 -216.026438) (xy 328.204508 -215.978888) (xy 328.246888 -215.936508)
			(xy 328.294438 -215.900021) (xy 328.346344 -215.870054) (xy 328.401717 -215.847118) (xy 328.45961 -215.831605)
			(xy 328.519032 -215.823782) (xy 328.578968 -215.823782) (xy 328.63839 -215.831605) (xy 328.696283 -215.847118)
			(xy 328.751656 -215.870054) (xy 328.803562 -215.900021) (xy 328.851112 -215.936508) (xy 328.893492 -215.978888)
			(xy 328.929979 -216.026438) (xy 328.959946 -216.078344) (xy 328.982882 -216.133717) (xy 328.998395 -216.19161)
			(xy 329.006218 -216.251032) (xy 329.006708 -216.281) (xy 329.006218 -216.310968) (xy 328.998395 -216.37039)
			(xy 328.982882 -216.428283) (xy 328.959946 -216.483656) (xy 328.929979 -216.535562) (xy 328.893492 -216.583112)
			(xy 328.851112 -216.625492) (xy 328.803562 -216.661979) (xy 328.751656 -216.691946) (xy 328.696283 -216.714882)
			(xy 328.63839 -216.730395) (xy 328.578968 -216.738218) (xy 328.519032 -216.738218) (xy 328.45961 -216.730395)
			(xy 328.401717 -216.714882) (xy 328.346344 -216.691946) (xy 328.294438 -216.661979) (xy 328.246888 -216.625492)
			(xy 328.204508 -216.583112) (xy 328.168021 -216.535562) (xy 328.138054 -216.483656) (xy 328.115118 -216.428283)
			(xy 328.099605 -216.37039) (xy 328.091782 -216.310968) (xy 326.974218 -216.310968) (xy 326.966395 -216.37039)
			(xy 326.950882 -216.428283) (xy 326.927946 -216.483656) (xy 326.897979 -216.535562) (xy 326.861492 -216.583112)
			(xy 326.819112 -216.625492) (xy 326.771562 -216.661979) (xy 326.719656 -216.691946) (xy 326.664283 -216.714882)
			(xy 326.60639 -216.730395) (xy 326.546968 -216.738218) (xy 326.487032 -216.738218) (xy 326.42761 -216.730395)
			(xy 326.369717 -216.714882) (xy 326.314344 -216.691946) (xy 326.262438 -216.661979) (xy 326.214888 -216.625492)
			(xy 326.172508 -216.583112) (xy 326.136021 -216.535562) (xy 326.106054 -216.483656) (xy 326.083118 -216.428283)
			(xy 326.067605 -216.37039) (xy 326.059782 -216.310968) (xy 322.335906 -216.310968) (xy 322.335906 -217.069666)
			(xy 324.525622 -217.069666) (xy 324.525622 -217.00973) (xy 324.533445 -216.950308) (xy 324.548958 -216.892415)
			(xy 324.571894 -216.837042) (xy 324.601861 -216.785136) (xy 324.638348 -216.737586) (xy 324.680728 -216.695206)
			(xy 324.728278 -216.658719) (xy 324.780184 -216.628752) (xy 324.835557 -216.605816) (xy 324.89345 -216.590303)
			(xy 324.952872 -216.58248) (xy 325.012808 -216.58248) (xy 325.07223 -216.590303) (xy 325.130123 -216.605816)
			(xy 325.185496 -216.628752) (xy 325.237402 -216.658719) (xy 325.284952 -216.695206) (xy 325.327332 -216.737586)
			(xy 325.363819 -216.785136) (xy 325.393786 -216.837042) (xy 325.416722 -216.892415) (xy 325.432235 -216.950308)
			(xy 325.440058 -217.00973) (xy 325.440548 -217.039698) (xy 325.440058 -217.069666) (xy 325.432235 -217.129088)
			(xy 325.416722 -217.186981) (xy 325.393786 -217.242354) (xy 325.363819 -217.29426) (xy 325.361716 -217.297)
			(xy 326.134982 -217.297) (xy 326.139053 -217.241378) (xy 326.151179 -217.186941) (xy 326.171102 -217.13485)
			(xy 326.198398 -217.086215) (xy 326.232484 -217.042072) (xy 326.272633 -217.003363) (xy 326.317991 -216.970912)
			(xy 326.367591 -216.945411) (xy 326.420375 -216.927404) (xy 326.475218 -216.917274) (xy 326.530952 -216.915237)
			(xy 326.586389 -216.921337) (xy 326.640346 -216.935443) (xy 326.691675 -216.957255) (xy 326.739281 -216.986309)
			(xy 326.782149 -217.021984) (xy 326.819366 -217.063521) (xy 326.850139 -217.110034) (xy 326.873811 -217.160531)
			(xy 326.889879 -217.213938) (xy 326.897999 -217.269114) (xy 326.898508 -217.297) (xy 326.897999 -217.324886)
			(xy 326.889879 -217.380062) (xy 326.873811 -217.433469) (xy 326.850139 -217.483966) (xy 326.819366 -217.530479)
			(xy 326.782149 -217.572016) (xy 326.739281 -217.607691) (xy 326.691675 -217.636745) (xy 326.640346 -217.658557)
			(xy 326.586389 -217.672663) (xy 326.530952 -217.678763) (xy 326.475218 -217.676726) (xy 326.420375 -217.666596)
			(xy 326.367591 -217.648589) (xy 326.317991 -217.623088) (xy 326.272633 -217.590637) (xy 326.232484 -217.551928)
			(xy 326.198398 -217.507785) (xy 326.171102 -217.45915) (xy 326.151179 -217.407059) (xy 326.139053 -217.352622)
			(xy 326.134982 -217.297) (xy 325.361716 -217.297) (xy 325.327332 -217.34181) (xy 325.284952 -217.38419)
			(xy 325.237402 -217.420677) (xy 325.185496 -217.450644) (xy 325.130123 -217.47358) (xy 325.07223 -217.489093)
			(xy 325.012808 -217.496916) (xy 324.952872 -217.496916) (xy 324.89345 -217.489093) (xy 324.835557 -217.47358)
			(xy 324.780184 -217.450644) (xy 324.728278 -217.420677) (xy 324.680728 -217.38419) (xy 324.638348 -217.34181)
			(xy 324.601861 -217.29426) (xy 324.571894 -217.242354) (xy 324.548958 -217.186981) (xy 324.533445 -217.129088)
			(xy 324.525622 -217.069666) (xy 322.335906 -217.069666) (xy 322.335906 -217.199464) (xy 322.336403 -217.209831)
			(xy 322.344594 -217.228879) (xy 322.359627 -217.24316) (xy 322.36918 -217.247216) (xy 322.458842 -217.279982)
			(xy 322.468718 -217.283106) (xy 322.489383 -217.282014) (xy 322.507934 -217.272844) (xy 322.514976 -217.26525)
			(xy 322.51523 -217.264996) (xy 322.533438 -217.244186) (xy 322.57483 -217.207523) (xy 322.621083 -217.177221)
			(xy 322.671226 -217.153916) (xy 322.724209 -217.138096) (xy 322.778921 -217.130093) (xy 322.806568 -217.129614)
			(xy 322.833821 -217.130075) (xy 322.887772 -217.137828) (xy 322.940071 -217.15318) (xy 322.989652 -217.17582)
			(xy 323.035507 -217.205285) (xy 323.076701 -217.240977) (xy 323.112396 -217.282168) (xy 323.141865 -217.32802)
			(xy 323.164509 -217.377599) (xy 323.179865 -217.429897) (xy 323.187623 -217.483847) (xy 323.187623 -217.538353)
			(xy 323.179865 -217.592303) (xy 323.164509 -217.644601) (xy 323.141865 -217.69418) (xy 323.112396 -217.740032)
			(xy 323.076701 -217.781223) (xy 323.035507 -217.816915) (xy 322.989652 -217.84638) (xy 322.940071 -217.86902)
			(xy 322.887772 -217.884372) (xy 322.833821 -217.892125) (xy 322.806568 -217.89263) (xy 322.77836 -217.89212)
			(xy 322.72256 -217.88381) (xy 322.668591 -217.867376) (xy 322.617629 -217.843175) (xy 322.570786 -217.811736)
			(xy 322.529082 -217.773743) (xy 322.493425 -217.730024) (xy 322.464593 -217.681532) (xy 322.443214 -217.629324)
			(xy 322.435982 -217.602054) (xy 322.432718 -217.591195) (xy 322.418452 -217.573606) (xy 322.398027 -217.563822)
			(xy 322.386706 -217.563192) (xy 322.365624 -217.563192) (xy 322.335906 -217.59291) (xy 322.335906 -217.747342)
			(xy 322.336668 -217.755724) (xy 322.338184 -217.763328) (xy 322.345173 -217.77716) (xy 322.350384 -217.782902)
			(xy 322.550282 -217.9828) (xy 322.556034 -217.987993) (xy 322.569868 -217.994959) (xy 322.57746 -217.996516)
			(xy 322.585842 -217.997278) (xy 323.548502 -217.997278) (xy 323.558573 -217.997701) (xy 323.577179 -218.005413)
			(xy 323.58457 -218.012264) (xy 323.911972 -218.339666) (xy 324.525622 -218.339666) (xy 324.525622 -218.27973)
			(xy 324.533445 -218.220308) (xy 324.548958 -218.162415) (xy 324.571894 -218.107042) (xy 324.601861 -218.055136)
			(xy 324.638348 -218.007586) (xy 324.680728 -217.965206) (xy 324.728278 -217.928719) (xy 324.780184 -217.898752)
			(xy 324.835557 -217.875816) (xy 324.89345 -217.860303) (xy 324.952872 -217.85248) (xy 325.012808 -217.85248)
			(xy 325.07223 -217.860303) (xy 325.130123 -217.875816) (xy 325.185496 -217.898752) (xy 325.237402 -217.928719)
			(xy 325.284952 -217.965206) (xy 325.327332 -218.007586) (xy 325.363819 -218.055136) (xy 325.393786 -218.107042)
			(xy 325.416722 -218.162415) (xy 325.432235 -218.220308) (xy 325.440058 -218.27973) (xy 325.440548 -218.309698)
			(xy 325.440494 -218.313) (xy 326.134982 -218.313) (xy 326.139053 -218.257378) (xy 326.151179 -218.202941)
			(xy 326.171102 -218.15085) (xy 326.198398 -218.102215) (xy 326.232484 -218.058072) (xy 326.272633 -218.019363)
			(xy 326.317991 -217.986912) (xy 326.367591 -217.961411) (xy 326.420375 -217.943404) (xy 326.475218 -217.933274)
			(xy 326.530952 -217.931237) (xy 326.586389 -217.937337) (xy 326.640346 -217.951443) (xy 326.691675 -217.973255)
			(xy 326.739281 -218.002309) (xy 326.782149 -218.037984) (xy 326.819366 -218.079521) (xy 326.850139 -218.126034)
			(xy 326.873811 -218.176531) (xy 326.889879 -218.229938) (xy 326.897999 -218.285114) (xy 326.898508 -218.313)
			(xy 326.897999 -218.340886) (xy 326.889879 -218.396062) (xy 326.873811 -218.449469) (xy 326.850139 -218.499966)
			(xy 326.819366 -218.546479) (xy 326.782149 -218.588016) (xy 326.739281 -218.623691) (xy 326.691675 -218.652745)
			(xy 326.640346 -218.674557) (xy 326.586389 -218.688663) (xy 326.530952 -218.694763) (xy 326.475218 -218.692726)
			(xy 326.420375 -218.682596) (xy 326.367591 -218.664589) (xy 326.317991 -218.639088) (xy 326.272633 -218.606637)
			(xy 326.232484 -218.567928) (xy 326.198398 -218.523785) (xy 326.171102 -218.47515) (xy 326.151179 -218.423059)
			(xy 326.139053 -218.368622) (xy 326.134982 -218.313) (xy 325.440494 -218.313) (xy 325.440058 -218.339666)
			(xy 325.432235 -218.399088) (xy 325.416722 -218.456981) (xy 325.393786 -218.512354) (xy 325.363819 -218.56426)
			(xy 325.327332 -218.61181) (xy 325.284952 -218.65419) (xy 325.237402 -218.690677) (xy 325.185496 -218.720644)
			(xy 325.130123 -218.74358) (xy 325.07223 -218.759093) (xy 325.012808 -218.766916) (xy 324.952872 -218.766916)
			(xy 324.89345 -218.759093) (xy 324.835557 -218.74358) (xy 324.780184 -218.720644) (xy 324.728278 -218.690677)
			(xy 324.680728 -218.65419) (xy 324.638348 -218.61181) (xy 324.601861 -218.56426) (xy 324.571894 -218.512354)
			(xy 324.548958 -218.456981) (xy 324.533445 -218.399088) (xy 324.525622 -218.339666) (xy 323.911972 -218.339666)
			(xy 324.11543 -218.543124) (xy 324.12228 -218.55052) (xy 324.130017 -218.569119) (xy 324.130416 -218.579192)
			(xy 324.130416 -219.609671) (xy 324.525559 -219.609671) (xy 324.525559 -219.549729) (xy 324.533384 -219.4903)
			(xy 324.548898 -219.432401) (xy 324.571838 -219.377023) (xy 324.601811 -219.325113) (xy 324.638303 -219.277559)
			(xy 324.68069 -219.235176) (xy 324.728246 -219.198688) (xy 324.780159 -219.168721) (xy 324.835539 -219.145786)
			(xy 324.89344 -219.130276) (xy 324.952869 -219.122457) (xy 324.98284 -219.12199) (xy 325.011993 -219.122481)
			(xy 325.069829 -219.129879) (xy 325.126256 -219.144562) (xy 325.180361 -219.166293) (xy 325.231269 -219.194721)
			(xy 325.278153 -219.229383) (xy 325.320255 -219.26972) (xy 325.356893 -219.315078) (xy 325.365469 -219.329)
			(xy 326.134982 -219.329) (xy 326.139053 -219.273378) (xy 326.151179 -219.218941) (xy 326.171102 -219.16685)
			(xy 326.198398 -219.118215) (xy 326.232484 -219.074072) (xy 326.272633 -219.035363) (xy 326.317991 -219.002912)
			(xy 326.367591 -218.977411) (xy 326.420375 -218.959404) (xy 326.475218 -218.949274) (xy 326.530952 -218.947237)
			(xy 326.586389 -218.953337) (xy 326.640346 -218.967443) (xy 326.691675 -218.989255) (xy 326.739281 -219.018309)
			(xy 326.782149 -219.053984) (xy 326.819366 -219.095521) (xy 326.850139 -219.142034) (xy 326.873811 -219.192531)
			(xy 326.889879 -219.245938) (xy 326.897999 -219.301114) (xy 326.898508 -219.329) (xy 326.897999 -219.356886)
			(xy 326.889879 -219.412062) (xy 326.873811 -219.465469) (xy 326.850139 -219.515966) (xy 326.819366 -219.562479)
			(xy 326.782149 -219.604016) (xy 326.739281 -219.639691) (xy 326.691675 -219.668745) (xy 326.640346 -219.690557)
			(xy 326.586389 -219.704663) (xy 326.530952 -219.710763) (xy 326.475218 -219.708726) (xy 326.420375 -219.698596)
			(xy 326.367591 -219.680589) (xy 326.317991 -219.655088) (xy 326.272633 -219.622637) (xy 326.232484 -219.583928)
			(xy 326.198398 -219.539785) (xy 326.171102 -219.49115) (xy 326.151179 -219.439059) (xy 326.139053 -219.384622)
			(xy 326.134982 -219.329) (xy 325.365469 -219.329) (xy 325.387474 -219.364721) (xy 325.411502 -219.417847)
			(xy 325.420482 -219.445586) (xy 325.423954 -219.455598) (xy 325.437773 -219.471641) (xy 325.447152 -219.476574)
			(xy 325.515224 -219.508578) (xy 325.524934 -219.512604) (xy 325.545921 -219.513259) (xy 325.555864 -219.509848)
			(xy 325.556372 -219.509848) (xy 325.579314 -219.500879) (xy 325.626921 -219.48823) (xy 325.675761 -219.48182)
			(xy 325.70039 -219.4814) (xy 325.727644 -219.481847) (xy 325.781597 -219.489603) (xy 325.833897 -219.504958)
			(xy 325.88348 -219.527601) (xy 325.929335 -219.557069) (xy 325.97053 -219.592763) (xy 326.006225 -219.633957)
			(xy 326.035695 -219.679812) (xy 326.058338 -219.729393) (xy 326.073695 -219.781693) (xy 326.081453 -219.835646)
			(xy 326.081453 -219.890154) (xy 326.073695 -219.944107) (xy 326.058338 -219.996407) (xy 326.035695 -220.045988)
			(xy 326.006225 -220.091843) (xy 325.97053 -220.133037) (xy 325.929335 -220.168731) (xy 325.88348 -220.198199)
			(xy 325.833897 -220.220842) (xy 325.781597 -220.236197) (xy 325.727644 -220.243953) (xy 325.70039 -220.244416)
			(xy 325.673189 -220.243941) (xy 325.619337 -220.236224) (xy 325.567128 -220.220933) (xy 325.517622 -220.19838)
			(xy 325.471822 -220.169021) (xy 325.430658 -220.133452) (xy 325.394966 -220.092395) (xy 325.36547 -220.046684)
			(xy 325.35368 -220.022166) (xy 325.348754 -220.012766) (xy 325.332879 -219.998721) (xy 325.322946 -219.994988)
			(xy 325.241412 -219.96908) (xy 325.220076 -219.971366) (xy 325.210932 -219.9767) (xy 325.184846 -219.991089)
			(xy 325.129762 -220.01378) (xy 325.072201 -220.029139) (xy 325.013135 -220.036906) (xy 324.983348 -220.037406)
			(xy 324.98284 -220.037406) (xy 324.952869 -220.036943) (xy 324.89344 -220.029124) (xy 324.835539 -220.013614)
			(xy 324.780159 -219.990679) (xy 324.728246 -219.960712) (xy 324.68069 -219.924224) (xy 324.638303 -219.881841)
			(xy 324.601811 -219.834287) (xy 324.571838 -219.782377) (xy 324.548898 -219.726999) (xy 324.533384 -219.6691)
			(xy 324.525559 -219.609671) (xy 324.130416 -219.609671) (xy 324.130416 -219.978732) (xy 324.134988 -219.988892)
			(xy 324.149085 -220.020804) (xy 324.168981 -220.08767) (xy 324.179057 -220.156703) (xy 324.179692 -220.191584)
			(xy 324.179179 -220.223512) (xy 324.17077 -220.286813) (xy 324.154096 -220.348454) (xy 324.129448 -220.407362)
			(xy 324.097255 -220.46251) (xy 324.058079 -220.512937) (xy 324.012602 -220.557765) (xy 323.961617 -220.596211)
			(xy 323.906011 -220.627607) (xy 323.846755 -220.651405) (xy 323.78488 -220.66719) (xy 323.753226 -220.67139)
			(xy 323.74459 -220.672406) (xy 323.72935 -220.679772) (xy 322.350638 -222.058484) (xy 322.347112 -222.062211)
			(xy 322.341472 -222.070781) (xy 322.339462 -222.075502) (xy 322.335906 -222.084138) (xy 322.335906 -224.689666)
			(xy 324.525622 -224.689666) (xy 324.525622 -224.62973) (xy 324.533445 -224.570308) (xy 324.548958 -224.512415)
			(xy 324.571894 -224.457042) (xy 324.601861 -224.405136) (xy 324.638348 -224.357586) (xy 324.680728 -224.315206)
			(xy 324.728278 -224.278719) (xy 324.780184 -224.248752) (xy 324.835557 -224.225816) (xy 324.89345 -224.210303)
			(xy 324.952872 -224.20248) (xy 325.012808 -224.20248) (xy 325.07223 -224.210303) (xy 325.130123 -224.225816)
			(xy 325.185496 -224.248752) (xy 325.237402 -224.278719) (xy 325.284952 -224.315206) (xy 325.327332 -224.357586)
			(xy 325.363819 -224.405136) (xy 325.393786 -224.457042) (xy 325.416722 -224.512415) (xy 325.432235 -224.570308)
			(xy 325.440058 -224.62973) (xy 325.440548 -224.659698) (xy 325.440058 -224.689666) (xy 325.432235 -224.749088)
			(xy 325.416722 -224.806981) (xy 325.393786 -224.862354) (xy 325.363819 -224.91426) (xy 325.327332 -224.96181)
			(xy 325.284952 -225.00419) (xy 325.237402 -225.040677) (xy 325.185496 -225.070644) (xy 325.130123 -225.09358)
			(xy 325.07223 -225.109093) (xy 325.012808 -225.116916) (xy 324.952872 -225.116916) (xy 324.89345 -225.109093)
			(xy 324.835557 -225.09358) (xy 324.780184 -225.070644) (xy 324.728278 -225.040677) (xy 324.680728 -225.00419)
			(xy 324.638348 -224.96181) (xy 324.601861 -224.91426) (xy 324.571894 -224.862354) (xy 324.548958 -224.806981)
			(xy 324.533445 -224.749088) (xy 324.525622 -224.689666) (xy 322.335906 -224.689666) (xy 322.335906 -225.959666)
			(xy 324.525622 -225.959666) (xy 324.525622 -225.89973) (xy 324.533445 -225.840308) (xy 324.548958 -225.782415)
			(xy 324.571894 -225.727042) (xy 324.601861 -225.675136) (xy 324.638348 -225.627586) (xy 324.680728 -225.585206)
			(xy 324.728278 -225.548719) (xy 324.780184 -225.518752) (xy 324.835557 -225.495816) (xy 324.89345 -225.480303)
			(xy 324.952872 -225.47248) (xy 325.012808 -225.47248) (xy 325.07223 -225.480303) (xy 325.130123 -225.495816)
			(xy 325.185496 -225.518752) (xy 325.237402 -225.548719) (xy 325.284952 -225.585206) (xy 325.327332 -225.627586)
			(xy 325.363819 -225.675136) (xy 325.393786 -225.727042) (xy 325.416722 -225.782415) (xy 325.432235 -225.840308)
			(xy 325.440058 -225.89973) (xy 325.440548 -225.929698) (xy 325.440058 -225.959666) (xy 325.432235 -226.019088)
			(xy 325.416722 -226.076981) (xy 325.393786 -226.132354) (xy 325.363819 -226.18426) (xy 325.327332 -226.23181)
			(xy 325.284952 -226.27419) (xy 325.237402 -226.310677) (xy 325.185496 -226.340644) (xy 325.130123 -226.36358)
			(xy 325.07223 -226.379093) (xy 325.012808 -226.386916) (xy 324.952872 -226.386916) (xy 324.89345 -226.379093)
			(xy 324.835557 -226.36358) (xy 324.780184 -226.340644) (xy 324.728278 -226.310677) (xy 324.680728 -226.27419)
			(xy 324.638348 -226.23181) (xy 324.601861 -226.18426) (xy 324.571894 -226.132354) (xy 324.548958 -226.076981)
			(xy 324.533445 -226.019088) (xy 324.525622 -225.959666) (xy 322.335906 -225.959666) (xy 322.335906 -226.61245)
			(xy 326.133204 -226.61245) (xy 326.137275 -226.556828) (xy 326.149401 -226.502391) (xy 326.169324 -226.4503)
			(xy 326.19662 -226.401665) (xy 326.230706 -226.357522) (xy 326.270855 -226.318813) (xy 326.316213 -226.286362)
			(xy 326.365813 -226.260861) (xy 326.418597 -226.242854) (xy 326.47344 -226.232724) (xy 326.529174 -226.230687)
			(xy 326.584611 -226.236787) (xy 326.638568 -226.250893) (xy 326.689897 -226.272705) (xy 326.737503 -226.301759)
			(xy 326.780371 -226.337434) (xy 326.817588 -226.378971) (xy 326.848361 -226.425484) (xy 326.872033 -226.475981)
			(xy 326.888101 -226.529388) (xy 326.896221 -226.584564) (xy 326.89673 -226.61245) (xy 326.896221 -226.640336)
			(xy 326.888101 -226.695512) (xy 326.872033 -226.748919) (xy 326.848361 -226.799416) (xy 326.817588 -226.845929)
			(xy 326.780371 -226.887466) (xy 326.737503 -226.923141) (xy 326.689897 -226.952195) (xy 326.638568 -226.974007)
			(xy 326.584611 -226.988113) (xy 326.529174 -226.994213) (xy 326.47344 -226.992176) (xy 326.418597 -226.982046)
			(xy 326.365813 -226.964039) (xy 326.316213 -226.938538) (xy 326.270855 -226.906087) (xy 326.230706 -226.867378)
			(xy 326.19662 -226.823235) (xy 326.169324 -226.7746) (xy 326.149401 -226.722509) (xy 326.137275 -226.668072)
			(xy 326.133204 -226.61245) (xy 322.335906 -226.61245) (xy 322.335906 -226.815904) (xy 322.336426 -226.825802)
			(xy 322.344008 -226.844095) (xy 322.350638 -226.851464) (xy 322.371974 -226.873308) (xy 322.378817 -226.87961)
			(xy 322.395746 -226.887287) (xy 322.404994 -226.888294) (xy 322.433742 -226.890551) (xy 322.490126 -226.902631)
			(xy 322.544051 -226.923058) (xy 322.594288 -226.951366) (xy 322.639694 -226.98691) (xy 322.679235 -227.028881)
			(xy 322.712011 -227.076325) (xy 322.737276 -227.128159) (xy 322.754454 -227.183205) (xy 322.763154 -227.240208)
			(xy 322.763642 -227.26904) (xy 322.76306 -227.297482) (xy 322.754519 -227.353724) (xy 322.746624 -227.381054)
			(xy 322.746624 -227.381562) (xy 322.74383 -227.390452) (xy 322.7451 -227.40874) (xy 322.781422 -227.487734)
			(xy 322.79463 -227.500688) (xy 322.803012 -227.504244) (xy 322.828133 -227.515768) (xy 322.875042 -227.544992)
			(xy 322.917243 -227.580678) (xy 322.953855 -227.62208) (xy 322.984109 -227.66833) (xy 323.007374 -227.718462)
			(xy 323.023163 -227.771426) (xy 323.031144 -227.826114) (xy 323.031612 -227.853748) (xy 323.031123 -227.880997)
			(xy 323.023361 -227.93494) (xy 323.008002 -227.987229) (xy 322.985358 -228.036801) (xy 322.95589 -228.082645)
			(xy 322.920199 -228.12383) (xy 322.87901 -228.159517) (xy 322.833162 -228.188979) (xy 322.783588 -228.211617)
			(xy 322.731297 -228.22697) (xy 322.677353 -228.234726) (xy 322.650104 -228.235256) (xy 322.64985 -228.235256)
			(xy 322.624205 -228.234841) (xy 322.573378 -228.227964) (xy 322.523934 -228.214328) (xy 322.476767 -228.194179)
			(xy 322.454524 -228.181408) (xy 322.448682 -228.177852) (xy 322.435474 -228.174296) (xy 322.386706 -228.174296)
			(xy 322.376684 -228.174714) (xy 322.358164 -228.182383) (xy 322.343989 -228.196556) (xy 322.336316 -228.215074)
			(xy 322.335906 -228.225096) (xy 322.335906 -228.272082) (xy 323.205838 -228.272082) (xy 323.205838 -228.212146)
			(xy 323.213661 -228.152724) (xy 323.229174 -228.094831) (xy 323.25211 -228.039458) (xy 323.282077 -227.987552)
			(xy 323.318564 -227.940002) (xy 323.360944 -227.897622) (xy 323.408494 -227.861135) (xy 323.4604 -227.831168)
			(xy 323.515773 -227.808232) (xy 323.573666 -227.792719) (xy 323.633088 -227.784896) (xy 323.693024 -227.784896)
			(xy 323.752446 -227.792719) (xy 323.810339 -227.808232) (xy 323.865712 -227.831168) (xy 323.917618 -227.861135)
			(xy 323.965168 -227.897622) (xy 324.007548 -227.940002) (xy 324.044035 -227.987552) (xy 324.074002 -228.039458)
			(xy 324.096938 -228.094831) (xy 324.112451 -228.152724) (xy 324.120274 -228.212146) (xy 324.120764 -228.242114)
			(xy 324.120274 -228.272082) (xy 324.11285 -228.328471) (xy 324.484663 -228.328471) (xy 324.484663 -228.268529)
			(xy 324.492488 -228.2091) (xy 324.508003 -228.151202) (xy 324.530943 -228.095823) (xy 324.560915 -228.043913)
			(xy 324.597407 -227.99636) (xy 324.639795 -227.953977) (xy 324.687352 -227.91749) (xy 324.739265 -227.887522)
			(xy 324.794645 -227.864588) (xy 324.852546 -227.849079) (xy 324.911975 -227.84126) (xy 324.941946 -227.840794)
			(xy 324.970251 -227.841226) (xy 325.026428 -227.848222) (xy 325.081313 -227.86209) (xy 325.13407 -227.882618)
			(xy 325.183895 -227.909493) (xy 325.230027 -227.942305) (xy 325.271762 -227.980553) (xy 325.290434 -228.00183)
			(xy 325.297038 -228.00945) (xy 325.314564 -228.018594) (xy 325.39559 -228.025706) (xy 325.405429 -228.026143)
			(xy 325.424246 -228.020386) (xy 325.432166 -228.01453) (xy 325.43242 -228.014276) (xy 325.452984 -227.997925)
			(xy 325.497751 -227.970428) (xy 325.545869 -227.949338) (xy 325.596427 -227.935053) (xy 325.648467 -227.927845)
			(xy 325.674736 -227.927408) (xy 325.701987 -227.927864) (xy 325.755933 -227.935625) (xy 325.808225 -227.950984)
			(xy 325.8578 -227.973628) (xy 325.903648 -228.003097) (xy 325.944836 -228.03879) (xy 325.980525 -228.079981)
			(xy 326.009989 -228.125831) (xy 326.032628 -228.175408) (xy 326.047982 -228.227702) (xy 326.055738 -228.281649)
			(xy 326.055738 -228.336151) (xy 326.047982 -228.390098) (xy 326.032628 -228.442392) (xy 326.009989 -228.491969)
			(xy 325.980525 -228.537819) (xy 325.944836 -228.57901) (xy 325.903648 -228.614703) (xy 325.8578 -228.644172)
			(xy 325.808225 -228.666816) (xy 325.755933 -228.682175) (xy 325.701987 -228.689936) (xy 325.674736 -228.690424)
			(xy 325.647366 -228.689955) (xy 325.593186 -228.682141) (xy 325.540682 -228.666654) (xy 325.490935 -228.643812)
			(xy 325.444969 -228.614086) (xy 325.424038 -228.596444) (xy 325.416244 -228.590257) (xy 325.397414 -228.583869)
			(xy 325.387462 -228.583998) (xy 325.316596 -228.588316) (xy 325.306705 -228.589391) (xy 325.288797 -228.59801)
			(xy 325.281798 -228.60508) (xy 325.26001 -228.62843) (xy 325.211057 -228.669446) (xy 325.156876 -228.703256)
			(xy 325.09852 -228.729204) (xy 325.037123 -228.746785) (xy 324.973878 -228.755658) (xy 324.941946 -228.75621)
			(xy 324.911975 -228.75574) (xy 324.852546 -228.747921) (xy 324.794645 -228.732412) (xy 324.739265 -228.709478)
			(xy 324.687352 -228.67951) (xy 324.639795 -228.643023) (xy 324.597407 -228.60064) (xy 324.560915 -228.553087)
			(xy 324.530943 -228.501177) (xy 324.508003 -228.445798) (xy 324.492488 -228.3879) (xy 324.484663 -228.328471)
			(xy 324.11285 -228.328471) (xy 324.112451 -228.331504) (xy 324.096938 -228.389397) (xy 324.074002 -228.44477)
			(xy 324.044035 -228.496676) (xy 324.007548 -228.544226) (xy 323.965168 -228.586606) (xy 323.917618 -228.623093)
			(xy 323.865712 -228.65306) (xy 323.810339 -228.675996) (xy 323.752446 -228.691509) (xy 323.693024 -228.699332)
			(xy 323.633088 -228.699332) (xy 323.573666 -228.691509) (xy 323.515773 -228.675996) (xy 323.4604 -228.65306)
			(xy 323.408494 -228.623093) (xy 323.360944 -228.586606) (xy 323.318564 -228.544226) (xy 323.282077 -228.496676)
			(xy 323.25211 -228.44477) (xy 323.229174 -228.389397) (xy 323.213661 -228.331504) (xy 323.205838 -228.272082)
			(xy 322.335906 -228.272082) (xy 322.335906 -228.905816) (xy 322.336397 -228.915821) (xy 322.34406 -228.934306)
			(xy 322.358212 -228.948453) (xy 322.376701 -228.956107) (xy 322.386706 -228.956616) (xy 326.085962 -228.956616)
		)
		(stroke
			(width 0)
			(type solid)
		)
		(fill yes)
		(layer "B.Cu")
		(net "P3V3_AUX")
	)
	(gr_poly
		(pts
			(xy 165.147752 -301.319692) (xy 165.158018 -301.319161) (xy 165.176878 -301.311029) (xy 165.184328 -301.303944)
			(xy 165.242494 -301.242476) (xy 165.249606 -301.222918) (xy 165.248844 -301.211996) (xy 165.24859 -301.2059)
			(xy 165.24859 -300.8249) (xy 165.249081 -300.80985) (xy 165.256871 -300.780775) (xy 165.271921 -300.754707)
			(xy 165.293206 -300.733423) (xy 165.319273 -300.718372) (xy 165.348348 -300.710581) (xy 165.363398 -300.710092)
			(xy 165.668198 -300.710092) (xy 165.676975 -300.710253) (xy 165.694323 -300.712938) (xy 165.702742 -300.715426)
			(xy 165.714172 -300.719236) (xy 165.738302 -300.715426) (xy 165.748208 -300.708314) (xy 165.757593 -300.700702)
			(xy 165.768601 -300.679229) (xy 165.76929 -300.667166) (xy 165.76929 -300.410626) (xy 165.769787 -300.387034)
			(xy 165.777153 -300.340425) (xy 165.791591 -300.295501) (xy 165.801802 -300.274228) (xy 165.803326 -300.271434)
			(xy 165.806628 -300.262036) (xy 165.806882 -300.26102) (xy 165.812978 -300.252384) (xy 165.819074 -300.244002)
			(xy 165.819836 -300.242986) (xy 165.820598 -300.241716) (xy 165.834822 -300.222158) (xy 165.836092 -300.220634)
			(xy 165.843069 -300.210512) (xy 165.850831 -300.187198) (xy 165.851332 -300.174914) (xy 165.851078 -300.174914)
			(xy 165.851332 -300.17466) (xy 165.850791 -300.1617) (xy 165.842102 -300.137279) (xy 165.834314 -300.126908)
			(xy 165.833298 -300.125638) (xy 165.833044 -300.125384) (xy 165.832536 -300.124622) (xy 165.820598 -300.108112)
			(xy 165.820344 -300.10735) (xy 165.812978 -300.097444) (xy 165.806882 -300.088808) (xy 165.806628 -300.087792)
			(xy 165.803326 -300.078394) (xy 165.801802 -300.0756) (xy 165.791592 -300.054325) (xy 165.777133 -300.009406)
			(xy 165.769769 -299.962795) (xy 165.76929 -299.939202) (xy 165.76929 -299.631354) (xy 165.768735 -299.621423)
			(xy 165.76105 -299.603099) (xy 165.747 -299.589048) (xy 165.728675 -299.581365) (xy 165.718744 -299.580808)
			(xy 165.414198 -299.580808) (xy 165.399148 -299.580317) (xy 165.370074 -299.572526) (xy 165.344007 -299.557476)
			(xy 165.322723 -299.536192) (xy 165.307673 -299.510124) (xy 165.299883 -299.48105) (xy 165.29939 -299.466)
			(xy 165.29939 -299.085) (xy 165.299881 -299.06995) (xy 165.307671 -299.040875) (xy 165.322721 -299.014807)
			(xy 165.344006 -298.993523) (xy 165.370073 -298.978472) (xy 165.399148 -298.970681) (xy 165.414198 -298.970192)
			(xy 165.560756 -298.970192) (xy 165.564562 -298.970123) (xy 165.572087 -298.968971) (xy 165.575742 -298.967906)
			(xy 165.596316 -298.961556) (xy 165.602412 -298.957492) (xy 165.621781 -298.945465) (xy 165.663227 -298.926471)
			(xy 165.706959 -298.913583) (xy 165.752082 -298.907064) (xy 165.774878 -298.906692) (xy 165.781736 -298.906946)
			(xy 165.78199 -298.906946) (xy 165.81191 -298.908299) (xy 165.870469 -298.920829) (xy 165.898322 -298.931838)
			(xy 165.898576 -298.931838) (xy 165.908024 -298.935391) (xy 165.928191 -298.935509) (xy 165.946831 -298.927808)
			(xy 165.954202 -298.920916) (xy 166.057326 -298.817792) (xy 166.059358 -298.81576) (xy 166.059866 -298.815252)
			(xy 166.06774 -298.807124) (xy 166.091616 -298.782486) (xy 166.095354 -298.778786) (xy 166.104062 -298.772892)
			(xy 166.108888 -298.770802) (xy 166.123366 -298.76496) (xy 166.12362 -298.764706) (xy 166.156132 -298.751498)
			(xy 166.197788 -298.734734) (xy 166.198042 -298.734734) (xy 166.207186 -298.730924) (xy 166.21183 -298.728878)
			(xy 166.22027 -298.723243) (xy 166.22395 -298.719748) (xy 166.275512 -298.668186) (xy 166.282907 -298.661332)
			(xy 166.301506 -298.653588) (xy 166.31158 -298.6532) (xy 166.409878 -298.6532) (xy 166.419248 -298.652721)
			(xy 166.436696 -298.645871) (xy 166.450504 -298.633194) (xy 166.45509 -298.625006) (xy 166.455598 -298.624244)
			(xy 166.500302 -298.525438) (xy 166.495984 -298.49572) (xy 166.486078 -298.484544) (xy 166.471253 -298.467055)
			(xy 166.446263 -298.428619) (xy 166.427054 -298.386991) (xy 166.414026 -298.343035) (xy 166.407447 -298.297663)
			(xy 166.407084 -298.27474) (xy 166.407399 -298.25379) (xy 166.412876 -298.21225) (xy 166.418006 -298.191936)
			(xy 166.419784 -298.185586) (xy 166.419784 -297.91406) (xy 166.420277 -297.899034) (xy 166.428052 -297.870005)
			(xy 166.443065 -297.843971) (xy 166.464294 -297.822701) (xy 166.490299 -297.807638) (xy 166.519313 -297.799806)
			(xy 166.534338 -297.799252) (xy 166.915592 -297.799252) (xy 166.930645 -297.799742) (xy 166.959725 -297.80753)
			(xy 166.9858 -297.822579) (xy 167.007092 -297.843862) (xy 167.022151 -297.86993) (xy 167.029952 -297.899007)
			(xy 167.0304 -297.91406) (xy 167.0304 -298.185586) (xy 167.032178 -298.191936) (xy 167.037291 -298.212254)
			(xy 167.042767 -298.253791) (xy 167.0431 -298.27474) (xy 167.042697 -298.29766) (xy 167.036113 -298.343026)
			(xy 167.023088 -298.386978) (xy 167.00389 -298.428605) (xy 166.978917 -298.467047) (xy 166.964106 -298.484544)
			(xy 166.9542 -298.49572) (xy 166.949882 -298.525438) (xy 166.994078 -298.623228) (xy 166.99484 -298.625006)
			(xy 166.995094 -298.625006) (xy 166.999656 -298.633202) (xy 167.013488 -298.645846) (xy 167.030939 -298.652679)
			(xy 167.040306 -298.6532) (xy 168.309798 -298.6532) (xy 168.319176 -298.652735) (xy 168.336647 -298.645902)
			(xy 168.350478 -298.633228) (xy 168.35501 -298.625006) (xy 168.355518 -298.624244) (xy 168.400222 -298.525438)
			(xy 168.395904 -298.49572) (xy 168.385998 -298.484544) (xy 168.371172 -298.467056) (xy 168.346181 -298.42862)
			(xy 168.326971 -298.386992) (xy 168.313941 -298.343036) (xy 168.307363 -298.297663) (xy 168.307004 -298.27474)
			(xy 168.307319 -298.25379) (xy 168.312796 -298.212251) (xy 168.317926 -298.191936) (xy 168.319704 -298.185586)
			(xy 168.319704 -297.91406) (xy 168.320197 -297.899035) (xy 168.327973 -297.870008) (xy 168.342986 -297.843977)
			(xy 168.364216 -297.822709) (xy 168.390221 -297.807651) (xy 168.419234 -297.799824) (xy 168.434258 -297.799252)
			(xy 168.815512 -297.799252) (xy 168.830563 -297.799744) (xy 168.859639 -297.807536) (xy 168.885709 -297.822586)
			(xy 168.906997 -297.843869) (xy 168.922053 -297.869935) (xy 168.929852 -297.899009) (xy 168.93032 -297.91406)
			(xy 168.93032 -298.185586) (xy 168.932098 -298.191936) (xy 168.93721 -298.212254) (xy 168.942686 -298.253791)
			(xy 168.94302 -298.27474) (xy 168.942617 -298.297661) (xy 168.936034 -298.343027) (xy 168.923009 -298.386979)
			(xy 168.903812 -298.428607) (xy 168.87884 -298.46705) (xy 168.864026 -298.484544) (xy 168.85412 -298.49572)
			(xy 168.849802 -298.525438) (xy 168.893998 -298.623228) (xy 168.89476 -298.625006) (xy 168.895014 -298.625006)
			(xy 168.899577 -298.6332) (xy 168.91341 -298.645839) (xy 168.93086 -298.652665) (xy 168.940226 -298.6532)
			(xy 170.209718 -298.6532) (xy 170.219094 -298.652731) (xy 170.236559 -298.645894) (xy 170.250384 -298.63322)
			(xy 170.25493 -298.625006) (xy 170.255438 -298.624244) (xy 170.300142 -298.525438) (xy 170.295824 -298.49572)
			(xy 170.285918 -298.484544) (xy 170.271096 -298.467054) (xy 170.24611 -298.428616) (xy 170.226905 -298.386988)
			(xy 170.213879 -298.343033) (xy 170.207302 -298.297662) (xy 170.206924 -298.27474) (xy 170.20724 -298.25379)
			(xy 170.212717 -298.212251) (xy 170.217846 -298.191936) (xy 170.219624 -298.185586) (xy 170.219624 -297.91406)
			(xy 170.220118 -297.899036) (xy 170.227894 -297.870011) (xy 170.242907 -297.843983) (xy 170.264138 -297.822718)
			(xy 170.290143 -297.807664) (xy 170.319155 -297.799842) (xy 170.334178 -297.799252) (xy 170.715432 -297.799252)
			(xy 170.730481 -297.799747) (xy 170.759553 -297.807542) (xy 170.785618 -297.822593) (xy 170.806902 -297.843875)
			(xy 170.821955 -297.86994) (xy 170.829752 -297.899011) (xy 170.83024 -297.91406) (xy 170.83024 -298.185586)
			(xy 170.832018 -298.191936) (xy 170.83713 -298.212254) (xy 170.842606 -298.253791) (xy 170.84294 -298.27474)
			(xy 170.842537 -298.297661) (xy 170.835954 -298.343027) (xy 170.82293 -298.38698) (xy 170.803734 -298.428608)
			(xy 170.778764 -298.467052) (xy 170.763946 -298.484544) (xy 170.75404 -298.49572) (xy 170.749722 -298.525438)
			(xy 170.793918 -298.623228) (xy 170.79468 -298.625006) (xy 170.794934 -298.625006) (xy 170.799493 -298.633208)
			(xy 170.813322 -298.645869) (xy 170.830774 -298.652722) (xy 170.840146 -298.6532) (xy 172.109638 -298.6532)
			(xy 172.119012 -298.652728) (xy 172.136472 -298.645886) (xy 172.150291 -298.633211) (xy 172.15485 -298.625006)
			(xy 172.155358 -298.624244) (xy 172.200062 -298.525438) (xy 172.195744 -298.49572) (xy 172.185838 -298.484544)
			(xy 172.167647 -298.462886) (xy 172.138443 -298.414456) (xy 172.118262 -298.361625) (xy 172.10774 -298.306058)
			(xy 172.106844 -298.277788) (xy 172.106844 -298.276264) (xy 172.106844 -298.27474) (xy 172.10716 -298.25379)
			(xy 172.112637 -298.212251) (xy 172.117766 -298.191936) (xy 172.119544 -298.185586) (xy 172.119544 -297.913806)
			(xy 172.120003 -297.899793) (xy 172.126883 -297.872619) (xy 172.140116 -297.847909) (xy 172.158921 -297.827122)
			(xy 172.182185 -297.811486) (xy 172.195236 -297.806364) (xy 172.197014 -297.805602) (xy 172.201586 -297.804078)
			(xy 172.20965 -297.801804) (xy 172.226228 -297.799377) (xy 172.234606 -297.799252) (xy 172.615606 -297.799252)
			(xy 172.630658 -297.799744) (xy 172.659735 -297.807534) (xy 172.685806 -297.822584) (xy 172.707095 -297.843867)
			(xy 172.722153 -297.869934) (xy 172.729952 -297.899009) (xy 172.730414 -297.91406) (xy 172.730414 -298.186094)
			(xy 172.732192 -298.192444) (xy 172.737179 -298.212458) (xy 172.742528 -298.253355) (xy 172.74286 -298.273978)
			(xy 172.74286 -298.27474) (xy 172.742457 -298.29766) (xy 172.735873 -298.343025) (xy 172.722846 -298.386976)
			(xy 172.703646 -298.428602) (xy 172.678671 -298.467042) (xy 172.663866 -298.484544) (xy 172.65396 -298.49572)
			(xy 172.649642 -298.525438) (xy 172.693838 -298.623228) (xy 172.6946 -298.625006) (xy 172.694854 -298.625006)
			(xy 172.699414 -298.633206) (xy 172.713244 -298.645862) (xy 172.730696 -298.652707) (xy 172.740066 -298.6532)
			(xy 174.009812 -298.6532) (xy 174.019189 -298.652732) (xy 174.036655 -298.645896) (xy 174.050483 -298.633222)
			(xy 174.055024 -298.625006) (xy 174.055532 -298.624244) (xy 174.100236 -298.525438) (xy 174.095918 -298.49572)
			(xy 174.086012 -298.484544) (xy 174.067932 -298.46304) (xy 174.038863 -298.41497) (xy 174.018684 -298.362543)
			(xy 174.008022 -298.307388) (xy 174.007018 -298.279312) (xy 174.007018 -298.27728) (xy 174.007018 -298.27474)
			(xy 174.007387 -298.253719) (xy 174.012988 -298.212051) (xy 174.018194 -298.191682) (xy 174.019972 -298.185078)
			(xy 174.019972 -298.049696) (xy 174.019718 -298.049696) (xy 174.019718 -297.91406) (xy 174.020212 -297.899036)
			(xy 174.027988 -297.87001) (xy 174.043001 -297.843981) (xy 174.064231 -297.822716) (xy 174.090236 -297.80766)
			(xy 174.119249 -297.799836) (xy 174.134272 -297.799252) (xy 174.530766 -297.799252) (xy 174.545821 -297.799739)
			(xy 174.574907 -297.807523) (xy 174.600988 -297.82257) (xy 174.622285 -297.843853) (xy 174.637349 -297.869924)
			(xy 174.645152 -297.899005) (xy 174.645574 -297.91406) (xy 174.645574 -298.21886) (xy 174.64548 -298.224487)
			(xy 174.644337 -298.235683) (xy 174.643288 -298.241212) (xy 174.642272 -298.25442) (xy 174.643034 -298.27474)
			(xy 174.642631 -298.297661) (xy 174.636048 -298.343027) (xy 174.623023 -298.386979) (xy 174.603827 -298.428608)
			(xy 174.578857 -298.467052) (xy 174.56404 -298.484544) (xy 174.554134 -298.49572) (xy 174.549816 -298.525438)
			(xy 174.594012 -298.623228) (xy 174.594774 -298.625006) (xy 174.595028 -298.625006) (xy 174.599587 -298.633209)
			(xy 174.613415 -298.645871) (xy 174.630868 -298.652726) (xy 174.64024 -298.6532) (xy 176.859692 -298.6532)
			(xy 176.869071 -298.652736) (xy 176.886543 -298.645904) (xy 176.900376 -298.633231) (xy 176.904904 -298.625006)
			(xy 176.905412 -298.624244) (xy 176.950116 -298.525438) (xy 176.945798 -298.49572) (xy 176.935892 -298.484544)
			(xy 176.917698 -298.462888) (xy 176.888489 -298.414458) (xy 176.868304 -298.361627) (xy 176.85778 -298.306059)
			(xy 176.856898 -298.277788) (xy 176.856898 -298.274486) (xy 176.857242 -298.253664) (xy 176.862726 -298.212382)
			(xy 176.86782 -298.19219) (xy 176.869598 -298.185586) (xy 176.869598 -297.91406) (xy 176.870094 -297.899014)
			(xy 176.877891 -297.869948) (xy 176.892944 -297.843891) (xy 176.914227 -297.822616) (xy 176.940291 -297.807573)
			(xy 176.969359 -297.799788) (xy 176.984406 -297.799252) (xy 177.365406 -297.799252) (xy 177.380458 -297.799744)
			(xy 177.409535 -297.807534) (xy 177.435606 -297.822584) (xy 177.456895 -297.843867) (xy 177.471953 -297.869934)
			(xy 177.479752 -297.899009) (xy 177.480214 -297.91406) (xy 177.480214 -298.175172) (xy 177.480722 -298.18203)
			(xy 177.481992 -298.19219) (xy 177.487043 -298.212261) (xy 177.492524 -298.253285) (xy 177.492914 -298.273978)
			(xy 177.492914 -298.277788) (xy 177.492026 -298.306057) (xy 177.481492 -298.361621) (xy 177.461306 -298.414449)
			(xy 177.432102 -298.462879) (xy 177.41392 -298.484544) (xy 177.404014 -298.49572) (xy 177.399696 -298.525438)
			(xy 177.443892 -298.623228) (xy 177.444654 -298.625006) (xy 177.444908 -298.625006) (xy 177.44947 -298.6332)
			(xy 177.463303 -298.645841) (xy 177.480753 -298.652669) (xy 177.49012 -298.6532) (xy 178.759866 -298.6532)
			(xy 178.769237 -298.652723) (xy 178.786689 -298.645876) (xy 178.8005 -298.633199) (xy 178.805078 -298.625006)
			(xy 178.805586 -298.624244) (xy 178.85029 -298.525438) (xy 178.845972 -298.49572) (xy 178.836066 -298.484544)
			(xy 178.821242 -298.467055) (xy 178.796252 -298.428618) (xy 178.777044 -298.38699) (xy 178.764016 -298.343035)
			(xy 178.757438 -298.297663) (xy 178.757072 -298.27474) (xy 178.757387 -298.25379) (xy 178.762864 -298.21225)
			(xy 178.767994 -298.191936) (xy 178.769772 -298.185586) (xy 178.769772 -297.91406) (xy 178.770265 -297.899033)
			(xy 178.77804 -297.870003) (xy 178.793052 -297.843968) (xy 178.814282 -297.822695) (xy 178.840286 -297.80763)
			(xy 178.869301 -297.799796) (xy 178.884326 -297.799252) (xy 179.26558 -297.799252) (xy 179.280634 -297.79974)
			(xy 179.309717 -297.807527) (xy 179.335794 -297.822575) (xy 179.357089 -297.843858) (xy 179.37215 -297.869927)
			(xy 179.379952 -297.899006) (xy 179.380388 -297.91406) (xy 179.380388 -298.185586) (xy 179.382166 -298.191936)
			(xy 179.387279 -298.212254) (xy 179.392755 -298.253791) (xy 179.393088 -298.27474) (xy 179.392685 -298.29766)
			(xy 179.386101 -298.343026) (xy 179.373075 -298.386977) (xy 179.353877 -298.428604) (xy 179.328903 -298.467046)
			(xy 179.314094 -298.484544) (xy 179.304188 -298.49572) (xy 179.29987 -298.525438) (xy 179.344066 -298.623228)
			(xy 179.344828 -298.625006) (xy 179.345082 -298.625006) (xy 179.349643 -298.633203) (xy 179.363475 -298.645851)
			(xy 179.380926 -298.652687) (xy 179.390294 -298.6532) (xy 180.659786 -298.6532) (xy 180.669165 -298.652737)
			(xy 180.686639 -298.645906) (xy 180.700474 -298.633234) (xy 180.704998 -298.625006) (xy 180.705506 -298.624244)
			(xy 180.75021 -298.525438) (xy 180.745892 -298.49572) (xy 180.735986 -298.484544) (xy 180.721161 -298.467056)
			(xy 180.69617 -298.428619) (xy 180.676961 -298.386991) (xy 180.663932 -298.343035) (xy 180.657353 -298.297663)
			(xy 180.656992 -298.27474) (xy 180.657307 -298.25379) (xy 180.662784 -298.212251) (xy 180.667914 -298.191936)
			(xy 180.669692 -298.185586) (xy 180.669692 -297.91406) (xy 180.670185 -297.899034) (xy 180.677961 -297.870006)
			(xy 180.692973 -297.843973) (xy 180.714203 -297.822704) (xy 180.740208 -297.807643) (xy 180.769221 -297.799813)
			(xy 180.784246 -297.799252) (xy 181.1655 -297.799252) (xy 181.180552 -297.799743) (xy 181.209631 -297.807533)
			(xy 181.235703 -297.822582) (xy 181.256994 -297.843865) (xy 181.272052 -297.869932) (xy 181.279852 -297.899008)
			(xy 181.280308 -297.91406) (xy 181.280308 -298.185586) (xy 181.282086 -298.191936) (xy 181.287199 -298.212254)
			(xy 181.292675 -298.253791) (xy 181.293008 -298.27474) (xy 181.292605 -298.297661) (xy 181.286021 -298.343026)
			(xy 181.272996 -298.386978) (xy 181.253799 -298.428606) (xy 181.228827 -298.467048) (xy 181.214014 -298.484544)
			(xy 181.204108 -298.49572) (xy 181.19979 -298.525438) (xy 181.243986 -298.623228) (xy 181.244748 -298.625006)
			(xy 181.245002 -298.625006) (xy 181.249564 -298.633201) (xy 181.263397 -298.645843) (xy 181.280847 -298.652673)
			(xy 181.290214 -298.6532) (xy 182.042816 -298.6532) (xy 182.051198 -298.652438) (xy 182.058804 -298.650925)
			(xy 182.072642 -298.643943) (xy 182.078376 -298.638722) (xy 182.226712 -298.490386) (xy 182.233566 -298.482991)
			(xy 182.241309 -298.464392) (xy 182.241698 -298.454318) (xy 182.241698 -297.889422) (xy 182.233062 -297.869864)
			(xy 182.22468 -297.862498) (xy 182.15991 -297.804586) (xy 182.13959 -297.798236) (xy 182.128668 -297.799506)
			(xy 182.115714 -297.800268) (xy 181.73446 -297.800268) (xy 181.719415 -297.799772) (xy 181.690354 -297.791974)
			(xy 181.6643 -297.77692) (xy 181.643031 -297.755636) (xy 181.627996 -297.729572) (xy 181.620218 -297.700505)
			(xy 181.619652 -297.68546) (xy 181.619652 -297.413934) (xy 181.617874 -297.407584) (xy 181.612759 -297.387267)
			(xy 181.60728 -297.345729) (xy 181.606952 -297.32478) (xy 181.607445 -297.299452) (xy 181.615481 -297.249436)
			(xy 181.631345 -297.201328) (xy 181.654636 -297.156344) (xy 181.684766 -297.115621) (xy 181.720972 -297.080192)
			(xy 181.762337 -297.050951) (xy 181.807815 -297.028639) (xy 181.856256 -297.013821) (xy 181.881272 -297.00982)
			(xy 181.901338 -297.007026) (xy 181.908196 -297.006518) (xy 181.92496 -297.006518) (xy 181.953524 -297.007204)
			(xy 182.009723 -297.017479) (xy 182.063193 -297.037602) (xy 182.088028 -297.05173) (xy 182.095926 -297.056052)
			(xy 182.113607 -297.059391) (xy 182.131348 -297.056394) (xy 182.139336 -297.052238) (xy 182.212742 -297.010582)
			(xy 182.216118 -297.008908) (xy 182.222368 -297.0047) (xy 182.225188 -297.0022) (xy 182.232738 -296.994704)
			(xy 182.241285 -296.97524) (xy 182.241698 -296.964608) (xy 182.241698 -294.835072) (xy 182.24115 -294.824472)
			(xy 182.232617 -294.805062) (xy 182.225188 -294.79748) (xy 182.222357 -294.794995) (xy 182.216109 -294.790787)
			(xy 182.212742 -294.789098) (xy 182.141368 -294.748712) (xy 182.132445 -294.744105) (xy 182.112536 -294.741598)
			(xy 182.10276 -294.743886) (xy 182.088282 -294.74795) (xy 182.082694 -294.750998) (xy 182.058498 -294.764133)
			(xy 182.006708 -294.782798) (xy 181.952485 -294.792303) (xy 181.92496 -294.792908) (xy 181.899973 -294.792415)
			(xy 181.850615 -294.784591) (xy 181.803088 -294.769144) (xy 181.758562 -294.746452) (xy 181.718134 -294.717075)
			(xy 181.682799 -294.681735) (xy 181.653427 -294.641304) (xy 181.630741 -294.596775) (xy 181.615299 -294.549246)
			(xy 181.607482 -294.499887) (xy 181.606952 -294.4749) (xy 181.60727 -294.453951) (xy 181.612753 -294.412413)
			(xy 181.617874 -294.392096) (xy 181.619652 -294.385746) (xy 181.619652 -294.11422) (xy 181.620138 -294.099187)
			(xy 181.627903 -294.070142) (xy 181.64291 -294.04409) (xy 181.66414 -294.022802) (xy 181.690151 -294.007723)
			(xy 181.719175 -293.999879) (xy 181.734206 -293.999412) (xy 182.115714 -293.999412) (xy 182.128668 -294.000174)
			(xy 182.13959 -294.001444) (xy 182.15991 -293.995094) (xy 182.22468 -293.937182) (xy 182.225442 -293.93642)
			(xy 182.232777 -293.928948) (xy 182.241176 -293.909793) (xy 182.241698 -293.899336) (xy 182.241698 -293.533322)
			(xy 182.234078 -293.514526) (xy 182.226712 -293.507414) (xy 182.028592 -293.309294) (xy 182.02148 -293.301928)
			(xy 182.002684 -293.294308) (xy 181.374034 -293.294308) (xy 181.362049 -293.294946) (xy 181.340686 -293.305806)
			(xy 181.33314 -293.315136) (xy 181.277514 -293.39159) (xy 181.273704 -293.415212) (xy 181.277514 -293.42715)
			(xy 181.284722 -293.450954) (xy 181.292502 -293.500074) (xy 181.293008 -293.52494) (xy 181.292694 -293.54589)
			(xy 181.28722 -293.58743) (xy 181.282086 -293.607744) (xy 181.280308 -293.614094) (xy 181.280308 -293.88562)
			(xy 181.279817 -293.900647) (xy 181.272045 -293.92968) (xy 181.257034 -293.955717) (xy 181.235804 -293.976991)
			(xy 181.209797 -293.992055) (xy 181.18078 -293.999887) (xy 181.165754 -294.000428) (xy 180.7845 -294.000428)
			(xy 180.769449 -293.999937) (xy 180.740372 -293.992147) (xy 180.714302 -293.977097) (xy 180.693015 -293.955814)
			(xy 180.677961 -293.929746) (xy 180.670166 -293.900671) (xy 180.669692 -293.88562) (xy 180.669692 -293.614094)
			(xy 180.667914 -293.607744) (xy 180.662803 -293.587426) (xy 180.657329 -293.545888) (xy 180.656992 -293.52494)
			(xy 180.657494 -293.500074) (xy 180.665281 -293.450955) (xy 180.672486 -293.42715) (xy 180.676296 -293.415212)
			(xy 180.672486 -293.39159) (xy 180.61686 -293.315136) (xy 180.609251 -293.305885) (xy 180.587924 -293.295046)
			(xy 180.575966 -293.294308) (xy 179.474114 -293.294308) (xy 179.462132 -293.29495) (xy 179.440775 -293.305815)
			(xy 179.43322 -293.315136) (xy 179.377594 -293.39159) (xy 179.373784 -293.415212) (xy 179.377594 -293.42715)
			(xy 179.384803 -293.450953) (xy 179.392583 -293.500074) (xy 179.393088 -293.52494) (xy 179.392774 -293.54589)
			(xy 179.387299 -293.58743) (xy 179.382166 -293.607744) (xy 179.380388 -293.614094) (xy 179.380388 -293.885874)
			(xy 179.379931 -293.899887) (xy 179.373052 -293.927059) (xy 179.359817 -293.951767) (xy 179.341009 -293.972549)
			(xy 179.31774 -293.988176) (xy 179.304696 -293.993316) (xy 179.302918 -293.994078) (xy 179.298346 -293.995602)
			(xy 179.290281 -293.997871) (xy 179.273703 -294.00029) (xy 179.265326 -294.000428) (xy 178.884326 -294.000428)
			(xy 178.869267 -293.999984) (xy 178.840173 -293.992196) (xy 178.814087 -293.977142) (xy 178.792786 -293.95585)
			(xy 178.777722 -293.929769) (xy 178.769922 -293.900679) (xy 178.769518 -293.88562) (xy 178.769518 -293.613586)
			(xy 178.76774 -293.607236) (xy 178.762754 -293.587222) (xy 178.757407 -293.546325) (xy 178.757072 -293.525702)
			(xy 178.757072 -293.52494) (xy 178.757574 -293.500074) (xy 178.76536 -293.450954) (xy 178.772566 -293.42715)
			(xy 178.776376 -293.415212) (xy 178.772566 -293.39159) (xy 178.71694 -293.315136) (xy 178.709336 -293.305872)
			(xy 178.68801 -293.295) (xy 178.676046 -293.294308) (xy 177.57394 -293.294308) (xy 177.561955 -293.294944)
			(xy 177.540589 -293.305803) (xy 177.533046 -293.315136) (xy 177.47742 -293.39159) (xy 177.47361 -293.415212)
			(xy 177.47742 -293.42715) (xy 177.484643 -293.451015) (xy 177.492423 -293.500264) (xy 177.492914 -293.525194)
			(xy 177.492914 -293.526972) (xy 177.49247 -293.547347) (xy 177.486986 -293.587731) (xy 177.481992 -293.60749)
			(xy 177.480214 -293.614094) (xy 177.480214 -293.88562) (xy 177.479721 -293.900669) (xy 177.471927 -293.92974)
			(xy 177.456876 -293.955803) (xy 177.435592 -293.977084) (xy 177.409527 -293.992132) (xy 177.380455 -293.999923)
			(xy 177.365406 -294.000428) (xy 176.984406 -294.000428) (xy 176.969354 -293.999938) (xy 176.940276 -293.992149)
			(xy 176.914205 -293.9771) (xy 176.892916 -293.955816) (xy 176.877861 -293.929748) (xy 176.870066 -293.900671)
			(xy 176.869598 -293.88562) (xy 176.869598 -293.624508) (xy 176.86909 -293.61765) (xy 176.86782 -293.60749)
			(xy 176.86277 -293.587419) (xy 176.857292 -293.546395) (xy 176.856898 -293.525702) (xy 176.856898 -293.521892)
			(xy 176.857591 -293.497792) (xy 176.865367 -293.450213) (xy 176.872392 -293.42715) (xy 176.876202 -293.415212)
			(xy 176.872392 -293.39159) (xy 176.816766 -293.315136) (xy 176.809157 -293.305884) (xy 176.78783 -293.295043)
			(xy 176.775872 -293.294308) (xy 174.72406 -293.294308) (xy 174.712084 -293.294961) (xy 174.690746 -293.30584)
			(xy 174.683166 -293.315136) (xy 174.62754 -293.39159) (xy 174.62373 -293.415212) (xy 174.62754 -293.42715)
			(xy 174.634762 -293.451016) (xy 174.642542 -293.500264) (xy 174.643034 -293.525194) (xy 174.643034 -293.526972)
			(xy 174.64259 -293.547347) (xy 174.637106 -293.587731) (xy 174.632112 -293.60749) (xy 174.630334 -293.614094)
			(xy 174.630334 -293.88562) (xy 174.629841 -293.90067) (xy 174.622047 -293.929743) (xy 174.606997 -293.955809)
			(xy 174.585714 -293.977093) (xy 174.559648 -293.992145) (xy 174.530576 -293.99994) (xy 174.515526 -294.000428)
			(xy 174.134526 -294.000428) (xy 174.119467 -293.999984) (xy 174.090373 -293.992196) (xy 174.064287 -293.977142)
			(xy 174.042986 -293.95585) (xy 174.027922 -293.929769) (xy 174.020122 -293.900679) (xy 174.019718 -293.88562)
			(xy 174.019718 -293.624508) (xy 174.01921 -293.61765) (xy 174.01794 -293.60749) (xy 174.012889 -293.587419)
			(xy 174.007411 -293.546395) (xy 174.007018 -293.525702) (xy 174.007018 -293.521892) (xy 174.007711 -293.497793)
			(xy 174.015488 -293.450214) (xy 174.022512 -293.42715) (xy 174.026322 -293.415212) (xy 174.022512 -293.39159)
			(xy 173.966886 -293.315136) (xy 173.959278 -293.305881) (xy 173.937952 -293.295031) (xy 173.925992 -293.294308)
			(xy 172.823886 -293.294308) (xy 172.811907 -293.294956) (xy 172.79056 -293.305828) (xy 172.782992 -293.315136)
			(xy 172.727366 -293.39159) (xy 172.723556 -293.415212) (xy 172.727366 -293.42715) (xy 172.734575 -293.450954)
			(xy 172.742356 -293.500074) (xy 172.74286 -293.52494) (xy 172.74286 -293.525702) (xy 172.742512 -293.546323)
			(xy 172.737158 -293.587218) (xy 172.732192 -293.607236) (xy 172.730414 -293.613586) (xy 172.730414 -293.88562)
			(xy 172.729921 -293.900669) (xy 172.722127 -293.92974) (xy 172.707076 -293.955803) (xy 172.685792 -293.977084)
			(xy 172.659727 -293.992132) (xy 172.630655 -293.999923) (xy 172.615606 -294.000428) (xy 172.234606 -294.000428)
			(xy 172.226231 -294.000274) (xy 172.209656 -293.997849) (xy 172.201586 -293.995602) (xy 172.197014 -293.994078)
			(xy 172.195236 -293.993316) (xy 172.182194 -293.98817) (xy 172.158921 -293.972547) (xy 172.140108 -293.951768)
			(xy 172.12687 -293.92706) (xy 172.11999 -293.899887) (xy 172.119544 -293.885874) (xy 172.119544 -293.614094)
			(xy 172.117766 -293.607744) (xy 172.112654 -293.587426) (xy 172.10718 -293.545889) (xy 172.106844 -293.52494)
			(xy 172.107345 -293.500074) (xy 172.115131 -293.450954) (xy 172.122338 -293.42715) (xy 172.126148 -293.415212)
			(xy 172.122338 -293.39159) (xy 172.066712 -293.315136) (xy 172.059106 -293.305876) (xy 172.03778 -293.295016)
			(xy 172.025818 -293.294308) (xy 170.923966 -293.294308) (xy 170.911989 -293.29496) (xy 170.89065 -293.305837)
			(xy 170.883072 -293.315136) (xy 170.827446 -293.39159) (xy 170.823636 -293.415212) (xy 170.827446 -293.42715)
			(xy 170.834653 -293.450954) (xy 170.842432 -293.500074) (xy 170.84294 -293.52494) (xy 170.842626 -293.54589)
			(xy 170.83715 -293.58743) (xy 170.832018 -293.607744) (xy 170.83024 -293.614094) (xy 170.83024 -293.88562)
			(xy 170.82975 -293.900649) (xy 170.821978 -293.929685) (xy 170.806967 -293.955726) (xy 170.785738 -293.977005)
			(xy 170.759731 -293.992075) (xy 170.730714 -293.999914) (xy 170.715686 -294.000428) (xy 170.334432 -294.000428)
			(xy 170.319372 -293.999985) (xy 170.290277 -293.992197) (xy 170.26419 -293.977144) (xy 170.242888 -293.955852)
			(xy 170.227823 -293.929771) (xy 170.220022 -293.900679) (xy 170.219624 -293.88562) (xy 170.219624 -293.614094)
			(xy 170.217846 -293.607744) (xy 170.212734 -293.587426) (xy 170.20726 -293.545888) (xy 170.206924 -293.52494)
			(xy 170.207425 -293.500074) (xy 170.215211 -293.450954) (xy 170.222418 -293.42715) (xy 170.226228 -293.415212)
			(xy 170.222418 -293.39159) (xy 170.166792 -293.315136) (xy 170.159185 -293.30588) (xy 170.137858 -293.295028)
			(xy 170.125898 -293.294308) (xy 169.024046 -293.294308) (xy 169.01206 -293.294943) (xy 168.990692 -293.305801)
			(xy 168.983152 -293.315136) (xy 168.927526 -293.39159) (xy 168.923716 -293.415212) (xy 168.927526 -293.42715)
			(xy 168.934734 -293.450954) (xy 168.942513 -293.500074) (xy 168.94302 -293.52494) (xy 168.942706 -293.54589)
			(xy 168.937232 -293.58743) (xy 168.932098 -293.607744) (xy 168.93032 -293.614094) (xy 168.93032 -293.88562)
			(xy 168.929829 -293.900648) (xy 168.922057 -293.929682) (xy 168.907047 -293.955721) (xy 168.885817 -293.976996)
			(xy 168.85981 -293.992063) (xy 168.830793 -293.999897) (xy 168.815766 -294.000428) (xy 168.434512 -294.000428)
			(xy 168.41946 -293.999939) (xy 168.390381 -293.99215) (xy 168.364308 -293.977102) (xy 168.343018 -293.955818)
			(xy 168.327962 -293.929749) (xy 168.320166 -293.900672) (xy 168.319704 -293.88562) (xy 168.319704 -293.614094)
			(xy 168.317926 -293.607744) (xy 168.312815 -293.587426) (xy 168.307341 -293.545888) (xy 168.307004 -293.52494)
			(xy 168.307505 -293.500074) (xy 168.31529 -293.450954) (xy 168.322498 -293.42715) (xy 168.326308 -293.415212)
			(xy 168.322498 -293.39159) (xy 168.266872 -293.315136) (xy 168.259264 -293.305883) (xy 168.237937 -293.295039)
			(xy 168.225978 -293.294308) (xy 167.124126 -293.294308) (xy 167.112142 -293.294947) (xy 167.090781 -293.30581)
			(xy 167.083232 -293.315136) (xy 167.027606 -293.39159) (xy 167.023796 -293.415212) (xy 167.027606 -293.42715)
			(xy 167.034814 -293.450954) (xy 167.042594 -293.500074) (xy 167.0431 -293.52494) (xy 167.042786 -293.54589)
			(xy 167.037312 -293.58743) (xy 167.032178 -293.607744) (xy 167.0304 -293.614094) (xy 167.0304 -293.88562)
			(xy 167.029909 -293.900647) (xy 167.022137 -293.929679) (xy 167.007126 -293.955715) (xy 166.985895 -293.976987)
			(xy 166.959888 -293.99205) (xy 166.930872 -293.99988) (xy 166.915846 -294.000428) (xy 166.534592 -294.000428)
			(xy 166.519542 -293.999936) (xy 166.490467 -293.992145) (xy 166.464398 -293.977095) (xy 166.443113 -293.955811)
			(xy 166.42806 -293.929744) (xy 166.420265 -293.90067) (xy 166.419784 -293.88562) (xy 166.419784 -293.614094)
			(xy 166.418006 -293.607744) (xy 166.412895 -293.587426) (xy 166.407422 -293.545888) (xy 166.407084 -293.52494)
			(xy 166.407682 -293.496325) (xy 166.417918 -293.440019) (xy 166.438084 -293.386461) (xy 166.452296 -293.361618)
			(xy 166.461186 -293.346632) (xy 166.456868 -293.312088) (xy 166.444422 -293.299642) (xy 166.000176 -292.855396)
			(xy 165.970458 -292.825424) (xy 165.949371 -292.841239) (xy 165.903051 -292.866386) (xy 165.853215 -292.883542)
			(xy 165.801231 -292.892238) (xy 165.774878 -292.892734) (xy 165.753858 -292.892361) (xy 165.712192 -292.886753)
			(xy 165.69182 -292.881558) (xy 165.685216 -292.87978) (xy 165.414198 -292.87978) (xy 165.408864 -292.87978)
			(xy 165.394328 -292.878663) (xy 165.36649 -292.870036) (xy 165.341702 -292.854709) (xy 165.321543 -292.833661)
			(xy 165.3073 -292.808234) (xy 165.299881 -292.78005) (xy 165.29939 -292.76548) (xy 165.29939 -292.574726)
			(xy 165.299644 -292.574726) (xy 165.299644 -292.384226) (xy 165.300087 -292.369201) (xy 165.307859 -292.340174)
			(xy 165.32288 -292.314148) (xy 165.344125 -292.292897) (xy 165.370148 -292.27787) (xy 165.399173 -292.270091)
			(xy 165.414198 -292.269672) (xy 165.685216 -292.269672) (xy 165.69182 -292.267894) (xy 165.712191 -292.262696)
			(xy 165.753857 -292.257087) (xy 165.774878 -292.256718) (xy 165.800751 -292.257242) (xy 165.85181 -292.265661)
			(xy 165.876478 -292.273482) (xy 165.882216 -292.275212) (xy 165.894153 -292.276247) (xy 165.9001 -292.275514)
			(xy 165.912546 -292.273736) (xy 165.954964 -292.243256) (xy 165.964345 -292.235644) (xy 165.97534 -292.214169)
			(xy 165.976046 -292.202108) (xy 165.976046 -291.047424) (xy 165.975373 -291.035355) (xy 165.964366 -291.013873)
			(xy 165.954964 -291.006276) (xy 165.923214 -290.983162) (xy 165.91153 -290.976812) (xy 165.900354 -290.974018)
			(xy 165.887908 -290.97224) (xy 165.876732 -290.97605) (xy 165.8523 -290.983771) (xy 165.801763 -290.992202)
			(xy 165.776148 -290.992814) (xy 165.770814 -290.992814) (xy 165.750814 -290.992228) (xy 165.711197 -290.986626)
			(xy 165.69182 -290.981638) (xy 165.685216 -290.97986) (xy 165.414198 -290.97986) (xy 165.408864 -290.97986)
			(xy 165.394329 -290.978743) (xy 165.366494 -290.970115) (xy 165.341708 -290.954788) (xy 165.321552 -290.933739)
			(xy 165.307313 -290.908313) (xy 165.299899 -290.880129) (xy 165.29939 -290.86556) (xy 165.29939 -290.674806)
			(xy 165.299644 -290.674806) (xy 165.299644 -290.484306) (xy 165.300089 -290.469283) (xy 165.307865 -290.44026)
			(xy 165.322887 -290.414238) (xy 165.344132 -290.392992) (xy 165.370152 -290.377968) (xy 165.399175 -290.37019)
			(xy 165.414198 -290.369752) (xy 165.685216 -290.369752) (xy 165.69182 -290.367974) (xy 165.712191 -290.362776)
			(xy 165.753857 -290.357168) (xy 165.774878 -290.356798) (xy 165.80275 -290.357375) (xy 165.857642 -290.367089)
			(xy 165.909999 -290.386223) (xy 165.93439 -290.399724) (xy 165.940232 -290.403026) (xy 165.952932 -290.406582)
			(xy 165.95979 -290.406582) (xy 165.969811 -290.406164) (xy 165.988329 -290.398495) (xy 166.0025 -290.384322)
			(xy 166.010166 -290.365803) (xy 166.01059 -290.355782) (xy 166.01059 -290.31819) (xy 166.011098 -290.317936)
			(xy 166.011098 -290.231322) (xy 166.003478 -290.212526) (xy 165.996112 -290.205414) (xy 165.840664 -290.049966)
			(xy 165.819074 -290.042346) (xy 165.807644 -290.043616) (xy 165.801802 -290.044124) (xy 165.801548 -290.044124)
			(xy 165.774878 -290.04514) (xy 165.765266 -290.045079) (xy 165.746075 -290.043936) (xy 165.736524 -290.042854)
			(xy 165.733476 -290.0426) (xy 164.86632 -290.0426) (xy 164.863272 -290.042854) (xy 164.85372 -290.043925)
			(xy 164.83453 -290.045067) (xy 164.824918 -290.04514) (xy 164.815306 -290.045077) (xy 164.796116 -290.043931)
			(xy 164.786564 -290.042854) (xy 164.783516 -290.0426) (xy 164.29482 -290.0426) (xy 164.276024 -290.05022)
			(xy 164.268912 -290.057586) (xy 164.222684 -290.103814) (xy 164.215831 -290.111209) (xy 164.208088 -290.129808)
			(xy 164.207698 -290.139882) (xy 164.207698 -291.649795) (xy 164.507323 -291.649795) (xy 164.507323 -291.599805)
			(xy 164.515143 -291.550431) (xy 164.530591 -291.502888) (xy 164.553287 -291.458348) (xy 164.582671 -291.417906)
			(xy 164.61802 -291.382559) (xy 164.658463 -291.353177) (xy 164.703005 -291.330484) (xy 164.750549 -291.315039)
			(xy 164.799923 -291.307221) (xy 164.824918 -291.306758) (xy 164.845938 -291.30713) (xy 164.887605 -291.312737)
			(xy 164.907976 -291.317934) (xy 164.91458 -291.319712) (xy 165.185598 -291.319712) (xy 165.200612 -291.320238)
			(xy 165.229617 -291.328008) (xy 165.255623 -291.343018) (xy 165.276859 -291.364248) (xy 165.291879 -291.39025)
			(xy 165.299658 -291.419252) (xy 165.300152 -291.434266) (xy 165.300152 -291.815266) (xy 165.299678 -291.830287)
			(xy 165.29191 -291.859308) (xy 165.276894 -291.885328) (xy 165.255654 -291.906574) (xy 165.229637 -291.921598)
			(xy 165.200619 -291.929374) (xy 165.185598 -291.92982) (xy 164.91458 -291.92982) (xy 164.907976 -291.931598)
			(xy 164.887604 -291.936793) (xy 164.845938 -291.942401) (xy 164.824918 -291.942774) (xy 164.799923 -291.942379)
			(xy 164.750549 -291.934561) (xy 164.703005 -291.919116) (xy 164.658463 -291.896423) (xy 164.61802 -291.867041)
			(xy 164.582671 -291.831694) (xy 164.553287 -291.791252) (xy 164.530591 -291.746712) (xy 164.515143 -291.699169)
			(xy 164.507323 -291.649795) (xy 164.207698 -291.649795) (xy 164.207698 -293.52494) (xy 164.50691 -293.52494)
			(xy 164.5074 -293.499951) (xy 164.515219 -293.450588) (xy 164.530663 -293.403056) (xy 164.553353 -293.358524)
			(xy 164.582729 -293.318091) (xy 164.618069 -293.282751) (xy 164.658502 -293.253375) (xy 164.703034 -293.230685)
			(xy 164.750566 -293.215241) (xy 164.799929 -293.207422) (xy 164.849907 -293.207422) (xy 164.89927 -293.215241)
			(xy 164.946802 -293.230685) (xy 164.991334 -293.253375) (xy 165.031767 -293.282751) (xy 165.067107 -293.318091)
			(xy 165.096483 -293.358524) (xy 165.119173 -293.403056) (xy 165.134617 -293.450588) (xy 165.142436 -293.499951)
			(xy 165.142926 -293.52494) (xy 165.142559 -293.545961) (xy 165.136949 -293.587627) (xy 165.13175 -293.607998)
			(xy 165.129972 -293.614602) (xy 165.129972 -293.88562) (xy 165.129537 -293.900653) (xy 165.12176 -293.929696)
			(xy 165.106741 -293.955742) (xy 165.085499 -293.97702) (xy 165.059479 -293.992084) (xy 165.03045 -293.999911)
			(xy 165.015418 -294.000428) (xy 164.634418 -294.000428) (xy 164.619373 -293.999989) (xy 164.59031 -293.992194)
			(xy 164.564262 -293.97713) (xy 164.54301 -293.955829) (xy 164.528006 -293.929746) (xy 164.520276 -293.900666)
			(xy 164.519864 -293.88562) (xy 164.519864 -293.614602) (xy 164.518086 -293.607998) (xy 164.512895 -293.587625)
			(xy 164.507284 -293.54596) (xy 164.50691 -293.52494) (xy 164.207698 -293.52494) (xy 164.207698 -294.4749)
			(xy 165.45687 -294.4749) (xy 165.457245 -294.45388) (xy 165.46285 -294.412213) (xy 165.468046 -294.391842)
			(xy 165.469824 -294.385238) (xy 165.469824 -294.11422) (xy 165.470298 -294.099189) (xy 165.478065 -294.070148)
			(xy 165.493076 -294.044103) (xy 165.51431 -294.022824) (xy 165.540324 -294.007758) (xy 165.569348 -293.99993)
			(xy 165.584378 -293.999412) (xy 165.965378 -293.999412) (xy 165.980418 -293.999913) (xy 166.009471 -294.007703)
			(xy 166.035513 -294.022757) (xy 166.056765 -294.044044) (xy 166.071773 -294.070112) (xy 166.079512 -294.099179)
			(xy 166.079932 -294.11422) (xy 166.079932 -294.385238) (xy 166.08171 -294.391842) (xy 166.086908 -294.412213)
			(xy 166.092514 -294.45388) (xy 166.092886 -294.4749) (xy 167.357044 -294.4749) (xy 167.35742 -294.45388)
			(xy 167.363024 -294.412213) (xy 167.36822 -294.391842) (xy 167.369744 -294.385238) (xy 167.369744 -294.11422)
			(xy 167.3703 -294.099175) (xy 167.378082 -294.070108) (xy 167.39312 -294.044045) (xy 167.414391 -294.022762)
			(xy 167.440445 -294.007708) (xy 167.469507 -293.999909) (xy 167.484552 -293.999412) (xy 167.865552 -293.999412)
			(xy 167.880607 -293.999881) (xy 167.909694 -294.007665) (xy 167.935774 -294.022715) (xy 167.957068 -294.044003)
			(xy 167.972124 -294.07008) (xy 167.979915 -294.099165) (xy 167.98036 -294.11422) (xy 167.98036 -294.385238)
			(xy 167.981884 -294.391842) (xy 167.987084 -294.412213) (xy 167.992688 -294.453879) (xy 167.99306 -294.4749)
			(xy 167.99257 -294.499889) (xy 167.984751 -294.549252) (xy 167.969307 -294.596784) (xy 167.946617 -294.641316)
			(xy 167.917241 -294.681749) (xy 167.881901 -294.717089) (xy 167.841468 -294.746465) (xy 167.796936 -294.769155)
			(xy 167.749404 -294.784599) (xy 167.700041 -294.792418) (xy 167.650063 -294.792418) (xy 167.6007 -294.784599)
			(xy 167.553168 -294.769155) (xy 167.508636 -294.746465) (xy 167.468203 -294.717089) (xy 167.432863 -294.681749)
			(xy 167.403487 -294.641316) (xy 167.380797 -294.596784) (xy 167.365353 -294.549252) (xy 167.357534 -294.499889)
			(xy 167.357044 -294.4749) (xy 166.092886 -294.4749) (xy 166.092396 -294.499889) (xy 166.084577 -294.549252)
			(xy 166.069133 -294.596784) (xy 166.046443 -294.641316) (xy 166.017067 -294.681749) (xy 165.981727 -294.717089)
			(xy 165.941294 -294.746465) (xy 165.896762 -294.769155) (xy 165.84923 -294.784599) (xy 165.799867 -294.792418)
			(xy 165.749889 -294.792418) (xy 165.700526 -294.784599) (xy 165.652994 -294.769155) (xy 165.608462 -294.746465)
			(xy 165.568029 -294.717089) (xy 165.532689 -294.681749) (xy 165.503313 -294.641316) (xy 165.480623 -294.596784)
			(xy 165.465179 -294.549252) (xy 165.45736 -294.499889) (xy 165.45687 -294.4749) (xy 164.207698 -294.4749)
			(xy 164.207698 -295.577514) (xy 168.472612 -295.577514) (xy 168.472612 -294.866314) (xy 168.473148 -294.851301)
			(xy 168.480915 -294.822296) (xy 168.495924 -294.79629) (xy 168.517151 -294.775053) (xy 168.543151 -294.760034)
			(xy 168.572153 -294.752254) (xy 168.587166 -294.75176) (xy 169.065194 -294.75176) (xy 169.075202 -294.751328)
			(xy 169.093664 -294.743588) (xy 169.101008 -294.736774) (xy 169.259504 -294.578278) (xy 169.266616 -294.553894)
			(xy 169.263822 -294.541194) (xy 169.260598 -294.524811) (xy 169.25716 -294.491596) (xy 169.256964 -294.4749)
			(xy 169.257339 -294.45388) (xy 169.262944 -294.412213) (xy 169.26814 -294.391842) (xy 169.269664 -294.385238)
			(xy 169.269664 -294.11422) (xy 169.2702 -294.099173) (xy 169.277983 -294.070103) (xy 169.293025 -294.044038)
			(xy 169.3143 -294.022755) (xy 169.340359 -294.007702) (xy 169.369425 -293.999906) (xy 169.384472 -293.999412)
			(xy 169.765472 -293.999412) (xy 169.780528 -293.999864) (xy 169.809616 -294.007653) (xy 169.835696 -294.022706)
			(xy 169.856989 -294.043998) (xy 169.872044 -294.070077) (xy 169.879835 -294.099164) (xy 169.88028 -294.11422)
			(xy 169.88028 -294.385238) (xy 169.881804 -294.391842) (xy 169.887002 -294.412213) (xy 169.892608 -294.45388)
			(xy 169.89298 -294.4749) (xy 171.156884 -294.4749) (xy 171.157258 -294.45388) (xy 171.162864 -294.412213)
			(xy 171.16806 -294.391842) (xy 171.169584 -294.385238) (xy 171.169584 -294.11422) (xy 171.170057 -294.099166)
			(xy 171.177845 -294.070082) (xy 171.192895 -294.044005) (xy 171.214183 -294.022712) (xy 171.240256 -294.007656)
			(xy 171.269338 -293.99986) (xy 171.284392 -293.999412) (xy 171.665392 -293.999412) (xy 171.680449 -293.999847)
			(xy 171.709538 -294.00764) (xy 171.735617 -294.022697) (xy 171.75691 -294.043992) (xy 171.771965 -294.070074)
			(xy 171.779755 -294.099163) (xy 171.7802 -294.11422) (xy 171.7802 -294.385238) (xy 171.781724 -294.391842)
			(xy 171.786923 -294.412213) (xy 171.792528 -294.45388) (xy 171.7929 -294.4749) (xy 171.79241 -294.499889)
			(xy 171.784591 -294.549252) (xy 171.769147 -294.596784) (xy 171.746457 -294.641316) (xy 171.717081 -294.681749)
			(xy 171.681741 -294.717089) (xy 171.641308 -294.746465) (xy 171.596776 -294.769155) (xy 171.549244 -294.784599)
			(xy 171.499881 -294.792418) (xy 171.449903 -294.792418) (xy 171.40054 -294.784599) (xy 171.353008 -294.769155)
			(xy 171.308476 -294.746465) (xy 171.268043 -294.717089) (xy 171.232703 -294.681749) (xy 171.203327 -294.641316)
			(xy 171.180637 -294.596784) (xy 171.165193 -294.549252) (xy 171.157374 -294.499889) (xy 171.156884 -294.4749)
			(xy 169.89298 -294.4749) (xy 169.892355 -294.503359) (xy 169.882218 -294.559366) (xy 169.862283 -294.612679)
			(xy 169.848276 -294.63746) (xy 169.845461 -294.642583) (xy 169.841993 -294.653741) (xy 169.841418 -294.659558)
			(xy 169.839192 -294.683323) (xy 169.827416 -294.729572) (xy 169.80762 -294.772999) (xy 169.780434 -294.812224)
			(xy 169.763948 -294.829484) (xy 169.529506 -295.063672) (xy 169.52278 -295.071074) (xy 169.51506 -295.0895)
			(xy 169.51452 -295.099486) (xy 169.51452 -295.577514) (xy 172.272452 -295.577514) (xy 172.272452 -294.866314)
			(xy 172.272907 -294.85127) (xy 172.280702 -294.822211) (xy 172.295763 -294.796165) (xy 172.317061 -294.774913)
			(xy 172.343139 -294.759908) (xy 172.372215 -294.752175) (xy 172.38726 -294.75176) (xy 172.865288 -294.75176)
			(xy 172.875296 -294.751325) (xy 172.893758 -294.743588) (xy 172.901102 -294.736774) (xy 173.059598 -294.578278)
			(xy 173.06671 -294.553894) (xy 173.063916 -294.541194) (xy 173.060692 -294.524811) (xy 173.057254 -294.491596)
			(xy 173.057058 -294.4749) (xy 173.057433 -294.45388) (xy 173.063038 -294.412213) (xy 173.068234 -294.391842)
			(xy 173.070012 -294.385238) (xy 173.070012 -294.11422) (xy 173.070498 -294.09919) (xy 173.078263 -294.070151)
			(xy 173.093273 -294.044107) (xy 173.114504 -294.022828) (xy 173.140515 -294.007761) (xy 173.169537 -293.999931)
			(xy 173.184566 -293.999412) (xy 173.565566 -293.999412) (xy 173.580605 -293.999924) (xy 173.609658 -294.007711)
			(xy 173.635701 -294.022762) (xy 173.656952 -294.044048) (xy 173.67196 -294.070114) (xy 173.6797 -294.09918)
			(xy 173.68012 -294.11422) (xy 173.68012 -294.385238) (xy 173.681898 -294.391842) (xy 173.687096 -294.412213)
			(xy 173.692702 -294.45388) (xy 173.693074 -294.4749) (xy 175.906938 -294.4749) (xy 175.907314 -294.45388)
			(xy 175.912918 -294.412213) (xy 175.918114 -294.391842) (xy 175.919892 -294.385238) (xy 175.919892 -294.11422)
			(xy 175.920397 -294.099192) (xy 175.928162 -294.070156) (xy 175.943167 -294.044113) (xy 175.964395 -294.022835)
			(xy 175.990401 -294.007767) (xy 176.019419 -293.999933) (xy 176.034446 -293.999412) (xy 176.415446 -293.999412)
			(xy 176.430489 -293.999854) (xy 176.459545 -294.00766) (xy 176.485586 -294.022727) (xy 176.506836 -294.044026)
			(xy 176.521842 -294.070102) (xy 176.52958 -294.099176) (xy 176.53 -294.11422) (xy 176.53 -294.385238)
			(xy 176.531778 -294.391842) (xy 176.536978 -294.412213) (xy 176.542582 -294.453879) (xy 176.542954 -294.4749)
			(xy 176.542464 -294.499889) (xy 176.534645 -294.549252) (xy 176.519201 -294.596784) (xy 176.496511 -294.641316)
			(xy 176.467135 -294.681749) (xy 176.431795 -294.717089) (xy 176.391362 -294.746465) (xy 176.34683 -294.769155)
			(xy 176.299298 -294.784599) (xy 176.249935 -294.792418) (xy 176.199957 -294.792418) (xy 176.150594 -294.784599)
			(xy 176.103062 -294.769155) (xy 176.05853 -294.746465) (xy 176.018097 -294.717089) (xy 175.982757 -294.681749)
			(xy 175.953381 -294.641316) (xy 175.930691 -294.596784) (xy 175.915247 -294.549252) (xy 175.907428 -294.499889)
			(xy 175.906938 -294.4749) (xy 173.693074 -294.4749) (xy 173.69245 -294.503359) (xy 173.682312 -294.559366)
			(xy 173.662377 -294.612679) (xy 173.64837 -294.63746) (xy 173.645554 -294.642582) (xy 173.642087 -294.653741)
			(xy 173.641512 -294.659558) (xy 173.639288 -294.683323) (xy 173.627511 -294.729573) (xy 173.607715 -294.772999)
			(xy 173.580528 -294.812224) (xy 173.564042 -294.829484) (xy 173.3296 -295.063672) (xy 173.322915 -295.071078)
			(xy 173.315344 -295.089519) (xy 173.314868 -295.099486) (xy 173.314868 -295.577514) (xy 177.02276 -295.577514)
			(xy 177.02276 -294.866314) (xy 177.023204 -294.851291) (xy 177.030979 -294.822268) (xy 177.046001 -294.796247)
			(xy 177.067247 -294.775001) (xy 177.093268 -294.759979) (xy 177.122291 -294.752204) (xy 177.137314 -294.75176)
			(xy 177.615342 -294.75176) (xy 177.625347 -294.751301) (xy 177.64381 -294.743581) (xy 177.651156 -294.736774)
			(xy 177.809398 -294.578532) (xy 177.81651 -294.554148) (xy 177.81397 -294.541194) (xy 177.810654 -294.524821)
			(xy 177.807095 -294.491604) (xy 177.806858 -294.4749) (xy 177.807233 -294.45388) (xy 177.812838 -294.412213)
			(xy 177.818034 -294.391842) (xy 177.819812 -294.385238) (xy 177.819812 -294.11422) (xy 177.820298 -294.09919)
			(xy 177.828063 -294.070151) (xy 177.843073 -294.044107) (xy 177.864304 -294.022828) (xy 177.890315 -294.007761)
			(xy 177.919337 -293.999931) (xy 177.934366 -293.999412) (xy 178.315366 -293.999412) (xy 178.330405 -293.999924)
			(xy 178.359458 -294.007711) (xy 178.385501 -294.022762) (xy 178.406752 -294.044048) (xy 178.42176 -294.070114)
			(xy 178.4295 -294.09918) (xy 178.42992 -294.11422) (xy 178.42992 -294.385238) (xy 178.431698 -294.391842)
			(xy 178.436896 -294.412213) (xy 178.442502 -294.45388) (xy 178.442874 -294.4749) (xy 179.707032 -294.4749)
			(xy 179.707405 -294.45388) (xy 179.713011 -294.412213) (xy 179.718208 -294.391842) (xy 179.719732 -294.385238)
			(xy 179.719732 -294.11422) (xy 179.720157 -294.099162) (xy 179.727949 -294.070071) (xy 179.743008 -294.043989)
			(xy 179.764305 -294.022695) (xy 179.790389 -294.007642) (xy 179.819482 -293.999855) (xy 179.83454 -293.999412)
			(xy 180.21554 -293.999412) (xy 180.230594 -293.999848) (xy 180.259673 -294.00765) (xy 180.285742 -294.022711)
			(xy 180.307025 -294.044006) (xy 180.322073 -294.070083) (xy 180.32986 -294.099166) (xy 180.330348 -294.11422)
			(xy 180.330348 -294.385238) (xy 180.331872 -294.391842) (xy 180.337072 -294.412213) (xy 180.342676 -294.453879)
			(xy 180.343048 -294.4749) (xy 180.342558 -294.499889) (xy 180.334739 -294.549252) (xy 180.319295 -294.596784)
			(xy 180.296605 -294.641316) (xy 180.267229 -294.681749) (xy 180.231889 -294.717089) (xy 180.191456 -294.746465)
			(xy 180.146924 -294.769155) (xy 180.099392 -294.784599) (xy 180.050029 -294.792418) (xy 180.000051 -294.792418)
			(xy 179.950688 -294.784599) (xy 179.903156 -294.769155) (xy 179.858624 -294.746465) (xy 179.818191 -294.717089)
			(xy 179.782851 -294.681749) (xy 179.753475 -294.641316) (xy 179.730785 -294.596784) (xy 179.715341 -294.549252)
			(xy 179.707522 -294.499889) (xy 179.707032 -294.4749) (xy 178.442874 -294.4749) (xy 178.442208 -294.503315)
			(xy 178.432065 -294.559233) (xy 178.412155 -294.612462) (xy 178.39817 -294.637206) (xy 178.395318 -294.642381)
			(xy 178.391851 -294.653674) (xy 178.391312 -294.659558) (xy 178.389153 -294.683362) (xy 178.377392 -294.729685)
			(xy 178.357583 -294.773179) (xy 178.330356 -294.812458) (xy 178.313842 -294.829738) (xy 178.079654 -295.063672)
			(xy 178.07292 -295.071067) (xy 178.065207 -295.089499) (xy 178.064668 -295.099486) (xy 178.064668 -295.577514)
			(xy 178.064177 -295.59253) (xy 178.056401 -295.621539) (xy 178.041384 -295.647547) (xy 178.020147 -295.668784)
			(xy 177.994139 -295.683801) (xy 177.96513 -295.691577) (xy 177.950114 -295.692068) (xy 177.137314 -295.692068)
			(xy 177.122299 -295.691552) (xy 177.093291 -295.683783) (xy 177.067283 -295.668771) (xy 177.046046 -295.647539)
			(xy 177.031028 -295.621535) (xy 177.023252 -295.592529) (xy 177.02276 -295.577514) (xy 173.314868 -295.577514)
			(xy 173.314418 -295.592557) (xy 173.306618 -295.621615) (xy 173.291554 -295.647659) (xy 173.270256 -295.668909)
			(xy 173.244179 -295.683915) (xy 173.215104 -295.691651) (xy 173.20006 -295.692068) (xy 172.38726 -295.692068)
			(xy 172.372226 -295.691654) (xy 172.343182 -295.683873) (xy 172.317136 -295.668849) (xy 172.295858 -295.647603)
			(xy 172.280794 -295.62158) (xy 172.272969 -295.592547) (xy 172.272452 -295.577514) (xy 169.51452 -295.577514)
			(xy 169.51412 -295.59254) (xy 169.506337 -295.621567) (xy 169.491306 -295.64759) (xy 169.470052 -295.668836)
			(xy 169.444022 -295.683856) (xy 169.414992 -295.691626) (xy 169.399966 -295.692068) (xy 168.587166 -295.692068)
			(xy 168.572149 -295.691594) (xy 168.543139 -295.683814) (xy 168.517131 -295.668793) (xy 168.495895 -295.647553)
			(xy 168.480878 -295.621542) (xy 168.473103 -295.592531) (xy 168.472612 -295.577514) (xy 164.207698 -295.577514)
			(xy 164.207698 -296.399791) (xy 164.507377 -296.399791) (xy 164.507377 -296.349809) (xy 164.515196 -296.300444)
			(xy 164.530641 -296.252909) (xy 164.553333 -296.208376) (xy 164.582712 -296.167941) (xy 164.618055 -296.1326)
			(xy 164.658492 -296.103224) (xy 164.703026 -296.080535) (xy 164.750561 -296.065092) (xy 164.799927 -296.057276)
			(xy 164.824918 -296.056812) (xy 164.845938 -296.057182) (xy 164.887605 -296.06279) (xy 164.907976 -296.067988)
			(xy 164.91458 -296.069512) (xy 165.205918 -296.069512) (xy 165.22096 -296.069979) (xy 165.250015 -296.077778)
			(xy 165.276056 -296.092839) (xy 165.297306 -296.114133) (xy 165.312313 -296.140206) (xy 165.320052 -296.169277)
			(xy 165.320472 -296.18432) (xy 165.320472 -296.399787) (xy 166.407602 -296.399787) (xy 166.407602 -296.349813)
			(xy 166.41542 -296.300454) (xy 166.430863 -296.252925) (xy 166.45355 -296.208397) (xy 166.482924 -296.167967)
			(xy 166.518261 -296.132629) (xy 166.55869 -296.103254) (xy 166.603218 -296.080566) (xy 166.650746 -296.065122)
			(xy 166.700105 -296.057303) (xy 166.725092 -296.056812) (xy 166.746112 -296.057187) (xy 166.787779 -296.062792)
			(xy 166.80815 -296.067988) (xy 166.814754 -296.069512) (xy 167.106092 -296.069512) (xy 167.121149 -296.069947)
			(xy 167.150238 -296.07774) (xy 167.176317 -296.092797) (xy 167.19761 -296.114092) (xy 167.212665 -296.140174)
			(xy 167.220455 -296.169263) (xy 167.2209 -296.18432) (xy 167.2209 -296.39979) (xy 168.307477 -296.39979)
			(xy 168.307477 -296.34981) (xy 168.315296 -296.300445) (xy 168.330741 -296.252911) (xy 168.353432 -296.208378)
			(xy 168.38281 -296.167943) (xy 168.418153 -296.132603) (xy 168.458588 -296.103226) (xy 168.503122 -296.080536)
			(xy 168.550656 -296.065093) (xy 168.600022 -296.057276) (xy 168.625012 -296.056812) (xy 168.646032 -296.057183)
			(xy 168.687699 -296.06279) (xy 168.70807 -296.067988) (xy 168.714674 -296.069512) (xy 169.006012 -296.069512)
			(xy 169.02107 -296.069929) (xy 169.050159 -296.077727) (xy 169.076239 -296.092789) (xy 169.097531 -296.114087)
			(xy 169.112585 -296.140171) (xy 169.120375 -296.169262) (xy 169.12082 -296.18432) (xy 169.12082 -296.399791)
			(xy 170.207377 -296.399791) (xy 170.207377 -296.349809) (xy 170.215196 -296.300442) (xy 170.230643 -296.252906)
			(xy 170.253336 -296.208372) (xy 170.282716 -296.167937) (xy 170.318061 -296.132595) (xy 170.358499 -296.103219)
			(xy 170.403036 -296.080531) (xy 170.450573 -296.065089) (xy 170.499941 -296.057274) (xy 170.524932 -296.056812)
			(xy 170.545953 -296.057179) (xy 170.587619 -296.062789) (xy 170.60799 -296.067988) (xy 170.614594 -296.069512)
			(xy 170.905932 -296.069512) (xy 170.920985 -296.069955) (xy 170.950064 -296.077755) (xy 170.976133 -296.092815)
			(xy 170.997417 -296.114108) (xy 171.012465 -296.140184) (xy 171.020252 -296.169267) (xy 171.02074 -296.18432)
			(xy 171.02074 -296.39979) (xy 172.107577 -296.39979) (xy 172.107577 -296.34981) (xy 172.115396 -296.300446)
			(xy 172.13084 -296.252912) (xy 172.153531 -296.20838) (xy 172.182909 -296.167945) (xy 172.21825 -296.132605)
			(xy 172.258685 -296.103228) (xy 172.303218 -296.080538) (xy 172.350751 -296.065094) (xy 172.400116 -296.057276)
			(xy 172.425106 -296.056812) (xy 172.446126 -296.057184) (xy 172.487793 -296.062791) (xy 172.508164 -296.067988)
			(xy 172.514768 -296.069512) (xy 172.806106 -296.069512) (xy 172.821147 -296.069989) (xy 172.850202 -296.077786)
			(xy 172.876243 -296.092844) (xy 172.897494 -296.114137) (xy 172.912501 -296.140208) (xy 172.92024 -296.169278)
			(xy 172.92066 -296.18432) (xy 172.92066 -296.399791) (xy 174.007477 -296.399791) (xy 174.007477 -296.349809)
			(xy 174.015296 -296.300443) (xy 174.030742 -296.252907) (xy 174.053435 -296.208374) (xy 174.082815 -296.167939)
			(xy 174.118158 -296.132598) (xy 174.158596 -296.103221) (xy 174.203131 -296.080532) (xy 174.250668 -296.06509)
			(xy 174.300035 -296.057275) (xy 174.325026 -296.056812) (xy 174.346047 -296.05718) (xy 174.387713 -296.06279)
			(xy 174.408084 -296.067988) (xy 174.414688 -296.069512) (xy 174.706026 -296.069512) (xy 174.721068 -296.069972)
			(xy 174.750123 -296.077773) (xy 174.776165 -296.092836) (xy 174.797415 -296.114131) (xy 174.812422 -296.140205)
			(xy 174.82016 -296.169277) (xy 174.82058 -296.18432) (xy 174.82058 -296.56532) (xy 176.491392 -296.56532)
			(xy 176.491392 -296.18432) (xy 176.491897 -296.169292) (xy 176.499662 -296.140256) (xy 176.514667 -296.114213)
			(xy 176.535895 -296.092935) (xy 176.561901 -296.077867) (xy 176.590919 -296.070033) (xy 176.605946 -296.069512)
			(xy 176.910746 -296.069512) (xy 176.926825 -296.070003) (xy 176.957731 -296.078891) (xy 176.984967 -296.095988)
			(xy 176.99609 -296.107612) (xy 177.002186 -296.107612) (xy 177.021585 -296.095575) (xy 177.063093 -296.076567)
			(xy 177.10689 -296.063684) (xy 177.152079 -296.05719) (xy 177.174906 -296.056812) (xy 177.197734 -296.057179)
			(xy 177.242928 -296.063659) (xy 177.286729 -296.076541) (xy 177.328234 -296.095561) (xy 177.347626 -296.107612)
			(xy 177.353722 -296.107612) (xy 177.36486 -296.096011) (xy 177.392099 -296.078939) (xy 177.422993 -296.070053)
			(xy 177.439066 -296.069512) (xy 177.743866 -296.069512) (xy 177.758905 -296.070024) (xy 177.787958 -296.077811)
			(xy 177.814001 -296.092862) (xy 177.835252 -296.114148) (xy 177.85026 -296.140214) (xy 177.858 -296.16928)
			(xy 177.85842 -296.18432) (xy 177.85842 -296.399787) (xy 178.757602 -296.399787) (xy 178.757602 -296.349813)
			(xy 178.765419 -296.300455) (xy 178.780861 -296.252928) (xy 178.803548 -296.208401) (xy 178.83292 -296.167971)
			(xy 178.868256 -296.132633) (xy 178.908684 -296.103258) (xy 178.953209 -296.080569) (xy 179.000736 -296.065124)
			(xy 179.050093 -296.057304) (xy 179.07508 -296.056812) (xy 179.0961 -296.057189) (xy 179.137767 -296.062792)
			(xy 179.158138 -296.067988) (xy 179.164742 -296.069512) (xy 179.45608 -296.069512) (xy 179.471137 -296.069957)
			(xy 179.500225 -296.077747) (xy 179.526304 -296.092803) (xy 179.547597 -296.114096) (xy 179.562653 -296.140175)
			(xy 179.570443 -296.169263) (xy 179.570888 -296.18432) (xy 179.570888 -296.399788) (xy 180.657502 -296.399788)
			(xy 180.657502 -296.349812) (xy 180.66532 -296.300452) (xy 180.680763 -296.252923) (xy 180.703452 -296.208395)
			(xy 180.732826 -296.167964) (xy 180.768164 -296.132626) (xy 180.808595 -296.103252) (xy 180.853123 -296.080563)
			(xy 180.900652 -296.06512) (xy 180.950012 -296.057302) (xy 180.975 -296.056812) (xy 180.99602 -296.057186)
			(xy 181.037687 -296.062791) (xy 181.058058 -296.067988) (xy 181.064662 -296.069512) (xy 181.356 -296.069512)
			(xy 181.371058 -296.06994) (xy 181.400146 -296.077735) (xy 181.426226 -296.092794) (xy 181.447518 -296.11409)
			(xy 181.462573 -296.140172) (xy 181.470363 -296.169262) (xy 181.470808 -296.18432) (xy 181.470808 -296.56532)
			(xy 181.470334 -296.580371) (xy 181.462539 -296.609446) (xy 181.447485 -296.635514) (xy 181.426198 -296.656797)
			(xy 181.400128 -296.671847) (xy 181.371051 -296.679637) (xy 181.356 -296.680128) (xy 181.064662 -296.680128)
			(xy 181.058058 -296.681652) (xy 181.037687 -296.686851) (xy 180.99602 -296.692456) (xy 180.975 -296.692828)
			(xy 180.950012 -296.692298) (xy 180.900652 -296.68448) (xy 180.853123 -296.669037) (xy 180.808595 -296.646348)
			(xy 180.768164 -296.616974) (xy 180.732826 -296.581636) (xy 180.703452 -296.541205) (xy 180.680763 -296.496677)
			(xy 180.66532 -296.449148) (xy 180.657502 -296.399788) (xy 179.570888 -296.399788) (xy 179.570888 -296.56532)
			(xy 179.570434 -296.580373) (xy 179.562637 -296.609451) (xy 179.54758 -296.63552) (xy 179.526289 -296.656805)
			(xy 179.500214 -296.671853) (xy 179.471133 -296.67964) (xy 179.45608 -296.680128) (xy 179.164742 -296.680128)
			(xy 179.158138 -296.681652) (xy 179.137768 -296.686855) (xy 179.096101 -296.692458) (xy 179.07508 -296.692828)
			(xy 179.050093 -296.692296) (xy 179.000736 -296.684476) (xy 178.953209 -296.669031) (xy 178.908684 -296.646342)
			(xy 178.868256 -296.616967) (xy 178.83292 -296.581629) (xy 178.803548 -296.541199) (xy 178.780861 -296.496672)
			(xy 178.765419 -296.449145) (xy 178.757602 -296.399787) (xy 177.85842 -296.399787) (xy 177.85842 -296.56532)
			(xy 177.857938 -296.580349) (xy 177.850165 -296.609385) (xy 177.835153 -296.635426) (xy 177.813922 -296.656703)
			(xy 177.787913 -296.67177) (xy 177.758894 -296.679605) (xy 177.743866 -296.680128) (xy 177.439066 -296.680128)
			(xy 177.422988 -296.679617) (xy 177.392085 -296.670735) (xy 177.364847 -296.653647) (xy 177.353722 -296.642028)
			(xy 177.347626 -296.642028) (xy 177.328227 -296.654064) (xy 177.286719 -296.673072) (xy 177.242921 -296.685955)
			(xy 177.197733 -296.692449) (xy 177.174906 -296.692828) (xy 177.152078 -296.692449) (xy 177.106885 -296.685972)
			(xy 177.063085 -296.673093) (xy 177.021579 -296.654077) (xy 177.002186 -296.642028) (xy 176.99609 -296.642028)
			(xy 176.984954 -296.653631) (xy 176.957713 -296.6707) (xy 176.926819 -296.679586) (xy 176.910746 -296.680128)
			(xy 176.605946 -296.680128) (xy 176.590902 -296.679665) (xy 176.561841 -296.671876) (xy 176.535792 -296.656818)
			(xy 176.514539 -296.635521) (xy 176.499534 -296.609442) (xy 176.491805 -296.580365) (xy 176.491392 -296.56532)
			(xy 174.82058 -296.56532) (xy 174.820137 -296.580352) (xy 174.812361 -296.609394) (xy 174.797343 -296.635439)
			(xy 174.776103 -296.656717) (xy 174.750085 -296.671782) (xy 174.721057 -296.67961) (xy 174.706026 -296.680128)
			(xy 174.414688 -296.680128) (xy 174.408084 -296.681652) (xy 174.387712 -296.686846) (xy 174.346046 -296.692455)
			(xy 174.325026 -296.692828) (xy 174.300035 -296.692325) (xy 174.250668 -296.68451) (xy 174.203131 -296.669068)
			(xy 174.158596 -296.646379) (xy 174.118158 -296.617002) (xy 174.082815 -296.581661) (xy 174.053435 -296.541226)
			(xy 174.030742 -296.496693) (xy 174.015296 -296.449157) (xy 174.007477 -296.399791) (xy 172.92066 -296.399791)
			(xy 172.92066 -296.56532) (xy 172.920237 -296.580354) (xy 172.912459 -296.609399) (xy 172.897438 -296.635446)
			(xy 172.876194 -296.656724) (xy 172.850171 -296.671788) (xy 172.821139 -296.679612) (xy 172.806106 -296.680128)
			(xy 172.514768 -296.680128) (xy 172.508164 -296.681652) (xy 172.487793 -296.68685) (xy 172.446126 -296.692456)
			(xy 172.425106 -296.692828) (xy 172.400116 -296.692324) (xy 172.350751 -296.684506) (xy 172.303218 -296.669062)
			(xy 172.258685 -296.646372) (xy 172.21825 -296.616995) (xy 172.182909 -296.581655) (xy 172.153531 -296.54122)
			(xy 172.13084 -296.496688) (xy 172.115396 -296.449154) (xy 172.107577 -296.39979) (xy 171.02074 -296.39979)
			(xy 171.02074 -296.56532) (xy 171.020235 -296.580368) (xy 171.012442 -296.609439) (xy 170.997393 -296.635503)
			(xy 170.976113 -296.656786) (xy 170.95005 -296.671838) (xy 170.92098 -296.679633) (xy 170.905932 -296.680128)
			(xy 170.614594 -296.680128) (xy 170.60799 -296.681652) (xy 170.587618 -296.686845) (xy 170.545952 -296.692454)
			(xy 170.524932 -296.692828) (xy 170.499941 -296.692326) (xy 170.450573 -296.684511) (xy 170.403036 -296.669069)
			(xy 170.358499 -296.646381) (xy 170.318061 -296.617005) (xy 170.282716 -296.581663) (xy 170.253336 -296.541228)
			(xy 170.230643 -296.496694) (xy 170.215196 -296.449158) (xy 170.207377 -296.399791) (xy 169.12082 -296.399791)
			(xy 169.12082 -296.56532) (xy 169.120335 -296.58037) (xy 169.11254 -296.609444) (xy 169.097488 -296.63551)
			(xy 169.076203 -296.656793) (xy 169.050136 -296.671843) (xy 169.021062 -296.679636) (xy 169.006012 -296.680128)
			(xy 168.714674 -296.680128) (xy 168.70807 -296.681652) (xy 168.687699 -296.686849) (xy 168.646032 -296.692455)
			(xy 168.625012 -296.692828) (xy 168.600022 -296.692324) (xy 168.550656 -296.684507) (xy 168.503122 -296.669064)
			(xy 168.458588 -296.646374) (xy 168.418153 -296.616997) (xy 168.38281 -296.581657) (xy 168.353432 -296.541222)
			(xy 168.330741 -296.496689) (xy 168.315296 -296.449155) (xy 168.307477 -296.39979) (xy 167.2209 -296.39979)
			(xy 167.2209 -296.56532) (xy 167.220434 -296.580372) (xy 167.212638 -296.609448) (xy 167.197583 -296.635516)
			(xy 167.176294 -296.6568) (xy 167.150222 -296.671849) (xy 167.121144 -296.679638) (xy 167.106092 -296.680128)
			(xy 166.814754 -296.680128) (xy 166.80815 -296.681652) (xy 166.78778 -296.686853) (xy 166.746113 -296.692457)
			(xy 166.725092 -296.692828) (xy 166.700105 -296.692297) (xy 166.650746 -296.684478) (xy 166.603218 -296.669034)
			(xy 166.55869 -296.646346) (xy 166.518261 -296.616971) (xy 166.482924 -296.581633) (xy 166.45355 -296.541203)
			(xy 166.430863 -296.496675) (xy 166.41542 -296.449146) (xy 166.407602 -296.399787) (xy 165.320472 -296.399787)
			(xy 165.320472 -296.56532) (xy 165.320037 -296.580353) (xy 165.31226 -296.609396) (xy 165.297241 -296.635442)
			(xy 165.275999 -296.65672) (xy 165.249979 -296.671784) (xy 165.22095 -296.679611) (xy 165.205918 -296.680128)
			(xy 164.91458 -296.680128) (xy 164.907976 -296.681652) (xy 164.887605 -296.686848) (xy 164.845938 -296.692455)
			(xy 164.824918 -296.692828) (xy 164.799927 -296.692324) (xy 164.750561 -296.684508) (xy 164.703026 -296.669065)
			(xy 164.658492 -296.646376) (xy 164.618055 -296.617) (xy 164.582712 -296.581659) (xy 164.553333 -296.541224)
			(xy 164.530641 -296.496691) (xy 164.515196 -296.449156) (xy 164.507377 -296.399791) (xy 164.207698 -296.399791)
			(xy 164.207698 -297.32478) (xy 165.45687 -297.32478) (xy 165.45736 -297.299791) (xy 165.465179 -297.250428)
			(xy 165.480623 -297.202896) (xy 165.503313 -297.158364) (xy 165.532689 -297.117931) (xy 165.568029 -297.082591)
			(xy 165.608462 -297.053215) (xy 165.652994 -297.030525) (xy 165.700526 -297.015081) (xy 165.749889 -297.007262)
			(xy 165.799867 -297.007262) (xy 165.84923 -297.015081) (xy 165.896762 -297.030525) (xy 165.941294 -297.053215)
			(xy 165.981727 -297.082591) (xy 166.017067 -297.117931) (xy 166.046443 -297.158364) (xy 166.069133 -297.202896)
			(xy 166.084577 -297.250428) (xy 166.092396 -297.299791) (xy 166.092886 -297.32478) (xy 167.357044 -297.32478)
			(xy 167.357534 -297.299791) (xy 167.365353 -297.250428) (xy 167.380797 -297.202896) (xy 167.403487 -297.158364)
			(xy 167.432863 -297.117931) (xy 167.468203 -297.082591) (xy 167.508636 -297.053215) (xy 167.553168 -297.030525)
			(xy 167.6007 -297.015081) (xy 167.650063 -297.007262) (xy 167.700041 -297.007262) (xy 167.749404 -297.015081)
			(xy 167.796936 -297.030525) (xy 167.841468 -297.053215) (xy 167.881901 -297.082591) (xy 167.917241 -297.117931)
			(xy 167.946617 -297.158364) (xy 167.969307 -297.202896) (xy 167.984751 -297.250428) (xy 167.99257 -297.299791)
			(xy 167.99306 -297.32478) (xy 169.256964 -297.32478) (xy 169.257454 -297.299791) (xy 169.265273 -297.250428)
			(xy 169.280717 -297.202896) (xy 169.303407 -297.158364) (xy 169.332783 -297.117931) (xy 169.368123 -297.082591)
			(xy 169.408556 -297.053215) (xy 169.453088 -297.030525) (xy 169.50062 -297.015081) (xy 169.549983 -297.007262)
			(xy 169.599961 -297.007262) (xy 169.649324 -297.015081) (xy 169.696856 -297.030525) (xy 169.741388 -297.053215)
			(xy 169.781821 -297.082591) (xy 169.817161 -297.117931) (xy 169.846537 -297.158364) (xy 169.869227 -297.202896)
			(xy 169.884671 -297.250428) (xy 169.89249 -297.299791) (xy 169.89298 -297.32478) (xy 171.156884 -297.32478)
			(xy 171.157374 -297.299791) (xy 171.165193 -297.250428) (xy 171.180637 -297.202896) (xy 171.203327 -297.158364)
			(xy 171.232703 -297.117931) (xy 171.268043 -297.082591) (xy 171.308476 -297.053215) (xy 171.353008 -297.030525)
			(xy 171.40054 -297.015081) (xy 171.449903 -297.007262) (xy 171.499881 -297.007262) (xy 171.549244 -297.015081)
			(xy 171.596776 -297.030525) (xy 171.641308 -297.053215) (xy 171.681741 -297.082591) (xy 171.717081 -297.117931)
			(xy 171.746457 -297.158364) (xy 171.769147 -297.202896) (xy 171.784591 -297.250428) (xy 171.79241 -297.299791)
			(xy 171.7929 -297.32478) (xy 173.057058 -297.32478) (xy 173.057548 -297.299791) (xy 173.065367 -297.250428)
			(xy 173.080811 -297.202896) (xy 173.103501 -297.158364) (xy 173.132877 -297.117931) (xy 173.168217 -297.082591)
			(xy 173.20865 -297.053215) (xy 173.253182 -297.030525) (xy 173.300714 -297.015081) (xy 173.350077 -297.007262)
			(xy 173.400055 -297.007262) (xy 173.449418 -297.015081) (xy 173.49695 -297.030525) (xy 173.541482 -297.053215)
			(xy 173.581915 -297.082591) (xy 173.617255 -297.117931) (xy 173.646631 -297.158364) (xy 173.669321 -297.202896)
			(xy 173.684765 -297.250428) (xy 173.692584 -297.299791) (xy 173.693074 -297.32478) (xy 175.906938 -297.32478)
			(xy 175.907428 -297.299791) (xy 175.915247 -297.250428) (xy 175.930691 -297.202896) (xy 175.953381 -297.158364)
			(xy 175.982757 -297.117931) (xy 176.018097 -297.082591) (xy 176.05853 -297.053215) (xy 176.103062 -297.030525)
			(xy 176.150594 -297.015081) (xy 176.199957 -297.007262) (xy 176.249935 -297.007262) (xy 176.299298 -297.015081)
			(xy 176.34683 -297.030525) (xy 176.391362 -297.053215) (xy 176.431795 -297.082591) (xy 176.467135 -297.117931)
			(xy 176.496511 -297.158364) (xy 176.519201 -297.202896) (xy 176.534645 -297.250428) (xy 176.542464 -297.299791)
			(xy 176.542954 -297.32478) (xy 177.806858 -297.32478) (xy 177.807348 -297.299791) (xy 177.815167 -297.250428)
			(xy 177.830611 -297.202896) (xy 177.853301 -297.158364) (xy 177.882677 -297.117931) (xy 177.918017 -297.082591)
			(xy 177.95845 -297.053215) (xy 178.002982 -297.030525) (xy 178.050514 -297.015081) (xy 178.099877 -297.007262)
			(xy 178.149855 -297.007262) (xy 178.199218 -297.015081) (xy 178.24675 -297.030525) (xy 178.291282 -297.053215)
			(xy 178.331715 -297.082591) (xy 178.367055 -297.117931) (xy 178.396431 -297.158364) (xy 178.419121 -297.202896)
			(xy 178.434565 -297.250428) (xy 178.442384 -297.299791) (xy 178.442874 -297.32478) (xy 179.707032 -297.32478)
			(xy 179.707522 -297.299791) (xy 179.715341 -297.250428) (xy 179.730785 -297.202896) (xy 179.753475 -297.158364)
			(xy 179.782851 -297.117931) (xy 179.818191 -297.082591) (xy 179.858624 -297.053215) (xy 179.903156 -297.030525)
			(xy 179.950688 -297.015081) (xy 180.000051 -297.007262) (xy 180.050029 -297.007262) (xy 180.099392 -297.015081)
			(xy 180.146924 -297.030525) (xy 180.191456 -297.053215) (xy 180.231889 -297.082591) (xy 180.267229 -297.117931)
			(xy 180.296605 -297.158364) (xy 180.319295 -297.202896) (xy 180.334739 -297.250428) (xy 180.342558 -297.299791)
			(xy 180.343048 -297.32478) (xy 180.342669 -297.3458) (xy 180.337067 -297.387466) (xy 180.331872 -297.407838)
			(xy 180.330348 -297.414442) (xy 180.330348 -297.68546) (xy 180.329782 -297.700505) (xy 180.322004 -297.729572)
			(xy 180.306969 -297.755636) (xy 180.2857 -297.77692) (xy 180.259646 -297.791974) (xy 180.230585 -297.799772)
			(xy 180.21554 -297.800268) (xy 179.83454 -297.800268) (xy 179.819483 -297.799825) (xy 179.790392 -297.792038)
			(xy 179.764311 -297.776984) (xy 179.743016 -297.755689) (xy 179.727962 -297.729608) (xy 179.720175 -297.700517)
			(xy 179.719732 -297.68546) (xy 179.719732 -297.414442) (xy 179.718208 -297.407838) (xy 179.713006 -297.387468)
			(xy 179.707403 -297.345801) (xy 179.707032 -297.32478) (xy 178.442874 -297.32478) (xy 178.442497 -297.3458)
			(xy 178.436894 -297.387467) (xy 178.431698 -297.407838) (xy 178.42992 -297.414442) (xy 178.42992 -297.68546)
			(xy 178.429385 -297.700486) (xy 178.421626 -297.72952) (xy 178.406626 -297.755561) (xy 178.385405 -297.776839)
			(xy 178.359404 -297.791909) (xy 178.330391 -297.799745) (xy 178.315366 -297.800268) (xy 177.934366 -297.800268)
			(xy 177.919322 -297.799835) (xy 177.890264 -297.79203) (xy 177.86422 -297.776963) (xy 177.84297 -297.755662)
			(xy 177.827964 -297.729582) (xy 177.820229 -297.700505) (xy 177.819812 -297.68546) (xy 177.819812 -297.414442)
			(xy 177.818034 -297.407838) (xy 177.812831 -297.387468) (xy 177.807228 -297.345801) (xy 177.806858 -297.32478)
			(xy 176.542954 -297.32478) (xy 176.542574 -297.3458) (xy 176.536973 -297.387466) (xy 176.531778 -297.407838)
			(xy 176.53 -297.414442) (xy 176.53 -297.68546) (xy 176.529485 -297.700488) (xy 176.521724 -297.729524)
			(xy 176.506721 -297.755568) (xy 176.485495 -297.776846) (xy 176.45949 -297.791914) (xy 176.430473 -297.799747)
			(xy 176.415446 -297.800268) (xy 176.034446 -297.800268) (xy 176.019405 -297.799765) (xy 175.99035 -297.79198)
			(xy 175.964306 -297.776928) (xy 175.943053 -297.75564) (xy 175.928046 -297.72957) (xy 175.920309 -297.700501)
			(xy 175.919892 -297.68546) (xy 175.919892 -297.414442) (xy 175.918114 -297.407838) (xy 175.91291 -297.387468)
			(xy 175.907308 -297.345801) (xy 175.906938 -297.32478) (xy 173.693074 -297.32478) (xy 173.692697 -297.3458)
			(xy 173.687094 -297.387467) (xy 173.681898 -297.407838) (xy 173.68012 -297.414442) (xy 173.68012 -297.68546)
			(xy 173.679585 -297.700486) (xy 173.671826 -297.72952) (xy 173.656826 -297.755561) (xy 173.635605 -297.776839)
			(xy 173.609604 -297.791909) (xy 173.580591 -297.799745) (xy 173.565566 -297.800268) (xy 173.184566 -297.800268)
			(xy 173.169522 -297.799835) (xy 173.140464 -297.79203) (xy 173.11442 -297.776963) (xy 173.09317 -297.755662)
			(xy 173.078164 -297.729582) (xy 173.070429 -297.700505) (xy 173.070012 -297.68546) (xy 173.070012 -297.414442)
			(xy 173.068234 -297.407838) (xy 173.063031 -297.387468) (xy 173.057428 -297.345801) (xy 173.057058 -297.32478)
			(xy 171.7929 -297.32478) (xy 171.792522 -297.3458) (xy 171.786919 -297.387467) (xy 171.781724 -297.407838)
			(xy 171.7802 -297.414442) (xy 171.7802 -297.68546) (xy 171.779726 -297.700515) (xy 171.771941 -297.7296)
			(xy 171.756892 -297.755679) (xy 171.735604 -297.776972) (xy 171.70953 -297.792029) (xy 171.680447 -297.799822)
			(xy 171.665392 -297.800268) (xy 171.284392 -297.800268) (xy 171.269332 -297.799867) (xy 171.240241 -297.792068)
			(xy 171.214159 -297.777005) (xy 171.192866 -297.755703) (xy 171.177813 -297.729615) (xy 171.170026 -297.70052)
			(xy 171.169584 -297.68546) (xy 171.169584 -297.414442) (xy 171.16806 -297.407838) (xy 171.162857 -297.387468)
			(xy 171.157254 -297.345801) (xy 171.156884 -297.32478) (xy 169.89298 -297.32478) (xy 169.892603 -297.3458)
			(xy 169.887 -297.387467) (xy 169.881804 -297.407838) (xy 169.88028 -297.414442) (xy 169.88028 -297.68546)
			(xy 169.879826 -297.700516) (xy 169.872039 -297.729605) (xy 169.856987 -297.755685) (xy 169.835695 -297.776979)
			(xy 169.809616 -297.792034) (xy 169.780528 -297.799824) (xy 169.765472 -297.800268) (xy 169.384472 -297.800268)
			(xy 169.369412 -297.799885) (xy 169.340319 -297.792082) (xy 169.314237 -297.777014) (xy 169.292945 -297.755709)
			(xy 169.277892 -297.729618) (xy 169.270106 -297.700521) (xy 169.269664 -297.68546) (xy 169.269664 -297.414442)
			(xy 169.26814 -297.407838) (xy 169.262937 -297.387468) (xy 169.257334 -297.345801) (xy 169.256964 -297.32478)
			(xy 167.99306 -297.32478) (xy 167.99268 -297.3458) (xy 167.987078 -297.387466) (xy 167.981884 -297.407838)
			(xy 167.98036 -297.414442) (xy 167.98036 -297.68546) (xy 167.979925 -297.700518) (xy 167.972137 -297.72961)
			(xy 167.957082 -297.755692) (xy 167.935786 -297.776987) (xy 167.909702 -297.79204) (xy 167.88061 -297.799826)
			(xy 167.865552 -297.800268) (xy 167.484552 -297.800268) (xy 167.469496 -297.799858) (xy 167.440414 -297.792053)
			(xy 167.414343 -297.776987) (xy 167.393059 -297.755687) (xy 167.378013 -297.729604) (xy 167.37023 -297.700516)
			(xy 167.369744 -297.68546) (xy 167.369744 -297.414442) (xy 167.36822 -297.407838) (xy 167.363016 -297.387468)
			(xy 167.357414 -297.345801) (xy 167.357044 -297.32478) (xy 166.092886 -297.32478) (xy 166.092509 -297.3458)
			(xy 166.086906 -297.387467) (xy 166.08171 -297.407838) (xy 166.079932 -297.414442) (xy 166.079932 -297.68546)
			(xy 166.079385 -297.700485) (xy 166.071628 -297.729517) (xy 166.05663 -297.755557) (xy 166.03541 -297.776835)
			(xy 166.009412 -297.791905) (xy 165.980402 -297.799743) (xy 165.965378 -297.800268) (xy 165.584378 -297.800268)
			(xy 165.569334 -297.799825) (xy 165.540276 -297.792023) (xy 165.514233 -297.776958) (xy 165.492982 -297.755658)
			(xy 165.477977 -297.72958) (xy 165.470241 -297.700504) (xy 165.469824 -297.68546) (xy 165.469824 -297.414442)
			(xy 165.468046 -297.407838) (xy 165.462843 -297.387468) (xy 165.45724 -297.345801) (xy 165.45687 -297.32478)
			(xy 164.207698 -297.32478) (xy 164.207698 -298.27474) (xy 164.50691 -298.27474) (xy 164.507291 -298.25372)
			(xy 164.512892 -298.212054) (xy 164.518086 -298.191682) (xy 164.519864 -298.185078) (xy 164.519864 -297.91406)
			(xy 164.520345 -297.899031) (xy 164.528121 -297.869997) (xy 164.543134 -297.843958) (xy 164.564365 -297.822682)
			(xy 164.590373 -297.807614) (xy 164.619391 -297.799777) (xy 164.634418 -297.799252) (xy 165.015418 -297.799252)
			(xy 165.030463 -297.799679) (xy 165.059524 -297.807482) (xy 165.08557 -297.822549) (xy 165.106821 -297.843852)
			(xy 165.121825 -297.869934) (xy 165.129557 -297.899014) (xy 165.129972 -297.91406) (xy 165.129972 -298.185078)
			(xy 165.13175 -298.191682) (xy 165.136957 -298.212051) (xy 165.142557 -298.253719) (xy 165.142926 -298.27474)
			(xy 165.142436 -298.299729) (xy 165.134617 -298.349092) (xy 165.119173 -298.396624) (xy 165.096483 -298.441156)
			(xy 165.067107 -298.481589) (xy 165.031767 -298.516929) (xy 164.991334 -298.546305) (xy 164.946802 -298.568995)
			(xy 164.89927 -298.584439) (xy 164.849907 -298.592258) (xy 164.799929 -298.592258) (xy 164.750566 -298.584439)
			(xy 164.703034 -298.568995) (xy 164.658502 -298.546305) (xy 164.618069 -298.516929) (xy 164.582729 -298.481589)
			(xy 164.553353 -298.441156) (xy 164.530663 -298.396624) (xy 164.515219 -298.349092) (xy 164.5074 -298.299729)
			(xy 164.50691 -298.27474) (xy 164.207698 -298.27474) (xy 164.207698 -300.199891) (xy 164.50737 -300.199891)
			(xy 164.50737 -300.149909) (xy 164.51519 -300.100542) (xy 164.530635 -300.053007) (xy 164.553328 -300.008473)
			(xy 164.582707 -299.968037) (xy 164.618051 -299.932696) (xy 164.658488 -299.903318) (xy 164.703023 -299.880629)
			(xy 164.75056 -299.865185) (xy 164.799927 -299.857369) (xy 164.824918 -299.856906) (xy 164.845938 -299.857276)
			(xy 164.887605 -299.862884) (xy 164.907976 -299.868082) (xy 164.91458 -299.86986) (xy 165.185598 -299.86986)
			(xy 165.200622 -299.870294) (xy 165.229645 -299.878071) (xy 165.255666 -299.893095) (xy 165.276912 -299.914343)
			(xy 165.291934 -299.940366) (xy 165.299708 -299.96939) (xy 165.300152 -299.984414) (xy 165.300152 -300.365414)
			(xy 165.299676 -300.380432) (xy 165.2919 -300.409443) (xy 165.27688 -300.435453) (xy 165.25564 -300.456689)
			(xy 165.229628 -300.471706) (xy 165.200616 -300.479479) (xy 165.185598 -300.479968) (xy 164.91458 -300.479968)
			(xy 164.907976 -300.481746) (xy 164.887604 -300.486942) (xy 164.845938 -300.492549) (xy 164.824918 -300.492922)
			(xy 164.799927 -300.492431) (xy 164.75056 -300.484615) (xy 164.703023 -300.469171) (xy 164.658488 -300.446482)
			(xy 164.618051 -300.417104) (xy 164.582707 -300.381763) (xy 164.553328 -300.341327) (xy 164.530635 -300.296793)
			(xy 164.51519 -300.249258) (xy 164.50737 -300.199891) (xy 164.207698 -300.199891) (xy 164.207698 -301.197518)
			(xy 164.208125 -301.207587) (xy 164.215843 -301.226187) (xy 164.222684 -301.233586) (xy 164.293804 -301.304706)
			(xy 164.294312 -301.305214) (xy 164.301689 -301.311807) (xy 164.319989 -301.319278) (xy 164.329872 -301.319692)
		)
		(stroke
			(width 0)
			(type solid)
		)
		(fill yes)
		(layer "B.Cu")
		(net "P0V8_PEX1")
	)
	(gr_poly
		(pts
			(xy 281.247596 -301.319692) (xy 281.257867 -301.319171) (xy 281.276742 -301.311053) (xy 281.284172 -301.303944)
			(xy 281.335226 -301.250096) (xy 281.338649 -301.246221) (xy 281.344019 -301.237389) (xy 281.345894 -301.23257)
			(xy 281.34945 -301.223172) (xy 281.348688 -301.212504) (xy 281.348434 -301.2059) (xy 281.348434 -300.8249)
			(xy 281.348881 -300.809846) (xy 281.356676 -300.780765) (xy 281.371733 -300.754693) (xy 281.393026 -300.733407)
			(xy 281.419104 -300.71836) (xy 281.448188 -300.710576) (xy 281.463242 -300.710092) (xy 281.768042 -300.710092)
			(xy 281.77682 -300.710248) (xy 281.79417 -300.712926) (xy 281.802586 -300.715426) (xy 281.806904 -300.716696)
			(xy 281.81046 -300.717966) (xy 281.818588 -300.717966) (xy 281.828523 -300.717435) (xy 281.846863 -300.70977)
			(xy 281.860908 -300.695706) (xy 281.868548 -300.677356) (xy 281.869134 -300.66742) (xy 281.869134 -300.410626)
			(xy 281.869681 -300.385201) (xy 281.878188 -300.335066) (xy 281.894888 -300.287034) (xy 281.919318 -300.242435)
			(xy 281.934666 -300.222158) (xy 281.937992 -300.217762) (xy 281.94348 -300.208201) (xy 281.945588 -300.203108)
			(xy 281.948077 -300.196327) (xy 281.950758 -300.182136) (xy 281.950922 -300.174914) (xy 281.951176 -300.17466)
			(xy 281.95067 -300.162907) (xy 281.943431 -300.140537) (xy 281.936952 -300.130718) (xy 281.934666 -300.12767)
			(xy 281.919322 -300.107389) (xy 281.894889 -300.06279) (xy 281.878181 -300.014761) (xy 281.869659 -299.964627)
			(xy 281.869134 -299.939202) (xy 281.869134 -299.631354) (xy 281.868578 -299.621427) (xy 281.860892 -299.603112)
			(xy 281.846839 -299.589076) (xy 281.828515 -299.58141) (xy 281.818588 -299.580808) (xy 281.514042 -299.580808)
			(xy 281.498982 -299.580366) (xy 281.469888 -299.572579) (xy 281.4438 -299.557526) (xy 281.422499 -299.536233)
			(xy 281.407437 -299.510151) (xy 281.39964 -299.481059) (xy 281.399234 -299.466) (xy 281.399234 -299.085)
			(xy 281.399681 -299.069946) (xy 281.407476 -299.040865) (xy 281.422533 -299.014793) (xy 281.443826 -298.993507)
			(xy 281.469904 -298.97846) (xy 281.498988 -298.970676) (xy 281.514042 -298.970192) (xy 281.6606 -298.970192)
			(xy 281.664407 -298.970128) (xy 281.671934 -298.968984) (xy 281.675586 -298.967906) (xy 281.69616 -298.961556)
			(xy 281.700224 -298.959016) (xy 281.719731 -298.946699) (xy 281.761552 -298.927224) (xy 281.805753 -298.914011)
			(xy 281.851401 -298.90734) (xy 281.874468 -298.906946) (xy 281.88158 -298.906946) (xy 281.911563 -298.908285)
			(xy 281.970248 -298.920822) (xy 281.998166 -298.931838) (xy 282.004516 -298.934632) (xy 282.012898 -298.937934)
			(xy 282.02763 -298.93514) (xy 282.03497 -298.933404) (xy 282.048275 -298.926312) (xy 282.053792 -298.92117)
			(xy 282.15717 -298.817792) (xy 282.17657 -298.799147) (xy 282.22066 -298.768313) (xy 282.26948 -298.745703)
			(xy 282.295346 -298.73829) (xy 282.30195 -298.736512) (xy 282.307538 -298.73321) (xy 282.31846 -298.725082)
			(xy 282.375356 -298.668186) (xy 282.382753 -298.661339) (xy 282.401353 -298.653612) (xy 282.411424 -298.6532)
			(xy 282.509722 -298.6532) (xy 282.519469 -298.65277) (xy 282.537548 -298.645484) (xy 282.551573 -298.631948)
			(xy 282.55595 -298.623228) (xy 282.59405 -298.5389) (xy 282.596817 -298.532215) (xy 282.598872 -298.517902)
			(xy 282.598114 -298.510706) (xy 282.59786 -298.510706) (xy 282.596596 -298.503601) (xy 282.59066 -298.490453)
			(xy 282.586176 -298.484798) (xy 282.585922 -298.484544) (xy 282.5711 -298.467054) (xy 282.546114 -298.428617)
			(xy 282.526908 -298.386988) (xy 282.513882 -298.343033) (xy 282.507305 -298.297662) (xy 282.506928 -298.27474)
			(xy 282.507297 -298.253719) (xy 282.512898 -298.212051) (xy 282.518104 -298.191682) (xy 282.519628 -298.185078)
			(xy 282.519628 -297.91406) (xy 282.520122 -297.899036) (xy 282.527898 -297.870012) (xy 282.542911 -297.843984)
			(xy 282.564142 -297.82272) (xy 282.590147 -297.807666) (xy 282.619159 -297.799845) (xy 282.634182 -297.799252)
			(xy 283.015436 -297.799252) (xy 283.030485 -297.799747) (xy 283.059556 -297.807543) (xy 283.08562 -297.822594)
			(xy 283.106903 -297.843877) (xy 283.121955 -297.86994) (xy 283.129752 -297.899011) (xy 283.130244 -297.91406)
			(xy 283.130244 -298.185078) (xy 283.131768 -298.191682) (xy 283.136961 -298.212054) (xy 283.142561 -298.25372)
			(xy 283.142944 -298.27474) (xy 283.142541 -298.297661) (xy 283.135958 -298.343027) (xy 283.122934 -298.38698)
			(xy 283.103738 -298.428609) (xy 283.078768 -298.467053) (xy 283.06395 -298.484544) (xy 283.063696 -298.484798)
			(xy 283.059203 -298.490446) (xy 283.053284 -298.503601) (xy 283.052012 -298.510706) (xy 283.051758 -298.510706)
			(xy 283.051 -298.5179) (xy 283.053069 -298.53221) (xy 283.055822 -298.5389) (xy 283.093922 -298.623228)
			(xy 283.098327 -298.631923) (xy 283.112368 -298.645418) (xy 283.130415 -298.652736) (xy 283.14015 -298.6532)
			(xy 284.409642 -298.6532) (xy 284.419387 -298.652766) (xy 284.43746 -298.645476) (xy 284.451479 -298.63194)
			(xy 284.45587 -298.623228) (xy 284.49397 -298.5389) (xy 284.496736 -298.532215) (xy 284.498791 -298.517902)
			(xy 284.498034 -298.510706) (xy 284.49778 -298.510706) (xy 284.496514 -298.503602) (xy 284.49057 -298.490461)
			(xy 284.486096 -298.484798) (xy 284.485842 -298.484544) (xy 284.471019 -298.467055) (xy 284.446031 -298.428617)
			(xy 284.426825 -298.386989) (xy 284.413798 -298.343034) (xy 284.40722 -298.297663) (xy 284.406848 -298.27474)
			(xy 284.407217 -298.253719) (xy 284.412817 -298.212051) (xy 284.418024 -298.191682) (xy 284.419548 -298.185078)
			(xy 284.419548 -297.91406) (xy 284.420041 -297.899032) (xy 284.427816 -297.87) (xy 284.442827 -297.843961)
			(xy 284.464056 -297.822685) (xy 284.49006 -297.807615) (xy 284.519075 -297.799775) (xy 284.534102 -297.799252)
			(xy 284.915356 -297.799252) (xy 284.930418 -297.799693) (xy 284.959517 -297.807479) (xy 284.98561 -297.822531)
			(xy 285.006918 -297.843823) (xy 285.021989 -297.869905) (xy 285.029796 -297.898999) (xy 285.030164 -297.91406)
			(xy 285.030164 -298.185078) (xy 285.031688 -298.191682) (xy 285.036883 -298.212053) (xy 285.042483 -298.25372)
			(xy 285.042864 -298.27474) (xy 285.042461 -298.29766) (xy 285.035877 -298.343026) (xy 285.02285 -298.386976)
			(xy 285.00365 -298.428603) (xy 284.978676 -298.467042) (xy 284.96387 -298.484544) (xy 284.963616 -298.484798)
			(xy 284.959121 -298.490445) (xy 284.9532 -298.5036) (xy 284.951932 -298.510706) (xy 284.951678 -298.510706)
			(xy 284.95092 -298.5179) (xy 284.952986 -298.532211) (xy 284.955742 -298.5389) (xy 284.993842 -298.623228)
			(xy 284.998248 -298.631921) (xy 285.012289 -298.64541) (xy 285.030336 -298.652722) (xy 285.04007 -298.6532)
			(xy 286.309562 -298.6532) (xy 286.319315 -298.65278) (xy 286.337412 -298.645508) (xy 286.351456 -298.631973)
			(xy 286.35579 -298.623228) (xy 286.39389 -298.5389) (xy 286.39666 -298.532216) (xy 286.398718 -298.517901)
			(xy 286.397954 -298.510706) (xy 286.3977 -298.510706) (xy 286.396435 -298.503602) (xy 286.390493 -298.490459)
			(xy 286.386016 -298.484798) (xy 286.385762 -298.484544) (xy 286.370938 -298.467055) (xy 286.345949 -298.428618)
			(xy 286.326741 -298.38699) (xy 286.313713 -298.343034) (xy 286.307135 -298.297663) (xy 286.306768 -298.27474)
			(xy 286.307137 -298.253719) (xy 286.312737 -298.212051) (xy 286.317944 -298.191682) (xy 286.319468 -298.185078)
			(xy 286.319468 -297.91406) (xy 286.319961 -297.899033) (xy 286.327736 -297.870003) (xy 286.342748 -297.843967)
			(xy 286.363977 -297.822694) (xy 286.389982 -297.807628) (xy 286.418996 -297.799792) (xy 286.434022 -297.799252)
			(xy 286.815276 -297.799252) (xy 286.83033 -297.79974) (xy 286.859414 -297.807526) (xy 286.885492 -297.822573)
			(xy 286.906788 -297.843857) (xy 286.92185 -297.869927) (xy 286.929652 -297.899006) (xy 286.930084 -297.91406)
			(xy 286.930084 -298.185078) (xy 286.931608 -298.191682) (xy 286.936802 -298.212054) (xy 286.942403 -298.25372)
			(xy 286.942784 -298.27474) (xy 286.942381 -298.29766) (xy 286.935797 -298.343026) (xy 286.922771 -298.386977)
			(xy 286.903572 -298.428604) (xy 286.878599 -298.467045) (xy 286.86379 -298.484544) (xy 286.863536 -298.484798)
			(xy 286.85904 -298.490445) (xy 286.853117 -298.503599) (xy 286.851852 -298.510706) (xy 286.851598 -298.510706)
			(xy 286.85084 -298.5179) (xy 286.852908 -298.532211) (xy 286.855662 -298.5389) (xy 286.893762 -298.623228)
			(xy 286.898168 -298.631918) (xy 286.912211 -298.645403) (xy 286.930258 -298.652707) (xy 286.93999 -298.6532)
			(xy 288.209482 -298.6532) (xy 288.219233 -298.652777) (xy 288.237324 -298.6455) (xy 288.251362 -298.631965)
			(xy 288.25571 -298.623228) (xy 288.29381 -298.5389) (xy 288.296579 -298.532216) (xy 288.298636 -298.517901)
			(xy 288.297874 -298.510706) (xy 288.29762 -298.510706) (xy 288.296355 -298.503601) (xy 288.290415 -298.490457)
			(xy 288.285936 -298.484798) (xy 288.285682 -298.484544) (xy 288.267488 -298.462888) (xy 288.23828 -298.414458)
			(xy 288.218096 -298.361627) (xy 288.207573 -298.306059) (xy 288.206688 -298.277788) (xy 288.206688 -298.274232)
			(xy 288.207049 -298.253148) (xy 288.212657 -298.211354) (xy 288.217864 -298.19092) (xy 288.219642 -298.184316)
			(xy 288.219642 -297.91406) (xy 288.220094 -297.89901) (xy 288.227895 -297.869938) (xy 288.242955 -297.843876)
			(xy 288.264248 -297.8226) (xy 288.290322 -297.807561) (xy 288.3194 -297.799782) (xy 288.33445 -297.799252)
			(xy 288.71545 -297.799252) (xy 288.730512 -297.799693) (xy 288.759613 -297.807477) (xy 288.785707 -297.822529)
			(xy 288.807016 -297.843821) (xy 288.822088 -297.869903) (xy 288.829895 -297.898998) (xy 288.830258 -297.91406)
			(xy 288.830258 -298.18584) (xy 288.83102 -298.188634) (xy 288.832036 -298.192698) (xy 288.837014 -298.212649)
			(xy 288.84237 -298.253418) (xy 288.842704 -298.273978) (xy 288.842704 -298.27474) (xy 288.842301 -298.297661)
			(xy 288.835717 -298.343026) (xy 288.822692 -298.386978) (xy 288.803494 -298.428606) (xy 288.778522 -298.467048)
			(xy 288.76371 -298.484544) (xy 288.763456 -298.484798) (xy 288.758966 -298.490447) (xy 288.753052 -298.503603)
			(xy 288.751772 -298.510706) (xy 288.751518 -298.510706) (xy 288.75076 -298.5179) (xy 288.752828 -298.53221)
			(xy 288.755582 -298.5389) (xy 288.793682 -298.623228) (xy 288.79809 -298.631916) (xy 288.812133 -298.645395)
			(xy 288.830179 -298.652692) (xy 288.83991 -298.6532) (xy 290.109656 -298.6532) (xy 290.119399 -298.652764)
			(xy 290.137468 -298.645471) (xy 290.151483 -298.631934) (xy 290.155884 -298.623228) (xy 290.193984 -298.5389)
			(xy 290.196754 -298.532216) (xy 290.198812 -298.517901) (xy 290.198048 -298.510706) (xy 290.197794 -298.510706)
			(xy 290.196528 -298.503602) (xy 290.190586 -298.490459) (xy 290.18611 -298.484798) (xy 290.185856 -298.484544)
			(xy 290.167774 -298.463041) (xy 290.138701 -298.414972) (xy 290.118519 -298.362545) (xy 290.107855 -298.307389)
			(xy 290.106862 -298.279312) (xy 290.106862 -298.274486) (xy 290.107569 -298.243309) (xy 290.119725 -298.182152)
			(xy 290.130992 -298.153074) (xy 290.134802 -298.143676) (xy 290.134802 -297.91406) (xy 290.135298 -297.899014)
			(xy 290.143095 -297.869949) (xy 290.158148 -297.843892) (xy 290.179432 -297.822618) (xy 290.205495 -297.807576)
			(xy 290.234564 -297.799791) (xy 290.24961 -297.799252) (xy 290.63061 -297.799252) (xy 290.645661 -297.799744)
			(xy 290.674738 -297.807536) (xy 290.700808 -297.822585) (xy 290.722096 -297.843868) (xy 290.737153 -297.869934)
			(xy 290.744952 -297.899009) (xy 290.745418 -297.91406) (xy 290.745418 -298.21886) (xy 290.745325 -298.224487)
			(xy 290.744182 -298.235683) (xy 290.743132 -298.241212) (xy 290.742116 -298.252896) (xy 290.742878 -298.27474)
			(xy 290.742475 -298.29766) (xy 290.735891 -298.343026) (xy 290.722865 -298.386977) (xy 290.703666 -298.428604)
			(xy 290.678692 -298.467044) (xy 290.663884 -298.484544) (xy 290.66363 -298.484798) (xy 290.659134 -298.490445)
			(xy 290.653211 -298.503599) (xy 290.651946 -298.510706) (xy 290.651692 -298.510706) (xy 290.650934 -298.5179)
			(xy 290.653001 -298.532211) (xy 290.655756 -298.5389) (xy 290.693856 -298.623228) (xy 290.698262 -298.631919)
			(xy 290.712305 -298.645405) (xy 290.730351 -298.652712) (xy 290.740084 -298.6532) (xy 292.959536 -298.6532)
			(xy 292.969281 -298.652767) (xy 292.987356 -298.645479) (xy 293.001377 -298.631942) (xy 293.005764 -298.623228)
			(xy 293.043864 -298.5389) (xy 293.04663 -298.532215) (xy 293.048686 -298.517902) (xy 293.047928 -298.510706)
			(xy 293.047674 -298.510706) (xy 293.046411 -298.5036) (xy 293.040476 -298.490452) (xy 293.03599 -298.484798)
			(xy 293.035736 -298.484544) (xy 293.020913 -298.467055) (xy 292.995926 -298.428617) (xy 292.97672 -298.386989)
			(xy 292.963693 -298.343034) (xy 292.957116 -298.297663) (xy 292.956742 -298.27474) (xy 292.956742 -298.274486)
			(xy 292.95707 -298.2536) (xy 292.96255 -298.212189) (xy 292.967664 -298.191936) (xy 292.96868 -298.187872)
			(xy 292.969442 -298.185078) (xy 292.969442 -297.91406) (xy 292.969894 -297.89901) (xy 292.977695 -297.869938)
			(xy 292.992755 -297.843876) (xy 293.014048 -297.8226) (xy 293.040122 -297.807561) (xy 293.0692 -297.799782)
			(xy 293.08425 -297.799252) (xy 293.46525 -297.799252) (xy 293.480312 -297.799693) (xy 293.509413 -297.807477)
			(xy 293.535507 -297.822529) (xy 293.556816 -297.843821) (xy 293.571888 -297.869903) (xy 293.579695 -297.898998)
			(xy 293.580058 -297.91406) (xy 293.580058 -298.185078) (xy 293.58082 -298.187872) (xy 293.581836 -298.191936)
			(xy 293.586923 -298.212194) (xy 293.592399 -298.253602) (xy 293.592758 -298.274486) (xy 293.592758 -298.27474)
			(xy 293.592355 -298.29766) (xy 293.585771 -298.343025) (xy 293.572743 -298.386976) (xy 293.553544 -298.428602)
			(xy 293.528569 -298.467042) (xy 293.513764 -298.484544) (xy 293.51351 -298.484798) (xy 293.509016 -298.490445)
			(xy 293.503095 -298.5036) (xy 293.501826 -298.510706) (xy 293.501572 -298.510706) (xy 293.500814 -298.5179)
			(xy 293.50288 -298.532211) (xy 293.505636 -298.5389) (xy 293.543736 -298.623228) (xy 293.548141 -298.631921)
			(xy 293.562183 -298.645413) (xy 293.58023 -298.652726) (xy 293.589964 -298.6532) (xy 294.85971 -298.6532)
			(xy 294.869458 -298.652772) (xy 294.887541 -298.645489) (xy 294.90157 -298.631953) (xy 294.905938 -298.623228)
			(xy 294.944038 -298.5389) (xy 294.946805 -298.532215) (xy 294.948861 -298.517901) (xy 294.948102 -298.510706)
			(xy 294.947848 -298.510706) (xy 294.946584 -298.503601) (xy 294.940647 -298.490454) (xy 294.936164 -298.484798)
			(xy 294.93591 -298.484544) (xy 294.921084 -298.467056) (xy 294.896091 -298.42862) (xy 294.876881 -298.386992)
			(xy 294.863851 -298.343036) (xy 294.857272 -298.297664) (xy 294.856916 -298.27474) (xy 294.857285 -298.253719)
			(xy 294.862886 -298.212051) (xy 294.868092 -298.191682) (xy 294.869616 -298.185078) (xy 294.869616 -297.91406)
			(xy 294.87011 -297.899036) (xy 294.877886 -297.87001) (xy 294.892899 -297.84398) (xy 294.914129 -297.822715)
			(xy 294.940134 -297.807659) (xy 294.969147 -297.799835) (xy 294.98417 -297.799252) (xy 295.365424 -297.799252)
			(xy 295.380474 -297.799746) (xy 295.409547 -297.80754) (xy 295.435615 -297.82259) (xy 295.4569 -297.843873)
			(xy 295.471954 -297.869938) (xy 295.479752 -297.89901) (xy 295.480232 -297.91406) (xy 295.480232 -298.185078)
			(xy 295.481756 -298.191682) (xy 295.48695 -298.212054) (xy 295.492549 -298.25372) (xy 295.492932 -298.27474)
			(xy 295.492529 -298.297661) (xy 295.485946 -298.343027) (xy 295.472921 -298.386979) (xy 295.453725 -298.428608)
			(xy 295.428754 -298.467051) (xy 295.413938 -298.484544) (xy 295.413684 -298.484798) (xy 295.409192 -298.490446)
			(xy 295.403274 -298.503601) (xy 295.402 -298.510706) (xy 295.401746 -298.510706) (xy 295.400988 -298.5179)
			(xy 295.403057 -298.53221) (xy 295.40581 -298.5389) (xy 295.44391 -298.623228) (xy 295.448314 -298.631924)
			(xy 295.462354 -298.645423) (xy 295.480402 -298.652745) (xy 295.490138 -298.6532) (xy 296.75963 -298.6532)
			(xy 296.769376 -298.652768) (xy 296.787453 -298.645481) (xy 296.801476 -298.631945) (xy 296.805858 -298.623228)
			(xy 296.843958 -298.5389) (xy 296.846725 -298.532215) (xy 296.84878 -298.517902) (xy 296.848022 -298.510706)
			(xy 296.847768 -298.510706) (xy 296.846504 -298.5036) (xy 296.840569 -298.490453) (xy 296.836084 -298.484798)
			(xy 296.83583 -298.484544) (xy 296.821007 -298.467054) (xy 296.796021 -298.428617) (xy 296.776815 -298.386989)
			(xy 296.763788 -298.343033) (xy 296.757211 -298.297663) (xy 296.756836 -298.27474) (xy 296.757205 -298.253719)
			(xy 296.762806 -298.212051) (xy 296.768012 -298.191682) (xy 296.769536 -298.185078) (xy 296.769536 -297.91406)
			(xy 296.77003 -297.899037) (xy 296.777806 -297.870013) (xy 296.79282 -297.843986) (xy 296.814051 -297.822724)
			(xy 296.840056 -297.807671) (xy 296.869067 -297.799852) (xy 296.88409 -297.799252) (xy 297.265344 -297.799252)
			(xy 297.280392 -297.799748) (xy 297.309461 -297.807545) (xy 297.335524 -297.822597) (xy 297.356805 -297.843879)
			(xy 297.371856 -297.869942) (xy 297.379652 -297.899012) (xy 297.380152 -297.91406) (xy 297.380152 -298.185078)
			(xy 297.381676 -298.191682) (xy 297.386869 -298.212054) (xy 297.392469 -298.25372) (xy 297.392852 -298.27474)
			(xy 297.392449 -298.297661) (xy 297.385866 -298.343027) (xy 297.372842 -298.38698) (xy 297.353647 -298.428609)
			(xy 297.328677 -298.467054) (xy 297.313858 -298.484544) (xy 297.313604 -298.484798) (xy 297.30911 -298.490445)
			(xy 297.30319 -298.503601) (xy 297.30192 -298.510706) (xy 297.301666 -298.510706) (xy 297.300908 -298.5179)
			(xy 297.302974 -298.532211) (xy 297.30573 -298.5389) (xy 297.34383 -298.623228) (xy 297.348235 -298.631922)
			(xy 297.362276 -298.645415) (xy 297.380323 -298.65273) (xy 297.390058 -298.6532) (xy 298.14266 -298.6532)
			(xy 298.152312 -298.652184) (xy 298.159559 -298.650562) (xy 298.172737 -298.643729) (xy 298.17822 -298.638722)
			(xy 298.327064 -298.489878) (xy 298.332047 -298.484377) (xy 298.338883 -298.471209) (xy 298.340526 -298.46397)
			(xy 298.341542 -298.454318) (xy 298.341542 -297.900344) (xy 298.341009 -297.89008) (xy 298.33287 -297.871226)
			(xy 298.325794 -297.863768) (xy 298.267628 -297.811952) (xy 298.263538 -297.808431) (xy 298.254187 -297.803047)
			(xy 298.249086 -297.801284) (xy 298.239434 -297.798236) (xy 298.228512 -297.799506) (xy 298.215558 -297.800268)
			(xy 297.834304 -297.800268) (xy 297.81925 -297.799821) (xy 297.790167 -297.792028) (xy 297.764094 -297.776971)
			(xy 297.742807 -297.755677) (xy 297.727759 -297.729599) (xy 297.719974 -297.700514) (xy 297.719496 -297.68546)
			(xy 297.719496 -297.414442) (xy 297.717972 -297.407838) (xy 297.712777 -297.387467) (xy 297.707174 -297.3458)
			(xy 297.706796 -297.32478) (xy 297.707288 -297.299792) (xy 297.715109 -297.250432) (xy 297.730555 -297.202902)
			(xy 297.753245 -297.158374) (xy 297.782622 -297.117944) (xy 297.817962 -297.082607) (xy 297.858395 -297.053233)
			(xy 297.902924 -297.030545) (xy 297.950455 -297.015103) (xy 297.999816 -297.007286) (xy 298.024804 -297.006772)
			(xy 298.024804 -297.006518) (xy 298.053411 -297.007184) (xy 298.109699 -297.017445) (xy 298.163253 -297.037583)
			(xy 298.188126 -297.05173) (xy 298.18838 -297.05173) (xy 298.194212 -297.055033) (xy 298.207085 -297.058752)
			(xy 298.21378 -297.059096) (xy 298.226988 -297.059096) (xy 298.315634 -297.008804) (xy 298.320968 -297.005502)
			(xy 298.329992 -296.998138) (xy 298.340726 -296.977495) (xy 298.341542 -296.965878) (xy 298.341542 -294.835072)
			(xy 298.341542 -294.833802) (xy 298.340685 -294.822194) (xy 298.32997 -294.801557) (xy 298.320968 -294.794178)
			(xy 298.315634 -294.790876) (xy 298.238926 -294.747188) (xy 298.23297 -294.744125) (xy 298.21997 -294.740921)
			(xy 298.213272 -294.740838) (xy 298.19981 -294.740838) (xy 298.187872 -294.74795) (xy 298.163024 -294.762032)
			(xy 298.109549 -294.782074) (xy 298.053358 -294.792259) (xy 298.024804 -294.792908) (xy 297.999813 -294.792444)
			(xy 297.950445 -294.784625) (xy 297.902908 -294.76918) (xy 297.858373 -294.746489) (xy 297.817936 -294.71711)
			(xy 297.782592 -294.681767) (xy 297.753213 -294.64133) (xy 297.730521 -294.596795) (xy 297.715076 -294.549259)
			(xy 297.707256 -294.499891) (xy 297.706796 -294.4749) (xy 297.707168 -294.45388) (xy 297.712773 -294.412213)
			(xy 297.717972 -294.391842) (xy 297.719496 -294.385238) (xy 297.719496 -294.11422) (xy 297.719982 -294.099189)
			(xy 297.727747 -294.070149) (xy 297.742756 -294.044102) (xy 297.763987 -294.022821) (xy 297.789998 -294.007751)
			(xy 297.819021 -293.999917) (xy 297.83405 -293.999412) (xy 298.215558 -293.999412) (xy 298.228512 -294.000174)
			(xy 298.239434 -294.001444) (xy 298.249086 -293.998396) (xy 298.254181 -293.996619) (xy 298.263537 -293.991246)
			(xy 298.267628 -293.987728) (xy 298.325794 -293.935912) (xy 298.332926 -293.928493) (xy 298.341074 -293.909615)
			(xy 298.341542 -293.899336) (xy 298.341542 -293.543482) (xy 298.341379 -293.537471) (xy 298.338564 -293.525785)
			(xy 298.335954 -293.520368) (xy 298.334112 -293.516896) (xy 298.329515 -293.510521) (xy 298.32681 -293.507668)
			(xy 298.128182 -293.30904) (xy 298.120812 -293.302296) (xy 298.10235 -293.294704) (xy 298.092368 -293.294308)
			(xy 297.473878 -293.294308) (xy 297.462548 -293.294912) (xy 297.442098 -293.30467) (xy 297.434508 -293.313104)
			(xy 297.38447 -293.382192) (xy 297.381109 -293.38707) (xy 297.376484 -293.397973) (xy 297.375326 -293.403782)
			(xy 297.373548 -293.415212) (xy 297.377358 -293.42715) (xy 297.384567 -293.450953) (xy 297.392348 -293.500074)
			(xy 297.392852 -293.52494) (xy 297.392478 -293.54596) (xy 297.386868 -293.587626) (xy 297.381676 -293.607998)
			(xy 297.380152 -293.614602) (xy 297.380152 -293.88562) (xy 297.379662 -293.900649) (xy 297.37189 -293.929686)
			(xy 297.35688 -293.955729) (xy 297.335651 -293.97701) (xy 297.309644 -293.992083) (xy 297.280626 -293.999925)
			(xy 297.265598 -294.000428) (xy 296.884344 -294.000428) (xy 296.869283 -293.999987) (xy 296.840186 -293.992201)
			(xy 296.814096 -293.977148) (xy 296.792791 -293.955856) (xy 296.777724 -293.929774) (xy 296.769922 -293.90068)
			(xy 296.769536 -293.88562) (xy 296.769536 -293.614602) (xy 296.768012 -293.607998) (xy 296.762812 -293.587627)
			(xy 296.757201 -293.545961) (xy 296.756836 -293.52494) (xy 296.757337 -293.500074) (xy 296.765123 -293.450954)
			(xy 296.77233 -293.42715) (xy 296.77233 -293.426896) (xy 296.773996 -293.421146) (xy 296.774888 -293.40921)
			(xy 296.774108 -293.403274) (xy 296.77233 -293.391844) (xy 296.71518 -293.313104) (xy 296.707561 -293.30471)
			(xy 296.687128 -293.294959) (xy 296.67581 -293.294308) (xy 295.573958 -293.294308) (xy 295.56263 -293.294916)
			(xy 295.542186 -293.30468) (xy 295.534588 -293.313104) (xy 295.48455 -293.382192) (xy 295.481189 -293.38707)
			(xy 295.476567 -293.397973) (xy 295.475406 -293.403782) (xy 295.473628 -293.415212) (xy 295.477438 -293.42715)
			(xy 295.484646 -293.450954) (xy 295.492425 -293.500074) (xy 295.492932 -293.52494) (xy 295.492932 -293.525448)
			(xy 295.492932 -293.531036) (xy 295.49226 -293.550715) (xy 295.486655 -293.589689) (xy 295.481756 -293.60876)
			(xy 295.479978 -293.615364) (xy 295.479978 -293.88562) (xy 295.479528 -293.900673) (xy 295.471731 -293.929751)
			(xy 295.456673 -293.95582) (xy 295.43538 -293.977103) (xy 295.409305 -293.99215) (xy 295.380223 -293.999935)
			(xy 295.36517 -294.000428) (xy 294.98417 -294.000428) (xy 294.969122 -293.999934) (xy 294.940051 -293.992138)
			(xy 294.913988 -293.977087) (xy 294.892707 -293.955804) (xy 294.877658 -293.929739) (xy 294.869865 -293.900669)
			(xy 294.869362 -293.88562) (xy 294.869362 -293.61384) (xy 294.8686 -293.611046) (xy 294.867584 -293.606982)
			(xy 294.862607 -293.587031) (xy 294.857253 -293.546262) (xy 294.856916 -293.525702) (xy 294.856916 -293.52494)
			(xy 294.857417 -293.500074) (xy 294.865203 -293.450954) (xy 294.87241 -293.42715) (xy 294.87241 -293.426896)
			(xy 294.874077 -293.421146) (xy 294.874969 -293.40921) (xy 294.874188 -293.403274) (xy 294.87241 -293.391844)
			(xy 294.81526 -293.313104) (xy 294.80764 -293.304714) (xy 294.787206 -293.294971) (xy 294.77589 -293.294308)
			(xy 293.673784 -293.294308) (xy 293.662453 -293.294911) (xy 293.642001 -293.304668) (xy 293.634414 -293.313104)
			(xy 293.584376 -293.382192) (xy 293.581014 -293.38707) (xy 293.576389 -293.397973) (xy 293.575232 -293.403782)
			(xy 293.573454 -293.415212) (xy 293.577264 -293.42715) (xy 293.584473 -293.450953) (xy 293.592254 -293.500074)
			(xy 293.592758 -293.52494) (xy 293.592758 -293.525194) (xy 293.592431 -293.54608) (xy 293.586954 -293.587492)
			(xy 293.581836 -293.607744) (xy 293.58082 -293.611808) (xy 293.580058 -293.614602) (xy 293.580058 -293.88562)
			(xy 293.579608 -293.900672) (xy 293.57181 -293.929748) (xy 293.556752 -293.955815) (xy 293.535459 -293.977095)
			(xy 293.509383 -293.992137) (xy 293.480302 -293.999917) (xy 293.46525 -294.000428) (xy 293.08425 -294.000428)
			(xy 293.069189 -293.999987) (xy 293.04009 -293.992202) (xy 293.013998 -293.977151) (xy 292.992692 -293.955858)
			(xy 292.977624 -293.929775) (xy 292.969822 -293.900681) (xy 292.969442 -293.88562) (xy 292.969442 -293.614602)
			(xy 292.96868 -293.611808) (xy 292.967664 -293.607744) (xy 292.962579 -293.587486) (xy 292.957105 -293.546078)
			(xy 292.956742 -293.525194) (xy 292.956742 -293.52494) (xy 292.957243 -293.500074) (xy 292.965029 -293.450954)
			(xy 292.972236 -293.42715) (xy 292.972236 -293.426896) (xy 292.973902 -293.421146) (xy 292.974794 -293.40921)
			(xy 292.974014 -293.403274) (xy 292.972236 -293.391844) (xy 292.915086 -293.313104) (xy 292.907467 -293.304709)
			(xy 292.887034 -293.294956) (xy 292.875716 -293.294308) (xy 290.823904 -293.294308) (xy 290.812571 -293.294907)
			(xy 290.792113 -293.304659) (xy 290.784534 -293.313104) (xy 290.734496 -293.382192) (xy 290.731138 -293.387071)
			(xy 290.726521 -293.397975) (xy 290.725352 -293.403782) (xy 290.723574 -293.415212) (xy 290.727384 -293.42715)
			(xy 290.734593 -293.450953) (xy 290.742373 -293.500074) (xy 290.742878 -293.52494) (xy 290.742878 -293.525194)
			(xy 290.742551 -293.54608) (xy 290.737075 -293.587492) (xy 290.731956 -293.607744) (xy 290.73094 -293.611808)
			(xy 290.730178 -293.614602) (xy 290.730178 -293.88562) (xy 290.729728 -293.900673) (xy 290.721931 -293.929751)
			(xy 290.706873 -293.95582) (xy 290.68558 -293.977103) (xy 290.659505 -293.99215) (xy 290.630423 -293.999935)
			(xy 290.61537 -294.000428) (xy 290.23437 -294.000428) (xy 290.219322 -293.999934) (xy 290.190251 -293.992138)
			(xy 290.164188 -293.977087) (xy 290.142907 -293.955804) (xy 290.127858 -293.929739) (xy 290.120065 -293.900669)
			(xy 290.119562 -293.88562) (xy 290.119562 -293.614602) (xy 290.1188 -293.611808) (xy 290.117784 -293.607744)
			(xy 290.112698 -293.587486) (xy 290.107224 -293.546078) (xy 290.106862 -293.525194) (xy 290.106862 -293.52494)
			(xy 290.107364 -293.500074) (xy 290.11515 -293.450954) (xy 290.122356 -293.42715) (xy 290.122356 -293.426896)
			(xy 290.124022 -293.421146) (xy 290.124913 -293.40921) (xy 290.124134 -293.403274) (xy 290.122356 -293.391844)
			(xy 290.065206 -293.313104) (xy 290.057588 -293.304706) (xy 290.037156 -293.294945) (xy 290.025836 -293.294308)
			(xy 288.92373 -293.294308) (xy 288.912405 -293.294922) (xy 288.89197 -293.304692) (xy 288.88436 -293.313104)
			(xy 288.834322 -293.382192) (xy 288.830963 -293.387071) (xy 288.826343 -293.397974) (xy 288.825178 -293.403782)
			(xy 288.8234 -293.415212) (xy 288.82721 -293.42715) (xy 288.834418 -293.450954) (xy 288.842198 -293.500074)
			(xy 288.842704 -293.52494) (xy 288.842704 -293.525702) (xy 288.842347 -293.54626) (xy 288.836999 -293.587029)
			(xy 288.832036 -293.606982) (xy 288.83102 -293.611046) (xy 288.830258 -293.61384) (xy 288.830258 -293.88562)
			(xy 288.829808 -293.900672) (xy 288.82201 -293.929748) (xy 288.806952 -293.955815) (xy 288.785659 -293.977095)
			(xy 288.759583 -293.992137) (xy 288.730502 -293.999917) (xy 288.71545 -294.000428) (xy 288.33445 -294.000428)
			(xy 288.319389 -293.999987) (xy 288.29029 -293.992202) (xy 288.264198 -293.977151) (xy 288.242892 -293.955858)
			(xy 288.227824 -293.929775) (xy 288.220022 -293.900681) (xy 288.219642 -293.88562) (xy 288.219642 -293.615364)
			(xy 288.217864 -293.60876) (xy 288.212808 -293.588943) (xy 288.207199 -293.548433) (xy 288.206688 -293.527988)
			(xy 288.206688 -293.521892) (xy 288.207381 -293.497792) (xy 288.215157 -293.450213) (xy 288.222182 -293.42715)
			(xy 288.222182 -293.426896) (xy 288.223849 -293.421146) (xy 288.224742 -293.40921) (xy 288.22396 -293.403274)
			(xy 288.222182 -293.391844) (xy 288.165032 -293.313104) (xy 288.15741 -293.304718) (xy 288.136976 -293.294986)
			(xy 288.125662 -293.294308) (xy 287.02381 -293.294308) (xy 287.012476 -293.294906) (xy 286.992016 -293.304656)
			(xy 286.98444 -293.313104) (xy 286.934402 -293.382192) (xy 286.931044 -293.387071) (xy 286.926426 -293.397975)
			(xy 286.925258 -293.403782) (xy 286.92348 -293.415212) (xy 286.92729 -293.42715) (xy 286.934499 -293.450953)
			(xy 286.942279 -293.500074) (xy 286.942784 -293.52494) (xy 286.94241 -293.54596) (xy 286.936799 -293.587625)
			(xy 286.931608 -293.607998) (xy 286.930084 -293.614602) (xy 286.930084 -293.88562) (xy 286.929593 -293.900646)
			(xy 286.92182 -293.929676) (xy 286.906808 -293.95571) (xy 286.885578 -293.97698) (xy 286.859571 -293.992039)
			(xy 286.830555 -293.999865) (xy 286.81553 -294.000428) (xy 286.434276 -294.000428) (xy 286.419227 -293.999934)
			(xy 286.390156 -293.99214) (xy 286.364091 -293.977089) (xy 286.342809 -293.955806) (xy 286.327758 -293.929741)
			(xy 286.319965 -293.900669) (xy 286.319468 -293.88562) (xy 286.319468 -293.614602) (xy 286.317944 -293.607998)
			(xy 286.312745 -293.587627) (xy 286.307135 -293.545961) (xy 286.306768 -293.52494) (xy 286.30727 -293.500074)
			(xy 286.315056 -293.450954) (xy 286.322262 -293.42715) (xy 286.322262 -293.426896) (xy 286.323928 -293.421146)
			(xy 286.324819 -293.40921) (xy 286.32404 -293.403274) (xy 286.322262 -293.391844) (xy 286.265112 -293.313104)
			(xy 286.257495 -293.304705) (xy 286.237062 -293.294942) (xy 286.225742 -293.294308) (xy 285.12389 -293.294308)
			(xy 285.112558 -293.29491) (xy 285.092105 -293.304665) (xy 285.08452 -293.313104) (xy 285.034482 -293.382192)
			(xy 285.03112 -293.38707) (xy 285.026494 -293.397972) (xy 285.025338 -293.403782) (xy 285.02356 -293.415212)
			(xy 285.02737 -293.42715) (xy 285.034579 -293.450953) (xy 285.04236 -293.500074) (xy 285.042864 -293.52494)
			(xy 285.042489 -293.54596) (xy 285.036878 -293.587625) (xy 285.031688 -293.607998) (xy 285.030164 -293.614602)
			(xy 285.030164 -293.88562) (xy 285.029673 -293.900645) (xy 285.0219 -293.929673) (xy 285.006887 -293.955705)
			(xy 284.985656 -293.976971) (xy 284.959649 -293.992027) (xy 284.930634 -293.999848) (xy 284.91561 -294.000428)
			(xy 284.534356 -294.000428) (xy 284.519309 -293.999932) (xy 284.490242 -293.992134) (xy 284.464182 -293.977082)
			(xy 284.442904 -293.955799) (xy 284.427857 -293.929736) (xy 284.420065 -293.900667) (xy 284.419548 -293.88562)
			(xy 284.419548 -293.614602) (xy 284.418024 -293.607998) (xy 284.412826 -293.587627) (xy 284.407216 -293.545961)
			(xy 284.406848 -293.52494) (xy 284.40735 -293.500074) (xy 284.415135 -293.450954) (xy 284.422342 -293.42715)
			(xy 284.422342 -293.426896) (xy 284.424008 -293.421146) (xy 284.4249 -293.40921) (xy 284.42412 -293.403274)
			(xy 284.422342 -293.391844) (xy 284.365192 -293.313104) (xy 284.357574 -293.304708) (xy 284.337141 -293.294953)
			(xy 284.325822 -293.294308) (xy 283.22397 -293.294308) (xy 283.21264 -293.294914) (xy 283.192193 -293.304674)
			(xy 283.1846 -293.313104) (xy 283.134562 -293.382192) (xy 283.131201 -293.38707) (xy 283.126577 -293.397973)
			(xy 283.125418 -293.403782) (xy 283.12364 -293.415212) (xy 283.12745 -293.42715) (xy 283.134657 -293.450954)
			(xy 283.142436 -293.500074) (xy 283.142944 -293.52494) (xy 283.14257 -293.54596) (xy 283.13696 -293.587626)
			(xy 283.131768 -293.607998) (xy 283.130244 -293.614602) (xy 283.130244 -293.88562) (xy 283.129754 -293.900649)
			(xy 283.121982 -293.929685) (xy 283.106972 -293.955727) (xy 283.085742 -293.977007) (xy 283.059736 -293.992078)
			(xy 283.030718 -293.999918) (xy 283.01569 -294.000428) (xy 282.634436 -294.000428) (xy 282.619376 -293.999986)
			(xy 282.59028 -293.992198) (xy 282.564192 -293.977146) (xy 282.542889 -293.955853) (xy 282.527823 -293.929772)
			(xy 282.520022 -293.90068) (xy 282.519628 -293.88562) (xy 282.519628 -293.614602) (xy 282.518104 -293.607998)
			(xy 282.512904 -293.587627) (xy 282.507293 -293.545961) (xy 282.506928 -293.52494) (xy 282.506928 -293.524432)
			(xy 282.507364 -293.501816) (xy 282.513844 -293.45705) (xy 282.526593 -293.413652) (xy 282.545354 -293.372493)
			(xy 282.55722 -293.353236) (xy 282.56103 -293.346632) (xy 282.558998 -293.32936) (xy 282.557548 -293.321015)
			(xy 282.550025 -293.305853) (xy 282.544266 -293.299642) (xy 282.10002 -292.855396) (xy 282.093848 -292.849585)
			(xy 282.078663 -292.84207) (xy 282.070302 -292.840664) (xy 282.05303 -292.838632) (xy 282.046426 -292.842442)
			(xy 282.027175 -292.854323) (xy 281.986022 -292.873108) (xy 281.942621 -292.885862) (xy 281.897848 -292.892329)
			(xy 281.87523 -292.892734) (xy 281.874722 -292.892734) (xy 281.853701 -292.892364) (xy 281.812034 -292.886762)
			(xy 281.791664 -292.881558) (xy 281.78506 -292.87978) (xy 281.508708 -292.87978) (xy 281.494169 -292.878668)
			(xy 281.466322 -292.870047) (xy 281.441523 -292.854724) (xy 281.421356 -292.833675) (xy 281.407106 -292.808244)
			(xy 281.399683 -292.780054) (xy 281.399234 -292.76548) (xy 281.399234 -292.384226) (xy 281.399718 -292.369227)
			(xy 281.407465 -292.340248) (xy 281.422439 -292.314256) (xy 281.443623 -292.293018) (xy 281.469577 -292.277977)
			(xy 281.498537 -292.270156) (xy 281.513534 -292.269672) (xy 281.78506 -292.269672) (xy 281.791664 -292.267894)
			(xy 281.812035 -292.262698) (xy 281.853702 -292.257096) (xy 281.874722 -292.256718) (xy 281.87523 -292.256718)
			(xy 281.902314 -292.257265) (xy 281.955694 -292.266467) (xy 281.981402 -292.275006) (xy 281.988006 -292.277292)
			(xy 282.000198 -292.275514) (xy 282.006205 -292.274423) (xy 282.017504 -292.269806) (xy 282.02255 -292.26637)
			(xy 282.054808 -292.243256) (xy 282.064183 -292.23564) (xy 282.075167 -292.214167) (xy 282.07589 -292.202108)
			(xy 282.07589 -291.047424) (xy 282.075215 -291.035357) (xy 282.0642 -291.013884) (xy 282.054808 -291.006276)
			(xy 282.02255 -290.983162) (xy 282.017519 -290.979695) (xy 282.006216 -290.975067) (xy 282.000198 -290.974018)
			(xy 281.988006 -290.97224) (xy 281.981402 -290.974526) (xy 281.955683 -290.98302) (xy 281.902309 -290.992211)
			(xy 281.87523 -290.992814) (xy 281.874722 -290.992814) (xy 281.853701 -290.992444) (xy 281.812034 -290.986841)
			(xy 281.791664 -290.981638) (xy 281.78506 -290.97986) (xy 281.508708 -290.97986) (xy 281.49417 -290.978748)
			(xy 281.466325 -290.970126) (xy 281.441529 -290.954802) (xy 281.421365 -290.933753) (xy 281.407119 -290.908322)
			(xy 281.399701 -290.880133) (xy 281.399234 -290.86556) (xy 281.399234 -290.484306) (xy 281.39972 -290.469309)
			(xy 281.407471 -290.440334) (xy 281.422447 -290.414347) (xy 281.44363 -290.393113) (xy 281.469582 -290.378075)
			(xy 281.498538 -290.370256) (xy 281.513534 -290.369752) (xy 281.78506 -290.369752) (xy 281.791664 -290.367974)
			(xy 281.812035 -290.362779) (xy 281.853702 -290.357176) (xy 281.874722 -290.356798) (xy 281.902593 -290.357379)
			(xy 281.957481 -290.3671) (xy 282.009835 -290.38624) (xy 282.034234 -290.399724) (xy 282.040076 -290.403026)
			(xy 282.05303 -290.406582) (xy 282.059634 -290.406582) (xy 282.069636 -290.406088) (xy 282.088113 -290.398422)
			(xy 282.102251 -290.384269) (xy 282.109898 -290.365784) (xy 282.110434 -290.355782) (xy 282.110434 -290.31819)
			(xy 282.110942 -290.317936) (xy 282.110942 -290.241482) (xy 282.110779 -290.235471) (xy 282.107964 -290.223785)
			(xy 282.105354 -290.218368) (xy 282.103512 -290.214896) (xy 282.098915 -290.208521) (xy 282.09621 -290.205668)
			(xy 281.947874 -290.057332) (xy 281.944259 -290.053895) (xy 281.935944 -290.048386) (xy 281.931364 -290.04641)
			(xy 281.92222 -290.0426) (xy 281.91714 -290.0426) (xy 281.907488 -290.043616) (xy 281.874722 -290.04514)
			(xy 281.874468 -290.04514) (xy 281.864919 -290.045071) (xy 281.845857 -290.043925) (xy 281.836368 -290.042854)
			(xy 281.83332 -290.0426) (xy 280.966164 -290.0426) (xy 280.963116 -290.042854) (xy 280.953564 -290.043926)
			(xy 280.934374 -290.045071) (xy 280.924762 -290.04514) (xy 280.91515 -290.045079) (xy 280.89596 -290.043935)
			(xy 280.886408 -290.042854) (xy 280.88336 -290.0426) (xy 280.404824 -290.0426) (xy 280.398815 -290.04277)
			(xy 280.387136 -290.045599) (xy 280.38171 -290.048188) (xy 280.378234 -290.050026) (xy 280.371852 -290.054616)
			(xy 280.36901 -290.057332) (xy 280.322274 -290.104068) (xy 280.319565 -290.106917) (xy 280.314965 -290.113292)
			(xy 280.31313 -290.116768) (xy 280.310548 -290.122195) (xy 280.307728 -290.133875) (xy 280.307542 -290.139882)
			(xy 280.307542 -291.64979) (xy 280.607248 -291.64979) (xy 280.607248 -291.59981) (xy 280.615066 -291.550445)
			(xy 280.63051 -291.502911) (xy 280.653199 -291.458378) (xy 280.682574 -291.417942) (xy 280.717913 -291.382599)
			(xy 280.758346 -291.353218) (xy 280.802876 -291.330524) (xy 280.850408 -291.315075) (xy 280.899772 -291.307251)
			(xy 280.924762 -291.306758) (xy 280.945782 -291.307141) (xy 280.987448 -291.31274) (xy 281.00782 -291.317934)
			(xy 281.014424 -291.319712) (xy 281.285442 -291.319712) (xy 281.300458 -291.320199) (xy 281.329465 -291.327979)
			(xy 281.355471 -291.342999) (xy 281.376706 -291.364235) (xy 281.391724 -291.390243) (xy 281.399502 -291.41925)
			(xy 281.399996 -291.434266) (xy 281.399996 -291.815266) (xy 281.399435 -291.830278) (xy 281.391673 -291.859281)
			(xy 281.37667 -291.885286) (xy 281.355447 -291.906523) (xy 281.329451 -291.921544) (xy 281.300453 -291.929325)
			(xy 281.285442 -291.92982) (xy 281.014424 -291.92982) (xy 281.00782 -291.931598) (xy 280.987451 -291.936804)
			(xy 280.945783 -291.942405) (xy 280.924762 -291.942774) (xy 280.899772 -291.942349) (xy 280.850408 -291.934525)
			(xy 280.802876 -291.919076) (xy 280.758346 -291.896382) (xy 280.717913 -291.867001) (xy 280.682574 -291.831658)
			(xy 280.653199 -291.791222) (xy 280.63051 -291.746689) (xy 280.615066 -291.699155) (xy 280.607248 -291.64979)
			(xy 280.307542 -291.64979) (xy 280.307542 -293.52494) (xy 280.606754 -293.52494) (xy 280.607244 -293.499951)
			(xy 280.615063 -293.450588) (xy 280.630507 -293.403056) (xy 280.653197 -293.358524) (xy 280.682573 -293.318091)
			(xy 280.717913 -293.282751) (xy 280.758346 -293.253375) (xy 280.802878 -293.230685) (xy 280.85041 -293.215241)
			(xy 280.899773 -293.207422) (xy 280.949751 -293.207422) (xy 280.999114 -293.215241) (xy 281.046646 -293.230685)
			(xy 281.091178 -293.253375) (xy 281.131611 -293.282751) (xy 281.166951 -293.318091) (xy 281.196327 -293.358524)
			(xy 281.219017 -293.403056) (xy 281.234461 -293.450588) (xy 281.24228 -293.499951) (xy 281.24277 -293.52494)
			(xy 281.242405 -293.545961) (xy 281.236794 -293.587627) (xy 281.231594 -293.607998) (xy 281.229816 -293.614602)
			(xy 281.229816 -293.88562) (xy 281.229338 -293.900649) (xy 281.221565 -293.929686) (xy 281.206552 -293.955727)
			(xy 281.18532 -293.977004) (xy 281.15931 -293.992072) (xy 281.13029 -293.999906) (xy 281.115262 -294.000428)
			(xy 280.734262 -294.000428) (xy 280.719214 -294.000038) (xy 280.69015 -293.992229) (xy 280.664102 -293.977154)
			(xy 280.642851 -293.955844) (xy 280.627849 -293.929755) (xy 280.62012 -293.900669) (xy 280.619708 -293.88562)
			(xy 280.619708 -293.614602) (xy 280.61793 -293.607998) (xy 280.612738 -293.587626) (xy 280.607128 -293.54596)
			(xy 280.606754 -293.52494) (xy 280.307542 -293.52494) (xy 280.307542 -294.4749) (xy 281.556714 -294.4749)
			(xy 281.557087 -294.45388) (xy 281.562693 -294.412213) (xy 281.56789 -294.391842) (xy 281.569668 -294.385238)
			(xy 281.569668 -294.11422) (xy 281.570197 -294.099194) (xy 281.577959 -294.070161) (xy 281.592961 -294.044121)
			(xy 281.614184 -294.022844) (xy 281.640185 -294.007774) (xy 281.669197 -293.999936) (xy 281.684222 -293.999412)
			(xy 282.065222 -293.999412) (xy 282.080264 -293.999875) (xy 282.109319 -294.007675) (xy 282.135361 -294.022737)
			(xy 282.156611 -294.044032) (xy 282.171618 -294.070106) (xy 282.179356 -294.099177) (xy 282.179776 -294.11422)
			(xy 282.179776 -294.385238) (xy 282.181554 -294.391842) (xy 282.186753 -294.412213) (xy 282.192358 -294.45388)
			(xy 282.19273 -294.4749) (xy 283.456888 -294.4749) (xy 283.457262 -294.45388) (xy 283.462868 -294.412213)
			(xy 283.468064 -294.391842) (xy 283.469588 -294.385238) (xy 283.469588 -294.11422) (xy 283.470057 -294.099165)
			(xy 283.477845 -294.070081) (xy 283.492896 -294.044004) (xy 283.514185 -294.022711) (xy 283.540259 -294.007654)
			(xy 283.569341 -293.99986) (xy 283.584396 -293.999412) (xy 283.965396 -293.999412) (xy 283.980453 -293.999843)
			(xy 284.009542 -294.007637) (xy 284.035621 -294.022696) (xy 284.056914 -294.043991) (xy 284.071969 -294.070073)
			(xy 284.079759 -294.099163) (xy 284.080204 -294.11422) (xy 284.080204 -294.385238) (xy 284.081728 -294.391842)
			(xy 284.086927 -294.412213) (xy 284.092532 -294.45388) (xy 284.092904 -294.4749) (xy 284.092414 -294.499889)
			(xy 284.084595 -294.549252) (xy 284.069151 -294.596784) (xy 284.046461 -294.641316) (xy 284.017085 -294.681749)
			(xy 283.981745 -294.717089) (xy 283.941312 -294.746465) (xy 283.89678 -294.769155) (xy 283.849248 -294.784599)
			(xy 283.799885 -294.792418) (xy 283.749907 -294.792418) (xy 283.700544 -294.784599) (xy 283.653012 -294.769155)
			(xy 283.60848 -294.746465) (xy 283.568047 -294.717089) (xy 283.532707 -294.681749) (xy 283.503331 -294.641316)
			(xy 283.480641 -294.596784) (xy 283.465197 -294.549252) (xy 283.457378 -294.499889) (xy 283.456888 -294.4749)
			(xy 282.19273 -294.4749) (xy 282.19224 -294.499889) (xy 282.184421 -294.549252) (xy 282.168977 -294.596784)
			(xy 282.146287 -294.641316) (xy 282.116911 -294.681749) (xy 282.081571 -294.717089) (xy 282.041138 -294.746465)
			(xy 281.996606 -294.769155) (xy 281.949074 -294.784599) (xy 281.899711 -294.792418) (xy 281.849733 -294.792418)
			(xy 281.80037 -294.784599) (xy 281.752838 -294.769155) (xy 281.708306 -294.746465) (xy 281.667873 -294.717089)
			(xy 281.632533 -294.681749) (xy 281.603157 -294.641316) (xy 281.580467 -294.596784) (xy 281.565023 -294.549252)
			(xy 281.557204 -294.499889) (xy 281.556714 -294.4749) (xy 280.307542 -294.4749) (xy 280.307542 -295.577514)
			(xy 284.572456 -295.577514) (xy 284.572456 -294.866314) (xy 284.572904 -294.851291) (xy 284.580678 -294.822269)
			(xy 284.5957 -294.796248) (xy 284.616945 -294.775002) (xy 284.642965 -294.75998) (xy 284.671987 -294.752205)
			(xy 284.68701 -294.75176) (xy 285.164784 -294.75176) (xy 285.174854 -294.751337) (xy 285.193452 -294.743615)
			(xy 285.200852 -294.736774) (xy 285.359094 -294.578532) (xy 285.36646 -294.55364) (xy 285.363666 -294.541194)
			(xy 285.360441 -294.524811) (xy 285.357003 -294.491596) (xy 285.356808 -294.4749) (xy 285.357182 -294.45388)
			(xy 285.362787 -294.412213) (xy 285.367984 -294.391842) (xy 285.369508 -294.385238) (xy 285.369508 -294.11422)
			(xy 285.369957 -294.099164) (xy 285.377747 -294.070076) (xy 285.392801 -294.043997) (xy 285.414094 -294.022704)
			(xy 285.440173 -294.007649) (xy 285.46926 -293.999857) (xy 285.484316 -293.999412) (xy 285.865316 -293.999412)
			(xy 285.880374 -293.999825) (xy 285.909464 -294.007624) (xy 285.935543 -294.022686) (xy 285.956836 -294.043985)
			(xy 285.97189 -294.07007) (xy 285.97968 -294.099162) (xy 285.980124 -294.11422) (xy 285.980124 -294.385238)
			(xy 285.981648 -294.391842) (xy 285.986847 -294.412213) (xy 285.992452 -294.45388) (xy 285.992824 -294.4749)
			(xy 287.256728 -294.4749) (xy 287.257101 -294.45388) (xy 287.262707 -294.412213) (xy 287.267904 -294.391842)
			(xy 287.269428 -294.385238) (xy 287.269428 -294.11422) (xy 287.269857 -294.099162) (xy 287.277649 -294.070072)
			(xy 287.292707 -294.04399) (xy 287.314003 -294.022697) (xy 287.340086 -294.007643) (xy 287.369178 -293.999855)
			(xy 287.384236 -293.999412) (xy 287.765236 -293.999412) (xy 287.780289 -293.999852) (xy 287.809368 -294.007653)
			(xy 287.835438 -294.022713) (xy 287.856721 -294.044007) (xy 287.871769 -294.070084) (xy 287.879556 -294.099166)
			(xy 287.880044 -294.11422) (xy 287.880044 -294.385238) (xy 287.881568 -294.391842) (xy 287.886768 -294.412213)
			(xy 287.892372 -294.453879) (xy 287.892744 -294.4749) (xy 287.892254 -294.499889) (xy 287.884435 -294.549252)
			(xy 287.868991 -294.596784) (xy 287.846301 -294.641316) (xy 287.816925 -294.681749) (xy 287.781585 -294.717089)
			(xy 287.741152 -294.746465) (xy 287.69662 -294.769155) (xy 287.649088 -294.784599) (xy 287.599725 -294.792418)
			(xy 287.549747 -294.792418) (xy 287.500384 -294.784599) (xy 287.452852 -294.769155) (xy 287.40832 -294.746465)
			(xy 287.367887 -294.717089) (xy 287.332547 -294.681749) (xy 287.303171 -294.641316) (xy 287.280481 -294.596784)
			(xy 287.265037 -294.549252) (xy 287.257218 -294.499889) (xy 287.256728 -294.4749) (xy 285.992824 -294.4749)
			(xy 285.992175 -294.503317) (xy 285.982042 -294.55924) (xy 285.962118 -294.612468) (xy 285.94812 -294.637206)
			(xy 285.945272 -294.642383) (xy 285.941802 -294.653674) (xy 285.941262 -294.659558) (xy 285.939052 -294.683325)
			(xy 285.927273 -294.729575) (xy 285.907473 -294.773002) (xy 285.880281 -294.812226) (xy 285.863792 -294.829484)
			(xy 285.62935 -295.063672) (xy 285.622537 -295.071093) (xy 285.6148 -295.089676) (xy 285.614364 -295.09974)
			(xy 285.614364 -295.577514) (xy 288.372296 -295.577514) (xy 288.372296 -294.866314) (xy 288.372845 -294.851323)
			(xy 288.380589 -294.822359) (xy 288.395555 -294.796379) (xy 288.416726 -294.775149) (xy 288.442664 -294.760111)
			(xy 288.471606 -294.752287) (xy 288.486596 -294.75176) (xy 288.964878 -294.75176) (xy 288.974947 -294.751333)
			(xy 288.993546 -294.743615) (xy 289.000946 -294.736774) (xy 289.159188 -294.578532) (xy 289.166554 -294.55364)
			(xy 289.16376 -294.541194) (xy 289.160535 -294.524811) (xy 289.157097 -294.491596) (xy 289.156902 -294.4749)
			(xy 289.157276 -294.45388) (xy 289.162881 -294.412213) (xy 289.168078 -294.391842) (xy 289.169856 -294.385238)
			(xy 289.169856 -294.11422) (xy 289.170397 -294.099195) (xy 289.178158 -294.070164) (xy 289.193158 -294.044125)
			(xy 289.214378 -294.022848) (xy 289.240376 -294.007777) (xy 289.269386 -293.999938) (xy 289.28441 -293.999412)
			(xy 289.66541 -293.999412) (xy 289.680451 -293.999886) (xy 289.709506 -294.007683) (xy 289.735548 -294.022743)
			(xy 289.756798 -294.044036) (xy 289.771805 -294.070108) (xy 289.779544 -294.099178) (xy 289.779964 -294.11422)
			(xy 289.779964 -294.385238) (xy 289.781742 -294.391842) (xy 289.786941 -294.412213) (xy 289.792546 -294.45388)
			(xy 289.792918 -294.4749) (xy 292.006782 -294.4749) (xy 292.007157 -294.45388) (xy 292.012762 -294.412213)
			(xy 292.017958 -294.391842) (xy 292.019736 -294.385238) (xy 292.019736 -294.11422) (xy 292.020198 -294.099188)
			(xy 292.027966 -294.070145) (xy 292.042979 -294.044099) (xy 292.064216 -294.022819) (xy 292.090232 -294.007754)
			(xy 292.119259 -293.999928) (xy 292.13429 -293.999412) (xy 292.51529 -293.999412) (xy 292.53033 -293.999903)
			(xy 292.559384 -294.007696) (xy 292.585426 -294.022751) (xy 292.606677 -294.044041) (xy 292.621685 -294.070111)
			(xy 292.629424 -294.099179) (xy 292.629844 -294.11422) (xy 292.629844 -294.385238) (xy 292.631622 -294.391842)
			(xy 292.636821 -294.412213) (xy 292.642426 -294.45388) (xy 292.642798 -294.4749) (xy 292.642308 -294.499889)
			(xy 292.634489 -294.549252) (xy 292.619045 -294.596784) (xy 292.596355 -294.641316) (xy 292.566979 -294.681749)
			(xy 292.531639 -294.717089) (xy 292.491206 -294.746465) (xy 292.446674 -294.769155) (xy 292.399142 -294.784599)
			(xy 292.349779 -294.792418) (xy 292.299801 -294.792418) (xy 292.250438 -294.784599) (xy 292.202906 -294.769155)
			(xy 292.158374 -294.746465) (xy 292.117941 -294.717089) (xy 292.082601 -294.681749) (xy 292.053225 -294.641316)
			(xy 292.030535 -294.596784) (xy 292.015091 -294.549252) (xy 292.007272 -294.499889) (xy 292.006782 -294.4749)
			(xy 289.792918 -294.4749) (xy 289.792256 -294.503316) (xy 289.782126 -294.559239) (xy 289.762208 -294.612466)
			(xy 289.748214 -294.637206) (xy 289.745365 -294.642383) (xy 289.741895 -294.653674) (xy 289.741356 -294.659558)
			(xy 289.739147 -294.683325) (xy 289.727368 -294.729576) (xy 289.707568 -294.773002) (xy 289.680375 -294.812226)
			(xy 289.663886 -294.829484) (xy 289.429698 -295.063672) (xy 289.422877 -295.071087) (xy 289.415146 -295.089675)
			(xy 289.414712 -295.09974) (xy 289.414712 -295.577514) (xy 293.122604 -295.577514) (xy 293.122604 -294.866314)
			(xy 293.123148 -294.851301) (xy 293.130914 -294.822298) (xy 293.145922 -294.796292) (xy 293.167148 -294.775056)
			(xy 293.193146 -294.760036) (xy 293.222146 -294.752255) (xy 293.237158 -294.75176) (xy 293.714932 -294.75176)
			(xy 293.725004 -294.751362) (xy 293.743603 -294.743623) (xy 293.751 -294.736774) (xy 293.900098 -294.587676)
			(xy 293.908565 -294.578245) (xy 293.915756 -294.553974) (xy 293.913814 -294.541448) (xy 293.913814 -294.54094)
			(xy 293.910517 -294.524628) (xy 293.906952 -294.49154) (xy 293.906702 -294.4749) (xy 293.907076 -294.45388)
			(xy 293.912681 -294.412213) (xy 293.917878 -294.391842) (xy 293.919656 -294.385238) (xy 293.919656 -294.11422)
			(xy 293.920197 -294.099195) (xy 293.927958 -294.070164) (xy 293.942958 -294.044125) (xy 293.964178 -294.022848)
			(xy 293.990176 -294.007777) (xy 294.019186 -293.999938) (xy 294.03421 -293.999412) (xy 294.41521 -293.999412)
			(xy 294.430251 -293.999886) (xy 294.459306 -294.007683) (xy 294.485348 -294.022743) (xy 294.506598 -294.044036)
			(xy 294.521605 -294.070108) (xy 294.529344 -294.099178) (xy 294.529764 -294.11422) (xy 294.529764 -294.385238)
			(xy 294.531542 -294.391842) (xy 294.536741 -294.412213) (xy 294.542346 -294.45388) (xy 294.542718 -294.4749)
			(xy 295.806876 -294.4749) (xy 295.807251 -294.45388) (xy 295.812856 -294.412213) (xy 295.818052 -294.391842)
			(xy 295.819576 -294.385238) (xy 295.819576 -294.11422) (xy 295.820057 -294.099166) (xy 295.827844 -294.070084)
			(xy 295.842893 -294.044008) (xy 295.864179 -294.022715) (xy 295.89025 -294.007658) (xy 295.91933 -293.999861)
			(xy 295.934384 -293.999412) (xy 296.315384 -293.999412) (xy 296.330441 -293.999853) (xy 296.359529 -294.007645)
			(xy 296.385609 -294.022701) (xy 296.406902 -294.043995) (xy 296.421957 -294.070075) (xy 296.429747 -294.099163)
			(xy 296.430192 -294.11422) (xy 296.430192 -294.385238) (xy 296.431716 -294.391842) (xy 296.436915 -294.412213)
			(xy 296.44252 -294.45388) (xy 296.442892 -294.4749) (xy 296.442402 -294.499889) (xy 296.434583 -294.549252)
			(xy 296.419139 -294.596784) (xy 296.396449 -294.641316) (xy 296.367073 -294.681749) (xy 296.331733 -294.717089)
			(xy 296.2913 -294.746465) (xy 296.246768 -294.769155) (xy 296.199236 -294.784599) (xy 296.149873 -294.792418)
			(xy 296.099895 -294.792418) (xy 296.050532 -294.784599) (xy 296.003 -294.769155) (xy 295.958468 -294.746465)
			(xy 295.918035 -294.717089) (xy 295.882695 -294.681749) (xy 295.853319 -294.641316) (xy 295.830629 -294.596784)
			(xy 295.815185 -294.549252) (xy 295.807366 -294.499889) (xy 295.806876 -294.4749) (xy 294.542718 -294.4749)
			(xy 294.542056 -294.503316) (xy 294.531926 -294.559239) (xy 294.512008 -294.612466) (xy 294.498014 -294.637206)
			(xy 294.495165 -294.642383) (xy 294.491695 -294.653674) (xy 294.491156 -294.659558) (xy 294.488985 -294.68336)
			(xy 294.477226 -294.729682) (xy 294.45742 -294.773176) (xy 294.430198 -294.812457) (xy 294.413686 -294.829738)
			(xy 294.179498 -295.063672) (xy 294.172677 -295.071087) (xy 294.164946 -295.089675) (xy 294.164512 -295.09974)
			(xy 294.164512 -295.577514) (xy 294.16412 -295.592541) (xy 294.156336 -295.621569) (xy 294.141304 -295.647593)
			(xy 294.120048 -295.668839) (xy 294.094017 -295.683858) (xy 294.064985 -295.691627) (xy 294.049958 -295.692068)
			(xy 293.237158 -295.692068) (xy 293.22214 -295.691601) (xy 293.193131 -295.683819) (xy 293.167122 -295.668796)
			(xy 293.145887 -295.647555) (xy 293.13087 -295.621543) (xy 293.123095 -295.592532) (xy 293.122604 -295.577514)
			(xy 289.414712 -295.577514) (xy 289.414279 -295.592514) (xy 289.40652 -295.621493) (xy 289.391534 -295.647482)
			(xy 289.37034 -295.668713) (xy 289.344377 -295.683744) (xy 289.315411 -295.691553) (xy 289.300412 -295.692068)
			(xy 288.487104 -295.692068) (xy 288.472072 -295.691616) (xy 288.443029 -295.683845) (xy 288.416983 -295.668829)
			(xy 288.395704 -295.647591) (xy 288.380639 -295.621573) (xy 288.372813 -295.592545) (xy 288.372296 -295.577514)
			(xy 285.614364 -295.577514) (xy 285.613877 -295.592531) (xy 285.606101 -295.62154) (xy 285.591083 -295.647549)
			(xy 285.569846 -295.668785) (xy 285.543836 -295.683802) (xy 285.514827 -295.691577) (xy 285.49981 -295.692068)
			(xy 284.68701 -295.692068) (xy 284.671995 -295.691555) (xy 284.642987 -295.683785) (xy 284.616979 -295.668773)
			(xy 284.595742 -295.647541) (xy 284.580724 -295.621535) (xy 284.572948 -295.592529) (xy 284.572456 -295.577514)
			(xy 280.307542 -295.577514) (xy 280.307542 -296.399786) (xy 280.607302 -296.399786) (xy 280.607302 -296.349814)
			(xy 280.615119 -296.300458) (xy 280.63056 -296.252932) (xy 280.653245 -296.208406) (xy 280.682615 -296.167977)
			(xy 280.717948 -296.13264) (xy 280.758374 -296.103265) (xy 280.802897 -296.080574) (xy 280.850421 -296.065128)
			(xy 280.899776 -296.057305) (xy 280.924762 -296.056812) (xy 280.92527 -296.056812) (xy 280.946219 -296.057143)
			(xy 280.987756 -296.062621) (xy 281.008074 -296.067734) (xy 281.011687 -296.06864) (xy 281.019081 -296.069534)
			(xy 281.022806 -296.069512) (xy 281.026362 -296.069512) (xy 281.331162 -296.069512) (xy 281.346201 -296.070027)
			(xy 281.375254 -296.077814) (xy 281.401296 -296.092863) (xy 281.422548 -296.114149) (xy 281.437556 -296.140215)
			(xy 281.445296 -296.16928) (xy 281.445716 -296.18432) (xy 281.445716 -296.399791) (xy 282.507377 -296.399791)
			(xy 282.507377 -296.349809) (xy 282.515197 -296.300441) (xy 282.530643 -296.252905) (xy 282.553336 -296.208371)
			(xy 282.582717 -296.167935) (xy 282.618063 -296.132594) (xy 282.658502 -296.103218) (xy 282.703038 -296.080529)
			(xy 282.750576 -296.065088) (xy 282.799945 -296.057274) (xy 282.824936 -296.056812) (xy 282.825444 -296.056812)
			(xy 282.846392 -296.057148) (xy 282.88793 -296.062622) (xy 282.908248 -296.067734) (xy 282.911862 -296.068635)
			(xy 282.919256 -296.069533) (xy 282.92298 -296.069512) (xy 282.926536 -296.069512) (xy 283.231336 -296.069512)
			(xy 283.246389 -296.069952) (xy 283.275468 -296.077753) (xy 283.301538 -296.092813) (xy 283.322821 -296.114107)
			(xy 283.337869 -296.140184) (xy 283.345656 -296.169266) (xy 283.346144 -296.18432) (xy 283.346144 -296.399785)
			(xy 284.407402 -296.399785) (xy 284.407402 -296.349815) (xy 284.415219 -296.300459) (xy 284.430659 -296.252933)
			(xy 284.453344 -296.208408) (xy 284.482713 -296.167979) (xy 284.518046 -296.132642) (xy 284.55847 -296.103267)
			(xy 284.602993 -296.080576) (xy 284.650516 -296.065129) (xy 284.699871 -296.057306) (xy 284.724856 -296.056812)
			(xy 284.725364 -296.056812) (xy 284.746313 -296.057144) (xy 284.78785 -296.062621) (xy 284.808168 -296.067734)
			(xy 284.811781 -296.068639) (xy 284.819175 -296.069534) (xy 284.8229 -296.069512) (xy 284.826456 -296.069512)
			(xy 285.131256 -296.069512) (xy 285.146312 -296.069978) (xy 285.175399 -296.077763) (xy 285.201479 -296.092813)
			(xy 285.222772 -296.114102) (xy 285.237828 -296.140179) (xy 285.245619 -296.169264) (xy 285.246064 -296.18432)
			(xy 285.246064 -296.399786) (xy 286.307302 -296.399786) (xy 286.307302 -296.349814) (xy 286.315119 -296.300456)
			(xy 286.330561 -296.252929) (xy 286.353247 -296.208402) (xy 286.382619 -296.167972) (xy 286.417954 -296.132635)
			(xy 286.458382 -296.10326) (xy 286.502907 -296.08057) (xy 286.550433 -296.065125) (xy 286.59979 -296.057304)
			(xy 286.624776 -296.056812) (xy 286.625284 -296.056812) (xy 286.646233 -296.05714) (xy 286.68777 -296.06262)
			(xy 286.708088 -296.067734) (xy 286.7117 -296.068643) (xy 286.719095 -296.069535) (xy 286.72282 -296.069512)
			(xy 286.726376 -296.069512) (xy 287.031176 -296.069512) (xy 287.046232 -296.06996) (xy 287.07532 -296.07775)
			(xy 287.1014 -296.092804) (xy 287.122693 -296.114097) (xy 287.137748 -296.140176) (xy 287.145539 -296.169264)
			(xy 287.145984 -296.18432) (xy 287.145984 -296.399785) (xy 288.207502 -296.399785) (xy 288.207502 -296.349815)
			(xy 288.215318 -296.30046) (xy 288.230759 -296.252935) (xy 288.253442 -296.20841) (xy 288.282812 -296.167981)
			(xy 288.318143 -296.132644) (xy 288.358567 -296.103269) (xy 288.403088 -296.080578) (xy 288.450611 -296.06513)
			(xy 288.499965 -296.057306) (xy 288.52495 -296.056812) (xy 288.525458 -296.056812) (xy 288.546407 -296.057145)
			(xy 288.587944 -296.062621) (xy 288.608262 -296.067734) (xy 288.611876 -296.068637) (xy 288.619269 -296.069534)
			(xy 288.622994 -296.069512) (xy 288.62655 -296.069512) (xy 288.93135 -296.069512) (xy 288.946389 -296.070038)
			(xy 288.975441 -296.077821) (xy 289.001483 -296.092869) (xy 289.022735 -296.114152) (xy 289.037744 -296.140217)
			(xy 289.045484 -296.169281) (xy 289.045904 -296.18432) (xy 289.045904 -296.399786) (xy 290.107402 -296.399786)
			(xy 290.107402 -296.349814) (xy 290.115219 -296.300457) (xy 290.13066 -296.25293) (xy 290.153346 -296.208404)
			(xy 290.182718 -296.167974) (xy 290.218052 -296.132637) (xy 290.258478 -296.103262) (xy 290.303002 -296.080572)
			(xy 290.350528 -296.065126) (xy 290.399884 -296.057305) (xy 290.42487 -296.056812) (xy 290.44589 -296.057191)
			(xy 290.487557 -296.062793) (xy 290.507928 -296.067988) (xy 290.514532 -296.069512) (xy 290.80587 -296.069512)
			(xy 290.82091 -296.07002) (xy 290.849963 -296.077808) (xy 290.876005 -296.09286) (xy 290.897256 -296.114147)
			(xy 290.912265 -296.140214) (xy 290.920004 -296.16928) (xy 290.920424 -296.18432) (xy 290.920424 -296.56532)
			(xy 290.919938 -296.580349) (xy 290.919202 -296.5831) (xy 292.651688 -296.5831) (xy 292.651688 -296.2021)
			(xy 292.65218 -296.187071) (xy 292.659948 -296.158035) (xy 292.674958 -296.131993) (xy 292.696188 -296.110715)
			(xy 292.722196 -296.095648) (xy 292.751214 -296.087814) (xy 292.766242 -296.087292) (xy 293.071042 -296.087292)
			(xy 293.078692 -296.087426) (xy 293.093855 -296.089464) (xy 293.101268 -296.091356) (xy 293.110181 -296.093438)
			(xy 293.128404 -296.091885) (xy 293.136828 -296.088308) (xy 293.158373 -296.078412) (xy 293.203666 -296.064404)
			(xy 293.250538 -296.057286) (xy 293.274242 -296.056812) (xy 293.27475 -296.056812) (xy 293.300056 -296.057303)
			(xy 293.350026 -296.065344) (xy 293.398096 -296.081184) (xy 293.4208 -296.092372) (xy 293.430596 -296.096743)
			(xy 293.451987 -296.09793) (xy 293.462202 -296.094658) (xy 293.472001 -296.091193) (xy 293.49245 -296.08749)
			(xy 293.502842 -296.087292) (xy 293.807642 -296.087292) (xy 293.822691 -296.087658) (xy 293.851759 -296.09547)
			(xy 293.877809 -296.110549) (xy 293.89906 -296.131864) (xy 293.914061 -296.157958) (xy 293.921786 -296.187049)
			(xy 293.922196 -296.2021) (xy 293.922196 -296.399791) (xy 294.857377 -296.399791) (xy 294.857377 -296.349809)
			(xy 294.865196 -296.300443) (xy 294.880642 -296.252908) (xy 294.903334 -296.208374) (xy 294.932714 -296.167939)
			(xy 294.968058 -296.132598) (xy 295.008495 -296.103222) (xy 295.05303 -296.080533) (xy 295.100566 -296.065091)
			(xy 295.149933 -296.057275) (xy 295.174924 -296.056812) (xy 295.195945 -296.057181) (xy 295.237611 -296.06279)
			(xy 295.257982 -296.067988) (xy 295.264586 -296.069512) (xy 295.555924 -296.069512) (xy 295.570977 -296.069962)
			(xy 295.600055 -296.07776) (xy 295.626125 -296.092818) (xy 295.647409 -296.11411) (xy 295.662457 -296.140186)
			(xy 295.670244 -296.169267) (xy 295.670732 -296.18432) (xy 295.670732 -296.399792) (xy 296.757277 -296.399792)
			(xy 296.757277 -296.349808) (xy 296.765097 -296.30044) (xy 296.780544 -296.252903) (xy 296.803238 -296.208368)
			(xy 296.83262 -296.167932) (xy 296.867966 -296.132591) (xy 296.908406 -296.103215) (xy 296.952944 -296.080527)
			(xy 297.000483 -296.065087) (xy 297.049852 -296.057274) (xy 297.074844 -296.056812) (xy 297.095865 -296.057177)
			(xy 297.137531 -296.062788) (xy 297.157902 -296.067988) (xy 297.164506 -296.069512) (xy 297.455844 -296.069512)
			(xy 297.470898 -296.069945) (xy 297.499977 -296.077747) (xy 297.526046 -296.092809) (xy 297.54733 -296.114105)
			(xy 297.562377 -296.140183) (xy 297.570164 -296.169266) (xy 297.570652 -296.18432) (xy 297.570652 -296.56532)
			(xy 297.570135 -296.580367) (xy 297.562343 -296.609436) (xy 297.547296 -296.635499) (xy 297.526018 -296.656782)
			(xy 297.499958 -296.671834) (xy 297.470891 -296.679632) (xy 297.455844 -296.680128) (xy 297.164506 -296.680128)
			(xy 297.157902 -296.681652) (xy 297.137529 -296.686843) (xy 297.095864 -296.692453) (xy 297.074844 -296.692828)
			(xy 297.049852 -296.692326) (xy 297.000483 -296.684513) (xy 296.952944 -296.669073) (xy 296.908406 -296.646385)
			(xy 296.867966 -296.617009) (xy 296.83262 -296.581668) (xy 296.803238 -296.541232) (xy 296.780544 -296.496697)
			(xy 296.765097 -296.44916) (xy 296.757277 -296.399792) (xy 295.670732 -296.399792) (xy 295.670732 -296.56532)
			(xy 295.670235 -296.580369) (xy 295.662442 -296.609441) (xy 295.647391 -296.635506) (xy 295.626109 -296.656789)
			(xy 295.600044 -296.67184) (xy 295.570973 -296.679634) (xy 295.555924 -296.680128) (xy 295.264586 -296.680128)
			(xy 295.257982 -296.681652) (xy 295.23761 -296.686847) (xy 295.195944 -296.692455) (xy 295.174924 -296.692828)
			(xy 295.149933 -296.692325) (xy 295.100566 -296.684509) (xy 295.05303 -296.669067) (xy 295.008495 -296.646378)
			(xy 294.968058 -296.617002) (xy 294.932714 -296.581661) (xy 294.903334 -296.541226) (xy 294.880642 -296.496692)
			(xy 294.865196 -296.449157) (xy 294.857377 -296.399791) (xy 293.922196 -296.399791) (xy 293.922196 -296.5831)
			(xy 293.92172 -296.59813) (xy 293.91395 -296.627169) (xy 293.898938 -296.653212) (xy 293.877705 -296.67449)
			(xy 293.851693 -296.689557) (xy 293.822671 -296.697388) (xy 293.807642 -296.697908) (xy 293.502842 -296.697908)
			(xy 293.486767 -296.697356) (xy 293.455865 -296.688494) (xy 293.428625 -296.671421) (xy 293.417498 -296.659808)
			(xy 293.416228 -296.659808) (xy 293.394232 -296.670176) (xy 293.347873 -296.684853) (xy 293.299824 -296.692324)
			(xy 293.275512 -296.692828) (xy 293.27475 -296.692828) (xy 293.248951 -296.692334) (xy 293.198024 -296.684042)
			(xy 293.173404 -296.676318) (xy 293.162668 -296.673304) (xy 293.140532 -296.675821) (xy 293.130732 -296.681144)
			(xy 293.117055 -296.688925) (xy 293.08677 -296.697425) (xy 293.071042 -296.697908) (xy 292.766242 -296.697908)
			(xy 292.751196 -296.697468) (xy 292.722132 -296.689676) (xy 292.696081 -296.674615) (xy 292.674828 -296.653313)
			(xy 292.659825 -296.627229) (xy 292.652098 -296.598147) (xy 292.651688 -296.5831) (xy 290.919202 -296.5831)
			(xy 290.912165 -296.609384) (xy 290.897154 -296.635424) (xy 290.875923 -296.656701) (xy 290.849916 -296.671769)
			(xy 290.820898 -296.679605) (xy 290.80587 -296.680128) (xy 290.514532 -296.680128) (xy 290.507928 -296.681652)
			(xy 290.487559 -296.686857) (xy 290.445891 -296.692458) (xy 290.42487 -296.692828) (xy 290.399884 -296.692295)
			(xy 290.350528 -296.684474) (xy 290.303002 -296.669028) (xy 290.258478 -296.646338) (xy 290.218052 -296.616963)
			(xy 290.182718 -296.581626) (xy 290.153346 -296.541196) (xy 290.13066 -296.49667) (xy 290.115219 -296.449143)
			(xy 290.107402 -296.399786) (xy 289.045904 -296.399786) (xy 289.045904 -296.56532) (xy 289.045437 -296.58035)
			(xy 289.037664 -296.609388) (xy 289.022649 -296.635431) (xy 289.001414 -296.656708) (xy 288.975402 -296.671775)
			(xy 288.946379 -296.679607) (xy 288.93135 -296.680128) (xy 288.622994 -296.680128) (xy 288.619268 -296.680097)
			(xy 288.611872 -296.680984) (xy 288.608262 -296.681906) (xy 288.587948 -296.687037) (xy 288.546408 -296.692513)
			(xy 288.525458 -296.692828) (xy 288.52495 -296.692828) (xy 288.499965 -296.692294) (xy 288.450611 -296.68447)
			(xy 288.403088 -296.669022) (xy 288.358567 -296.646331) (xy 288.318143 -296.616956) (xy 288.282812 -296.581619)
			(xy 288.253442 -296.54119) (xy 288.230759 -296.496665) (xy 288.215318 -296.44914) (xy 288.207502 -296.399785)
			(xy 287.145984 -296.399785) (xy 287.145984 -296.56532) (xy 287.145578 -296.580379) (xy 287.137778 -296.609469)
			(xy 287.122714 -296.635549) (xy 287.101414 -296.656841) (xy 287.075328 -296.671895) (xy 287.046235 -296.679684)
			(xy 287.031176 -296.680128) (xy 286.72282 -296.680128) (xy 286.719094 -296.680081) (xy 286.711697 -296.680979)
			(xy 286.708088 -296.681906) (xy 286.687773 -296.687032) (xy 286.646234 -296.692511) (xy 286.625284 -296.692828)
			(xy 286.624776 -296.692828) (xy 286.59979 -296.692296) (xy 286.550433 -296.684475) (xy 286.502907 -296.66903)
			(xy 286.458382 -296.64634) (xy 286.417954 -296.616965) (xy 286.382619 -296.581628) (xy 286.353247 -296.541198)
			(xy 286.330561 -296.496671) (xy 286.315119 -296.449144) (xy 286.307302 -296.399786) (xy 285.246064 -296.399786)
			(xy 285.246064 -296.56532) (xy 285.245678 -296.58038) (xy 285.237876 -296.609474) (xy 285.222809 -296.635556)
			(xy 285.201504 -296.656848) (xy 285.175414 -296.671901) (xy 285.146317 -296.679687) (xy 285.131256 -296.680128)
			(xy 284.8229 -296.680128) (xy 284.819174 -296.680099) (xy 284.811778 -296.680985) (xy 284.808168 -296.681906)
			(xy 284.787853 -296.687035) (xy 284.746314 -296.692512) (xy 284.725364 -296.692828) (xy 284.724856 -296.692828)
			(xy 284.699871 -296.692294) (xy 284.650516 -296.684471) (xy 284.602993 -296.669024) (xy 284.55847 -296.646333)
			(xy 284.518046 -296.616958) (xy 284.482713 -296.581621) (xy 284.453344 -296.541192) (xy 284.430659 -296.496667)
			(xy 284.415219 -296.449141) (xy 284.407402 -296.399785) (xy 283.346144 -296.399785) (xy 283.346144 -296.56532)
			(xy 283.345635 -296.580368) (xy 283.337843 -296.609438) (xy 283.322794 -296.635502) (xy 283.301515 -296.656785)
			(xy 283.275453 -296.671837) (xy 283.246384 -296.679633) (xy 283.231336 -296.680128) (xy 282.92298 -296.680128)
			(xy 282.919254 -296.680094) (xy 282.911858 -296.680983) (xy 282.908248 -296.681906) (xy 282.887934 -296.687039)
			(xy 282.846394 -296.692514) (xy 282.825444 -296.692828) (xy 282.824936 -296.692828) (xy 282.799945 -296.692326)
			(xy 282.750576 -296.684512) (xy 282.703038 -296.669071) (xy 282.658502 -296.646382) (xy 282.618063 -296.617006)
			(xy 282.582717 -296.581665) (xy 282.553336 -296.541229) (xy 282.530643 -296.496695) (xy 282.515197 -296.449159)
			(xy 282.507377 -296.399791) (xy 281.445716 -296.399791) (xy 281.445716 -296.56532) (xy 281.445238 -296.580349)
			(xy 281.437465 -296.609386) (xy 281.422452 -296.635427) (xy 281.40122 -296.656704) (xy 281.37521 -296.671772)
			(xy 281.34619 -296.679606) (xy 281.331162 -296.680128) (xy 281.022806 -296.680128) (xy 281.01908 -296.6801)
			(xy 281.011684 -296.680985) (xy 281.008074 -296.681906) (xy 280.987759 -296.687034) (xy 280.94622 -296.692512)
			(xy 280.92527 -296.692828) (xy 280.924762 -296.692828) (xy 280.899776 -296.692295) (xy 280.850421 -296.684472)
			(xy 280.802897 -296.669026) (xy 280.758374 -296.646335) (xy 280.717948 -296.61696) (xy 280.682615 -296.581623)
			(xy 280.653245 -296.541194) (xy 280.63056 -296.496668) (xy 280.615119 -296.449142) (xy 280.607302 -296.399786)
			(xy 280.307542 -296.399786) (xy 280.307542 -297.32478) (xy 281.556714 -297.32478) (xy 281.557204 -297.299791)
			(xy 281.565023 -297.250428) (xy 281.580467 -297.202896) (xy 281.603157 -297.158364) (xy 281.632533 -297.117931)
			(xy 281.667873 -297.082591) (xy 281.708306 -297.053215) (xy 281.752838 -297.030525) (xy 281.80037 -297.015081)
			(xy 281.849733 -297.007262) (xy 281.899711 -297.007262) (xy 281.949074 -297.015081) (xy 281.996606 -297.030525)
			(xy 282.041138 -297.053215) (xy 282.081571 -297.082591) (xy 282.116911 -297.117931) (xy 282.146287 -297.158364)
			(xy 282.168977 -297.202896) (xy 282.184421 -297.250428) (xy 282.19224 -297.299791) (xy 282.19273 -297.32478)
			(xy 283.456888 -297.32478) (xy 283.457378 -297.299791) (xy 283.465197 -297.250428) (xy 283.480641 -297.202896)
			(xy 283.503331 -297.158364) (xy 283.532707 -297.117931) (xy 283.568047 -297.082591) (xy 283.60848 -297.053215)
			(xy 283.653012 -297.030525) (xy 283.700544 -297.015081) (xy 283.749907 -297.007262) (xy 283.799885 -297.007262)
			(xy 283.849248 -297.015081) (xy 283.89678 -297.030525) (xy 283.941312 -297.053215) (xy 283.981745 -297.082591)
			(xy 284.017085 -297.117931) (xy 284.046461 -297.158364) (xy 284.069151 -297.202896) (xy 284.084595 -297.250428)
			(xy 284.092414 -297.299791) (xy 284.092904 -297.32478) (xy 285.356808 -297.32478) (xy 285.357298 -297.299791)
			(xy 285.365117 -297.250428) (xy 285.380561 -297.202896) (xy 285.403251 -297.158364) (xy 285.432627 -297.117931)
			(xy 285.467967 -297.082591) (xy 285.5084 -297.053215) (xy 285.552932 -297.030525) (xy 285.600464 -297.015081)
			(xy 285.649827 -297.007262) (xy 285.699805 -297.007262) (xy 285.749168 -297.015081) (xy 285.7967 -297.030525)
			(xy 285.841232 -297.053215) (xy 285.881665 -297.082591) (xy 285.917005 -297.117931) (xy 285.946381 -297.158364)
			(xy 285.969071 -297.202896) (xy 285.984515 -297.250428) (xy 285.992334 -297.299791) (xy 285.992824 -297.32478)
			(xy 287.256728 -297.32478) (xy 287.257218 -297.299791) (xy 287.265037 -297.250428) (xy 287.280481 -297.202896)
			(xy 287.303171 -297.158364) (xy 287.332547 -297.117931) (xy 287.367887 -297.082591) (xy 287.40832 -297.053215)
			(xy 287.452852 -297.030525) (xy 287.500384 -297.015081) (xy 287.549747 -297.007262) (xy 287.599725 -297.007262)
			(xy 287.649088 -297.015081) (xy 287.69662 -297.030525) (xy 287.741152 -297.053215) (xy 287.781585 -297.082591)
			(xy 287.816925 -297.117931) (xy 287.846301 -297.158364) (xy 287.868991 -297.202896) (xy 287.884435 -297.250428)
			(xy 287.892254 -297.299791) (xy 287.892744 -297.32478) (xy 289.156902 -297.32478) (xy 289.157392 -297.299791)
			(xy 289.165211 -297.250428) (xy 289.180655 -297.202896) (xy 289.203345 -297.158364) (xy 289.232721 -297.117931)
			(xy 289.268061 -297.082591) (xy 289.308494 -297.053215) (xy 289.353026 -297.030525) (xy 289.400558 -297.015081)
			(xy 289.449921 -297.007262) (xy 289.499899 -297.007262) (xy 289.549262 -297.015081) (xy 289.596794 -297.030525)
			(xy 289.641326 -297.053215) (xy 289.681759 -297.082591) (xy 289.717099 -297.117931) (xy 289.746475 -297.158364)
			(xy 289.769165 -297.202896) (xy 289.784609 -297.250428) (xy 289.792428 -297.299791) (xy 289.792918 -297.32478)
			(xy 292.006782 -297.32478) (xy 292.007272 -297.299791) (xy 292.015091 -297.250428) (xy 292.030535 -297.202896)
			(xy 292.053225 -297.158364) (xy 292.082601 -297.117931) (xy 292.117941 -297.082591) (xy 292.158374 -297.053215)
			(xy 292.202906 -297.030525) (xy 292.250438 -297.015081) (xy 292.299801 -297.007262) (xy 292.349779 -297.007262)
			(xy 292.399142 -297.015081) (xy 292.446674 -297.030525) (xy 292.491206 -297.053215) (xy 292.531639 -297.082591)
			(xy 292.566979 -297.117931) (xy 292.596355 -297.158364) (xy 292.619045 -297.202896) (xy 292.634489 -297.250428)
			(xy 292.642308 -297.299791) (xy 292.642798 -297.32478) (xy 293.906702 -297.32478) (xy 293.907192 -297.299791)
			(xy 293.915011 -297.250428) (xy 293.930455 -297.202896) (xy 293.953145 -297.158364) (xy 293.982521 -297.117931)
			(xy 294.017861 -297.082591) (xy 294.058294 -297.053215) (xy 294.102826 -297.030525) (xy 294.150358 -297.015081)
			(xy 294.199721 -297.007262) (xy 294.249699 -297.007262) (xy 294.299062 -297.015081) (xy 294.346594 -297.030525)
			(xy 294.391126 -297.053215) (xy 294.431559 -297.082591) (xy 294.466899 -297.117931) (xy 294.496275 -297.158364)
			(xy 294.518965 -297.202896) (xy 294.534409 -297.250428) (xy 294.542228 -297.299791) (xy 294.542718 -297.32478)
			(xy 295.806876 -297.32478) (xy 295.807366 -297.299791) (xy 295.815185 -297.250428) (xy 295.830629 -297.202896)
			(xy 295.853319 -297.158364) (xy 295.882695 -297.117931) (xy 295.918035 -297.082591) (xy 295.958468 -297.053215)
			(xy 296.003 -297.030525) (xy 296.050532 -297.015081) (xy 296.099895 -297.007262) (xy 296.149873 -297.007262)
			(xy 296.199236 -297.015081) (xy 296.246768 -297.030525) (xy 296.2913 -297.053215) (xy 296.331733 -297.082591)
			(xy 296.367073 -297.117931) (xy 296.396449 -297.158364) (xy 296.419139 -297.202896) (xy 296.434583 -297.250428)
			(xy 296.442402 -297.299791) (xy 296.442892 -297.32478) (xy 296.442514 -297.3458) (xy 296.436911 -297.387467)
			(xy 296.431716 -297.407838) (xy 296.430192 -297.414442) (xy 296.430192 -297.68546) (xy 296.429726 -297.700515)
			(xy 296.42194 -297.729602) (xy 296.40689 -297.755681) (xy 296.385601 -297.776975) (xy 296.359524 -297.792031)
			(xy 296.330439 -297.799823) (xy 296.315384 -297.800268) (xy 295.934384 -297.800268) (xy 295.919324 -297.799875)
			(xy 295.890232 -297.792074) (xy 295.86415 -297.777009) (xy 295.842857 -297.755705) (xy 295.827804 -297.729616)
			(xy 295.820018 -297.70052) (xy 295.819576 -297.68546) (xy 295.819576 -297.414442) (xy 295.818052 -297.407838)
			(xy 295.812849 -297.387468) (xy 295.807246 -297.345801) (xy 295.806876 -297.32478) (xy 294.542718 -297.32478)
			(xy 294.54234 -297.3458) (xy 294.536737 -297.387467) (xy 294.531542 -297.407838) (xy 294.529764 -297.414442)
			(xy 294.529764 -297.68546) (xy 294.529284 -297.700491) (xy 294.521521 -297.729533) (xy 294.506512 -297.755579)
			(xy 294.485279 -297.776859) (xy 294.459265 -297.791925) (xy 294.43024 -297.799751) (xy 294.41521 -297.800268)
			(xy 294.03421 -297.800268) (xy 294.019168 -297.799797) (xy 293.990111 -297.792002) (xy 293.964067 -297.776944)
			(xy 293.942816 -297.75565) (xy 293.927809 -297.729575) (xy 293.920073 -297.700503) (xy 293.919656 -297.68546)
			(xy 293.919656 -297.414442) (xy 293.917878 -297.407838) (xy 293.912675 -297.387468) (xy 293.907073 -297.345801)
			(xy 293.906702 -297.32478) (xy 292.642798 -297.32478) (xy 292.64242 -297.3458) (xy 292.636817 -297.387467)
			(xy 292.631622 -297.407838) (xy 292.629844 -297.414442) (xy 292.629844 -297.68546) (xy 292.629285 -297.700484)
			(xy 292.621529 -297.729514) (xy 292.606533 -297.755553) (xy 292.585316 -297.776831) (xy 292.55932 -297.791902)
			(xy 292.530313 -297.799742) (xy 292.51529 -297.800268) (xy 292.13429 -297.800268) (xy 292.119247 -297.799814)
			(xy 292.090189 -297.792015) (xy 292.064146 -297.776952) (xy 292.042895 -297.755655) (xy 292.027889 -297.729578)
			(xy 292.020153 -297.700504) (xy 292.019736 -297.68546) (xy 292.019736 -297.414442) (xy 292.017958 -297.407838)
			(xy 292.012755 -297.387468) (xy 292.007152 -297.345801) (xy 292.006782 -297.32478) (xy 289.792918 -297.32478)
			(xy 289.79254 -297.3458) (xy 289.786937 -297.387467) (xy 289.781742 -297.407838) (xy 289.779964 -297.414442)
			(xy 289.779964 -297.68546) (xy 289.779484 -297.700491) (xy 289.771721 -297.729533) (xy 289.756712 -297.755579)
			(xy 289.735479 -297.776859) (xy 289.709465 -297.791925) (xy 289.68044 -297.799751) (xy 289.66541 -297.800268)
			(xy 289.28441 -297.800268) (xy 289.269368 -297.799797) (xy 289.240311 -297.792002) (xy 289.214267 -297.776944)
			(xy 289.193016 -297.75565) (xy 289.178009 -297.729575) (xy 289.170273 -297.700503) (xy 289.169856 -297.68546)
			(xy 289.169856 -297.414442) (xy 289.168078 -297.407838) (xy 289.162875 -297.387468) (xy 289.157273 -297.345801)
			(xy 289.156902 -297.32478) (xy 287.892744 -297.32478) (xy 287.892365 -297.3458) (xy 287.886763 -297.387467)
			(xy 287.881568 -297.407838) (xy 287.880044 -297.414442) (xy 287.880044 -297.68546) (xy 287.879526 -297.700511)
			(xy 287.871745 -297.72959) (xy 287.856703 -297.755664) (xy 287.835425 -297.776957) (xy 287.809361 -297.792016)
			(xy 287.780287 -297.799816) (xy 287.765236 -297.800268) (xy 287.384236 -297.800268) (xy 287.369178 -297.799829)
			(xy 287.340088 -297.79204) (xy 287.314006 -297.776985) (xy 287.292712 -297.755691) (xy 287.277658 -297.729608)
			(xy 287.269871 -297.700518) (xy 287.269428 -297.68546) (xy 287.269428 -297.414442) (xy 287.267904 -297.407838)
			(xy 287.262702 -297.387468) (xy 287.257099 -297.345801) (xy 287.256728 -297.32478) (xy 285.992824 -297.32478)
			(xy 285.992445 -297.3458) (xy 285.986843 -297.387467) (xy 285.981648 -297.407838) (xy 285.980124 -297.414442)
			(xy 285.980124 -297.68546) (xy 285.979626 -297.700513) (xy 285.971843 -297.729595) (xy 285.956798 -297.755671)
			(xy 285.935515 -297.776964) (xy 285.909447 -297.792022) (xy 285.880369 -297.799819) (xy 285.865316 -297.800268)
			(xy 285.484316 -297.800268) (xy 285.469258 -297.799846) (xy 285.440166 -297.792053) (xy 285.414085 -297.776994)
			(xy 285.392791 -297.755696) (xy 285.377738 -297.729611) (xy 285.369951 -297.700519) (xy 285.369508 -297.68546)
			(xy 285.369508 -297.414442) (xy 285.367984 -297.407838) (xy 285.362782 -297.387468) (xy 285.357179 -297.345801)
			(xy 285.356808 -297.32478) (xy 284.092904 -297.32478) (xy 284.092526 -297.3458) (xy 284.086923 -297.387467)
			(xy 284.081728 -297.407838) (xy 284.080204 -297.414442) (xy 284.080204 -297.68546) (xy 284.079726 -297.700514)
			(xy 284.071941 -297.729599) (xy 284.056893 -297.755677) (xy 284.035606 -297.776971) (xy 284.009533 -297.792028)
			(xy 283.98045 -297.799821) (xy 283.965396 -297.800268) (xy 283.584396 -297.800268) (xy 283.569337 -297.799864)
			(xy 283.540245 -297.792066) (xy 283.514163 -297.777003) (xy 283.49287 -297.755702) (xy 283.477817 -297.729614)
			(xy 283.47003 -297.70052) (xy 283.469588 -297.68546) (xy 283.469588 -297.414442) (xy 283.468064 -297.407838)
			(xy 283.462861 -297.387468) (xy 283.457258 -297.345801) (xy 283.456888 -297.32478) (xy 282.19273 -297.32478)
			(xy 282.192351 -297.3458) (xy 282.186749 -297.387467) (xy 282.181554 -297.407838) (xy 282.179776 -297.414442)
			(xy 282.179776 -297.68546) (xy 282.179284 -297.70049) (xy 282.171522 -297.72953) (xy 282.156515 -297.755575)
			(xy 282.135284 -297.776855) (xy 282.109273 -297.791921) (xy 282.080251 -297.79975) (xy 282.065222 -297.800268)
			(xy 281.684222 -297.800268) (xy 281.66918 -297.799786) (xy 281.640124 -297.791995) (xy 281.61408 -297.776938)
			(xy 281.592828 -297.755646) (xy 281.577822 -297.729574) (xy 281.570085 -297.700502) (xy 281.569668 -297.68546)
			(xy 281.569668 -297.414442) (xy 281.56789 -297.407838) (xy 281.562688 -297.387468) (xy 281.557085 -297.345801)
			(xy 281.556714 -297.32478) (xy 280.307542 -297.32478) (xy 280.307542 -298.27474) (xy 280.606754 -298.27474)
			(xy 280.607137 -298.25372) (xy 280.612737 -298.212054) (xy 280.61793 -298.191682) (xy 280.619708 -298.185078)
			(xy 280.619708 -297.91406) (xy 280.620145 -297.899028) (xy 280.627925 -297.869987) (xy 280.642945 -297.843944)
			(xy 280.664186 -297.822666) (xy 280.690204 -297.807601) (xy 280.719231 -297.799771) (xy 280.734262 -297.799252)
			(xy 281.115262 -297.799252) (xy 281.130305 -297.799728) (xy 281.159363 -297.807517) (xy 281.18541 -297.822574)
			(xy 281.206662 -297.843867) (xy 281.221668 -297.869943) (xy 281.229401 -297.899017) (xy 281.229816 -297.91406)
			(xy 281.229816 -298.185078) (xy 281.231594 -298.191682) (xy 281.2368 -298.212051) (xy 281.242401 -298.253719)
			(xy 281.24277 -298.27474) (xy 281.24228 -298.299729) (xy 281.234461 -298.349092) (xy 281.219017 -298.396624)
			(xy 281.196327 -298.441156) (xy 281.166951 -298.481589) (xy 281.131611 -298.516929) (xy 281.091178 -298.546305)
			(xy 281.046646 -298.568995) (xy 280.999114 -298.584439) (xy 280.949751 -298.592258) (xy 280.899773 -298.592258)
			(xy 280.85041 -298.584439) (xy 280.802878 -298.568995) (xy 280.758346 -298.546305) (xy 280.717913 -298.516929)
			(xy 280.682573 -298.481589) (xy 280.653197 -298.441156) (xy 280.630507 -298.396624) (xy 280.615063 -298.349092)
			(xy 280.607244 -298.299729) (xy 280.606754 -298.27474) (xy 280.307542 -298.27474) (xy 280.307542 -300.199886)
			(xy 280.607296 -300.199886) (xy 280.607296 -300.149914) (xy 280.615113 -300.100557) (xy 280.630554 -300.05303)
			(xy 280.65324 -300.008503) (xy 280.682611 -299.968073) (xy 280.717944 -299.932735) (xy 280.758371 -299.903359)
			(xy 280.802895 -299.880669) (xy 280.85042 -299.865222) (xy 280.899776 -299.857399) (xy 280.924762 -299.856906)
			(xy 280.945782 -299.857287) (xy 280.987448 -299.862888) (xy 281.00782 -299.868082) (xy 281.014424 -299.86986)
			(xy 281.285442 -299.86986) (xy 281.300462 -299.870299) (xy 281.329476 -299.878084) (xy 281.355487 -299.893111)
			(xy 281.376723 -299.914358) (xy 281.391738 -299.940376) (xy 281.399508 -299.969394) (xy 281.399996 -299.984414)
			(xy 281.399996 -300.365414) (xy 281.399477 -300.380428) (xy 281.391704 -300.409433) (xy 281.376691 -300.435438)
			(xy 281.35546 -300.456674) (xy 281.329458 -300.471693) (xy 281.300456 -300.479473) (xy 281.285442 -300.479968)
			(xy 281.014424 -300.479968) (xy 281.00782 -300.481746) (xy 280.987451 -300.486952) (xy 280.945783 -300.492553)
			(xy 280.924762 -300.492922) (xy 280.899776 -300.492401) (xy 280.85042 -300.484578) (xy 280.802895 -300.469131)
			(xy 280.758371 -300.446441) (xy 280.717944 -300.417065) (xy 280.682611 -300.381727) (xy 280.65324 -300.341297)
			(xy 280.630554 -300.29677) (xy 280.615113 -300.249243) (xy 280.607296 -300.199886) (xy 280.307542 -300.199886)
			(xy 280.307542 -301.197518) (xy 280.308558 -301.20717) (xy 280.310189 -301.214412) (xy 280.317036 -301.227576)
			(xy 280.32202 -301.233078) (xy 280.393902 -301.30496) (xy 280.401271 -301.311706) (xy 280.419733 -301.319304)
			(xy 280.429716 -301.319692)
		)
		(stroke
			(width 0)
			(type solid)
		)
		(fill yes)
		(layer "B.Cu")
		(net "P0V8_PEX2")
	)
	(gr_poly
		(pts
			(xy 397.347694 -301.319692) (xy 397.357965 -301.319172) (xy 397.376841 -301.311054) (xy 397.38427 -301.303944)
			(xy 397.435324 -301.250096) (xy 397.438747 -301.246222) (xy 397.444117 -301.237389) (xy 397.445992 -301.23257)
			(xy 397.449548 -301.223172) (xy 397.448786 -301.212504) (xy 397.448532 -301.2059) (xy 397.448532 -300.8249)
			(xy 397.448979 -300.809846) (xy 397.456774 -300.780764) (xy 397.471831 -300.754692) (xy 397.493124 -300.733406)
			(xy 397.519202 -300.718358) (xy 397.548286 -300.710574) (xy 397.56334 -300.710092) (xy 397.86814 -300.710092)
			(xy 397.876918 -300.710248) (xy 397.894268 -300.712926) (xy 397.902684 -300.715426) (xy 397.906748 -300.716696)
			(xy 397.910558 -300.717966) (xy 397.918686 -300.717966) (xy 397.928622 -300.717435) (xy 397.946962 -300.709771)
			(xy 397.961008 -300.695706) (xy 397.968648 -300.677356) (xy 397.969232 -300.66742) (xy 397.969232 -300.410626)
			(xy 397.969779 -300.385201) (xy 397.978286 -300.335066) (xy 397.994986 -300.287034) (xy 398.019416 -300.242435)
			(xy 398.034764 -300.222158) (xy 398.03809 -300.217762) (xy 398.043578 -300.208201) (xy 398.045686 -300.203108)
			(xy 398.048173 -300.196327) (xy 398.050851 -300.182135) (xy 398.05102 -300.174914) (xy 398.051274 -300.17466)
			(xy 398.050768 -300.162907) (xy 398.043529 -300.140537) (xy 398.03705 -300.130718) (xy 398.034764 -300.12767)
			(xy 398.01942 -300.107389) (xy 397.994988 -300.06279) (xy 397.97828 -300.014761) (xy 397.969758 -299.964627)
			(xy 397.969232 -299.939202) (xy 397.969232 -299.631354) (xy 397.968678 -299.62142) (xy 397.960995 -299.603088)
			(xy 397.946945 -299.589028) (xy 397.92862 -299.58133) (xy 397.918686 -299.580808) (xy 397.61414 -299.580808)
			(xy 397.599081 -299.580365) (xy 397.569986 -299.572579) (xy 397.543899 -299.557526) (xy 397.522599 -299.536232)
			(xy 397.507537 -299.510151) (xy 397.49974 -299.481059) (xy 397.499332 -299.466) (xy 397.499332 -299.085)
			(xy 397.499779 -299.069946) (xy 397.507574 -299.040864) (xy 397.522631 -299.014792) (xy 397.543924 -298.993506)
			(xy 397.570002 -298.978458) (xy 397.599086 -298.970674) (xy 397.61414 -298.970192) (xy 397.760698 -298.970192)
			(xy 397.764505 -298.970128) (xy 397.772032 -298.968984) (xy 397.775684 -298.967906) (xy 397.796258 -298.961556)
			(xy 397.800322 -298.959016) (xy 397.819829 -298.946699) (xy 397.86165 -298.927224) (xy 397.905851 -298.914011)
			(xy 397.951499 -298.907339) (xy 397.974566 -298.906946) (xy 397.981678 -298.906946) (xy 398.011661 -298.908285)
			(xy 398.070346 -298.920821) (xy 398.098264 -298.931838) (xy 398.104614 -298.934632) (xy 398.112996 -298.937934)
			(xy 398.127728 -298.93514) (xy 398.135061 -298.933391) (xy 398.148348 -298.926282) (xy 398.15389 -298.92117)
			(xy 398.257268 -298.817792) (xy 398.276668 -298.799147) (xy 398.320758 -298.768313) (xy 398.369578 -298.745702)
			(xy 398.395444 -298.73829) (xy 398.402048 -298.736512) (xy 398.407636 -298.73321) (xy 398.418558 -298.725082)
			(xy 398.475454 -298.668186) (xy 398.482851 -298.661339) (xy 398.501451 -298.653611) (xy 398.511522 -298.6532)
			(xy 398.60982 -298.6532) (xy 398.619567 -298.65277) (xy 398.637647 -298.645485) (xy 398.651673 -298.631949)
			(xy 398.656048 -298.623228) (xy 398.694148 -298.5389) (xy 398.696915 -298.532215) (xy 398.69897 -298.517901)
			(xy 398.698212 -298.510706) (xy 398.697958 -298.510706) (xy 398.696694 -298.503601) (xy 398.690758 -298.490454)
			(xy 398.686274 -298.484798) (xy 398.68602 -298.484544) (xy 398.671198 -298.467054) (xy 398.646212 -298.428616)
			(xy 398.627007 -298.386988) (xy 398.613981 -298.343033) (xy 398.607404 -298.297662) (xy 398.607026 -298.27474)
			(xy 398.607395 -298.253719) (xy 398.612996 -298.212051) (xy 398.618202 -298.191682) (xy 398.61998 -298.185078)
			(xy 398.61998 -298.049696) (xy 398.619726 -297.91406) (xy 398.62022 -297.899036) (xy 398.627996 -297.870012)
			(xy 398.643009 -297.843983) (xy 398.66424 -297.822719) (xy 398.690245 -297.807665) (xy 398.719257 -297.799843)
			(xy 398.73428 -297.799252) (xy 399.115534 -297.799252) (xy 399.130574 -297.799705) (xy 399.159626 -297.807509)
			(xy 399.185662 -297.822574) (xy 399.206906 -297.843872) (xy 399.221904 -297.869947) (xy 399.229633 -297.899018)
			(xy 399.230088 -297.91406) (xy 399.230088 -298.185078) (xy 399.231866 -298.191682) (xy 399.237059 -298.212054)
			(xy 399.242659 -298.25372) (xy 399.243042 -298.27474) (xy 399.242639 -298.297661) (xy 399.236056 -298.343027)
			(xy 399.223032 -298.38698) (xy 399.203836 -298.428609) (xy 399.178866 -298.467053) (xy 399.164048 -298.484544)
			(xy 399.163794 -298.484798) (xy 399.159301 -298.490446) (xy 399.153382 -298.503601) (xy 399.15211 -298.510706)
			(xy 399.151856 -298.510706) (xy 399.151098 -298.5179) (xy 399.153167 -298.53221) (xy 399.15592 -298.5389)
			(xy 399.19402 -298.623228) (xy 399.198425 -298.631923) (xy 399.212465 -298.645419) (xy 399.230513 -298.652737)
			(xy 399.240248 -298.6532) (xy 400.50974 -298.6532) (xy 400.519485 -298.652766) (xy 400.537559 -298.645477)
			(xy 400.551579 -298.63194) (xy 400.555968 -298.623228) (xy 400.594068 -298.5389) (xy 400.596834 -298.532215)
			(xy 400.598889 -298.517902) (xy 400.598132 -298.510706) (xy 400.597878 -298.510706) (xy 400.596612 -298.503602)
			(xy 400.590668 -298.490461) (xy 400.586194 -298.484798) (xy 400.58594 -298.484544) (xy 400.571117 -298.467055)
			(xy 400.546129 -298.428617) (xy 400.526923 -298.386989) (xy 400.513896 -298.343034) (xy 400.507319 -298.297663)
			(xy 400.506946 -298.27474) (xy 400.507315 -298.253719) (xy 400.512915 -298.212051) (xy 400.518122 -298.191682)
			(xy 400.5199 -298.185078) (xy 400.5199 -298.049696) (xy 400.519646 -297.91406) (xy 400.520139 -297.899032)
			(xy 400.527914 -297.869999) (xy 400.542925 -297.843961) (xy 400.564154 -297.822684) (xy 400.590158 -297.807614)
			(xy 400.619173 -297.799773) (xy 400.6342 -297.799252) (xy 401.015454 -297.799252) (xy 401.030501 -297.799695)
			(xy 401.05957 -297.807486) (xy 401.085625 -297.822546) (xy 401.106885 -297.843845) (xy 401.121897 -297.869929)
			(xy 401.129632 -297.899012) (xy 401.130008 -297.91406) (xy 401.130008 -298.185078) (xy 401.131786 -298.191682)
			(xy 401.136979 -298.212054) (xy 401.142578 -298.25372) (xy 401.142962 -298.27474) (xy 401.142559 -298.29766)
			(xy 401.135975 -298.343026) (xy 401.122948 -298.386976) (xy 401.103748 -298.428602) (xy 401.078773 -298.467042)
			(xy 401.063968 -298.484544) (xy 401.063714 -298.484798) (xy 401.059219 -298.490445) (xy 401.053299 -298.5036)
			(xy 401.05203 -298.510706) (xy 401.051776 -298.510706) (xy 401.051018 -298.5179) (xy 401.053084 -298.532211)
			(xy 401.05584 -298.5389) (xy 401.09394 -298.623228) (xy 401.098346 -298.631921) (xy 401.112387 -298.645411)
			(xy 401.130434 -298.652723) (xy 401.140168 -298.6532) (xy 402.40966 -298.6532) (xy 402.419403 -298.652763)
			(xy 402.437471 -298.64547) (xy 402.451484 -298.631932) (xy 402.455888 -298.623228) (xy 402.493988 -298.5389)
			(xy 402.496758 -298.532216) (xy 402.498816 -298.517901) (xy 402.498052 -298.510706) (xy 402.497798 -298.510706)
			(xy 402.496532 -298.503602) (xy 402.49059 -298.490459) (xy 402.486114 -298.484798) (xy 402.48586 -298.484544)
			(xy 402.471036 -298.467055) (xy 402.446047 -298.428618) (xy 402.42684 -298.38699) (xy 402.413812 -298.343034)
			(xy 402.407234 -298.297663) (xy 402.406866 -298.27474) (xy 402.407235 -298.253719) (xy 402.412835 -298.212051)
			(xy 402.418042 -298.191682) (xy 402.41982 -298.185078) (xy 402.41982 -298.049696) (xy 402.419566 -297.91406)
			(xy 402.420059 -297.899033) (xy 402.427834 -297.870002) (xy 402.442846 -297.843966) (xy 402.464075 -297.822693)
			(xy 402.49008 -297.807626) (xy 402.519094 -297.799791) (xy 402.53412 -297.799252) (xy 402.915374 -297.799252)
			(xy 402.93042 -297.799698) (xy 402.959484 -297.807491) (xy 402.985534 -297.822553) (xy 403.00679 -297.843852)
			(xy 403.021798 -297.869933) (xy 403.029533 -297.899014) (xy 403.029928 -297.91406) (xy 403.029928 -298.185078)
			(xy 403.031706 -298.191682) (xy 403.0369 -298.212054) (xy 403.042501 -298.25372) (xy 403.042882 -298.27474)
			(xy 403.042479 -298.29766) (xy 403.035895 -298.343026) (xy 403.022869 -298.386977) (xy 403.00367 -298.428604)
			(xy 402.978696 -298.467045) (xy 402.963888 -298.484544) (xy 402.963634 -298.484798) (xy 402.959138 -298.490444)
			(xy 402.953215 -298.503599) (xy 402.95195 -298.510706) (xy 402.951696 -298.510706) (xy 402.950938 -298.5179)
			(xy 402.953005 -298.532211) (xy 402.95576 -298.5389) (xy 402.99386 -298.623228) (xy 402.998266 -298.631919)
			(xy 403.012309 -298.645403) (xy 403.030355 -298.652709) (xy 403.040088 -298.6532) (xy 404.30958 -298.6532)
			(xy 404.319331 -298.652777) (xy 404.337423 -298.645501) (xy 404.351461 -298.631965) (xy 404.355808 -298.623228)
			(xy 404.393908 -298.5389) (xy 404.396677 -298.532216) (xy 404.398734 -298.517901) (xy 404.397972 -298.510706)
			(xy 404.397718 -298.510706) (xy 404.396453 -298.503601) (xy 404.390513 -298.490457) (xy 404.386034 -298.484798)
			(xy 404.38578 -298.484544) (xy 404.367586 -298.462887) (xy 404.338379 -298.414458) (xy 404.318195 -298.361627)
			(xy 404.307671 -298.306059) (xy 404.306786 -298.277788) (xy 404.306786 -298.274232) (xy 404.307147 -298.253148)
			(xy 404.312755 -298.211354) (xy 404.317962 -298.19092) (xy 404.31974 -298.184316) (xy 404.31974 -297.91406)
			(xy 404.320192 -297.89901) (xy 404.327993 -297.869938) (xy 404.343053 -297.843876) (xy 404.364346 -297.822599)
			(xy 404.390419 -297.807559) (xy 404.419498 -297.799781) (xy 404.434548 -297.799252) (xy 404.815548 -297.799252)
			(xy 404.830596 -297.799749) (xy 404.859664 -297.807546) (xy 404.885726 -297.822599) (xy 404.907006 -297.843881)
			(xy 404.922057 -297.869943) (xy 404.929852 -297.899012) (xy 404.930356 -297.91406) (xy 404.930356 -298.18584)
			(xy 404.931118 -298.188634) (xy 404.932134 -298.192698) (xy 404.937112 -298.212649) (xy 404.942468 -298.253418)
			(xy 404.942802 -298.273978) (xy 404.942802 -298.27474) (xy 404.942399 -298.29766) (xy 404.935815 -298.343026)
			(xy 404.92279 -298.386978) (xy 404.903592 -298.428605) (xy 404.87862 -298.467047) (xy 404.863808 -298.484544)
			(xy 404.863554 -298.484798) (xy 404.859064 -298.490447) (xy 404.85315 -298.503603) (xy 404.85187 -298.510706)
			(xy 404.851616 -298.510706) (xy 404.850858 -298.5179) (xy 404.852926 -298.53221) (xy 404.85568 -298.5389)
			(xy 404.89378 -298.623228) (xy 404.898188 -298.631916) (xy 404.912231 -298.645396) (xy 404.930277 -298.652694)
			(xy 404.940008 -298.6532) (xy 406.209754 -298.6532) (xy 406.219497 -298.652764) (xy 406.237567 -298.645472)
			(xy 406.251583 -298.631934) (xy 406.255982 -298.623228) (xy 406.294082 -298.5389) (xy 406.296852 -298.532216)
			(xy 406.29891 -298.517901) (xy 406.298146 -298.510706) (xy 406.297892 -298.510706) (xy 406.296626 -298.503602)
			(xy 406.290684 -298.49046) (xy 406.286208 -298.484798) (xy 406.285954 -298.484544) (xy 406.267872 -298.463041)
			(xy 406.238799 -298.414972) (xy 406.218618 -298.362545) (xy 406.207954 -298.307389) (xy 406.20696 -298.279312)
			(xy 406.20696 -298.274486) (xy 406.207667 -298.243309) (xy 406.219823 -298.182152) (xy 406.23109 -298.153074)
			(xy 406.2349 -298.143676) (xy 406.2349 -297.91406) (xy 406.235396 -297.899014) (xy 406.243193 -297.869949)
			(xy 406.258246 -297.843891) (xy 406.27953 -297.822617) (xy 406.305593 -297.807575) (xy 406.334662 -297.799789)
			(xy 406.349708 -297.799252) (xy 406.730708 -297.799252) (xy 406.745759 -297.799744) (xy 406.774836 -297.807535)
			(xy 406.800907 -297.822585) (xy 406.822196 -297.843867) (xy 406.837253 -297.869934) (xy 406.845052 -297.899009)
			(xy 406.845516 -297.91406) (xy 406.845516 -298.21886) (xy 406.845423 -298.224487) (xy 406.84428 -298.235683)
			(xy 406.84323 -298.241212) (xy 406.842214 -298.252896) (xy 406.842976 -298.27474) (xy 406.842573 -298.29766)
			(xy 406.835989 -298.343026) (xy 406.822962 -298.386977) (xy 406.803764 -298.428603) (xy 406.77879 -298.467044)
			(xy 406.763982 -298.484544) (xy 406.763728 -298.484798) (xy 406.759232 -298.490445) (xy 406.75331 -298.503599)
			(xy 406.752044 -298.510706) (xy 406.75179 -298.510706) (xy 406.751032 -298.5179) (xy 406.753099 -298.532211)
			(xy 406.755854 -298.5389) (xy 406.793954 -298.623228) (xy 406.79836 -298.631919) (xy 406.812403 -298.645406)
			(xy 406.830449 -298.652713) (xy 406.840182 -298.6532) (xy 409.059634 -298.6532) (xy 409.069379 -298.652767)
			(xy 409.087455 -298.64548) (xy 409.101477 -298.631943) (xy 409.105862 -298.623228) (xy 409.143962 -298.5389)
			(xy 409.146729 -298.532215) (xy 409.148784 -298.517902) (xy 409.148026 -298.510706) (xy 409.147772 -298.510706)
			(xy 409.146509 -298.5036) (xy 409.140573 -298.490452) (xy 409.136088 -298.484798) (xy 409.135834 -298.484544)
			(xy 409.121011 -298.467054) (xy 409.096024 -298.428617) (xy 409.076818 -298.386989) (xy 409.063792 -298.343033)
			(xy 409.057214 -298.297663) (xy 409.05684 -298.27474) (xy 409.05684 -298.274486) (xy 409.057168 -298.2536)
			(xy 409.062648 -298.212189) (xy 409.067762 -298.191936) (xy 409.068778 -298.187872) (xy 409.06954 -298.185078)
			(xy 409.06954 -297.91406) (xy 409.069992 -297.89901) (xy 409.077793 -297.869938) (xy 409.092853 -297.843876)
			(xy 409.114146 -297.822599) (xy 409.140219 -297.807559) (xy 409.169298 -297.799781) (xy 409.184348 -297.799252)
			(xy 409.565348 -297.799252) (xy 409.580396 -297.799749) (xy 409.609464 -297.807546) (xy 409.635526 -297.822599)
			(xy 409.656806 -297.843881) (xy 409.671857 -297.869943) (xy 409.679652 -297.899012) (xy 409.680156 -297.91406)
			(xy 409.680156 -298.185078) (xy 409.680918 -298.187872) (xy 409.681934 -298.191936) (xy 409.687021 -298.212194)
			(xy 409.692497 -298.253602) (xy 409.692856 -298.274486) (xy 409.692856 -298.27474) (xy 409.692453 -298.29766)
			(xy 409.685868 -298.343025) (xy 409.672841 -298.386976) (xy 409.653642 -298.428602) (xy 409.628666 -298.467041)
			(xy 409.613862 -298.484544) (xy 409.613608 -298.484798) (xy 409.609114 -298.490445) (xy 409.603194 -298.5036)
			(xy 409.601924 -298.510706) (xy 409.60167 -298.510706) (xy 409.600912 -298.5179) (xy 409.602978 -298.532211)
			(xy 409.605734 -298.5389) (xy 409.643834 -298.623228) (xy 409.648239 -298.631921) (xy 409.662281 -298.645413)
			(xy 409.680328 -298.652727) (xy 409.690062 -298.6532) (xy 410.959808 -298.6532) (xy 410.969556 -298.652772)
			(xy 410.98764 -298.64549) (xy 411.001669 -298.631954) (xy 411.006036 -298.623228) (xy 411.044136 -298.5389)
			(xy 411.046903 -298.532215) (xy 411.04896 -298.517901) (xy 411.0482 -298.510706) (xy 411.047946 -298.510706)
			(xy 411.046682 -298.503601) (xy 411.040744 -298.490455) (xy 411.036262 -298.484798) (xy 411.036008 -298.484544)
			(xy 411.021182 -298.467056) (xy 410.996189 -298.42862) (xy 410.976979 -298.386992) (xy 410.963949 -298.343036)
			(xy 410.95737 -298.297663) (xy 410.957014 -298.27474) (xy 410.957383 -298.253719) (xy 410.962984 -298.212051)
			(xy 410.96819 -298.191682) (xy 410.969968 -298.185078) (xy 410.969968 -298.049696) (xy 410.969714 -297.91406)
			(xy 410.970208 -297.899036) (xy 410.977983 -297.87001) (xy 410.992997 -297.84398) (xy 411.014227 -297.822714)
			(xy 411.040232 -297.807657) (xy 411.069245 -297.799833) (xy 411.084268 -297.799252) (xy 411.465522 -297.799252)
			(xy 411.480563 -297.799704) (xy 411.509617 -297.807505) (xy 411.535657 -297.82257) (xy 411.556903 -297.843868)
			(xy 411.571903 -297.869944) (xy 411.579633 -297.899017) (xy 411.580076 -297.91406) (xy 411.580076 -298.185078)
			(xy 411.581854 -298.191682) (xy 411.587048 -298.212054) (xy 411.592647 -298.25372) (xy 411.59303 -298.27474)
			(xy 411.592627 -298.297661) (xy 411.586044 -298.343027) (xy 411.573019 -298.386979) (xy 411.553823 -298.428608)
			(xy 411.528852 -298.467051) (xy 411.514036 -298.484544) (xy 411.513782 -298.484798) (xy 411.50929 -298.490446)
			(xy 411.503373 -298.503602) (xy 411.502098 -298.510706) (xy 411.501844 -298.510706) (xy 411.501086 -298.5179)
			(xy 411.503155 -298.53221) (xy 411.505908 -298.5389) (xy 411.544008 -298.623228) (xy 411.548412 -298.631924)
			(xy 411.562452 -298.645423) (xy 411.5805 -298.652747) (xy 411.590236 -298.6532) (xy 412.859728 -298.6532)
			(xy 412.869474 -298.652769) (xy 412.887552 -298.645482) (xy 412.901575 -298.631945) (xy 412.905956 -298.623228)
			(xy 412.944056 -298.5389) (xy 412.946823 -298.532215) (xy 412.948878 -298.517902) (xy 412.94812 -298.510706)
			(xy 412.947866 -298.510706) (xy 412.946602 -298.503601) (xy 412.940667 -298.490453) (xy 412.936182 -298.484798)
			(xy 412.935928 -298.484544) (xy 412.921105 -298.467054) (xy 412.896119 -298.428617) (xy 412.876913 -298.386989)
			(xy 412.863887 -298.343033) (xy 412.85731 -298.297663) (xy 412.856934 -298.27474) (xy 412.857303 -298.253719)
			(xy 412.862904 -298.212051) (xy 412.86811 -298.191682) (xy 412.869888 -298.185078) (xy 412.869888 -298.049696)
			(xy 412.869634 -297.91406) (xy 412.870128 -297.899036) (xy 412.877904 -297.870013) (xy 412.892918 -297.843985)
			(xy 412.914148 -297.822723) (xy 412.940153 -297.80767) (xy 412.969165 -297.79985) (xy 412.984188 -297.799252)
			(xy 413.365442 -297.799252) (xy 413.380482 -297.799706) (xy 413.409531 -297.807511) (xy 413.435566 -297.822577)
			(xy 413.456808 -297.843875) (xy 413.471805 -297.869949) (xy 413.479533 -297.899019) (xy 413.479996 -297.91406)
			(xy 413.479996 -298.185078) (xy 413.481774 -298.191682) (xy 413.486967 -298.212054) (xy 413.492567 -298.25372)
			(xy 413.49295 -298.27474) (xy 413.492547 -298.297661) (xy 413.485964 -298.343027) (xy 413.47294 -298.38698)
			(xy 413.453745 -298.428609) (xy 413.428775 -298.467054) (xy 413.413956 -298.484544) (xy 413.413702 -298.484798)
			(xy 413.409208 -298.490446) (xy 413.403289 -298.503601) (xy 413.402018 -298.510706) (xy 413.401764 -298.510706)
			(xy 413.401006 -298.5179) (xy 413.403072 -298.532211) (xy 413.405828 -298.5389) (xy 413.443928 -298.623228)
			(xy 413.448333 -298.631922) (xy 413.462374 -298.645416) (xy 413.480421 -298.652732) (xy 413.490156 -298.6532)
			(xy 414.242758 -298.6532) (xy 414.25241 -298.652184) (xy 414.259657 -298.650562) (xy 414.272835 -298.64373)
			(xy 414.278318 -298.638722) (xy 414.427162 -298.489878) (xy 414.432145 -298.484377) (xy 414.438982 -298.471209)
			(xy 414.440624 -298.46397) (xy 414.44164 -298.454318) (xy 414.44164 -297.900344) (xy 414.441107 -297.89008)
			(xy 414.432967 -297.871226) (xy 414.425892 -297.863768) (xy 414.367726 -297.811952) (xy 414.363636 -297.808431)
			(xy 414.354285 -297.803048) (xy 414.349184 -297.801284) (xy 414.339532 -297.798236) (xy 414.32861 -297.799506)
			(xy 414.315656 -297.800268) (xy 413.934402 -297.800268) (xy 413.919357 -297.799819) (xy 413.890296 -297.792022)
			(xy 413.864249 -297.77696) (xy 413.842995 -297.755661) (xy 413.827987 -297.729583) (xy 413.82025 -297.700505)
			(xy 413.819848 -297.68546) (xy 413.819848 -297.414442) (xy 413.81807 -297.407838) (xy 413.812875 -297.387467)
			(xy 413.807272 -297.3458) (xy 413.806894 -297.32478) (xy 413.807386 -297.299792) (xy 413.815207 -297.250431)
			(xy 413.830653 -297.202902) (xy 413.853343 -297.158374) (xy 413.88272 -297.117943) (xy 413.91806 -297.082606)
			(xy 413.958493 -297.053232) (xy 414.003022 -297.030544) (xy 414.050553 -297.015102) (xy 414.099914 -297.007284)
			(xy 414.124902 -297.006772) (xy 414.124902 -297.006518) (xy 414.153509 -297.007184) (xy 414.209797 -297.017445)
			(xy 414.263352 -297.037582) (xy 414.288224 -297.05173) (xy 414.288478 -297.05173) (xy 414.29431 -297.055034)
			(xy 414.307183 -297.058753) (xy 414.313878 -297.059096) (xy 414.327086 -297.059096) (xy 414.415732 -297.008804)
			(xy 414.421066 -297.005502) (xy 414.430091 -296.998139) (xy 414.440825 -296.977496) (xy 414.44164 -296.965878)
			(xy 414.44164 -294.835072) (xy 414.44164 -294.833802) (xy 414.440783 -294.822194) (xy 414.430067 -294.801558)
			(xy 414.421066 -294.794178) (xy 414.415732 -294.790876) (xy 414.339024 -294.747188) (xy 414.33307 -294.744113)
			(xy 414.32007 -294.740884) (xy 414.31337 -294.740838) (xy 414.299908 -294.740838) (xy 414.28797 -294.74795)
			(xy 414.263122 -294.762031) (xy 414.209647 -294.782074) (xy 414.153456 -294.792258) (xy 414.124902 -294.792908)
			(xy 414.099911 -294.792444) (xy 414.050543 -294.784625) (xy 414.003007 -294.76918) (xy 413.958472 -294.746488)
			(xy 413.918035 -294.717109) (xy 413.882692 -294.681766) (xy 413.853313 -294.64133) (xy 413.830621 -294.596795)
			(xy 413.815175 -294.549259) (xy 413.807356 -294.499891) (xy 413.806894 -294.4749) (xy 413.807266 -294.45388)
			(xy 413.812871 -294.412213) (xy 413.81807 -294.391842) (xy 413.819848 -294.385238) (xy 413.819848 -294.249856)
			(xy 413.819594 -294.11422) (xy 413.82008 -294.099189) (xy 413.827845 -294.070148) (xy 413.842854 -294.044102)
			(xy 413.864085 -294.02282) (xy 413.890096 -294.00775) (xy 413.919118 -293.999916) (xy 413.934148 -293.999412)
			(xy 414.315656 -293.999412) (xy 414.32861 -294.000174) (xy 414.339532 -294.001444) (xy 414.349184 -293.998396)
			(xy 414.354279 -293.996619) (xy 414.363635 -293.991246) (xy 414.367726 -293.987728) (xy 414.425892 -293.935912)
			(xy 414.433024 -293.928493) (xy 414.441172 -293.909615) (xy 414.44164 -293.899336) (xy 414.44164 -293.543482)
			(xy 414.441477 -293.537471) (xy 414.438662 -293.525785) (xy 414.436052 -293.520368) (xy 414.43421 -293.516896)
			(xy 414.429612 -293.510521) (xy 414.426908 -293.507668) (xy 414.22828 -293.30904) (xy 414.22091 -293.302297)
			(xy 414.202448 -293.294705) (xy 414.192466 -293.294308) (xy 413.573976 -293.294308) (xy 413.562646 -293.294913)
			(xy 413.542197 -293.304671) (xy 413.534606 -293.313104) (xy 413.484568 -293.382192) (xy 413.481207 -293.38707)
			(xy 413.476582 -293.397973) (xy 413.475424 -293.403782) (xy 413.473646 -293.415212) (xy 413.477456 -293.42715)
			(xy 413.484665 -293.450953) (xy 413.492446 -293.500074) (xy 413.49295 -293.52494) (xy 413.492576 -293.54596)
			(xy 413.486966 -293.587626) (xy 413.481774 -293.607998) (xy 413.479996 -293.614602) (xy 413.479996 -293.749984)
			(xy 413.48025 -293.88562) (xy 413.47976 -293.900649) (xy 413.471988 -293.929686) (xy 413.456978 -293.955729)
			(xy 413.435749 -293.977009) (xy 413.409742 -293.992082) (xy 413.380724 -293.999923) (xy 413.365696 -294.000428)
			(xy 412.984442 -294.000428) (xy 412.969396 -293.999984) (xy 412.94033 -293.992193) (xy 412.914278 -293.977132)
			(xy 412.893022 -293.955832) (xy 412.878016 -293.929749) (xy 412.870285 -293.900667) (xy 412.869888 -293.88562)
			(xy 412.869888 -293.614602) (xy 412.86811 -293.607998) (xy 412.86291 -293.587627) (xy 412.857299 -293.545961)
			(xy 412.856934 -293.52494) (xy 412.857435 -293.500074) (xy 412.865221 -293.450954) (xy 412.872428 -293.42715)
			(xy 412.872428 -293.426896) (xy 412.874094 -293.421146) (xy 412.874986 -293.40921) (xy 412.874206 -293.403274)
			(xy 412.872428 -293.391844) (xy 412.815278 -293.313104) (xy 412.807659 -293.304711) (xy 412.787226 -293.29496)
			(xy 412.775908 -293.294308) (xy 411.674056 -293.294308) (xy 411.662728 -293.294917) (xy 411.642285 -293.30468)
			(xy 411.634686 -293.313104) (xy 411.584648 -293.382192) (xy 411.581287 -293.38707) (xy 411.576665 -293.397973)
			(xy 411.575504 -293.403782) (xy 411.573726 -293.415212) (xy 411.577536 -293.42715) (xy 411.584744 -293.450954)
			(xy 411.592523 -293.500074) (xy 411.59303 -293.52494) (xy 411.59303 -293.525448) (xy 411.59303 -293.531036)
			(xy 411.592358 -293.550715) (xy 411.586753 -293.589689) (xy 411.581854 -293.60876) (xy 411.580076 -293.615364)
			(xy 411.580076 -293.88562) (xy 411.579626 -293.900673) (xy 411.571829 -293.929751) (xy 411.556771 -293.95582)
			(xy 411.535478 -293.977102) (xy 411.509402 -293.992149) (xy 411.480321 -293.999933) (xy 411.465268 -294.000428)
			(xy 411.084268 -294.000428) (xy 411.06922 -293.999933) (xy 411.04015 -293.992138) (xy 411.014087 -293.977086)
			(xy 410.992807 -293.955803) (xy 410.977758 -293.929739) (xy 410.969965 -293.900668) (xy 410.96946 -293.88562)
			(xy 410.96946 -293.61384) (xy 410.968698 -293.611046) (xy 410.967682 -293.606982) (xy 410.962705 -293.587031)
			(xy 410.957351 -293.546262) (xy 410.957014 -293.525702) (xy 410.957014 -293.52494) (xy 410.957515 -293.500074)
			(xy 410.965301 -293.450954) (xy 410.972508 -293.42715) (xy 410.972508 -293.426896) (xy 410.974175 -293.421146)
			(xy 410.975067 -293.40921) (xy 410.974286 -293.403274) (xy 410.972508 -293.391844) (xy 410.915358 -293.313104)
			(xy 410.907737 -293.304714) (xy 410.887304 -293.294972) (xy 410.875988 -293.294308) (xy 409.773882 -293.294308)
			(xy 409.762551 -293.294911) (xy 409.7421 -293.304669) (xy 409.734512 -293.313104) (xy 409.684474 -293.382192)
			(xy 409.681112 -293.38707) (xy 409.676488 -293.397973) (xy 409.67533 -293.403782) (xy 409.673552 -293.415212)
			(xy 409.677362 -293.42715) (xy 409.684571 -293.450953) (xy 409.692352 -293.500074) (xy 409.692856 -293.52494)
			(xy 409.692856 -293.525194) (xy 409.692529 -293.54608) (xy 409.687052 -293.587492) (xy 409.681934 -293.607744)
			(xy 409.680918 -293.611808) (xy 409.680156 -293.614602) (xy 409.680156 -293.88562) (xy 409.679663 -293.900671)
			(xy 409.67187 -293.929746) (xy 409.65682 -293.955815) (xy 409.635537 -293.977102) (xy 409.609472 -293.992159)
			(xy 409.580399 -293.999959) (xy 409.565348 -294.000428) (xy 409.184348 -294.000428) (xy 409.169287 -293.999987)
			(xy 409.140189 -293.992202) (xy 409.114097 -293.97715) (xy 409.092792 -293.955857) (xy 409.077724 -293.929774)
			(xy 409.069922 -293.900681) (xy 409.06954 -293.88562) (xy 409.06954 -293.614602) (xy 409.068778 -293.611808)
			(xy 409.067762 -293.607744) (xy 409.062677 -293.587486) (xy 409.057203 -293.546078) (xy 409.05684 -293.525194)
			(xy 409.05684 -293.52494) (xy 409.057341 -293.500074) (xy 409.065127 -293.450954) (xy 409.072334 -293.42715)
			(xy 409.072334 -293.426896) (xy 409.074 -293.421146) (xy 409.074892 -293.40921) (xy 409.074112 -293.403274)
			(xy 409.072334 -293.391844) (xy 409.015184 -293.313104) (xy 409.007565 -293.30471) (xy 408.987132 -293.294957)
			(xy 408.975814 -293.294308) (xy 406.924002 -293.294308) (xy 406.912669 -293.294907) (xy 406.892212 -293.30466)
			(xy 406.884632 -293.313104) (xy 406.834594 -293.382192) (xy 406.831237 -293.387071) (xy 406.826619 -293.397975)
			(xy 406.82545 -293.403782) (xy 406.823672 -293.415212) (xy 406.827482 -293.42715) (xy 406.834691 -293.450953)
			(xy 406.842471 -293.500074) (xy 406.842976 -293.52494) (xy 406.842976 -293.525194) (xy 406.842649 -293.54608)
			(xy 406.837173 -293.587492) (xy 406.832054 -293.607744) (xy 406.831038 -293.611808) (xy 406.830276 -293.614602)
			(xy 406.830276 -293.88562) (xy 406.829826 -293.900673) (xy 406.822029 -293.929751) (xy 406.806971 -293.95582)
			(xy 406.785678 -293.977102) (xy 406.759602 -293.992149) (xy 406.730521 -293.999933) (xy 406.715468 -294.000428)
			(xy 406.334468 -294.000428) (xy 406.31942 -293.999933) (xy 406.29035 -293.992138) (xy 406.264287 -293.977086)
			(xy 406.243007 -293.955803) (xy 406.227958 -293.929739) (xy 406.220165 -293.900668) (xy 406.21966 -293.88562)
			(xy 406.21966 -293.614602) (xy 406.218898 -293.611808) (xy 406.217882 -293.607744) (xy 406.212796 -293.587486)
			(xy 406.207322 -293.546078) (xy 406.20696 -293.525194) (xy 406.20696 -293.52494) (xy 406.207462 -293.500074)
			(xy 406.215248 -293.450954) (xy 406.222454 -293.42715) (xy 406.222454 -293.426896) (xy 406.22412 -293.421146)
			(xy 406.225012 -293.40921) (xy 406.224232 -293.403274) (xy 406.222454 -293.391844) (xy 406.165304 -293.313104)
			(xy 406.157686 -293.304706) (xy 406.137253 -293.294946) (xy 406.125934 -293.294308) (xy 405.023828 -293.294308)
			(xy 405.012503 -293.294922) (xy 404.992069 -293.304693) (xy 404.984458 -293.313104) (xy 404.93442 -293.382192)
			(xy 404.931061 -293.387071) (xy 404.926441 -293.397974) (xy 404.925276 -293.403782) (xy 404.923498 -293.415212)
			(xy 404.927308 -293.42715) (xy 404.934516 -293.450954) (xy 404.942296 -293.500074) (xy 404.942802 -293.52494)
			(xy 404.942802 -293.525702) (xy 404.942445 -293.54626) (xy 404.937097 -293.587029) (xy 404.932134 -293.606982)
			(xy 404.931118 -293.611046) (xy 404.930356 -293.61384) (xy 404.930356 -293.88562) (xy 404.929863 -293.900671)
			(xy 404.92207 -293.929746) (xy 404.90702 -293.955815) (xy 404.885737 -293.977102) (xy 404.859672 -293.992159)
			(xy 404.830599 -293.999959) (xy 404.815548 -294.000428) (xy 404.434548 -294.000428) (xy 404.419487 -293.999987)
			(xy 404.390389 -293.992202) (xy 404.364297 -293.97715) (xy 404.342992 -293.955857) (xy 404.327924 -293.929774)
			(xy 404.320122 -293.900681) (xy 404.31974 -293.88562) (xy 404.31974 -293.615364) (xy 404.317962 -293.60876)
			(xy 404.312906 -293.588943) (xy 404.307297 -293.548433) (xy 404.306786 -293.527988) (xy 404.306786 -293.521892)
			(xy 404.307479 -293.497792) (xy 404.315255 -293.450213) (xy 404.32228 -293.42715) (xy 404.32228 -293.426896)
			(xy 404.323947 -293.421146) (xy 404.324841 -293.40921) (xy 404.324058 -293.403274) (xy 404.32228 -293.391844)
			(xy 404.26513 -293.313104) (xy 404.257508 -293.304718) (xy 404.237074 -293.294987) (xy 404.22576 -293.294308)
			(xy 403.123908 -293.294308) (xy 403.112575 -293.294906) (xy 403.092115 -293.304657) (xy 403.084538 -293.313104)
			(xy 403.0345 -293.382192) (xy 403.031142 -293.387071) (xy 403.026524 -293.397975) (xy 403.025356 -293.403782)
			(xy 403.023578 -293.415212) (xy 403.027388 -293.42715) (xy 403.034597 -293.450953) (xy 403.042377 -293.500074)
			(xy 403.042882 -293.52494) (xy 403.042508 -293.54596) (xy 403.036897 -293.587625) (xy 403.031706 -293.607998)
			(xy 403.029928 -293.614602) (xy 403.029928 -293.749984) (xy 403.030182 -293.88562) (xy 403.029691 -293.900646)
			(xy 403.021918 -293.929676) (xy 403.006906 -293.95571) (xy 402.985675 -293.976979) (xy 402.959669 -293.992038)
			(xy 402.930653 -293.999863) (xy 402.915628 -294.000428) (xy 402.534374 -294.000428) (xy 402.519334 -293.999976)
			(xy 402.490283 -293.992173) (xy 402.464247 -293.977108) (xy 402.443005 -293.955809) (xy 402.428009 -293.929733)
			(xy 402.420284 -293.900661) (xy 402.41982 -293.88562) (xy 402.41982 -293.614602) (xy 402.418042 -293.607998)
			(xy 402.412843 -293.587627) (xy 402.407233 -293.545961) (xy 402.406866 -293.52494) (xy 402.407368 -293.500074)
			(xy 402.415154 -293.450954) (xy 402.42236 -293.42715) (xy 402.42236 -293.426896) (xy 402.424026 -293.421146)
			(xy 402.424917 -293.40921) (xy 402.424138 -293.403274) (xy 402.42236 -293.391844) (xy 402.36521 -293.313104)
			(xy 402.357593 -293.304706) (xy 402.33716 -293.294943) (xy 402.32584 -293.294308) (xy 401.223988 -293.294308)
			(xy 401.212657 -293.29491) (xy 401.192204 -293.304666) (xy 401.184618 -293.313104) (xy 401.13458 -293.382192)
			(xy 401.131218 -293.38707) (xy 401.126593 -293.397972) (xy 401.125436 -293.403782) (xy 401.123658 -293.415212)
			(xy 401.127468 -293.42715) (xy 401.134677 -293.450954) (xy 401.142458 -293.500074) (xy 401.142962 -293.52494)
			(xy 401.142588 -293.54596) (xy 401.136978 -293.587626) (xy 401.131786 -293.607998) (xy 401.130008 -293.614602)
			(xy 401.130008 -293.749984) (xy 401.130262 -293.88562) (xy 401.129771 -293.900645) (xy 401.121998 -293.929673)
			(xy 401.106985 -293.955704) (xy 401.085754 -293.97697) (xy 401.059747 -293.992025) (xy 401.030732 -293.999846)
			(xy 401.015708 -294.000428) (xy 400.634454 -294.000428) (xy 400.619416 -293.999973) (xy 400.590369 -293.992167)
			(xy 400.564338 -293.977101) (xy 400.5431 -293.955803) (xy 400.528107 -293.929728) (xy 400.520384 -293.90066)
			(xy 400.5199 -293.88562) (xy 400.5199 -293.614602) (xy 400.518122 -293.607998) (xy 400.512924 -293.587627)
			(xy 400.507314 -293.545961) (xy 400.506946 -293.52494) (xy 400.507448 -293.500074) (xy 400.515233 -293.450954)
			(xy 400.52244 -293.42715) (xy 400.52244 -293.426896) (xy 400.524106 -293.421146) (xy 400.524998 -293.40921)
			(xy 400.524218 -293.403274) (xy 400.52244 -293.391844) (xy 400.46529 -293.313104) (xy 400.457672 -293.304709)
			(xy 400.437238 -293.294954) (xy 400.42592 -293.294308) (xy 399.324068 -293.294308) (xy 399.312739 -293.294914)
			(xy 399.292292 -293.304675) (xy 399.284698 -293.313104) (xy 399.23466 -293.382192) (xy 399.231299 -293.38707)
			(xy 399.226675 -293.397973) (xy 399.225516 -293.403782) (xy 399.223738 -293.415212) (xy 399.227548 -293.42715)
			(xy 399.234755 -293.450954) (xy 399.242534 -293.500074) (xy 399.243042 -293.52494) (xy 399.242668 -293.54596)
			(xy 399.237058 -293.587626) (xy 399.231866 -293.607998) (xy 399.230088 -293.614602) (xy 399.230088 -293.749984)
			(xy 399.230342 -293.88562) (xy 399.229852 -293.900649) (xy 399.22208 -293.929685) (xy 399.20707 -293.955727)
			(xy 399.18584 -293.977006) (xy 399.159833 -293.992077) (xy 399.130816 -293.999916) (xy 399.115788 -294.000428)
			(xy 398.734534 -294.000428) (xy 398.719489 -293.999983) (xy 398.690425 -293.99219) (xy 398.664375 -293.977129)
			(xy 398.64312 -293.955829) (xy 398.628115 -293.929747) (xy 398.620385 -293.900666) (xy 398.61998 -293.88562)
			(xy 398.61998 -293.614602) (xy 398.618202 -293.607998) (xy 398.613002 -293.587627) (xy 398.607391 -293.545961)
			(xy 398.607026 -293.52494) (xy 398.607026 -293.524432) (xy 398.607462 -293.501816) (xy 398.613942 -293.45705)
			(xy 398.626691 -293.413652) (xy 398.645452 -293.372493) (xy 398.657318 -293.353236) (xy 398.661128 -293.346632)
			(xy 398.659096 -293.32936) (xy 398.657646 -293.321015) (xy 398.650123 -293.305853) (xy 398.644364 -293.299642)
			(xy 398.200118 -292.855396) (xy 398.193946 -292.849585) (xy 398.178761 -292.842071) (xy 398.1704 -292.840664)
			(xy 398.153128 -292.838632) (xy 398.146524 -292.842442) (xy 398.127273 -292.854323) (xy 398.08612 -292.873107)
			(xy 398.042719 -292.885862) (xy 397.997946 -292.892328) (xy 397.975328 -292.892734) (xy 397.97482 -292.892734)
			(xy 397.953799 -292.892364) (xy 397.912132 -292.886761) (xy 397.891762 -292.881558) (xy 397.885158 -292.87978)
			(xy 397.608806 -292.87978) (xy 397.594267 -292.878668) (xy 397.56642 -292.870047) (xy 397.541622 -292.854723)
			(xy 397.521455 -292.833674) (xy 397.507206 -292.808244) (xy 397.499783 -292.780054) (xy 397.499332 -292.76548)
			(xy 397.499332 -292.384226) (xy 397.499816 -292.369227) (xy 397.507563 -292.340248) (xy 397.522537 -292.314256)
			(xy 397.543721 -292.293017) (xy 397.569675 -292.277976) (xy 397.598635 -292.270155) (xy 397.613632 -292.269672)
			(xy 397.885158 -292.269672) (xy 397.891762 -292.267894) (xy 397.912133 -292.262698) (xy 397.9538 -292.257095)
			(xy 397.97482 -292.256718) (xy 397.975328 -292.256718) (xy 398.002412 -292.257265) (xy 398.055792 -292.266466)
			(xy 398.0815 -292.275006) (xy 398.088104 -292.277292) (xy 398.100296 -292.275514) (xy 398.106303 -292.274423)
			(xy 398.117602 -292.269807) (xy 398.122648 -292.26637) (xy 398.154906 -292.243256) (xy 398.164281 -292.235641)
			(xy 398.175266 -292.214167) (xy 398.175988 -292.202108) (xy 398.175988 -291.047424) (xy 398.175313 -291.035357)
			(xy 398.164298 -291.013885) (xy 398.154906 -291.006276) (xy 398.122648 -290.983162) (xy 398.117617 -290.979695)
			(xy 398.106314 -290.975067) (xy 398.100296 -290.974018) (xy 398.088104 -290.97224) (xy 398.0815 -290.974526)
			(xy 398.05578 -290.983019) (xy 398.002407 -290.992211) (xy 397.975328 -290.992814) (xy 397.97482 -290.992814)
			(xy 397.953799 -290.992444) (xy 397.912132 -290.986841) (xy 397.891762 -290.981638) (xy 397.885158 -290.97986)
			(xy 397.608806 -290.97986) (xy 397.594268 -290.978748) (xy 397.566423 -290.970126) (xy 397.541628 -290.954802)
			(xy 397.521464 -290.933752) (xy 397.507219 -290.908322) (xy 397.499801 -290.880133) (xy 397.499332 -290.86556)
			(xy 397.499332 -290.484306) (xy 397.499818 -290.469309) (xy 397.507569 -290.440334) (xy 397.522544 -290.414346)
			(xy 397.543728 -290.393112) (xy 397.56968 -290.378074) (xy 397.598636 -290.370254) (xy 397.613632 -290.369752)
			(xy 397.885158 -290.369752) (xy 397.891762 -290.367974) (xy 397.912133 -290.362779) (xy 397.9538 -290.357176)
			(xy 397.97482 -290.356798) (xy 398.002691 -290.357379) (xy 398.05758 -290.367099) (xy 398.109933 -290.386239)
			(xy 398.134332 -290.399724) (xy 398.140174 -290.403026) (xy 398.153128 -290.406582) (xy 398.159732 -290.406582)
			(xy 398.169734 -290.406088) (xy 398.188212 -290.398422) (xy 398.20235 -290.38427) (xy 398.209998 -290.365785)
			(xy 398.210532 -290.355782) (xy 398.210532 -290.31819) (xy 398.21104 -290.317936) (xy 398.21104 -290.241482)
			(xy 398.210877 -290.235471) (xy 398.208062 -290.223785) (xy 398.205452 -290.218368) (xy 398.20361 -290.214896)
			(xy 398.199012 -290.208521) (xy 398.196308 -290.205668) (xy 398.047972 -290.057332) (xy 398.044357 -290.053895)
			(xy 398.036042 -290.048386) (xy 398.031462 -290.04641) (xy 398.022318 -290.0426) (xy 398.017238 -290.0426)
			(xy 398.007586 -290.043616) (xy 397.97482 -290.04514) (xy 397.974566 -290.04514) (xy 397.965017 -290.045071)
			(xy 397.945955 -290.043925) (xy 397.936466 -290.042854) (xy 397.933418 -290.0426) (xy 397.066262 -290.0426)
			(xy 397.063214 -290.042854) (xy 397.053662 -290.043926) (xy 397.034472 -290.045071) (xy 397.02486 -290.04514)
			(xy 397.015248 -290.045079) (xy 396.996058 -290.043934) (xy 396.986506 -290.042854) (xy 396.983458 -290.0426)
			(xy 396.504922 -290.0426) (xy 396.498913 -290.042771) (xy 396.487234 -290.0456) (xy 396.481808 -290.048188)
			(xy 396.478333 -290.050026) (xy 396.47195 -290.054616) (xy 396.469108 -290.057332) (xy 396.422372 -290.104068)
			(xy 396.419663 -290.106917) (xy 396.415064 -290.113292) (xy 396.413228 -290.116768) (xy 396.410646 -290.122195)
			(xy 396.407827 -290.133875) (xy 396.40764 -290.139882) (xy 396.40764 -291.64979) (xy 396.707348 -291.64979)
			(xy 396.707348 -291.59981) (xy 396.715166 -291.550446) (xy 396.73061 -291.502912) (xy 396.753298 -291.458379)
			(xy 396.782674 -291.417943) (xy 396.818012 -291.3826) (xy 396.858445 -291.353219) (xy 396.902975 -291.330525)
			(xy 396.950507 -291.315076) (xy 396.99987 -291.307251) (xy 397.02486 -291.306758) (xy 397.04588 -291.307141)
			(xy 397.087546 -291.312741) (xy 397.107918 -291.317934) (xy 397.114522 -291.319712) (xy 397.38554 -291.319712)
			(xy 397.400572 -291.320145) (xy 397.429614 -291.327925) (xy 397.455658 -291.342946) (xy 397.476935 -291.364188)
			(xy 397.492 -291.390206) (xy 397.499829 -291.419234) (xy 397.500348 -291.434266) (xy 397.500348 -291.815266)
			(xy 397.499837 -291.830261) (xy 397.492093 -291.859233) (xy 397.477122 -291.885218) (xy 397.455943 -291.90645)
			(xy 397.429994 -291.921484) (xy 397.401042 -291.9293) (xy 397.386048 -291.92982) (xy 397.114522 -291.92982)
			(xy 397.107918 -291.931598) (xy 397.087549 -291.936804) (xy 397.045881 -291.942405) (xy 397.02486 -291.942774)
			(xy 396.99987 -291.942349) (xy 396.950507 -291.934524) (xy 396.902975 -291.919075) (xy 396.858444 -291.896381)
			(xy 396.818012 -291.867) (xy 396.782674 -291.831657) (xy 396.753298 -291.791221) (xy 396.73061 -291.746688)
			(xy 396.715166 -291.699154) (xy 396.707348 -291.64979) (xy 396.40764 -291.64979) (xy 396.40764 -293.52494)
			(xy 396.706852 -293.52494) (xy 396.707342 -293.499951) (xy 396.715161 -293.450588) (xy 396.730605 -293.403056)
			(xy 396.753295 -293.358524) (xy 396.782671 -293.318091) (xy 396.818011 -293.282751) (xy 396.858444 -293.253375)
			(xy 396.902976 -293.230685) (xy 396.950508 -293.215241) (xy 396.999871 -293.207422) (xy 397.049849 -293.207422)
			(xy 397.099212 -293.215241) (xy 397.146744 -293.230685) (xy 397.191276 -293.253375) (xy 397.231709 -293.282751)
			(xy 397.267049 -293.318091) (xy 397.296425 -293.358524) (xy 397.319115 -293.403056) (xy 397.334559 -293.450588)
			(xy 397.342378 -293.499951) (xy 397.342868 -293.52494) (xy 397.342503 -293.545961) (xy 397.336892 -293.587627)
			(xy 397.331692 -293.607998) (xy 397.330168 -293.614602) (xy 397.330168 -293.88562) (xy 397.329778 -293.90068)
			(xy 397.321977 -293.929773) (xy 397.30691 -293.955854) (xy 397.285606 -293.977147) (xy 397.259517 -293.9922)
			(xy 397.23042 -293.999986) (xy 397.21536 -294.000428) (xy 396.83436 -294.000428) (xy 396.81931 -293.999952)
			(xy 396.790237 -293.992154) (xy 396.764171 -293.977099) (xy 396.742889 -293.955813) (xy 396.727838 -293.929745)
			(xy 396.720045 -293.90067) (xy 396.719552 -293.88562) (xy 396.719552 -293.614602) (xy 396.718028 -293.607998)
			(xy 396.712836 -293.587626) (xy 396.707226 -293.54596) (xy 396.706852 -293.52494) (xy 396.40764 -293.52494)
			(xy 396.40764 -294.4749) (xy 397.656812 -294.4749) (xy 397.657186 -294.45388) (xy 397.662791 -294.412213)
			(xy 397.667988 -294.391842) (xy 397.669512 -294.385238) (xy 397.669512 -294.11422) (xy 397.669957 -294.099163)
			(xy 397.677747 -294.070075) (xy 397.692803 -294.043996) (xy 397.714096 -294.022703) (xy 397.740175 -294.007647)
			(xy 397.769263 -293.999857) (xy 397.78432 -293.999412) (xy 398.16532 -293.999412) (xy 398.180373 -293.999866)
			(xy 398.209451 -294.007663) (xy 398.23552 -294.02272) (xy 398.256805 -294.044011) (xy 398.271853 -294.070086)
			(xy 398.27964 -294.099167) (xy 398.280128 -294.11422) (xy 398.280128 -294.385238) (xy 398.281652 -294.391842)
			(xy 398.286851 -294.412213) (xy 398.292456 -294.45388) (xy 398.292828 -294.4749) (xy 399.556986 -294.4749)
			(xy 399.55736 -294.45388) (xy 399.562966 -294.412213) (xy 399.568162 -294.391842) (xy 399.56994 -294.385238)
			(xy 399.56994 -294.11422) (xy 399.570398 -294.099188) (xy 399.578166 -294.070145) (xy 399.59318 -294.044097)
			(xy 399.614417 -294.022818) (xy 399.640435 -294.007753) (xy 399.669463 -293.999928) (xy 399.684494 -293.999412)
			(xy 400.065494 -293.999412) (xy 400.080535 -293.9999) (xy 400.109589 -294.007693) (xy 400.135631 -294.02275)
			(xy 400.156881 -294.04404) (xy 400.171889 -294.07011) (xy 400.179628 -294.099179) (xy 400.180048 -294.11422)
			(xy 400.180048 -294.385238) (xy 400.181826 -294.391842) (xy 400.187025 -294.412213) (xy 400.19263 -294.45388)
			(xy 400.193002 -294.4749) (xy 400.192512 -294.499889) (xy 400.184693 -294.549252) (xy 400.169249 -294.596784)
			(xy 400.146559 -294.641316) (xy 400.117183 -294.681749) (xy 400.081843 -294.717089) (xy 400.04141 -294.746465)
			(xy 399.996878 -294.769155) (xy 399.949346 -294.784599) (xy 399.899983 -294.792418) (xy 399.850005 -294.792418)
			(xy 399.800642 -294.784599) (xy 399.75311 -294.769155) (xy 399.708578 -294.746465) (xy 399.668145 -294.717089)
			(xy 399.632805 -294.681749) (xy 399.603429 -294.641316) (xy 399.580739 -294.596784) (xy 399.565295 -294.549252)
			(xy 399.557476 -294.499889) (xy 399.556986 -294.4749) (xy 398.292828 -294.4749) (xy 398.292338 -294.499889)
			(xy 398.284519 -294.549252) (xy 398.269075 -294.596784) (xy 398.246385 -294.641316) (xy 398.217009 -294.681749)
			(xy 398.181669 -294.717089) (xy 398.141236 -294.746465) (xy 398.096704 -294.769155) (xy 398.049172 -294.784599)
			(xy 397.999809 -294.792418) (xy 397.949831 -294.792418) (xy 397.900468 -294.784599) (xy 397.852936 -294.769155)
			(xy 397.808404 -294.746465) (xy 397.767971 -294.717089) (xy 397.732631 -294.681749) (xy 397.703255 -294.641316)
			(xy 397.680565 -294.596784) (xy 397.665121 -294.549252) (xy 397.657302 -294.499889) (xy 397.656812 -294.4749)
			(xy 396.40764 -294.4749) (xy 396.40764 -295.577514) (xy 400.6723 -295.577514) (xy 400.6723 -294.866314)
			(xy 400.672845 -294.851323) (xy 400.680589 -294.822358) (xy 400.695556 -294.796378) (xy 400.716728 -294.775148)
			(xy 400.742666 -294.76011) (xy 400.77161 -294.752286) (xy 400.7866 -294.75176) (xy 401.264882 -294.75176)
			(xy 401.274952 -294.751335) (xy 401.29355 -294.743615) (xy 401.30095 -294.736774) (xy 401.459192 -294.578532)
			(xy 401.466558 -294.55364) (xy 401.463764 -294.541194) (xy 401.460539 -294.524811) (xy 401.457101 -294.491596)
			(xy 401.456906 -294.4749) (xy 401.45728 -294.45388) (xy 401.462885 -294.412213) (xy 401.468082 -294.391842)
			(xy 401.46986 -294.385238) (xy 401.46986 -294.11422) (xy 401.470397 -294.099194) (xy 401.478158 -294.070163)
			(xy 401.493159 -294.044124) (xy 401.51438 -294.022846) (xy 401.540379 -294.007776) (xy 401.56939 -293.999937)
			(xy 401.584414 -293.999412) (xy 401.965414 -293.999412) (xy 401.980455 -293.999882) (xy 402.00951 -294.00768)
			(xy 402.035552 -294.022741) (xy 402.056802 -294.044034) (xy 402.071809 -294.070107) (xy 402.079548 -294.099178)
			(xy 402.079968 -294.11422) (xy 402.079968 -294.385238) (xy 402.081746 -294.391842) (xy 402.086945 -294.412213)
			(xy 402.09255 -294.45388) (xy 402.092922 -294.4749) (xy 403.356826 -294.4749) (xy 403.357199 -294.45388)
			(xy 403.362805 -294.412213) (xy 403.368002 -294.391842) (xy 403.36978 -294.385238) (xy 403.36978 -294.11422)
			(xy 403.370297 -294.099193) (xy 403.37806 -294.070158) (xy 403.393064 -294.044117) (xy 403.414289 -294.022839)
			(xy 403.440293 -294.00777) (xy 403.469308 -293.999935) (xy 403.484334 -293.999412) (xy 403.865334 -293.999412)
			(xy 403.880376 -293.999865) (xy 403.909432 -294.007668) (xy 403.935474 -294.022732) (xy 403.956723 -294.044029)
			(xy 403.97173 -294.070104) (xy 403.979468 -294.099177) (xy 403.979888 -294.11422) (xy 403.979888 -294.385238)
			(xy 403.981666 -294.391842) (xy 403.986866 -294.412213) (xy 403.99247 -294.453879) (xy 403.992842 -294.4749)
			(xy 403.992352 -294.499889) (xy 403.984533 -294.549252) (xy 403.969089 -294.596784) (xy 403.946399 -294.641316)
			(xy 403.917023 -294.681749) (xy 403.881683 -294.717089) (xy 403.84125 -294.746465) (xy 403.796718 -294.769155)
			(xy 403.749186 -294.784599) (xy 403.699823 -294.792418) (xy 403.649845 -294.792418) (xy 403.600482 -294.784599)
			(xy 403.55295 -294.769155) (xy 403.508418 -294.746465) (xy 403.467985 -294.717089) (xy 403.432645 -294.681749)
			(xy 403.403269 -294.641316) (xy 403.380579 -294.596784) (xy 403.365135 -294.549252) (xy 403.357316 -294.499889)
			(xy 403.356826 -294.4749) (xy 402.092922 -294.4749) (xy 402.092273 -294.503317) (xy 402.08214 -294.55924)
			(xy 402.062216 -294.612468) (xy 402.048218 -294.637206) (xy 402.04537 -294.642383) (xy 402.0419 -294.653674)
			(xy 402.04136 -294.659558) (xy 402.03915 -294.683325) (xy 402.027371 -294.729576) (xy 402.007571 -294.773002)
			(xy 401.980379 -294.812226) (xy 401.96389 -294.829484) (xy 401.729702 -295.063672) (xy 401.722882 -295.071088)
			(xy 401.715151 -295.089675) (xy 401.714716 -295.09974) (xy 401.714716 -295.577514) (xy 404.472648 -295.577514)
			(xy 404.472648 -294.866314) (xy 404.473104 -294.851292) (xy 404.480877 -294.822271) (xy 404.495898 -294.79625)
			(xy 404.517141 -294.775005) (xy 404.54316 -294.759982) (xy 404.57218 -294.752206) (xy 404.587202 -294.75176)
			(xy 405.064976 -294.75176) (xy 405.075045 -294.751332) (xy 405.093644 -294.743614) (xy 405.101044 -294.736774)
			(xy 405.259286 -294.578532) (xy 405.266652 -294.55364) (xy 405.263858 -294.541194) (xy 405.260635 -294.524811)
			(xy 405.257196 -294.491596) (xy 405.257 -294.4749) (xy 405.257374 -294.45388) (xy 405.262979 -294.412213)
			(xy 405.268176 -294.391842) (xy 405.2697 -294.385238) (xy 405.2697 -294.11422) (xy 405.270157 -294.099164)
			(xy 405.277946 -294.070078) (xy 405.292999 -294.044) (xy 405.31429 -294.022707) (xy 405.340367 -294.007651)
			(xy 405.369452 -293.999858) (xy 405.384508 -293.999412) (xy 405.765508 -293.999412) (xy 405.780566 -293.999833)
			(xy 405.809655 -294.00763) (xy 405.835734 -294.02269) (xy 405.857027 -294.043988) (xy 405.872081 -294.070071)
			(xy 405.879871 -294.099162) (xy 405.880316 -294.11422) (xy 405.880316 -294.385238) (xy 405.88184 -294.391842)
			(xy 405.887039 -294.412213) (xy 405.892644 -294.45388) (xy 405.893016 -294.4749) (xy 408.10688 -294.4749)
			(xy 408.107255 -294.45388) (xy 408.11286 -294.412213) (xy 408.118056 -294.391842) (xy 408.11958 -294.385238)
			(xy 408.11958 -294.11422) (xy 408.120057 -294.099166) (xy 408.127844 -294.070083) (xy 408.142894 -294.044006)
			(xy 408.164181 -294.022714) (xy 408.190253 -294.007657) (xy 408.219334 -293.999861) (xy 408.234388 -293.999412)
			(xy 408.615388 -293.999412) (xy 408.630445 -293.99985) (xy 408.659533 -294.007642) (xy 408.685613 -294.022699)
			(xy 408.706906 -294.043994) (xy 408.721961 -294.070074) (xy 408.729751 -294.099163) (xy 408.730196 -294.11422)
			(xy 408.730196 -294.385238) (xy 408.73172 -294.391842) (xy 408.736919 -294.412213) (xy 408.742524 -294.45388)
			(xy 408.742896 -294.4749) (xy 408.742406 -294.499889) (xy 408.734587 -294.549252) (xy 408.719143 -294.596784)
			(xy 408.696453 -294.641316) (xy 408.667077 -294.681749) (xy 408.631737 -294.717089) (xy 408.591304 -294.746465)
			(xy 408.546772 -294.769155) (xy 408.49924 -294.784599) (xy 408.449877 -294.792418) (xy 408.399899 -294.792418)
			(xy 408.350536 -294.784599) (xy 408.303004 -294.769155) (xy 408.258472 -294.746465) (xy 408.218039 -294.717089)
			(xy 408.182699 -294.681749) (xy 408.153323 -294.641316) (xy 408.130633 -294.596784) (xy 408.115189 -294.549252)
			(xy 408.10737 -294.499889) (xy 408.10688 -294.4749) (xy 405.893016 -294.4749) (xy 405.892354 -294.503316)
			(xy 405.882225 -294.559239) (xy 405.862306 -294.612466) (xy 405.848312 -294.637206) (xy 405.845463 -294.642383)
			(xy 405.841993 -294.653674) (xy 405.841454 -294.659558) (xy 405.839246 -294.683325) (xy 405.827466 -294.729576)
			(xy 405.807666 -294.773002) (xy 405.780474 -294.812226) (xy 405.763984 -294.829484) (xy 405.529542 -295.063672)
			(xy 405.522728 -295.071093) (xy 405.514992 -295.089676) (xy 405.514556 -295.09974) (xy 405.514556 -295.577514)
			(xy 409.222448 -295.577514) (xy 409.222448 -294.866314) (xy 409.222945 -294.851319) (xy 409.230694 -294.822346)
			(xy 409.245668 -294.796362) (xy 409.26685 -294.775131) (xy 409.2928 -294.760096) (xy 409.321754 -294.752281)
			(xy 409.336748 -294.75176) (xy 409.81503 -294.75176) (xy 409.825102 -294.751361) (xy 409.843701 -294.743623)
			(xy 409.851098 -294.736774) (xy 410.000196 -294.587676) (xy 410.008663 -294.578245) (xy 410.015854 -294.553974)
			(xy 410.013912 -294.541448) (xy 410.013912 -294.54094) (xy 410.010615 -294.524628) (xy 410.00705 -294.49154)
			(xy 410.0068 -294.4749) (xy 410.007174 -294.45388) (xy 410.012779 -294.412213) (xy 410.017976 -294.391842)
			(xy 410.0195 -294.385238) (xy 410.0195 -294.11422) (xy 410.019957 -294.099164) (xy 410.027746 -294.070078)
			(xy 410.042799 -294.044) (xy 410.06409 -294.022707) (xy 410.090167 -294.007651) (xy 410.119252 -293.999858)
			(xy 410.134308 -293.999412) (xy 410.515308 -293.999412) (xy 410.530366 -293.999833) (xy 410.559455 -294.00763)
			(xy 410.585534 -294.02269) (xy 410.606827 -294.043988) (xy 410.621881 -294.070071) (xy 410.629671 -294.099162)
			(xy 410.630116 -294.11422) (xy 410.630116 -294.385238) (xy 410.63164 -294.391842) (xy 410.636839 -294.412213)
			(xy 410.642444 -294.45388) (xy 410.642816 -294.4749) (xy 411.906974 -294.4749) (xy 411.907349 -294.45388)
			(xy 411.912954 -294.412213) (xy 411.91815 -294.391842) (xy 411.919928 -294.385238) (xy 411.919928 -294.11422)
			(xy 411.920398 -294.099189) (xy 411.928165 -294.070147) (xy 411.943177 -294.044101) (xy 411.964412 -294.022822)
			(xy 411.990427 -294.007757) (xy 412.019452 -293.999929) (xy 412.034482 -293.999412) (xy 412.415482 -293.999412)
			(xy 412.430522 -293.99991) (xy 412.459576 -294.007701) (xy 412.485618 -294.022755) (xy 412.506869 -294.044043)
			(xy 412.521877 -294.070112) (xy 412.529616 -294.099179) (xy 412.530036 -294.11422) (xy 412.530036 -294.385238)
			(xy 412.531814 -294.391842) (xy 412.537013 -294.412213) (xy 412.542618 -294.45388) (xy 412.54299 -294.4749)
			(xy 412.5425 -294.499889) (xy 412.534681 -294.549252) (xy 412.519237 -294.596784) (xy 412.496547 -294.641316)
			(xy 412.467171 -294.681749) (xy 412.431831 -294.717089) (xy 412.391398 -294.746465) (xy 412.346866 -294.769155)
			(xy 412.299334 -294.784599) (xy 412.249971 -294.792418) (xy 412.199993 -294.792418) (xy 412.15063 -294.784599)
			(xy 412.103098 -294.769155) (xy 412.058566 -294.746465) (xy 412.018133 -294.717089) (xy 411.982793 -294.681749)
			(xy 411.953417 -294.641316) (xy 411.930727 -294.596784) (xy 411.915283 -294.549252) (xy 411.907464 -294.499889)
			(xy 411.906974 -294.4749) (xy 410.642816 -294.4749) (xy 410.642154 -294.503316) (xy 410.632025 -294.559239)
			(xy 410.612106 -294.612466) (xy 410.598112 -294.637206) (xy 410.595263 -294.642383) (xy 410.591793 -294.653674)
			(xy 410.591254 -294.659558) (xy 410.589083 -294.68336) (xy 410.577325 -294.729682) (xy 410.557518 -294.773176)
			(xy 410.530296 -294.812457) (xy 410.513784 -294.829738) (xy 410.27985 -295.063672) (xy 410.273037 -295.071093)
			(xy 410.2653 -295.089676) (xy 410.264864 -295.09974) (xy 410.264864 -295.577514) (xy 410.26438 -295.59251)
			(xy 410.256625 -295.621481) (xy 410.241648 -295.647465) (xy 410.220464 -295.668695) (xy 410.194513 -295.683729)
			(xy 410.165558 -295.691547) (xy 410.150564 -295.692068) (xy 409.337256 -295.692068) (xy 409.322222 -295.691658)
			(xy 409.293177 -295.683875) (xy 409.267131 -295.66885) (xy 409.245854 -295.647604) (xy 409.23079 -295.62158)
			(xy 409.222965 -295.592548) (xy 409.222448 -295.577514) (xy 405.514556 -295.577514) (xy 405.514076 -295.592531)
			(xy 405.5063 -295.621542) (xy 405.491281 -295.647551) (xy 405.470042 -295.668788) (xy 405.444031 -295.683805)
			(xy 405.415019 -295.691578) (xy 405.400002 -295.692068) (xy 404.587202 -295.692068) (xy 404.572186 -295.691562)
			(xy 404.543178 -295.683791) (xy 404.51717 -295.668776) (xy 404.495933 -295.647543) (xy 404.480916 -295.621536)
			(xy 404.47314 -295.592529) (xy 404.472648 -295.577514) (xy 401.714716 -295.577514) (xy 401.714279 -295.592514)
			(xy 401.706521 -295.621492) (xy 401.691535 -295.647481) (xy 401.670341 -295.668712) (xy 401.64438 -295.683743)
			(xy 401.615415 -295.691552) (xy 401.600416 -295.692068) (xy 400.787108 -295.692068) (xy 400.772076 -295.691613)
			(xy 400.743033 -295.683842) (xy 400.716987 -295.668828) (xy 400.695708 -295.64759) (xy 400.680643 -295.621572)
			(xy 400.672817 -295.592545) (xy 400.6723 -295.577514) (xy 396.40764 -295.577514) (xy 396.40764 -296.399786)
			(xy 396.707402 -296.399786) (xy 396.707402 -296.349814) (xy 396.715219 -296.300458) (xy 396.730659 -296.252932)
			(xy 396.753344 -296.208407) (xy 396.782715 -296.167978) (xy 396.818047 -296.132641) (xy 396.858473 -296.103265)
			(xy 396.902995 -296.080575) (xy 396.950519 -296.065128) (xy 396.999874 -296.057305) (xy 397.02486 -296.056812)
			(xy 397.025368 -296.056812) (xy 397.046317 -296.057143) (xy 397.087854 -296.062621) (xy 397.108172 -296.067734)
			(xy 397.111785 -296.06864) (xy 397.119179 -296.069534) (xy 397.122904 -296.069512) (xy 397.12646 -296.069512)
			(xy 397.43126 -296.069512) (xy 397.446316 -296.069974) (xy 397.475403 -296.07776) (xy 397.501483 -296.092811)
			(xy 397.522777 -296.114101) (xy 397.537832 -296.140178) (xy 397.545623 -296.169264) (xy 397.546068 -296.18432)
			(xy 397.546068 -296.399791) (xy 398.607477 -296.399791) (xy 398.607477 -296.349809) (xy 398.615297 -296.300442)
			(xy 398.630743 -296.252906) (xy 398.653436 -296.208371) (xy 398.682817 -296.167936) (xy 398.718162 -296.132595)
			(xy 398.7586 -296.103218) (xy 398.803137 -296.08053) (xy 398.850675 -296.065089) (xy 398.900043 -296.057274)
			(xy 398.925034 -296.056812) (xy 398.925542 -296.056812) (xy 398.94649 -296.057148) (xy 398.988028 -296.062622)
			(xy 399.008346 -296.067734) (xy 399.01196 -296.068634) (xy 399.019354 -296.069532) (xy 399.023078 -296.069512)
			(xy 399.026634 -296.069512) (xy 399.331434 -296.069512) (xy 399.346476 -296.069965) (xy 399.375532 -296.077768)
			(xy 399.401574 -296.092832) (xy 399.422823 -296.114129) (xy 399.43783 -296.140204) (xy 399.445568 -296.169277)
			(xy 399.445988 -296.18432) (xy 399.445988 -296.399785) (xy 400.507502 -296.399785) (xy 400.507502 -296.349815)
			(xy 400.515318 -296.300459) (xy 400.530759 -296.252934) (xy 400.553443 -296.208409) (xy 400.582813 -296.16798)
			(xy 400.618145 -296.132643) (xy 400.658569 -296.103267) (xy 400.703091 -296.080577) (xy 400.750614 -296.065129)
			(xy 400.799969 -296.057306) (xy 400.824954 -296.056812) (xy 400.825462 -296.056812) (xy 400.846411 -296.057144)
			(xy 400.887948 -296.062621) (xy 400.908266 -296.067734) (xy 400.911879 -296.068638) (xy 400.919273 -296.069534)
			(xy 400.922998 -296.069512) (xy 400.926554 -296.069512) (xy 401.231354 -296.069512) (xy 401.246393 -296.070034)
			(xy 401.275446 -296.077819) (xy 401.301488 -296.092867) (xy 401.322739 -296.114151) (xy 401.337748 -296.140216)
			(xy 401.345488 -296.16928) (xy 401.345908 -296.18432) (xy 401.345908 -296.399786) (xy 402.407402 -296.399786)
			(xy 402.407402 -296.349814) (xy 402.415219 -296.300456) (xy 402.430661 -296.252929) (xy 402.453347 -296.208403)
			(xy 402.482719 -296.167973) (xy 402.518053 -296.132636) (xy 402.55848 -296.10326) (xy 402.603005 -296.080571)
			(xy 402.650531 -296.065125) (xy 402.699888 -296.057304) (xy 402.724874 -296.056812) (xy 402.725382 -296.056812)
			(xy 402.746331 -296.057141) (xy 402.787868 -296.06262) (xy 402.808186 -296.067734) (xy 402.811798 -296.068642)
			(xy 402.819193 -296.069535) (xy 402.822918 -296.069512) (xy 402.826474 -296.069512) (xy 403.131274 -296.069512)
			(xy 403.146314 -296.070017) (xy 403.175367 -296.077806) (xy 403.201409 -296.092858) (xy 403.22266 -296.114146)
			(xy 403.237669 -296.140213) (xy 403.245408 -296.16928) (xy 403.245828 -296.18432) (xy 403.245828 -296.399792)
			(xy 404.307477 -296.399792) (xy 404.307477 -296.349808) (xy 404.315297 -296.300439) (xy 404.330744 -296.252902)
			(xy 404.353439 -296.208367) (xy 404.382821 -296.167931) (xy 404.418168 -296.13259) (xy 404.458608 -296.103214)
			(xy 404.503147 -296.080526) (xy 404.550686 -296.065086) (xy 404.600056 -296.057273) (xy 404.625048 -296.056812)
			(xy 404.625556 -296.056812) (xy 404.646505 -296.057146) (xy 404.688042 -296.062621) (xy 404.70836 -296.067734)
			(xy 404.711974 -296.068637) (xy 404.719367 -296.069533) (xy 404.723092 -296.069512) (xy 404.726648 -296.069512)
			(xy 405.031448 -296.069512) (xy 405.046502 -296.069941) (xy 405.075581 -296.077745) (xy 405.101651 -296.092808)
			(xy 405.122934 -296.114104) (xy 405.137981 -296.140182) (xy 405.145768 -296.169266) (xy 405.146256 -296.18432)
			(xy 405.146256 -296.399786) (xy 406.207502 -296.399786) (xy 406.207502 -296.349814) (xy 406.215319 -296.300457)
			(xy 406.23076 -296.252931) (xy 406.253446 -296.208404) (xy 406.282817 -296.167975) (xy 406.318151 -296.132638)
			(xy 406.358577 -296.103262) (xy 406.403101 -296.080573) (xy 406.450626 -296.065126) (xy 406.499982 -296.057305)
			(xy 406.524968 -296.056812) (xy 406.545988 -296.057192) (xy 406.587655 -296.062793) (xy 406.608026 -296.067988)
			(xy 406.61463 -296.069512) (xy 406.905968 -296.069512) (xy 406.921024 -296.069967) (xy 406.950112 -296.077755)
			(xy 406.976191 -296.092808) (xy 406.997485 -296.114099) (xy 407.01254 -296.140177) (xy 407.020331 -296.169264)
			(xy 407.020776 -296.18432) (xy 407.020776 -296.56532) (xy 407.020378 -296.580379) (xy 407.019648 -296.5831)
			(xy 408.751532 -296.5831) (xy 408.751532 -296.2021) (xy 408.75194 -296.187041) (xy 408.759737 -296.157949)
			(xy 408.774799 -296.131868) (xy 408.796099 -296.110574) (xy 408.822186 -296.095521) (xy 408.851281 -296.087735)
			(xy 408.86634 -296.087292) (xy 409.17114 -296.087292) (xy 409.17879 -296.087426) (xy 409.193953 -296.089464)
			(xy 409.201366 -296.091356) (xy 409.210279 -296.093437) (xy 409.228502 -296.091884) (xy 409.236926 -296.088308)
			(xy 409.258471 -296.078413) (xy 409.303764 -296.064404) (xy 409.350636 -296.057286) (xy 409.37434 -296.056812)
			(xy 409.374848 -296.056812) (xy 409.400154 -296.057304) (xy 409.450124 -296.065344) (xy 409.498194 -296.081184)
			(xy 409.520898 -296.092372) (xy 409.530694 -296.096742) (xy 409.552085 -296.097929) (xy 409.5623 -296.094658)
			(xy 409.572099 -296.091194) (xy 409.592548 -296.087491) (xy 409.60294 -296.087292) (xy 409.90774 -296.087292)
			(xy 409.922792 -296.087748) (xy 409.951868 -296.095548) (xy 409.977935 -296.110606) (xy 409.999218 -296.131897)
			(xy 410.014267 -296.157969) (xy 410.022057 -296.187048) (xy 410.022548 -296.2021) (xy 410.022548 -296.399791)
			(xy 410.957477 -296.399791) (xy 410.957477 -296.349809) (xy 410.965296 -296.300443) (xy 410.980742 -296.252908)
			(xy 411.003434 -296.208375) (xy 411.032813 -296.16794) (xy 411.068157 -296.132599) (xy 411.108594 -296.103222)
			(xy 411.153129 -296.080533) (xy 411.200665 -296.065091) (xy 411.250031 -296.057275) (xy 411.275022 -296.056812)
			(xy 411.296043 -296.057181) (xy 411.337709 -296.06279) (xy 411.35808 -296.067988) (xy 411.364684 -296.069512)
			(xy 411.656022 -296.069512) (xy 411.671064 -296.069975) (xy 411.700119 -296.077775) (xy 411.726161 -296.092837)
			(xy 411.747411 -296.114132) (xy 411.762418 -296.140206) (xy 411.770156 -296.169277) (xy 411.770576 -296.18432)
			(xy 411.770576 -296.399792) (xy 412.857377 -296.399792) (xy 412.857377 -296.349808) (xy 412.865197 -296.30044)
			(xy 412.880644 -296.252904) (xy 412.903338 -296.208369) (xy 412.932719 -296.167933) (xy 412.968065 -296.132592)
			(xy 413.008505 -296.103216) (xy 413.053043 -296.080528) (xy 413.100581 -296.065087) (xy 413.14995 -296.057274)
			(xy 413.174942 -296.056812) (xy 413.195963 -296.057177) (xy 413.237629 -296.062788) (xy 413.258 -296.067988)
			(xy 413.264604 -296.069512) (xy 413.555942 -296.069512) (xy 413.570985 -296.069958) (xy 413.60004 -296.077763)
			(xy 413.626082 -296.092829) (xy 413.647332 -296.114127) (xy 413.662338 -296.140203) (xy 413.670076 -296.169276)
			(xy 413.670496 -296.18432) (xy 413.670496 -296.56532) (xy 413.670037 -296.580351) (xy 413.662263 -296.60939)
			(xy 413.647247 -296.635434) (xy 413.62601 -296.656711) (xy 413.599996 -296.671777) (xy 413.570972 -296.679608)
			(xy 413.555942 -296.680128) (xy 413.264604 -296.680128) (xy 413.258 -296.681652) (xy 413.237627 -296.686843)
			(xy 413.195962 -296.692453) (xy 413.174942 -296.692828) (xy 413.14995 -296.692326) (xy 413.100581 -296.684513)
			(xy 413.053043 -296.669072) (xy 413.008505 -296.646384) (xy 412.968065 -296.617008) (xy 412.932719 -296.581667)
			(xy 412.903338 -296.541231) (xy 412.880644 -296.496696) (xy 412.865197 -296.44916) (xy 412.857377 -296.399792)
			(xy 411.770576 -296.399792) (xy 411.770576 -296.56532) (xy 411.770137 -296.580353) (xy 411.762361 -296.609395)
			(xy 411.747342 -296.63544) (xy 411.726101 -296.656718) (xy 411.700082 -296.671783) (xy 411.671054 -296.67961)
			(xy 411.656022 -296.680128) (xy 411.364684 -296.680128) (xy 411.35808 -296.681652) (xy 411.337708 -296.686847)
			(xy 411.296042 -296.692455) (xy 411.275022 -296.692828) (xy 411.250031 -296.692325) (xy 411.200665 -296.684509)
			(xy 411.153129 -296.669067) (xy 411.108594 -296.646378) (xy 411.068157 -296.617001) (xy 411.032813 -296.58166)
			(xy 411.003434 -296.541225) (xy 410.980742 -296.496692) (xy 410.965296 -296.449157) (xy 410.957477 -296.399791)
			(xy 410.022548 -296.399791) (xy 410.022548 -296.5831) (xy 410.022018 -296.598147) (xy 410.01423 -296.627215)
			(xy 409.999187 -296.653279) (xy 409.977911 -296.674562) (xy 409.951853 -296.689615) (xy 409.922787 -296.697412)
			(xy 409.90774 -296.697908) (xy 409.60294 -296.697908) (xy 409.586865 -296.697358) (xy 409.555963 -296.688494)
			(xy 409.528723 -296.671421) (xy 409.517596 -296.659808) (xy 409.516326 -296.659808) (xy 409.49433 -296.670177)
			(xy 409.447971 -296.684853) (xy 409.399922 -296.692325) (xy 409.37561 -296.692828) (xy 409.374848 -296.692828)
			(xy 409.349049 -296.692335) (xy 409.298122 -296.684042) (xy 409.273502 -296.676318) (xy 409.262766 -296.673303)
			(xy 409.24063 -296.67582) (xy 409.23083 -296.681144) (xy 409.217154 -296.688925) (xy 409.186868 -296.697426)
			(xy 409.17114 -296.697908) (xy 408.86634 -296.697908) (xy 408.851286 -296.697426) (xy 408.822202 -296.689642)
			(xy 408.796124 -296.674594) (xy 408.774831 -296.653308) (xy 408.759774 -296.627236) (xy 408.751979 -296.598154)
			(xy 408.751532 -296.5831) (xy 407.019648 -296.5831) (xy 407.012577 -296.609471) (xy 406.997512 -296.635552)
			(xy 406.97621 -296.656844) (xy 406.950123 -296.671897) (xy 406.921028 -296.679685) (xy 406.905968 -296.680128)
			(xy 406.61463 -296.680128) (xy 406.608026 -296.681652) (xy 406.587657 -296.686857) (xy 406.545989 -296.692458)
			(xy 406.524968 -296.692828) (xy 406.499982 -296.692295) (xy 406.450626 -296.684474) (xy 406.403101 -296.669027)
			(xy 406.358577 -296.646338) (xy 406.318151 -296.616962) (xy 406.282817 -296.581625) (xy 406.253446 -296.541196)
			(xy 406.23076 -296.496669) (xy 406.215319 -296.449143) (xy 406.207502 -296.399786) (xy 405.146256 -296.399786)
			(xy 405.146256 -296.56532) (xy 405.145735 -296.580367) (xy 405.137944 -296.609435) (xy 405.122897 -296.635498)
			(xy 405.10162 -296.65678) (xy 405.075561 -296.671833) (xy 405.046495 -296.679631) (xy 405.031448 -296.680128)
			(xy 404.723092 -296.680128) (xy 404.719366 -296.680097) (xy 404.71197 -296.680984) (xy 404.70836 -296.681906)
			(xy 404.688046 -296.687037) (xy 404.646506 -296.692513) (xy 404.625556 -296.692828) (xy 404.625048 -296.692828)
			(xy 404.600056 -296.692327) (xy 404.550686 -296.684514) (xy 404.503147 -296.669074) (xy 404.458608 -296.646386)
			(xy 404.418168 -296.61701) (xy 404.382821 -296.581669) (xy 404.353439 -296.541233) (xy 404.330744 -296.496698)
			(xy 404.315297 -296.449161) (xy 404.307477 -296.399792) (xy 403.245828 -296.399792) (xy 403.245828 -296.56532)
			(xy 403.245338 -296.580348) (xy 403.237566 -296.609383) (xy 403.222555 -296.635423) (xy 403.201325 -296.6567)
			(xy 403.175318 -296.671768) (xy 403.146301 -296.679604) (xy 403.131274 -296.680128) (xy 402.822918 -296.680128)
			(xy 402.819192 -296.68008) (xy 402.811795 -296.680979) (xy 402.808186 -296.681906) (xy 402.787871 -296.687032)
			(xy 402.746332 -296.692511) (xy 402.725382 -296.692828) (xy 402.724874 -296.692828) (xy 402.699888 -296.692296)
			(xy 402.650531 -296.684475) (xy 402.603005 -296.669029) (xy 402.55848 -296.64634) (xy 402.518053 -296.616964)
			(xy 402.482719 -296.581627) (xy 402.453347 -296.541197) (xy 402.430661 -296.496671) (xy 402.415219 -296.449144)
			(xy 402.407402 -296.399786) (xy 401.345908 -296.399786) (xy 401.345908 -296.56532) (xy 401.345438 -296.58035)
			(xy 401.337664 -296.609387) (xy 401.32265 -296.63543) (xy 401.301416 -296.656707) (xy 401.275405 -296.671774)
			(xy 401.246383 -296.679607) (xy 401.231354 -296.680128) (xy 400.922998 -296.680128) (xy 400.919272 -296.680098)
			(xy 400.911876 -296.680984) (xy 400.908266 -296.681906) (xy 400.887951 -296.687036) (xy 400.846412 -296.692512)
			(xy 400.825462 -296.692828) (xy 400.824954 -296.692828) (xy 400.799969 -296.692294) (xy 400.750614 -296.684471)
			(xy 400.703091 -296.669023) (xy 400.658569 -296.646333) (xy 400.618145 -296.616957) (xy 400.582813 -296.58162)
			(xy 400.553443 -296.541191) (xy 400.530759 -296.496666) (xy 400.515318 -296.449141) (xy 400.507502 -296.399785)
			(xy 399.445988 -296.399785) (xy 399.445988 -296.56532) (xy 399.445537 -296.580352) (xy 399.437762 -296.609392)
			(xy 399.422745 -296.635436) (xy 399.401507 -296.656714) (xy 399.375491 -296.67178) (xy 399.346465 -296.679609)
			(xy 399.331434 -296.680128) (xy 399.023078 -296.680128) (xy 399.019352 -296.680094) (xy 399.011956 -296.680983)
			(xy 399.008346 -296.681906) (xy 398.988032 -296.68704) (xy 398.946492 -296.692514) (xy 398.925542 -296.692828)
			(xy 398.925034 -296.692828) (xy 398.900043 -296.692326) (xy 398.850675 -296.684511) (xy 398.803137 -296.66907)
			(xy 398.7586 -296.646382) (xy 398.718162 -296.617005) (xy 398.682817 -296.581664) (xy 398.653436 -296.541229)
			(xy 398.630743 -296.496694) (xy 398.615297 -296.449158) (xy 398.607477 -296.399791) (xy 397.546068 -296.399791)
			(xy 397.546068 -296.56532) (xy 397.545678 -296.58038) (xy 397.537877 -296.609473) (xy 397.52281 -296.635554)
			(xy 397.501506 -296.656847) (xy 397.475417 -296.6719) (xy 397.44632 -296.679686) (xy 397.43126 -296.680128)
			(xy 397.122904 -296.680128) (xy 397.119178 -296.680099) (xy 397.111782 -296.680985) (xy 397.108172 -296.681906)
			(xy 397.087857 -296.687035) (xy 397.046318 -296.692512) (xy 397.025368 -296.692828) (xy 397.02486 -296.692828)
			(xy 396.999874 -296.692295) (xy 396.950519 -296.684472) (xy 396.902995 -296.669025) (xy 396.858473 -296.646335)
			(xy 396.818047 -296.616959) (xy 396.782715 -296.581622) (xy 396.753344 -296.541193) (xy 396.730659 -296.496668)
			(xy 396.715219 -296.449142) (xy 396.707402 -296.399786) (xy 396.40764 -296.399786) (xy 396.40764 -297.32478)
			(xy 397.656812 -297.32478) (xy 397.657302 -297.299791) (xy 397.665121 -297.250428) (xy 397.680565 -297.202896)
			(xy 397.703255 -297.158364) (xy 397.732631 -297.117931) (xy 397.767971 -297.082591) (xy 397.808404 -297.053215)
			(xy 397.852936 -297.030525) (xy 397.900468 -297.015081) (xy 397.949831 -297.007262) (xy 397.999809 -297.007262)
			(xy 398.049172 -297.015081) (xy 398.096704 -297.030525) (xy 398.141236 -297.053215) (xy 398.181669 -297.082591)
			(xy 398.217009 -297.117931) (xy 398.246385 -297.158364) (xy 398.269075 -297.202896) (xy 398.284519 -297.250428)
			(xy 398.292338 -297.299791) (xy 398.292828 -297.32478) (xy 399.556986 -297.32478) (xy 399.557476 -297.299791)
			(xy 399.565295 -297.250428) (xy 399.580739 -297.202896) (xy 399.603429 -297.158364) (xy 399.632805 -297.117931)
			(xy 399.668145 -297.082591) (xy 399.708578 -297.053215) (xy 399.75311 -297.030525) (xy 399.800642 -297.015081)
			(xy 399.850005 -297.007262) (xy 399.899983 -297.007262) (xy 399.949346 -297.015081) (xy 399.996878 -297.030525)
			(xy 400.04141 -297.053215) (xy 400.081843 -297.082591) (xy 400.117183 -297.117931) (xy 400.146559 -297.158364)
			(xy 400.169249 -297.202896) (xy 400.184693 -297.250428) (xy 400.192512 -297.299791) (xy 400.193002 -297.32478)
			(xy 401.456906 -297.32478) (xy 401.457396 -297.299791) (xy 401.465215 -297.250428) (xy 401.480659 -297.202896)
			(xy 401.503349 -297.158364) (xy 401.532725 -297.117931) (xy 401.568065 -297.082591) (xy 401.608498 -297.053215)
			(xy 401.65303 -297.030525) (xy 401.700562 -297.015081) (xy 401.749925 -297.007262) (xy 401.799903 -297.007262)
			(xy 401.849266 -297.015081) (xy 401.896798 -297.030525) (xy 401.94133 -297.053215) (xy 401.981763 -297.082591)
			(xy 402.017103 -297.117931) (xy 402.046479 -297.158364) (xy 402.069169 -297.202896) (xy 402.084613 -297.250428)
			(xy 402.092432 -297.299791) (xy 402.092922 -297.32478) (xy 403.356826 -297.32478) (xy 403.357316 -297.299791)
			(xy 403.365135 -297.250428) (xy 403.380579 -297.202896) (xy 403.403269 -297.158364) (xy 403.432645 -297.117931)
			(xy 403.467985 -297.082591) (xy 403.508418 -297.053215) (xy 403.55295 -297.030525) (xy 403.600482 -297.015081)
			(xy 403.649845 -297.007262) (xy 403.699823 -297.007262) (xy 403.749186 -297.015081) (xy 403.796718 -297.030525)
			(xy 403.84125 -297.053215) (xy 403.881683 -297.082591) (xy 403.917023 -297.117931) (xy 403.946399 -297.158364)
			(xy 403.969089 -297.202896) (xy 403.984533 -297.250428) (xy 403.992352 -297.299791) (xy 403.992842 -297.32478)
			(xy 405.257 -297.32478) (xy 405.25749 -297.299791) (xy 405.265309 -297.250428) (xy 405.280753 -297.202896)
			(xy 405.303443 -297.158364) (xy 405.332819 -297.117931) (xy 405.368159 -297.082591) (xy 405.408592 -297.053215)
			(xy 405.453124 -297.030525) (xy 405.500656 -297.015081) (xy 405.550019 -297.007262) (xy 405.599997 -297.007262)
			(xy 405.64936 -297.015081) (xy 405.696892 -297.030525) (xy 405.741424 -297.053215) (xy 405.781857 -297.082591)
			(xy 405.817197 -297.117931) (xy 405.846573 -297.158364) (xy 405.869263 -297.202896) (xy 405.884707 -297.250428)
			(xy 405.892526 -297.299791) (xy 405.893016 -297.32478) (xy 408.10688 -297.32478) (xy 408.10737 -297.299791)
			(xy 408.115189 -297.250428) (xy 408.130633 -297.202896) (xy 408.153323 -297.158364) (xy 408.182699 -297.117931)
			(xy 408.218039 -297.082591) (xy 408.258472 -297.053215) (xy 408.303004 -297.030525) (xy 408.350536 -297.015081)
			(xy 408.399899 -297.007262) (xy 408.449877 -297.007262) (xy 408.49924 -297.015081) (xy 408.546772 -297.030525)
			(xy 408.591304 -297.053215) (xy 408.631737 -297.082591) (xy 408.667077 -297.117931) (xy 408.696453 -297.158364)
			(xy 408.719143 -297.202896) (xy 408.734587 -297.250428) (xy 408.742406 -297.299791) (xy 408.742896 -297.32478)
			(xy 410.0068 -297.32478) (xy 410.00729 -297.299791) (xy 410.015109 -297.250428) (xy 410.030553 -297.202896)
			(xy 410.053243 -297.158364) (xy 410.082619 -297.117931) (xy 410.117959 -297.082591) (xy 410.158392 -297.053215)
			(xy 410.202924 -297.030525) (xy 410.250456 -297.015081) (xy 410.299819 -297.007262) (xy 410.349797 -297.007262)
			(xy 410.39916 -297.015081) (xy 410.446692 -297.030525) (xy 410.491224 -297.053215) (xy 410.531657 -297.082591)
			(xy 410.566997 -297.117931) (xy 410.596373 -297.158364) (xy 410.619063 -297.202896) (xy 410.634507 -297.250428)
			(xy 410.642326 -297.299791) (xy 410.642816 -297.32478) (xy 411.906974 -297.32478) (xy 411.907464 -297.299791)
			(xy 411.915283 -297.250428) (xy 411.930727 -297.202896) (xy 411.953417 -297.158364) (xy 411.982793 -297.117931)
			(xy 412.018133 -297.082591) (xy 412.058566 -297.053215) (xy 412.103098 -297.030525) (xy 412.15063 -297.015081)
			(xy 412.199993 -297.007262) (xy 412.249971 -297.007262) (xy 412.299334 -297.015081) (xy 412.346866 -297.030525)
			(xy 412.391398 -297.053215) (xy 412.431831 -297.082591) (xy 412.467171 -297.117931) (xy 412.496547 -297.158364)
			(xy 412.519237 -297.202896) (xy 412.534681 -297.250428) (xy 412.5425 -297.299791) (xy 412.54299 -297.32478)
			(xy 412.542613 -297.3458) (xy 412.53701 -297.387467) (xy 412.531814 -297.407838) (xy 412.530036 -297.414442)
			(xy 412.530036 -297.68546) (xy 412.529485 -297.700485) (xy 412.521728 -297.729516) (xy 412.506731 -297.755556)
			(xy 412.485512 -297.776834) (xy 412.459515 -297.791904) (xy 412.430506 -297.799743) (xy 412.415482 -297.800268)
			(xy 412.034482 -297.800268) (xy 412.019439 -297.799821) (xy 411.990381 -297.79202) (xy 411.964337 -297.776956)
			(xy 411.943086 -297.755657) (xy 411.928081 -297.72958) (xy 411.920345 -297.700504) (xy 411.919928 -297.68546)
			(xy 411.919928 -297.414442) (xy 411.91815 -297.407838) (xy 411.912947 -297.387468) (xy 411.907344 -297.345801)
			(xy 411.906974 -297.32478) (xy 410.642816 -297.32478) (xy 410.642438 -297.3458) (xy 410.636835 -297.387467)
			(xy 410.63164 -297.407838) (xy 410.630116 -297.414442) (xy 410.630116 -297.68546) (xy 410.629626 -297.700513)
			(xy 410.621843 -297.729597) (xy 410.606796 -297.755674) (xy 410.585512 -297.776967) (xy 410.559441 -297.792024)
			(xy 410.530361 -297.79982) (xy 410.515308 -297.800268) (xy 410.134308 -297.800268) (xy 410.119249 -297.799853)
			(xy 410.090158 -297.792058) (xy 410.064076 -297.776998) (xy 410.042783 -297.755698) (xy 410.027729 -297.729613)
			(xy 410.019943 -297.700519) (xy 410.0195 -297.68546) (xy 410.0195 -297.414442) (xy 410.017976 -297.407838)
			(xy 410.012773 -297.387468) (xy 410.007171 -297.345801) (xy 410.0068 -297.32478) (xy 408.742896 -297.32478)
			(xy 408.742518 -297.3458) (xy 408.736915 -297.387467) (xy 408.73172 -297.407838) (xy 408.730196 -297.414442)
			(xy 408.730196 -297.68546) (xy 408.729726 -297.700515) (xy 408.721941 -297.729601) (xy 408.706891 -297.75568)
			(xy 408.685602 -297.776974) (xy 408.659527 -297.79203) (xy 408.630443 -297.799822) (xy 408.615388 -297.800268)
			(xy 408.234388 -297.800268) (xy 408.219328 -297.799871) (xy 408.190236 -297.792071) (xy 408.164155 -297.777006)
			(xy 408.142862 -297.755704) (xy 408.127809 -297.729616) (xy 408.120022 -297.70052) (xy 408.11958 -297.68546)
			(xy 408.11958 -297.414442) (xy 408.118056 -297.407838) (xy 408.112853 -297.387468) (xy 408.10725 -297.345801)
			(xy 408.10688 -297.32478) (xy 405.893016 -297.32478) (xy 405.892638 -297.3458) (xy 405.887035 -297.387467)
			(xy 405.88184 -297.407838) (xy 405.880316 -297.414442) (xy 405.880316 -297.68546) (xy 405.879826 -297.700513)
			(xy 405.872043 -297.729597) (xy 405.856996 -297.755674) (xy 405.835712 -297.776967) (xy 405.809641 -297.792024)
			(xy 405.780561 -297.79982) (xy 405.765508 -297.800268) (xy 405.384508 -297.800268) (xy 405.369449 -297.799853)
			(xy 405.340358 -297.792058) (xy 405.314276 -297.776998) (xy 405.292983 -297.755698) (xy 405.277929 -297.729613)
			(xy 405.270143 -297.700519) (xy 405.2697 -297.68546) (xy 405.2697 -297.414442) (xy 405.268176 -297.407838)
			(xy 405.262973 -297.387468) (xy 405.257371 -297.345801) (xy 405.257 -297.32478) (xy 403.992842 -297.32478)
			(xy 403.992463 -297.3458) (xy 403.986861 -297.387467) (xy 403.981666 -297.407838) (xy 403.979888 -297.414442)
			(xy 403.979888 -297.68546) (xy 403.979384 -297.700489) (xy 403.971623 -297.729527) (xy 403.956618 -297.755572)
			(xy 403.93539 -297.776851) (xy 403.909381 -297.791918) (xy 403.880362 -297.799748) (xy 403.865334 -297.800268)
			(xy 403.484334 -297.800268) (xy 403.469293 -297.799776) (xy 403.440237 -297.791987) (xy 403.414193 -297.776933)
			(xy 403.392941 -297.755643) (xy 403.377934 -297.729572) (xy 403.370197 -297.700502) (xy 403.36978 -297.68546)
			(xy 403.36978 -297.414442) (xy 403.368002 -297.407838) (xy 403.3628 -297.387468) (xy 403.357197 -297.345801)
			(xy 403.356826 -297.32478) (xy 402.092922 -297.32478) (xy 402.092543 -297.3458) (xy 402.086941 -297.387467)
			(xy 402.081746 -297.407838) (xy 402.079968 -297.414442) (xy 402.079968 -297.68546) (xy 402.079484 -297.700491)
			(xy 402.071721 -297.729532) (xy 402.056713 -297.755578) (xy 402.03548 -297.776858) (xy 402.009467 -297.791924)
			(xy 401.980443 -297.799751) (xy 401.965414 -297.800268) (xy 401.584414 -297.800268) (xy 401.569372 -297.799793)
			(xy 401.540315 -297.792) (xy 401.514271 -297.776942) (xy 401.49302 -297.755649) (xy 401.478013 -297.729575)
			(xy 401.470277 -297.700503) (xy 401.46986 -297.68546) (xy 401.46986 -297.414442) (xy 401.468082 -297.407838)
			(xy 401.46288 -297.387468) (xy 401.457277 -297.345801) (xy 401.456906 -297.32478) (xy 400.193002 -297.32478)
			(xy 400.192624 -297.3458) (xy 400.187021 -297.387467) (xy 400.181826 -297.407838) (xy 400.180048 -297.414442)
			(xy 400.180048 -297.68546) (xy 400.179485 -297.700484) (xy 400.171729 -297.729513) (xy 400.156734 -297.755552)
			(xy 400.135518 -297.776829) (xy 400.109523 -297.791901) (xy 400.080517 -297.799741) (xy 400.065494 -297.800268)
			(xy 399.684494 -297.800268) (xy 399.669451 -297.799811) (xy 399.640394 -297.792013) (xy 399.61435 -297.776951)
			(xy 399.593099 -297.755654) (xy 399.578093 -297.729578) (xy 399.570357 -297.700504) (xy 399.56994 -297.68546)
			(xy 399.56994 -297.414442) (xy 399.568162 -297.407838) (xy 399.562959 -297.387468) (xy 399.557356 -297.345801)
			(xy 399.556986 -297.32478) (xy 398.292828 -297.32478) (xy 398.292449 -297.3458) (xy 398.286847 -297.387467)
			(xy 398.281652 -297.407838) (xy 398.280128 -297.414442) (xy 398.280128 -297.68546) (xy 398.279626 -297.700512)
			(xy 398.271844 -297.729594) (xy 398.256799 -297.75567) (xy 398.235517 -297.776962) (xy 398.209449 -297.792021)
			(xy 398.180372 -297.799818) (xy 398.16532 -297.800268) (xy 397.78432 -297.800268) (xy 397.769262 -297.799843)
			(xy 397.740171 -297.792051) (xy 397.714089 -297.776992) (xy 397.692795 -297.755695) (xy 397.677742 -297.729611)
			(xy 397.669955 -297.700518) (xy 397.669512 -297.68546) (xy 397.669512 -297.414442) (xy 397.667988 -297.407838)
			(xy 397.662786 -297.387468) (xy 397.657183 -297.345801) (xy 397.656812 -297.32478) (xy 396.40764 -297.32478)
			(xy 396.40764 -298.27474) (xy 396.706852 -298.27474) (xy 396.707235 -298.25372) (xy 396.712835 -298.212054)
			(xy 396.718028 -298.191682) (xy 396.719552 -298.185078) (xy 396.719552 -297.91406) (xy 396.720048 -297.899011)
			(xy 396.727844 -297.869941) (xy 396.742896 -297.843878) (xy 396.764178 -297.822596) (xy 396.790241 -297.807544)
			(xy 396.819311 -297.799748) (xy 396.83436 -297.799252) (xy 397.21536 -297.799252) (xy 397.230405 -297.799818)
			(xy 397.259472 -297.807596) (xy 397.285536 -297.822631) (xy 397.30682 -297.8439) (xy 397.321874 -297.869954)
			(xy 397.329672 -297.899015) (xy 397.330168 -297.91406) (xy 397.330168 -298.185078) (xy 397.331692 -298.191682)
			(xy 397.336898 -298.212051) (xy 397.342499 -298.253719) (xy 397.342868 -298.27474) (xy 397.342378 -298.299729)
			(xy 397.334559 -298.349092) (xy 397.319115 -298.396624) (xy 397.296425 -298.441156) (xy 397.267049 -298.481589)
			(xy 397.231709 -298.516929) (xy 397.191276 -298.546305) (xy 397.146744 -298.568995) (xy 397.099212 -298.584439)
			(xy 397.049849 -298.592258) (xy 396.999871 -298.592258) (xy 396.950508 -298.584439) (xy 396.902976 -298.568995)
			(xy 396.858444 -298.546305) (xy 396.818011 -298.516929) (xy 396.782671 -298.481589) (xy 396.753295 -298.441156)
			(xy 396.730605 -298.396624) (xy 396.715161 -298.349092) (xy 396.707342 -298.299729) (xy 396.706852 -298.27474)
			(xy 396.40764 -298.27474) (xy 396.40764 -300.199886) (xy 396.707396 -300.199886) (xy 396.707396 -300.149914)
			(xy 396.715213 -300.100557) (xy 396.730654 -300.05303) (xy 396.753339 -300.008504) (xy 396.78271 -299.968074)
			(xy 396.818043 -299.932736) (xy 396.85847 -299.90336) (xy 396.902993 -299.880669) (xy 396.950518 -299.865222)
			(xy 396.999874 -299.857399) (xy 397.02486 -299.856906) (xy 397.04588 -299.857288) (xy 397.087546 -299.862888)
			(xy 397.107918 -299.868082) (xy 397.114522 -299.86986) (xy 397.38554 -299.86986) (xy 397.400568 -299.870345)
			(xy 397.429602 -299.87812) (xy 397.455641 -299.893133) (xy 397.476917 -299.914364) (xy 397.491985 -299.94037)
			(xy 397.499823 -299.969387) (xy 397.500348 -299.984414) (xy 397.500348 -300.365414) (xy 397.499879 -300.380411)
			(xy 397.492124 -300.409385) (xy 397.477144 -300.43537) (xy 397.455956 -300.4566) (xy 397.430002 -300.471634)
			(xy 397.401044 -300.479449) (xy 397.386048 -300.479968) (xy 397.114522 -300.479968) (xy 397.107918 -300.481746)
			(xy 397.087549 -300.486953) (xy 397.045881 -300.492553) (xy 397.02486 -300.492922) (xy 396.999874 -300.492401)
			(xy 396.950518 -300.484578) (xy 396.902993 -300.469131) (xy 396.85847 -300.44644) (xy 396.818043 -300.417064)
			(xy 396.78271 -300.381726) (xy 396.753339 -300.341296) (xy 396.730654 -300.29677) (xy 396.715213 -300.249243)
			(xy 396.707396 -300.199886) (xy 396.40764 -300.199886) (xy 396.40764 -301.197518) (xy 396.408656 -301.20717)
			(xy 396.410287 -301.214412) (xy 396.417134 -301.227576) (xy 396.422118 -301.233078) (xy 396.494 -301.30496)
			(xy 396.501369 -301.311706) (xy 396.519831 -301.319305) (xy 396.529814 -301.319692)
		)
		(stroke
			(width 0)
			(type solid)
		)
		(fill yes)
		(layer "B.Cu")
		(net "P0V8_PEX3")
	)
	(gr_poly
		(pts
			(xy 49.047654 -301.319692) (xy 49.05792 -301.31916) (xy 49.076779 -301.311028) (xy 49.08423 -301.303944)
			(xy 49.135284 -301.250096) (xy 49.138704 -301.246219) (xy 49.144068 -301.237385) (xy 49.145952 -301.23257)
			(xy 49.149508 -301.223172) (xy 49.148746 -301.212504) (xy 49.148492 -301.2059) (xy 49.148492 -300.8249)
			(xy 49.148983 -300.80985) (xy 49.156773 -300.780775) (xy 49.171824 -300.754708) (xy 49.193108 -300.733424)
			(xy 49.219175 -300.718373) (xy 49.24825 -300.710583) (xy 49.2633 -300.710092) (xy 49.5681 -300.710092)
			(xy 49.576877 -300.710253) (xy 49.594225 -300.712939) (xy 49.602644 -300.715426) (xy 49.606708 -300.716696)
			(xy 49.610518 -300.717966) (xy 49.618646 -300.717966) (xy 49.628587 -300.717442) (xy 49.646941 -300.709784)
			(xy 49.660999 -300.695719) (xy 49.668647 -300.677361) (xy 49.669192 -300.66742) (xy 49.669192 -300.410626)
			(xy 49.669739 -300.385201) (xy 49.678245 -300.335065) (xy 49.694943 -300.287032) (xy 49.719371 -300.242431)
			(xy 49.734724 -300.222158) (xy 49.738048 -300.21776) (xy 49.743532 -300.208199) (xy 49.745646 -300.203108)
			(xy 49.748134 -300.196327) (xy 49.750813 -300.182135) (xy 49.75098 -300.174914) (xy 49.751234 -300.17466)
			(xy 49.750727 -300.162908) (xy 49.743485 -300.140539) (xy 49.73701 -300.130718) (xy 49.734724 -300.12767)
			(xy 49.719382 -300.107388) (xy 49.694953 -300.062789) (xy 49.678247 -300.01476) (xy 49.669726 -299.964627)
			(xy 49.669192 -299.939202) (xy 49.669192 -299.631354) (xy 49.668637 -299.621423) (xy 49.660953 -299.603098)
			(xy 49.646902 -299.589047) (xy 49.628577 -299.581363) (xy 49.618646 -299.580808) (xy 49.3141 -299.580808)
			(xy 49.29905 -299.580317) (xy 49.269975 -299.572527) (xy 49.243908 -299.557476) (xy 49.222624 -299.536192)
			(xy 49.207573 -299.510125) (xy 49.199783 -299.48105) (xy 49.199292 -299.466) (xy 49.199292 -299.085)
			(xy 49.199783 -299.06995) (xy 49.207573 -299.040875) (xy 49.222624 -299.014808) (xy 49.243908 -298.993524)
			(xy 49.269975 -298.978473) (xy 49.29905 -298.970683) (xy 49.3141 -298.970192) (xy 49.460658 -298.970192)
			(xy 49.464464 -298.970123) (xy 49.471989 -298.968971) (xy 49.475644 -298.967906) (xy 49.496218 -298.961556)
			(xy 49.500282 -298.959016) (xy 49.51979 -298.946702) (xy 49.561612 -298.927235) (xy 49.605813 -298.914031)
			(xy 49.65146 -298.907367) (xy 49.674526 -298.906946) (xy 49.681638 -298.906946) (xy 49.711622 -298.908282)
			(xy 49.77031 -298.920811) (xy 49.798224 -298.931838) (xy 49.804574 -298.934632) (xy 49.812956 -298.937934)
			(xy 49.827688 -298.93514) (xy 49.835024 -298.933396) (xy 49.848318 -298.926294) (xy 49.85385 -298.92117)
			(xy 49.957228 -298.817792) (xy 49.976627 -298.799145) (xy 50.020714 -298.768305) (xy 50.069533 -298.745688)
			(xy 50.095404 -298.73829) (xy 50.102008 -298.736512) (xy 50.107596 -298.73321) (xy 50.118518 -298.725082)
			(xy 50.175414 -298.668186) (xy 50.182809 -298.661332) (xy 50.201408 -298.65359) (xy 50.211482 -298.6532)
			(xy 50.30978 -298.6532) (xy 50.319531 -298.652777) (xy 50.337623 -298.645501) (xy 50.351661 -298.631965)
			(xy 50.356008 -298.623228) (xy 50.394108 -298.5389) (xy 50.396877 -298.532216) (xy 50.398934 -298.517901)
			(xy 50.398172 -298.510706) (xy 50.397918 -298.510706) (xy 50.396653 -298.503601) (xy 50.390713 -298.490457)
			(xy 50.386234 -298.484798) (xy 50.38598 -298.484544) (xy 50.371155 -298.467055) (xy 50.346165 -298.428619)
			(xy 50.326956 -298.386991) (xy 50.313927 -298.343035) (xy 50.307349 -298.297663) (xy 50.306986 -298.27474)
			(xy 50.307355 -298.253719) (xy 50.312955 -298.212051) (xy 50.318162 -298.191682) (xy 50.31994 -298.185078)
			(xy 50.31994 -298.049696) (xy 50.319686 -297.91406) (xy 50.320179 -297.899034) (xy 50.327954 -297.870005)
			(xy 50.342967 -297.843972) (xy 50.364197 -297.822701) (xy 50.390201 -297.807639) (xy 50.419215 -297.799808)
			(xy 50.43424 -297.799252) (xy 50.815494 -297.799252) (xy 50.830538 -297.7997) (xy 50.859598 -297.807497)
			(xy 50.885644 -297.82256) (xy 50.906895 -297.843859) (xy 50.9219 -297.869938) (xy 50.929633 -297.899015)
			(xy 50.930048 -297.91406) (xy 50.930048 -298.185078) (xy 50.931826 -298.191682) (xy 50.93702 -298.212054)
			(xy 50.94262 -298.25372) (xy 50.943002 -298.27474) (xy 50.942599 -298.29766) (xy 50.936015 -298.343026)
			(xy 50.92299 -298.386978) (xy 50.903792 -298.428605) (xy 50.87882 -298.467047) (xy 50.864008 -298.484544)
			(xy 50.863754 -298.484798) (xy 50.859264 -298.490447) (xy 50.85335 -298.503603) (xy 50.85207 -298.510706)
			(xy 50.851816 -298.510706) (xy 50.851058 -298.5179) (xy 50.853126 -298.53221) (xy 50.85588 -298.5389)
			(xy 50.89398 -298.623228) (xy 50.898388 -298.631916) (xy 50.912431 -298.645396) (xy 50.930477 -298.652694)
			(xy 50.940208 -298.6532) (xy 52.2097 -298.6532) (xy 52.219449 -298.652773) (xy 52.237535 -298.645493)
			(xy 52.251567 -298.631957) (xy 52.255928 -298.623228) (xy 52.294028 -298.5389) (xy 52.296796 -298.532215)
			(xy 52.298852 -298.517901) (xy 52.298092 -298.510706) (xy 52.297838 -298.510706) (xy 52.296574 -298.503601)
			(xy 52.290635 -298.490455) (xy 52.286154 -298.484798) (xy 52.2859 -298.484544) (xy 52.271074 -298.467056)
			(xy 52.246082 -298.42862) (xy 52.226872 -298.386992) (xy 52.213843 -298.343036) (xy 52.207264 -298.297663)
			(xy 52.206906 -298.27474) (xy 52.207275 -298.253719) (xy 52.212876 -298.212051) (xy 52.218082 -298.191682)
			(xy 52.21986 -298.185078) (xy 52.21986 -298.049696) (xy 52.219606 -297.91406) (xy 52.220099 -297.899035)
			(xy 52.227875 -297.870008) (xy 52.242888 -297.843977) (xy 52.264118 -297.82271) (xy 52.290123 -297.807652)
			(xy 52.319136 -297.799825) (xy 52.33416 -297.799252) (xy 52.715414 -297.799252) (xy 52.730456 -297.799703)
			(xy 52.759512 -297.807503) (xy 52.785553 -297.822567) (xy 52.8068 -297.843865) (xy 52.821802 -297.869943)
			(xy 52.829533 -297.899017) (xy 52.829968 -297.91406) (xy 52.829968 -298.185078) (xy 52.831746 -298.191682)
			(xy 52.83694 -298.212054) (xy 52.84254 -298.25372) (xy 52.842922 -298.27474) (xy 52.842519 -298.297661)
			(xy 52.835936 -298.343027) (xy 52.822911 -298.386979) (xy 52.803714 -298.428607) (xy 52.778743 -298.46705)
			(xy 52.763928 -298.484544) (xy 52.763674 -298.484798) (xy 52.759182 -298.490447) (xy 52.753266 -298.503602)
			(xy 52.75199 -298.510706) (xy 52.751736 -298.510706) (xy 52.750978 -298.5179) (xy 52.753047 -298.53221)
			(xy 52.7558 -298.5389) (xy 52.7939 -298.623228) (xy 52.798303 -298.631925) (xy 52.812343 -298.645426)
			(xy 52.830391 -298.652752) (xy 52.840128 -298.6532) (xy 54.10962 -298.6532) (xy 54.119367 -298.65277)
			(xy 54.137447 -298.645485) (xy 54.151473 -298.631949) (xy 54.155848 -298.623228) (xy 54.193948 -298.5389)
			(xy 54.196715 -298.532215) (xy 54.19877 -298.517901) (xy 54.198012 -298.510706) (xy 54.197758 -298.510706)
			(xy 54.196494 -298.503601) (xy 54.190558 -298.490454) (xy 54.186074 -298.484798) (xy 54.18582 -298.484544)
			(xy 54.170998 -298.467054) (xy 54.146012 -298.428616) (xy 54.126807 -298.386988) (xy 54.113781 -298.343033)
			(xy 54.107204 -298.297662) (xy 54.106826 -298.27474) (xy 54.107195 -298.253719) (xy 54.112796 -298.212051)
			(xy 54.118002 -298.191682) (xy 54.11978 -298.185078) (xy 54.11978 -298.049696) (xy 54.119526 -297.91406)
			(xy 54.12002 -297.899036) (xy 54.127796 -297.870012) (xy 54.142809 -297.843983) (xy 54.16404 -297.822719)
			(xy 54.190045 -297.807665) (xy 54.219057 -297.799843) (xy 54.23408 -297.799252) (xy 54.615334 -297.799252)
			(xy 54.630374 -297.799705) (xy 54.659426 -297.807509) (xy 54.685462 -297.822574) (xy 54.706706 -297.843872)
			(xy 54.721704 -297.869947) (xy 54.729433 -297.899018) (xy 54.729888 -297.91406) (xy 54.729888 -298.185078)
			(xy 54.731666 -298.191682) (xy 54.736859 -298.212054) (xy 54.742459 -298.25372) (xy 54.742842 -298.27474)
			(xy 54.742439 -298.297661) (xy 54.735856 -298.343027) (xy 54.722832 -298.38698) (xy 54.703636 -298.428609)
			(xy 54.678666 -298.467053) (xy 54.663848 -298.484544) (xy 54.663594 -298.484798) (xy 54.659101 -298.490446)
			(xy 54.653182 -298.503601) (xy 54.65191 -298.510706) (xy 54.651656 -298.510706) (xy 54.650898 -298.5179)
			(xy 54.652967 -298.53221) (xy 54.65572 -298.5389) (xy 54.69382 -298.623228) (xy 54.698225 -298.631923)
			(xy 54.712265 -298.645419) (xy 54.730313 -298.652737) (xy 54.740048 -298.6532) (xy 56.00954 -298.6532)
			(xy 56.019285 -298.652766) (xy 56.037359 -298.645477) (xy 56.051379 -298.63194) (xy 56.055768 -298.623228)
			(xy 56.093868 -298.5389) (xy 56.096634 -298.532215) (xy 56.098689 -298.517902) (xy 56.097932 -298.510706)
			(xy 56.097678 -298.510706) (xy 56.096412 -298.503602) (xy 56.090468 -298.490461) (xy 56.085994 -298.484798)
			(xy 56.08574 -298.484544) (xy 56.067549 -298.462886) (xy 56.038344 -298.414456) (xy 56.018163 -298.361625)
			(xy 56.007641 -298.306058) (xy 56.006746 -298.277788) (xy 56.006746 -298.274232) (xy 56.007107 -298.253148)
			(xy 56.012716 -298.211354) (xy 56.017922 -298.19092) (xy 56.0197 -298.184316) (xy 56.0197 -297.91406)
			(xy 56.020196 -297.899014) (xy 56.027993 -297.869949) (xy 56.043046 -297.843891) (xy 56.06433 -297.822617)
			(xy 56.090393 -297.807575) (xy 56.119462 -297.799789) (xy 56.134508 -297.799252) (xy 56.515508 -297.799252)
			(xy 56.530559 -297.799744) (xy 56.559636 -297.807535) (xy 56.585707 -297.822585) (xy 56.606996 -297.843867)
			(xy 56.622053 -297.869934) (xy 56.629852 -297.899009) (xy 56.630316 -297.91406) (xy 56.630316 -298.18584)
			(xy 56.631078 -298.188634) (xy 56.632094 -298.192698) (xy 56.637073 -298.212649) (xy 56.642429 -298.253418)
			(xy 56.642762 -298.273978) (xy 56.642762 -298.27474) (xy 56.642359 -298.29766) (xy 56.635775 -298.343026)
			(xy 56.622748 -298.386976) (xy 56.603548 -298.428602) (xy 56.578573 -298.467042) (xy 56.563768 -298.484544)
			(xy 56.563514 -298.484798) (xy 56.559019 -298.490445) (xy 56.553099 -298.5036) (xy 56.55183 -298.510706)
			(xy 56.551576 -298.510706) (xy 56.550818 -298.5179) (xy 56.552884 -298.532211) (xy 56.55564 -298.5389)
			(xy 56.59374 -298.623228) (xy 56.598146 -298.631921) (xy 56.612187 -298.645411) (xy 56.630234 -298.652723)
			(xy 56.639968 -298.6532) (xy 57.909714 -298.6532) (xy 57.919462 -298.652771) (xy 57.937543 -298.645487)
			(xy 57.951571 -298.631951) (xy 57.955942 -298.623228) (xy 57.994042 -298.5389) (xy 57.996809 -298.532215)
			(xy 57.998865 -298.517901) (xy 57.998106 -298.510706) (xy 57.997852 -298.510706) (xy 57.996588 -298.503601)
			(xy 57.990651 -298.490454) (xy 57.986168 -298.484798) (xy 57.985914 -298.484544) (xy 57.967834 -298.46304)
			(xy 57.938765 -298.41497) (xy 57.918586 -298.362543) (xy 57.907923 -298.307388) (xy 57.90692 -298.279312)
			(xy 57.90692 -298.274486) (xy 57.907627 -298.243309) (xy 57.919785 -298.182153) (xy 57.93105 -298.153074)
			(xy 57.93486 -298.143676) (xy 57.93486 -297.91406) (xy 57.935356 -297.899012) (xy 57.943152 -297.869943)
			(xy 57.958204 -297.84388) (xy 57.979487 -297.822599) (xy 58.00555 -297.807549) (xy 58.03462 -297.799755)
			(xy 58.049668 -297.799252) (xy 58.430668 -297.799252) (xy 58.445723 -297.799739) (xy 58.474808 -297.807523)
			(xy 58.500889 -297.82257) (xy 58.522186 -297.843854) (xy 58.537249 -297.869925) (xy 58.545052 -297.899005)
			(xy 58.545476 -297.91406) (xy 58.545476 -298.21886) (xy 58.545382 -298.224487) (xy 58.544239 -298.235683)
			(xy 58.54319 -298.241212) (xy 58.542174 -298.252896) (xy 58.542936 -298.27474) (xy 58.542533 -298.297661)
			(xy 58.53595 -298.343027) (xy 58.522926 -298.386979) (xy 58.503729 -298.428608) (xy 58.478759 -298.467052)
			(xy 58.463942 -298.484544) (xy 58.463688 -298.484798) (xy 58.459195 -298.490446) (xy 58.453278 -298.503601)
			(xy 58.452004 -298.510706) (xy 58.45175 -298.510706) (xy 58.450992 -298.5179) (xy 58.453061 -298.53221)
			(xy 58.455814 -298.5389) (xy 58.493914 -298.623228) (xy 58.498318 -298.631924) (xy 58.512359 -298.645421)
			(xy 58.530406 -298.652742) (xy 58.540142 -298.6532) (xy 60.759594 -298.6532) (xy 60.769344 -298.652774)
			(xy 60.787431 -298.645495) (xy 60.801465 -298.63196) (xy 60.805822 -298.623228) (xy 60.843922 -298.5389)
			(xy 60.84669 -298.532215) (xy 60.848747 -298.517901) (xy 60.847986 -298.510706) (xy 60.847732 -298.510706)
			(xy 60.846468 -298.503601) (xy 60.840529 -298.490456) (xy 60.836048 -298.484798) (xy 60.835794 -298.484544)
			(xy 60.820968 -298.467056) (xy 60.795977 -298.42862) (xy 60.776767 -298.386992) (xy 60.763738 -298.343035)
			(xy 60.75716 -298.297663) (xy 60.7568 -298.27474) (xy 60.7568 -298.274486) (xy 60.757128 -298.2536)
			(xy 60.762607 -298.212189) (xy 60.767722 -298.191936) (xy 60.768738 -298.187872) (xy 60.7695 -298.185078)
			(xy 60.7695 -297.91406) (xy 60.769996 -297.899014) (xy 60.777793 -297.869949) (xy 60.792846 -297.843891)
			(xy 60.81413 -297.822617) (xy 60.840193 -297.807575) (xy 60.869262 -297.799789) (xy 60.884308 -297.799252)
			(xy 61.265308 -297.799252) (xy 61.280359 -297.799744) (xy 61.309436 -297.807535) (xy 61.335507 -297.822585)
			(xy 61.356796 -297.843867) (xy 61.371853 -297.869934) (xy 61.379652 -297.899009) (xy 61.380116 -297.91406)
			(xy 61.380116 -298.185078) (xy 61.380878 -298.187872) (xy 61.381894 -298.191936) (xy 61.386981 -298.212194)
			(xy 61.392459 -298.253602) (xy 61.392816 -298.274486) (xy 61.392816 -298.27474) (xy 61.392413 -298.297661)
			(xy 61.38583 -298.343027) (xy 61.372805 -298.386979) (xy 61.353607 -298.428607) (xy 61.328636 -298.467049)
			(xy 61.313822 -298.484544) (xy 61.313568 -298.484798) (xy 61.309077 -298.490447) (xy 61.303162 -298.503602)
			(xy 61.301884 -298.510706) (xy 61.30163 -298.510706) (xy 61.300872 -298.5179) (xy 61.30294 -298.53221)
			(xy 61.305694 -298.5389) (xy 61.343794 -298.623228) (xy 61.348197 -298.631926) (xy 61.362237 -298.645429)
			(xy 61.380285 -298.652757) (xy 61.390022 -298.6532) (xy 62.659768 -298.6532) (xy 62.66952 -298.652779)
			(xy 62.687616 -298.645505) (xy 62.701658 -298.631971) (xy 62.705996 -298.623228) (xy 62.744096 -298.5389)
			(xy 62.746865 -298.532216) (xy 62.748923 -298.517901) (xy 62.74816 -298.510706) (xy 62.747906 -298.510706)
			(xy 62.746641 -298.503602) (xy 62.7407 -298.490458) (xy 62.736222 -298.484798) (xy 62.735968 -298.484544)
			(xy 62.721144 -298.467055) (xy 62.696154 -298.428618) (xy 62.676946 -298.38699) (xy 62.663918 -298.343035)
			(xy 62.65734 -298.297663) (xy 62.656974 -298.27474) (xy 62.657343 -298.253719) (xy 62.662943 -298.212051)
			(xy 62.66815 -298.191682) (xy 62.669928 -298.185078) (xy 62.669928 -298.049696) (xy 62.669674 -297.91406)
			(xy 62.670167 -297.899034) (xy 62.677942 -297.870004) (xy 62.692954 -297.843968) (xy 62.714184 -297.822696)
			(xy 62.740188 -297.807632) (xy 62.769203 -297.799798) (xy 62.784228 -297.799252) (xy 63.165482 -297.799252)
			(xy 63.180527 -297.799699) (xy 63.20959 -297.807494) (xy 63.235638 -297.822556) (xy 63.256892 -297.843855)
			(xy 63.271899 -297.869935) (xy 63.279633 -297.899014) (xy 63.280036 -297.91406) (xy 63.280036 -298.185078)
			(xy 63.281814 -298.191682) (xy 63.287008 -298.212054) (xy 63.292609 -298.25372) (xy 63.29299 -298.27474)
			(xy 63.292587 -298.29766) (xy 63.286003 -298.343026) (xy 63.272977 -298.386977) (xy 63.253779 -298.428605)
			(xy 63.228806 -298.467046) (xy 63.213996 -298.484544) (xy 63.213742 -298.484798) (xy 63.209246 -298.490444)
			(xy 63.203322 -298.503599) (xy 63.202058 -298.510706) (xy 63.201804 -298.510706) (xy 63.201046 -298.5179)
			(xy 63.203114 -298.532211) (xy 63.205868 -298.5389) (xy 63.243968 -298.623228) (xy 63.248375 -298.631918)
			(xy 63.262418 -298.6454) (xy 63.280464 -298.652703) (xy 63.290196 -298.6532) (xy 64.559688 -298.6532)
			(xy 64.569438 -298.652775) (xy 64.587528 -298.645497) (xy 64.601563 -298.631962) (xy 64.605916 -298.623228)
			(xy 64.644016 -298.5389) (xy 64.646784 -298.532215) (xy 64.648841 -298.517901) (xy 64.64808 -298.510706)
			(xy 64.647826 -298.510706) (xy 64.646561 -298.503601) (xy 64.640622 -298.490456) (xy 64.636142 -298.484798)
			(xy 64.635888 -298.484544) (xy 64.621063 -298.467056) (xy 64.596072 -298.428619) (xy 64.576862 -298.386991)
			(xy 64.563833 -298.343035) (xy 64.557255 -298.297663) (xy 64.556894 -298.27474) (xy 64.557263 -298.253719)
			(xy 64.562863 -298.212051) (xy 64.56807 -298.191682) (xy 64.569848 -298.185078) (xy 64.569848 -298.049696)
			(xy 64.569594 -297.91406) (xy 64.570087 -297.899035) (xy 64.577863 -297.870007) (xy 64.592875 -297.843974)
			(xy 64.614105 -297.822705) (xy 64.64011 -297.807644) (xy 64.669124 -297.799815) (xy 64.684148 -297.799252)
			(xy 65.065402 -297.799252) (xy 65.080445 -297.799701) (xy 65.109503 -297.8075) (xy 65.135547 -297.822563)
			(xy 65.156797 -297.843861) (xy 65.171801 -297.86994) (xy 65.179533 -297.899016) (xy 65.179956 -297.91406)
			(xy 65.179956 -298.185078) (xy 65.181734 -298.191682) (xy 65.186928 -298.212054) (xy 65.192528 -298.25372)
			(xy 65.19291 -298.27474) (xy 65.192507 -298.297661) (xy 65.185924 -298.343027) (xy 65.172898 -298.386978)
			(xy 65.153701 -298.428606) (xy 65.128729 -298.467048) (xy 65.113916 -298.484544) (xy 65.113662 -298.484798)
			(xy 65.109171 -298.490447) (xy 65.103257 -298.503602) (xy 65.101978 -298.510706) (xy 65.101724 -298.510706)
			(xy 65.100966 -298.5179) (xy 65.103034 -298.53221) (xy 65.105788 -298.5389) (xy 65.143888 -298.623228)
			(xy 65.148291 -298.631927) (xy 65.16233 -298.645431) (xy 65.180378 -298.652761) (xy 65.190116 -298.6532)
			(xy 65.942718 -298.6532) (xy 65.95237 -298.652184) (xy 65.959613 -298.650555) (xy 65.97278 -298.643711)
			(xy 65.978278 -298.638722) (xy 66.127122 -298.489878) (xy 66.132109 -298.484379) (xy 66.138951 -298.471212)
			(xy 66.140584 -298.46397) (xy 66.1416 -298.454318) (xy 66.1416 -297.900344) (xy 66.141069 -297.890078)
			(xy 66.132936 -297.871218) (xy 66.125852 -297.863768) (xy 66.067686 -297.811952) (xy 66.063595 -297.808434)
			(xy 66.054241 -297.803058) (xy 66.049144 -297.801284) (xy 66.039492 -297.798236) (xy 66.02857 -297.799506)
			(xy 66.015616 -297.800268) (xy 65.634362 -297.800268) (xy 65.619321 -297.799815) (xy 65.590269 -297.79201)
			(xy 65.56423 -297.776945) (xy 65.542985 -297.755648) (xy 65.527983 -297.729573) (xy 65.520249 -297.700502)
			(xy 65.519808 -297.68546) (xy 65.519808 -297.414442) (xy 65.51803 -297.407838) (xy 65.512835 -297.387467)
			(xy 65.507233 -297.3458) (xy 65.506854 -297.32478) (xy 65.507346 -297.299791) (xy 65.515166 -297.250428)
			(xy 65.530612 -297.202896) (xy 65.553302 -297.158365) (xy 65.582678 -297.117931) (xy 65.618017 -297.08259)
			(xy 65.658449 -297.053211) (xy 65.702979 -297.030519) (xy 65.75051 -297.015071) (xy 65.799873 -297.007247)
			(xy 65.824862 -297.006772) (xy 65.824862 -297.006518) (xy 65.853468 -297.007189) (xy 65.909751 -297.01746)
			(xy 65.963299 -297.037605) (xy 65.988184 -297.05173) (xy 65.988438 -297.05173) (xy 65.994269 -297.055038)
			(xy 66.007142 -297.058768) (xy 66.013838 -297.059096) (xy 66.027046 -297.059096) (xy 66.115692 -297.008804)
			(xy 66.121026 -297.005502) (xy 66.130042 -296.998134) (xy 66.140763 -296.977492) (xy 66.1416 -296.965878)
			(xy 66.1416 -294.835072) (xy 66.1416 -294.833802) (xy 66.140745 -294.822192) (xy 66.130038 -294.801547)
			(xy 66.121026 -294.794178) (xy 66.115692 -294.790876) (xy 66.038984 -294.747188) (xy 66.033029 -294.744118)
			(xy 66.020029 -294.740899) (xy 66.01333 -294.740838) (xy 65.999868 -294.740838) (xy 65.98793 -294.74795)
			(xy 65.963083 -294.762036) (xy 65.909609 -294.782088) (xy 65.853417 -294.792283) (xy 65.824862 -294.792908)
			(xy 65.799875 -294.792415) (xy 65.750516 -294.784592) (xy 65.702989 -294.769144) (xy 65.658463 -294.746453)
			(xy 65.618035 -294.717075) (xy 65.5827 -294.681736) (xy 65.553328 -294.641304) (xy 65.530641 -294.596776)
			(xy 65.515199 -294.549247) (xy 65.507382 -294.499887) (xy 65.506854 -294.4749) (xy 65.507226 -294.453879)
			(xy 65.51283 -294.412213) (xy 65.51803 -294.391842) (xy 65.519808 -294.385238) (xy 65.519808 -294.249856)
			(xy 65.519554 -294.11422) (xy 65.52004 -294.099187) (xy 65.527805 -294.070142) (xy 65.542812 -294.044091)
			(xy 65.564042 -294.022803) (xy 65.590053 -294.007725) (xy 65.619077 -293.999881) (xy 65.634108 -293.999412)
			(xy 66.015616 -293.999412) (xy 66.02857 -294.000174) (xy 66.039492 -294.001444) (xy 66.049144 -293.998396)
			(xy 66.054236 -293.996614) (xy 66.063585 -293.991233) (xy 66.067686 -293.987728) (xy 66.125852 -293.935912)
			(xy 66.132978 -293.92849) (xy 66.141116 -293.909613) (xy 66.1416 -293.899336) (xy 66.1416 -293.543482)
			(xy 66.141436 -293.537471) (xy 66.138619 -293.525786) (xy 66.136012 -293.520368) (xy 66.134172 -293.516894)
			(xy 66.129578 -293.510516) (xy 66.126868 -293.507668) (xy 65.92824 -293.30904) (xy 65.920834 -293.302345)
			(xy 65.902398 -293.294742) (xy 65.892426 -293.294308) (xy 65.273936 -293.294308) (xy 65.26261 -293.294921)
			(xy 65.242174 -293.30469) (xy 65.234566 -293.313104) (xy 65.184528 -293.382192) (xy 65.181169 -293.387071)
			(xy 65.176548 -293.397974) (xy 65.175384 -293.403782) (xy 65.173606 -293.415212) (xy 65.177416 -293.42715)
			(xy 65.184624 -293.450954) (xy 65.192404 -293.500074) (xy 65.19291 -293.52494) (xy 65.192536 -293.54596)
			(xy 65.186925 -293.587625) (xy 65.181734 -293.607998) (xy 65.179956 -293.614602) (xy 65.179956 -293.749984)
			(xy 65.18021 -293.88562) (xy 65.179719 -293.900647) (xy 65.171947 -293.92968) (xy 65.156936 -293.955718)
			(xy 65.135706 -293.976992) (xy 65.109699 -293.992056) (xy 65.080682 -293.999888) (xy 65.065656 -294.000428)
			(xy 64.684402 -294.000428) (xy 64.669359 -293.999979) (xy 64.640302 -293.992181) (xy 64.61426 -293.977118)
			(xy 64.593012 -293.955818) (xy 64.578012 -293.92974) (xy 64.570285 -293.900664) (xy 64.569848 -293.88562)
			(xy 64.569848 -293.614602) (xy 64.56807 -293.607998) (xy 64.562871 -293.587627) (xy 64.55726 -293.545961)
			(xy 64.556894 -293.52494) (xy 64.557396 -293.500074) (xy 64.565183 -293.450955) (xy 64.572388 -293.42715)
			(xy 64.572388 -293.426896) (xy 64.574055 -293.421146) (xy 64.574948 -293.40921) (xy 64.574166 -293.403274)
			(xy 64.572388 -293.391844) (xy 64.515238 -293.313104) (xy 64.507616 -293.304717) (xy 64.487183 -293.294983)
			(xy 64.475868 -293.294308) (xy 63.374016 -293.294308) (xy 63.362682 -293.294904) (xy 63.34222 -293.304653)
			(xy 63.334646 -293.313104) (xy 63.284608 -293.382192) (xy 63.28125 -293.387071) (xy 63.276631 -293.397975)
			(xy 63.275464 -293.403782) (xy 63.273686 -293.415212) (xy 63.277496 -293.42715) (xy 63.284705 -293.450953)
			(xy 63.292485 -293.500074) (xy 63.29299 -293.52494) (xy 63.29299 -293.525448) (xy 63.29299 -293.531036)
			(xy 63.292317 -293.550714) (xy 63.286713 -293.589689) (xy 63.281814 -293.60876) (xy 63.280036 -293.615364)
			(xy 63.280036 -293.88562) (xy 63.279543 -293.90067) (xy 63.271749 -293.929743) (xy 63.256699 -293.955809)
			(xy 63.235416 -293.977094) (xy 63.20935 -293.992146) (xy 63.180278 -293.999942) (xy 63.165228 -294.000428)
			(xy 62.784228 -294.000428) (xy 62.769169 -293.999985) (xy 62.740075 -293.992196) (xy 62.713988 -293.977143)
			(xy 62.692687 -293.95585) (xy 62.677622 -293.92977) (xy 62.669822 -293.900679) (xy 62.66942 -293.88562)
			(xy 62.66942 -293.61384) (xy 62.668658 -293.611046) (xy 62.667642 -293.606982) (xy 62.662664 -293.587031)
			(xy 62.65731 -293.546262) (xy 62.656974 -293.525702) (xy 62.656974 -293.52494) (xy 62.657476 -293.500074)
			(xy 62.665262 -293.450954) (xy 62.672468 -293.42715) (xy 62.672468 -293.426896) (xy 62.674136 -293.421146)
			(xy 62.675029 -293.40921) (xy 62.674246 -293.403274) (xy 62.672468 -293.391844) (xy 62.615318 -293.313104)
			(xy 62.607701 -293.304704) (xy 62.587268 -293.294938) (xy 62.575948 -293.294308) (xy 61.473842 -293.294308)
			(xy 61.462515 -293.29492) (xy 61.442077 -293.304687) (xy 61.434472 -293.313104) (xy 61.384434 -293.382192)
			(xy 61.381074 -293.38707) (xy 61.376453 -293.397974) (xy 61.37529 -293.403782) (xy 61.373512 -293.415212)
			(xy 61.377322 -293.42715) (xy 61.38453 -293.450954) (xy 61.39231 -293.500074) (xy 61.392816 -293.52494)
			(xy 61.392816 -293.525194) (xy 61.392489 -293.54608) (xy 61.387013 -293.587492) (xy 61.381894 -293.607744)
			(xy 61.380878 -293.611808) (xy 61.380116 -293.614602) (xy 61.380116 -293.88562) (xy 61.379623 -293.900669)
			(xy 61.371829 -293.92974) (xy 61.356778 -293.955804) (xy 61.335494 -293.977085) (xy 61.309429 -293.992134)
			(xy 61.280357 -293.999924) (xy 61.265308 -294.000428) (xy 60.884308 -294.000428) (xy 60.869256 -293.999938)
			(xy 60.840178 -293.992149) (xy 60.814106 -293.9771) (xy 60.792817 -293.955816) (xy 60.777762 -293.929748)
			(xy 60.769966 -293.900672) (xy 60.7695 -293.88562) (xy 60.7695 -293.614602) (xy 60.768738 -293.611808)
			(xy 60.767722 -293.607744) (xy 60.762636 -293.587486) (xy 60.757161 -293.546078) (xy 60.7568 -293.525194)
			(xy 60.7568 -293.52494) (xy 60.757301 -293.500074) (xy 60.765086 -293.450954) (xy 60.772294 -293.42715)
			(xy 60.772294 -293.426896) (xy 60.773961 -293.421146) (xy 60.774854 -293.40921) (xy 60.774072 -293.403274)
			(xy 60.772294 -293.391844) (xy 60.715144 -293.313104) (xy 60.707523 -293.304716) (xy 60.687089 -293.294979)
			(xy 60.675774 -293.294308) (xy 58.623962 -293.294308) (xy 58.612633 -293.294915) (xy 58.592189 -293.304678)
			(xy 58.584592 -293.313104) (xy 58.534554 -293.382192) (xy 58.531193 -293.38707) (xy 58.52657 -293.397973)
			(xy 58.52541 -293.403782) (xy 58.523632 -293.415212) (xy 58.527442 -293.42715) (xy 58.53465 -293.450954)
			(xy 58.542429 -293.500074) (xy 58.542936 -293.52494) (xy 58.542936 -293.525194) (xy 58.542609 -293.54608)
			(xy 58.537134 -293.587492) (xy 58.532014 -293.607744) (xy 58.530998 -293.611808) (xy 58.530236 -293.614602)
			(xy 58.530236 -293.88562) (xy 58.529743 -293.90067) (xy 58.521949 -293.929743) (xy 58.506899 -293.955809)
			(xy 58.485616 -293.977094) (xy 58.45955 -293.992146) (xy 58.430478 -293.999942) (xy 58.415428 -294.000428)
			(xy 58.034428 -294.000428) (xy 58.019369 -293.999985) (xy 57.990275 -293.992196) (xy 57.964188 -293.977143)
			(xy 57.942887 -293.95585) (xy 57.927822 -293.92977) (xy 57.920022 -293.900679) (xy 57.91962 -293.88562)
			(xy 57.91962 -293.614602) (xy 57.918858 -293.611808) (xy 57.917842 -293.607744) (xy 57.912755 -293.587486)
			(xy 57.90728 -293.546078) (xy 57.90692 -293.525194) (xy 57.90692 -293.52494) (xy 57.907421 -293.500074)
			(xy 57.915207 -293.450954) (xy 57.922414 -293.42715) (xy 57.922414 -293.426896) (xy 57.924081 -293.421146)
			(xy 57.924973 -293.40921) (xy 57.924192 -293.403274) (xy 57.922414 -293.391844) (xy 57.865264 -293.313104)
			(xy 57.857644 -293.304713) (xy 57.837211 -293.294968) (xy 57.825894 -293.294308) (xy 56.723788 -293.294308)
			(xy 56.712457 -293.29491) (xy 56.692004 -293.304666) (xy 56.684418 -293.313104) (xy 56.63438 -293.382192)
			(xy 56.631018 -293.38707) (xy 56.626393 -293.397972) (xy 56.625236 -293.403782) (xy 56.623458 -293.415212)
			(xy 56.627268 -293.42715) (xy 56.634477 -293.450954) (xy 56.642258 -293.500074) (xy 56.642762 -293.52494)
			(xy 56.642762 -293.525702) (xy 56.642405 -293.54626) (xy 56.637058 -293.587029) (xy 56.632094 -293.606982)
			(xy 56.631078 -293.611046) (xy 56.630316 -293.61384) (xy 56.630316 -293.88562) (xy 56.629823 -293.900669)
			(xy 56.622029 -293.92974) (xy 56.606978 -293.955804) (xy 56.585694 -293.977085) (xy 56.559629 -293.992134)
			(xy 56.530557 -293.999924) (xy 56.515508 -294.000428) (xy 56.134508 -294.000428) (xy 56.119456 -293.999938)
			(xy 56.090378 -293.992149) (xy 56.064306 -293.9771) (xy 56.043017 -293.955816) (xy 56.027962 -293.929748)
			(xy 56.020166 -293.900672) (xy 56.0197 -293.88562) (xy 56.0197 -293.615364) (xy 56.017922 -293.60876)
			(xy 56.012852 -293.588946) (xy 56.007241 -293.548434) (xy 56.006746 -293.527988) (xy 56.006746 -293.521892)
			(xy 56.007439 -293.497793) (xy 56.015217 -293.450214) (xy 56.02224 -293.42715) (xy 56.02224 -293.426896)
			(xy 56.023906 -293.421146) (xy 56.024798 -293.40921) (xy 56.024018 -293.403274) (xy 56.02224 -293.391844)
			(xy 55.96509 -293.313104) (xy 55.957472 -293.304709) (xy 55.937038 -293.294954) (xy 55.92572 -293.294308)
			(xy 54.823868 -293.294308) (xy 54.812539 -293.294914) (xy 54.792092 -293.304675) (xy 54.784498 -293.313104)
			(xy 54.73446 -293.382192) (xy 54.731099 -293.38707) (xy 54.726475 -293.397973) (xy 54.725316 -293.403782)
			(xy 54.723538 -293.415212) (xy 54.727348 -293.42715) (xy 54.734555 -293.450954) (xy 54.742334 -293.500074)
			(xy 54.742842 -293.52494) (xy 54.742468 -293.54596) (xy 54.736858 -293.587626) (xy 54.731666 -293.607998)
			(xy 54.729888 -293.614602) (xy 54.729888 -293.749984) (xy 54.730142 -293.88562) (xy 54.729652 -293.900649)
			(xy 54.72188 -293.929685) (xy 54.70687 -293.955727) (xy 54.68564 -293.977006) (xy 54.659633 -293.992077)
			(xy 54.630616 -293.999916) (xy 54.615588 -294.000428) (xy 54.234334 -294.000428) (xy 54.219289 -293.999983)
			(xy 54.190225 -293.99219) (xy 54.164175 -293.977129) (xy 54.14292 -293.955829) (xy 54.127915 -293.929747)
			(xy 54.120185 -293.900666) (xy 54.11978 -293.88562) (xy 54.11978 -293.614602) (xy 54.118002 -293.607998)
			(xy 54.112802 -293.587627) (xy 54.107191 -293.545961) (xy 54.106826 -293.52494) (xy 54.107327 -293.500074)
			(xy 54.115113 -293.450954) (xy 54.12232 -293.42715) (xy 54.12232 -293.426896) (xy 54.123986 -293.421146)
			(xy 54.124879 -293.40921) (xy 54.124098 -293.403274) (xy 54.12232 -293.391844) (xy 54.06517 -293.313104)
			(xy 54.05755 -293.304712) (xy 54.037117 -293.294965) (xy 54.0258 -293.294308) (xy 52.923948 -293.294308)
			(xy 52.912621 -293.294918) (xy 52.892181 -293.304684) (xy 52.884578 -293.313104) (xy 52.83454 -293.382192)
			(xy 52.83118 -293.38707) (xy 52.826558 -293.397974) (xy 52.825396 -293.403782) (xy 52.823618 -293.415212)
			(xy 52.827428 -293.42715) (xy 52.834636 -293.450954) (xy 52.842415 -293.500074) (xy 52.842922 -293.52494)
			(xy 52.842548 -293.54596) (xy 52.836937 -293.587626) (xy 52.831746 -293.607998) (xy 52.829968 -293.614602)
			(xy 52.829968 -293.749984) (xy 52.830222 -293.88562) (xy 52.829731 -293.900648) (xy 52.821959 -293.929682)
			(xy 52.806949 -293.955721) (xy 52.785719 -293.976997) (xy 52.759712 -293.992064) (xy 52.730695 -293.999899)
			(xy 52.715668 -294.000428) (xy 52.334414 -294.000428) (xy 52.31937 -293.999981) (xy 52.290311 -293.992185)
			(xy 52.264266 -293.977122) (xy 52.243015 -293.955822) (xy 52.228013 -293.929742) (xy 52.220285 -293.900665)
			(xy 52.21986 -293.88562) (xy 52.21986 -293.614602) (xy 52.218082 -293.607998) (xy 52.212883 -293.587627)
			(xy 52.207272 -293.545961) (xy 52.206906 -293.52494) (xy 52.207407 -293.500074) (xy 52.215192 -293.450954)
			(xy 52.2224 -293.42715) (xy 52.2224 -293.426896) (xy 52.224067 -293.421146) (xy 52.22496 -293.40921)
			(xy 52.224178 -293.403274) (xy 52.2224 -293.391844) (xy 52.16525 -293.313104) (xy 52.157629 -293.304715)
			(xy 52.137196 -293.294976) (xy 52.12588 -293.294308) (xy 51.024028 -293.294308) (xy 51.012703 -293.294922)
			(xy 50.992269 -293.304693) (xy 50.984658 -293.313104) (xy 50.93462 -293.382192) (xy 50.931261 -293.387071)
			(xy 50.926641 -293.397974) (xy 50.925476 -293.403782) (xy 50.923698 -293.415212) (xy 50.927508 -293.42715)
			(xy 50.934716 -293.450954) (xy 50.942496 -293.500074) (xy 50.943002 -293.52494) (xy 50.942628 -293.54596)
			(xy 50.937017 -293.587625) (xy 50.931826 -293.607998) (xy 50.930048 -293.614602) (xy 50.930048 -293.749984)
			(xy 50.930302 -293.88562) (xy 50.929811 -293.900647) (xy 50.922039 -293.929679) (xy 50.907028 -293.955716)
			(xy 50.885797 -293.976988) (xy 50.85979 -293.992051) (xy 50.830774 -293.999881) (xy 50.815748 -294.000428)
			(xy 50.434494 -294.000428) (xy 50.419452 -293.999978) (xy 50.390397 -293.992179) (xy 50.364356 -293.977115)
			(xy 50.34311 -293.955816) (xy 50.328111 -293.929738) (xy 50.320384 -293.900663) (xy 50.31994 -293.88562)
			(xy 50.31994 -293.614602) (xy 50.318162 -293.607998) (xy 50.312963 -293.587627) (xy 50.307353 -293.545961)
			(xy 50.306986 -293.52494) (xy 50.307584 -293.496325) (xy 50.31782 -293.440019) (xy 50.337986 -293.386461)
			(xy 50.352198 -293.361618) (xy 50.356516 -293.354252) (xy 50.360072 -293.337742) (xy 50.359056 -293.32936)
			(xy 50.357604 -293.321016) (xy 50.350077 -293.305858) (xy 50.344324 -293.299642) (xy 49.900078 -292.855396)
			(xy 49.893909 -292.849577) (xy 49.878726 -292.842045) (xy 49.87036 -292.840664) (xy 49.861978 -292.839648)
			(xy 49.845468 -292.843204) (xy 49.838102 -292.847522) (xy 49.813224 -292.861657) (xy 49.759671 -292.881793)
			(xy 49.703386 -292.892051) (xy 49.67478 -292.892734) (xy 49.65376 -292.892361) (xy 49.612094 -292.886754)
			(xy 49.591722 -292.881558) (xy 49.585118 -292.87978) (xy 49.308766 -292.87978) (xy 49.29423 -292.878664)
			(xy 49.266392 -292.870036) (xy 49.241603 -292.85471) (xy 49.221444 -292.833662) (xy 49.2072 -292.808235)
			(xy 49.199781 -292.78005) (xy 49.199292 -292.76548) (xy 49.199292 -292.384226) (xy 49.199776 -292.36923)
			(xy 49.207525 -292.340257) (xy 49.222501 -292.314272) (xy 49.243686 -292.293044) (xy 49.26964 -292.278015)
			(xy 49.298597 -292.270207) (xy 49.313592 -292.269672) (xy 49.585118 -292.269672) (xy 49.591722 -292.267894)
			(xy 49.612093 -292.262696) (xy 49.653759 -292.257087) (xy 49.67478 -292.256718) (xy 49.675288 -292.256718)
			(xy 49.702372 -292.257262) (xy 49.755755 -292.266457) (xy 49.78146 -292.275006) (xy 49.788064 -292.277292)
			(xy 49.800256 -292.275514) (xy 49.80626 -292.274416) (xy 49.817552 -292.26979) (xy 49.822608 -292.26637)
			(xy 49.854866 -292.243256) (xy 49.864247 -292.235644) (xy 49.875241 -292.214169) (xy 49.875948 -292.202108)
			(xy 49.875948 -291.047424) (xy 49.875275 -291.035355) (xy 49.864268 -291.013873) (xy 49.854866 -291.006276)
			(xy 49.822608 -290.983162) (xy 49.817576 -290.979699) (xy 49.806272 -290.97508) (xy 49.800256 -290.974018)
			(xy 49.788064 -290.97224) (xy 49.78146 -290.974526) (xy 49.755741 -290.983025) (xy 49.702368 -290.992226)
			(xy 49.675288 -290.992814) (xy 49.67478 -290.992814) (xy 49.65376 -290.992441) (xy 49.612094 -290.986833)
			(xy 49.591722 -290.981638) (xy 49.585118 -290.97986) (xy 49.308766 -290.97986) (xy 49.294231 -290.978743)
			(xy 49.266395 -290.970115) (xy 49.241609 -290.954788) (xy 49.221453 -290.93374) (xy 49.207213 -290.908313)
			(xy 49.199799 -290.880129) (xy 49.199292 -290.86556) (xy 49.199292 -290.484306) (xy 49.199779 -290.469312)
			(xy 49.20753 -290.440343) (xy 49.222508 -290.414363) (xy 49.243693 -290.393139) (xy 49.269645 -290.378113)
			(xy 49.298599 -290.370307) (xy 49.313592 -290.369752) (xy 49.585118 -290.369752) (xy 49.591722 -290.367974)
			(xy 49.612093 -290.362776) (xy 49.65376 -290.357168) (xy 49.67478 -290.356798) (xy 49.702652 -290.357375)
			(xy 49.757544 -290.36709) (xy 49.809901 -290.386224) (xy 49.834292 -290.399724) (xy 49.840134 -290.403026)
			(xy 49.853088 -290.406582) (xy 49.859692 -290.406582) (xy 49.869713 -290.406164) (xy 49.88823 -290.398495)
			(xy 49.9024 -290.384321) (xy 49.910066 -290.365803) (xy 49.910492 -290.355782) (xy 49.910492 -290.31819)
			(xy 49.911 -290.317936) (xy 49.911 -290.241482) (xy 49.910836 -290.235471) (xy 49.908019 -290.223786)
			(xy 49.905412 -290.218368) (xy 49.903572 -290.214894) (xy 49.898978 -290.208516) (xy 49.896268 -290.205668)
			(xy 49.747932 -290.057332) (xy 49.744315 -290.053897) (xy 49.735998 -290.048395) (xy 49.731422 -290.04641)
			(xy 49.722278 -290.0426) (xy 49.717198 -290.0426) (xy 49.707546 -290.043616) (xy 49.67478 -290.04514)
			(xy 49.674526 -290.04514) (xy 49.664977 -290.045072) (xy 49.645914 -290.04393) (xy 49.636426 -290.042854)
			(xy 49.633378 -290.0426) (xy 48.766222 -290.0426) (xy 48.763174 -290.042854) (xy 48.753622 -290.043925)
			(xy 48.734432 -290.045068) (xy 48.72482 -290.04514) (xy 48.715208 -290.045077) (xy 48.696018 -290.043931)
			(xy 48.686466 -290.042854) (xy 48.683418 -290.0426) (xy 48.204882 -290.0426) (xy 48.198871 -290.042764)
			(xy 48.187186 -290.045581) (xy 48.181768 -290.048188) (xy 48.178294 -290.050028) (xy 48.171916 -290.054622)
			(xy 48.169068 -290.057332) (xy 48.122332 -290.104068) (xy 48.119625 -290.106918) (xy 48.115028 -290.113295)
			(xy 48.113188 -290.116768) (xy 48.110608 -290.122196) (xy 48.107791 -290.133875) (xy 48.1076 -290.139882)
			(xy 48.1076 -291.649795) (xy 48.407223 -291.649795) (xy 48.407223 -291.599805) (xy 48.415043 -291.550431)
			(xy 48.430491 -291.502888) (xy 48.453187 -291.458347) (xy 48.482571 -291.417905) (xy 48.517921 -291.382558)
			(xy 48.558364 -291.353177) (xy 48.602906 -291.330484) (xy 48.65045 -291.315038) (xy 48.699825 -291.307221)
			(xy 48.72482 -291.306758) (xy 48.74584 -291.307129) (xy 48.787507 -291.312737) (xy 48.807878 -291.317934)
			(xy 48.814482 -291.319712) (xy 49.0855 -291.319712) (xy 49.100531 -291.32018) (xy 49.129571 -291.327951)
			(xy 49.155615 -291.342964) (xy 49.176893 -291.364199) (xy 49.191959 -291.390212) (xy 49.199789 -291.419236)
			(xy 49.200308 -291.434266) (xy 49.200308 -291.815266) (xy 49.199837 -291.830264) (xy 49.192089 -291.859242)
			(xy 49.177112 -291.885231) (xy 49.155924 -291.906464) (xy 49.129967 -291.921496) (xy 49.101005 -291.929305)
			(xy 49.086008 -291.92982) (xy 48.814482 -291.92982) (xy 48.807878 -291.931598) (xy 48.787506 -291.936792)
			(xy 48.74584 -291.942401) (xy 48.72482 -291.942774) (xy 48.699825 -291.942379) (xy 48.65045 -291.934562)
			(xy 48.602906 -291.919116) (xy 48.558364 -291.896423) (xy 48.517921 -291.867042) (xy 48.482571 -291.831695)
			(xy 48.453187 -291.791253) (xy 48.430491 -291.746712) (xy 48.415043 -291.699169) (xy 48.407223 -291.649795)
			(xy 48.1076 -291.649795) (xy 48.1076 -293.52494) (xy 48.406812 -293.52494) (xy 48.407302 -293.499951)
			(xy 48.415121 -293.450588) (xy 48.430565 -293.403056) (xy 48.453255 -293.358524) (xy 48.482631 -293.318091)
			(xy 48.517971 -293.282751) (xy 48.558404 -293.253375) (xy 48.602936 -293.230685) (xy 48.650468 -293.215241)
			(xy 48.699831 -293.207422) (xy 48.749809 -293.207422) (xy 48.799172 -293.215241) (xy 48.846704 -293.230685)
			(xy 48.891236 -293.253375) (xy 48.931669 -293.282751) (xy 48.967009 -293.318091) (xy 48.996385 -293.358524)
			(xy 49.019075 -293.403056) (xy 49.034519 -293.450588) (xy 49.042338 -293.499951) (xy 49.042828 -293.52494)
			(xy 49.042461 -293.545961) (xy 49.036851 -293.587627) (xy 49.031652 -293.607998) (xy 49.030128 -293.614602)
			(xy 49.030128 -293.88562) (xy 49.029635 -293.900669) (xy 49.021841 -293.929742) (xy 49.00679 -293.955807)
			(xy 48.985507 -293.97709) (xy 48.959442 -293.992141) (xy 48.930369 -293.999935) (xy 48.91532 -294.000428)
			(xy 48.53432 -294.000428) (xy 48.519272 -293.9999) (xy 48.490201 -293.992116) (xy 48.464136 -293.977073)
			(xy 48.442852 -293.955796) (xy 48.4278 -293.929736) (xy 48.420005 -293.900667) (xy 48.419512 -293.88562)
			(xy 48.419512 -293.614602) (xy 48.417988 -293.607998) (xy 48.412797 -293.587625) (xy 48.407186 -293.54596)
			(xy 48.406812 -293.52494) (xy 48.1076 -293.52494) (xy 48.1076 -294.4749) (xy 49.356772 -294.4749)
			(xy 49.357147 -294.45388) (xy 49.362752 -294.412213) (xy 49.367948 -294.391842) (xy 49.369472 -294.385238)
			(xy 49.369472 -294.11422) (xy 49.37 -294.099172) (xy 49.377784 -294.070101) (xy 49.392827 -294.044036)
			(xy 49.414104 -294.022752) (xy 49.440164 -294.0077) (xy 49.469233 -293.999905) (xy 49.48428 -293.999412)
			(xy 49.86528 -293.999412) (xy 49.880337 -293.999857) (xy 49.909425 -294.007647) (xy 49.935504 -294.022703)
			(xy 49.956797 -294.043996) (xy 49.971853 -294.070075) (xy 49.979643 -294.099163) (xy 49.980088 -294.11422)
			(xy 49.980088 -294.385238) (xy 49.981612 -294.391842) (xy 49.98681 -294.412213) (xy 49.992416 -294.45388)
			(xy 49.992788 -294.4749) (xy 51.256946 -294.4749) (xy 51.257322 -294.45388) (xy 51.262926 -294.412213)
			(xy 51.268122 -294.391842) (xy 51.2699 -294.385238) (xy 51.2699 -294.11422) (xy 51.270397 -294.099191)
			(xy 51.278162 -294.070154) (xy 51.293169 -294.044111) (xy 51.314399 -294.022832) (xy 51.340407 -294.007765)
			(xy 51.369426 -293.999933) (xy 51.384454 -293.999412) (xy 51.765454 -293.999412) (xy 51.780493 -293.999934)
			(xy 51.809546 -294.007719) (xy 51.835588 -294.022767) (xy 51.856839 -294.044051) (xy 51.871848 -294.070116)
			(xy 51.879588 -294.09918) (xy 51.880008 -294.11422) (xy 51.880008 -294.385238) (xy 51.881786 -294.391842)
			(xy 51.886986 -294.412213) (xy 51.89259 -294.453879) (xy 51.892962 -294.4749) (xy 51.892472 -294.499889)
			(xy 51.884653 -294.549252) (xy 51.869209 -294.596784) (xy 51.846519 -294.641316) (xy 51.817143 -294.681749)
			(xy 51.781803 -294.717089) (xy 51.74137 -294.746465) (xy 51.696838 -294.769155) (xy 51.649306 -294.784599)
			(xy 51.599943 -294.792418) (xy 51.549965 -294.792418) (xy 51.500602 -294.784599) (xy 51.45307 -294.769155)
			(xy 51.408538 -294.746465) (xy 51.368105 -294.717089) (xy 51.332765 -294.681749) (xy 51.303389 -294.641316)
			(xy 51.280699 -294.596784) (xy 51.265255 -294.549252) (xy 51.257436 -294.499889) (xy 51.256946 -294.4749)
			(xy 49.992788 -294.4749) (xy 49.992298 -294.499889) (xy 49.984479 -294.549252) (xy 49.969035 -294.596784)
			(xy 49.946345 -294.641316) (xy 49.916969 -294.681749) (xy 49.881629 -294.717089) (xy 49.841196 -294.746465)
			(xy 49.796664 -294.769155) (xy 49.749132 -294.784599) (xy 49.699769 -294.792418) (xy 49.649791 -294.792418)
			(xy 49.600428 -294.784599) (xy 49.552896 -294.769155) (xy 49.508364 -294.746465) (xy 49.467931 -294.717089)
			(xy 49.432591 -294.681749) (xy 49.403215 -294.641316) (xy 49.380525 -294.596784) (xy 49.365081 -294.549252)
			(xy 49.357262 -294.499889) (xy 49.356772 -294.4749) (xy 48.1076 -294.4749) (xy 48.1076 -295.577514)
			(xy 52.37226 -295.577514) (xy 52.37226 -294.866314) (xy 52.372746 -294.851318) (xy 52.380495 -294.822344)
			(xy 52.395471 -294.796358) (xy 52.416655 -294.775126) (xy 52.442608 -294.760093) (xy 52.471565 -294.752279)
			(xy 52.48656 -294.75176) (xy 52.964842 -294.75176) (xy 52.974915 -294.751367) (xy 52.993513 -294.743625)
			(xy 53.00091 -294.736774) (xy 53.124354 -294.61333) (xy 53.127777 -294.609705) (xy 53.133271 -294.601386)
			(xy 53.135276 -294.59682) (xy 53.159152 -294.539416) (xy 53.16093 -294.5257) (xy 53.159914 -294.519096)
			(xy 53.158498 -294.508229) (xy 53.15697 -294.486366) (xy 53.156866 -294.475408) (xy 53.156866 -294.4749)
			(xy 53.157241 -294.45388) (xy 53.162846 -294.412213) (xy 53.168042 -294.391842) (xy 53.16982 -294.385238)
			(xy 53.16982 -294.11422) (xy 53.170298 -294.099189) (xy 53.178064 -294.070149) (xy 53.193075 -294.044104)
			(xy 53.214308 -294.022825) (xy 53.240321 -294.007759) (xy 53.269345 -293.99993) (xy 53.284374 -293.999412)
			(xy 53.665374 -293.999412) (xy 53.680414 -293.999917) (xy 53.709467 -294.007706) (xy 53.735509 -294.022758)
			(xy 53.75676 -294.044046) (xy 53.771769 -294.070113) (xy 53.779508 -294.09918) (xy 53.779928 -294.11422)
			(xy 53.779928 -294.385238) (xy 53.781706 -294.391842) (xy 53.786904 -294.412213) (xy 53.79251 -294.45388)
			(xy 53.792882 -294.4749) (xy 55.056786 -294.4749) (xy 55.05716 -294.45388) (xy 55.062766 -294.412213)
			(xy 55.067962 -294.391842) (xy 55.06974 -294.385238) (xy 55.06974 -294.11422) (xy 55.070198 -294.099188)
			(xy 55.077966 -294.070145) (xy 55.09298 -294.044097) (xy 55.114217 -294.022818) (xy 55.140235 -294.007753)
			(xy 55.169263 -293.999928) (xy 55.184294 -293.999412) (xy 55.565294 -293.999412) (xy 55.580335 -293.9999)
			(xy 55.609389 -294.007693) (xy 55.635431 -294.02275) (xy 55.656681 -294.04404) (xy 55.671689 -294.07011)
			(xy 55.679428 -294.099179) (xy 55.679848 -294.11422) (xy 55.679848 -294.385238) (xy 55.681626 -294.391842)
			(xy 55.686825 -294.412213) (xy 55.69243 -294.45388) (xy 55.692802 -294.4749) (xy 55.692312 -294.499889)
			(xy 55.684493 -294.549252) (xy 55.669049 -294.596784) (xy 55.646359 -294.641316) (xy 55.616983 -294.681749)
			(xy 55.581643 -294.717089) (xy 55.54121 -294.746465) (xy 55.496678 -294.769155) (xy 55.449146 -294.784599)
			(xy 55.399783 -294.792418) (xy 55.349805 -294.792418) (xy 55.300442 -294.784599) (xy 55.25291 -294.769155)
			(xy 55.208378 -294.746465) (xy 55.167945 -294.717089) (xy 55.132605 -294.681749) (xy 55.103229 -294.641316)
			(xy 55.080539 -294.596784) (xy 55.065095 -294.549252) (xy 55.057276 -294.499889) (xy 55.056786 -294.4749)
			(xy 53.792882 -294.4749) (xy 53.792419 -294.499404) (xy 53.784894 -294.547831) (xy 53.770025 -294.594528)
			(xy 53.748162 -294.638389) (xy 53.719824 -294.678374) (xy 53.685684 -294.713533) (xy 53.66639 -294.728646)
			(xy 53.666136 -294.728646) (xy 53.660998 -294.732874) (xy 53.652891 -294.743418) (xy 53.650134 -294.749474)
			(xy 53.604414 -294.85971) (xy 53.593828 -294.883743) (xy 53.564796 -294.927494) (xy 53.546756 -294.946578)
			(xy 53.429662 -295.063672) (xy 53.422836 -295.071083) (xy 53.415109 -295.089674) (xy 53.414676 -295.09974)
			(xy 53.414676 -295.577514) (xy 56.172608 -295.577514) (xy 56.172608 -294.866314) (xy 56.173148 -294.851301)
			(xy 56.180915 -294.822297) (xy 56.195923 -294.796291) (xy 56.217149 -294.775055) (xy 56.243149 -294.760035)
			(xy 56.272149 -294.752255) (xy 56.287162 -294.75176) (xy 56.764936 -294.75176) (xy 56.775009 -294.751364)
			(xy 56.793607 -294.743624) (xy 56.801004 -294.736774) (xy 56.959246 -294.578532) (xy 56.966612 -294.55364)
			(xy 56.963818 -294.541194) (xy 56.960594 -294.524811) (xy 56.957156 -294.491596) (xy 56.95696 -294.4749)
			(xy 56.957335 -294.45388) (xy 56.96294 -294.412213) (xy 56.968136 -294.391842) (xy 56.96966 -294.385238)
			(xy 56.96966 -294.11422) (xy 56.9702 -294.099173) (xy 56.977983 -294.070104) (xy 56.993024 -294.04404)
			(xy 57.014298 -294.022756) (xy 57.040356 -294.007703) (xy 57.069422 -293.999907) (xy 57.084468 -293.999412)
			(xy 57.465468 -293.999412) (xy 57.480524 -293.999867) (xy 57.509612 -294.007655) (xy 57.535691 -294.022708)
			(xy 57.556985 -294.043999) (xy 57.57204 -294.070077) (xy 57.579831 -294.099164) (xy 57.580276 -294.11422)
			(xy 57.580276 -294.385238) (xy 57.5818 -294.391842) (xy 57.586998 -294.412213) (xy 57.592604 -294.45388)
			(xy 57.592976 -294.4749) (xy 59.80684 -294.4749) (xy 59.807216 -294.45388) (xy 59.81282 -294.412213)
			(xy 59.818016 -294.391842) (xy 59.81954 -294.385238) (xy 59.81954 -294.11422) (xy 59.819957 -294.099161)
			(xy 59.82775 -294.070069) (xy 59.84281 -294.043986) (xy 59.864109 -294.022693) (xy 59.890195 -294.007639)
			(xy 59.919289 -293.999854) (xy 59.934348 -293.999412) (xy 60.315348 -293.999412) (xy 60.330402 -293.999841)
			(xy 60.359481 -294.007645) (xy 60.385551 -294.022708) (xy 60.406834 -294.044004) (xy 60.421881 -294.070082)
			(xy 60.429668 -294.099166) (xy 60.430156 -294.11422) (xy 60.430156 -294.385238) (xy 60.43168 -294.391842)
			(xy 60.43688 -294.412213) (xy 60.442484 -294.453879) (xy 60.442856 -294.4749) (xy 60.442366 -294.499889)
			(xy 60.434547 -294.549252) (xy 60.419103 -294.596784) (xy 60.396413 -294.641316) (xy 60.367037 -294.681749)
			(xy 60.331697 -294.717089) (xy 60.291264 -294.746465) (xy 60.246732 -294.769155) (xy 60.1992 -294.784599)
			(xy 60.149837 -294.792418) (xy 60.099859 -294.792418) (xy 60.050496 -294.784599) (xy 60.002964 -294.769155)
			(xy 59.958432 -294.746465) (xy 59.917999 -294.717089) (xy 59.882659 -294.681749) (xy 59.853283 -294.641316)
			(xy 59.830593 -294.596784) (xy 59.815149 -294.549252) (xy 59.80733 -294.499889) (xy 59.80684 -294.4749)
			(xy 57.592976 -294.4749) (xy 57.59232 -294.503316) (xy 57.582189 -294.559239) (xy 57.562268 -294.612467)
			(xy 57.548272 -294.637206) (xy 57.54542 -294.642381) (xy 57.541953 -294.653674) (xy 57.541414 -294.659558)
			(xy 57.539189 -294.683323) (xy 57.527413 -294.729573) (xy 57.507617 -294.772999) (xy 57.48043 -294.812224)
			(xy 57.463944 -294.829484) (xy 57.229502 -295.063672) (xy 57.222682 -295.071088) (xy 57.214951 -295.089675)
			(xy 57.214516 -295.09974) (xy 57.214516 -295.577514) (xy 60.922408 -295.577514) (xy 60.922408 -294.866314)
			(xy 60.922945 -294.851322) (xy 60.93069 -294.822356) (xy 60.945658 -294.796375) (xy 60.966831 -294.775145)
			(xy 60.992772 -294.760108) (xy 61.021717 -294.752285) (xy 61.036708 -294.75176) (xy 61.51499 -294.75176)
			(xy 61.52506 -294.75134) (xy 61.543659 -294.743617) (xy 61.551058 -294.736774) (xy 61.700156 -294.587676)
			(xy 61.708629 -294.57825) (xy 61.715814 -294.553975) (xy 61.713872 -294.541448) (xy 61.713872 -294.54094)
			(xy 61.710575 -294.524628) (xy 61.70701 -294.49154) (xy 61.70676 -294.4749) (xy 61.707135 -294.45388)
			(xy 61.71274 -294.412213) (xy 61.717936 -294.391842) (xy 61.71946 -294.385238) (xy 61.71946 -294.11422)
			(xy 61.72 -294.099173) (xy 61.727783 -294.070104) (xy 61.742824 -294.04404) (xy 61.764098 -294.022756)
			(xy 61.790156 -294.007703) (xy 61.819222 -293.999907) (xy 61.834268 -293.999412) (xy 62.215268 -293.999412)
			(xy 62.230324 -293.999867) (xy 62.259412 -294.007655) (xy 62.285491 -294.022708) (xy 62.306785 -294.043999)
			(xy 62.32184 -294.070077) (xy 62.329631 -294.099164) (xy 62.330076 -294.11422) (xy 62.330076 -294.385238)
			(xy 62.3316 -294.391842) (xy 62.336798 -294.412213) (xy 62.342404 -294.45388) (xy 62.342776 -294.4749)
			(xy 63.606934 -294.4749) (xy 63.607307 -294.45388) (xy 63.612913 -294.412213) (xy 63.61811 -294.391842)
			(xy 63.619888 -294.385238) (xy 63.619888 -294.11422) (xy 63.620397 -294.099192) (xy 63.628161 -294.070157)
			(xy 63.643166 -294.044115) (xy 63.664393 -294.022836) (xy 63.690399 -294.007768) (xy 63.719415 -293.999934)
			(xy 63.734442 -293.999412) (xy 64.115442 -293.999412) (xy 64.130485 -293.999858) (xy 64.15954 -294.007663)
			(xy 64.185582 -294.022729) (xy 64.206832 -294.044027) (xy 64.221838 -294.070103) (xy 64.229576 -294.099176)
			(xy 64.229996 -294.11422) (xy 64.229996 -294.385238) (xy 64.231774 -294.391842) (xy 64.236974 -294.412213)
			(xy 64.242578 -294.453879) (xy 64.24295 -294.4749) (xy 64.24246 -294.499889) (xy 64.234641 -294.549252)
			(xy 64.219197 -294.596784) (xy 64.196507 -294.641316) (xy 64.167131 -294.681749) (xy 64.131791 -294.717089)
			(xy 64.091358 -294.746465) (xy 64.046826 -294.769155) (xy 63.999294 -294.784599) (xy 63.949931 -294.792418)
			(xy 63.899953 -294.792418) (xy 63.85059 -294.784599) (xy 63.803058 -294.769155) (xy 63.758526 -294.746465)
			(xy 63.718093 -294.717089) (xy 63.682753 -294.681749) (xy 63.653377 -294.641316) (xy 63.630687 -294.596784)
			(xy 63.615243 -294.549252) (xy 63.607424 -294.499889) (xy 63.606934 -294.4749) (xy 62.342776 -294.4749)
			(xy 62.34212 -294.503316) (xy 62.331989 -294.559239) (xy 62.312068 -294.612467) (xy 62.298072 -294.637206)
			(xy 62.29522 -294.642381) (xy 62.291753 -294.653674) (xy 62.291214 -294.659558) (xy 62.289055 -294.683362)
			(xy 62.277294 -294.729685) (xy 62.257485 -294.773179) (xy 62.230258 -294.812458) (xy 62.213744 -294.829738)
			(xy 61.97981 -295.063672) (xy 61.972991 -295.071089) (xy 61.965259 -295.089675) (xy 61.964824 -295.09974)
			(xy 61.964824 -295.577514) (xy 61.964379 -295.592513) (xy 61.956622 -295.62149) (xy 61.941637 -295.647478)
			(xy 61.920445 -295.668709) (xy 61.894485 -295.683741) (xy 61.865522 -295.691551) (xy 61.850524 -295.692068)
			(xy 61.037216 -295.692068) (xy 61.022184 -295.691606) (xy 60.993142 -295.683837) (xy 60.967096 -295.668824)
			(xy 60.945817 -295.647587) (xy 60.930751 -295.621571) (xy 60.922925 -295.592545) (xy 60.922408 -295.577514)
			(xy 57.214516 -295.577514) (xy 57.21412 -295.59254) (xy 57.206337 -295.621568) (xy 57.191305 -295.647592)
			(xy 57.17005 -295.668837) (xy 57.14402 -295.683857) (xy 57.114989 -295.691626) (xy 57.099962 -295.692068)
			(xy 56.287162 -295.692068) (xy 56.272145 -295.691598) (xy 56.243135 -295.683816) (xy 56.217127 -295.668794)
			(xy 56.195891 -295.647554) (xy 56.180874 -295.621543) (xy 56.173099 -295.592531) (xy 56.172608 -295.577514)
			(xy 53.414676 -295.577514) (xy 53.41418 -295.592509) (xy 53.406427 -295.621478) (xy 53.391451 -295.647461)
			(xy 53.370269 -295.668691) (xy 53.344321 -295.683726) (xy 53.315369 -295.691545) (xy 53.300376 -295.692068)
			(xy 52.487068 -295.692068) (xy 52.472034 -295.691647) (xy 52.44299 -295.683868) (xy 52.416944 -295.668845)
			(xy 52.395666 -295.647601) (xy 52.380602 -295.621579) (xy 52.372777 -295.592547) (xy 52.37226 -295.577514)
			(xy 48.1076 -295.577514) (xy 48.1076 -296.399791) (xy 48.407277 -296.399791) (xy 48.407277 -296.349809)
			(xy 48.415096 -296.300444) (xy 48.430542 -296.252909) (xy 48.453234 -296.208376) (xy 48.482613 -296.167941)
			(xy 48.517956 -296.1326) (xy 48.558393 -296.103223) (xy 48.602927 -296.080534) (xy 48.650463 -296.065091)
			(xy 48.699829 -296.057275) (xy 48.72482 -296.056812) (xy 48.725328 -296.056812) (xy 48.746277 -296.057132)
			(xy 48.787815 -296.062617) (xy 48.808132 -296.067734) (xy 48.811742 -296.068652) (xy 48.819139 -296.069539)
			(xy 48.822864 -296.069512) (xy 48.82642 -296.069512) (xy 49.13122 -296.069512) (xy 49.146273 -296.069966)
			(xy 49.175351 -296.077763) (xy 49.20142 -296.09282) (xy 49.222705 -296.114111) (xy 49.237753 -296.140186)
			(xy 49.24554 -296.169267) (xy 49.246028 -296.18432) (xy 49.246028 -296.399787) (xy 50.307502 -296.399787)
			(xy 50.307502 -296.349813) (xy 50.31532 -296.300453) (xy 50.330763 -296.252925) (xy 50.35345 -296.208397)
			(xy 50.382825 -296.167966) (xy 50.418162 -296.132628) (xy 50.458592 -296.103254) (xy 50.503119 -296.080565)
			(xy 50.550647 -296.065121) (xy 50.600007 -296.057303) (xy 50.624994 -296.056812) (xy 50.625502 -296.056812)
			(xy 50.646451 -296.057137) (xy 50.687989 -296.062618) (xy 50.708306 -296.067734) (xy 50.711917 -296.068647)
			(xy 50.719313 -296.069537) (xy 50.723038 -296.069512) (xy 50.726594 -296.069512) (xy 51.031394 -296.069512)
			(xy 51.046435 -296.07) (xy 51.075489 -296.077793) (xy 51.101531 -296.09285) (xy 51.122781 -296.11414)
			(xy 51.137789 -296.14021) (xy 51.145528 -296.169279) (xy 51.145948 -296.18432) (xy 51.145948 -296.39979)
			(xy 52.207377 -296.39979) (xy 52.207377 -296.34981) (xy 52.215196 -296.300444) (xy 52.230641 -296.25291)
			(xy 52.253332 -296.208377) (xy 52.282711 -296.167943) (xy 52.318053 -296.132602) (xy 52.358489 -296.103225)
			(xy 52.403023 -296.080536) (xy 52.450558 -296.065093) (xy 52.499924 -296.057276) (xy 52.524914 -296.056812)
			(xy 52.525422 -296.056812) (xy 52.546371 -296.057133) (xy 52.587909 -296.062617) (xy 52.608226 -296.067734)
			(xy 52.611836 -296.068651) (xy 52.619233 -296.069538) (xy 52.622958 -296.069512) (xy 52.626514 -296.069512)
			(xy 52.931314 -296.069512) (xy 52.946355 -296.069982) (xy 52.97541 -296.07778) (xy 53.001452 -296.092841)
			(xy 53.022702 -296.114134) (xy 53.037709 -296.140207) (xy 53.045448 -296.169278) (xy 53.045868 -296.18432)
			(xy 53.045868 -296.399791) (xy 54.107277 -296.399791) (xy 54.107277 -296.349809) (xy 54.115097 -296.300442)
			(xy 54.130543 -296.252906) (xy 54.153236 -296.208371) (xy 54.182617 -296.167936) (xy 54.217962 -296.132595)
			(xy 54.2584 -296.103218) (xy 54.302937 -296.08053) (xy 54.350475 -296.065089) (xy 54.399843 -296.057274)
			(xy 54.424834 -296.056812) (xy 54.425342 -296.056812) (xy 54.44629 -296.057148) (xy 54.487828 -296.062622)
			(xy 54.508146 -296.067734) (xy 54.51176 -296.068634) (xy 54.519154 -296.069532) (xy 54.522878 -296.069512)
			(xy 54.526434 -296.069512) (xy 54.831234 -296.069512) (xy 54.846276 -296.069965) (xy 54.875332 -296.077768)
			(xy 54.901374 -296.092832) (xy 54.922623 -296.114129) (xy 54.93763 -296.140204) (xy 54.945368 -296.169277)
			(xy 54.945788 -296.18432) (xy 54.945788 -296.39979) (xy 56.007477 -296.39979) (xy 56.007477 -296.34981)
			(xy 56.015296 -296.300445) (xy 56.030741 -296.252912) (xy 56.053431 -296.208379) (xy 56.082809 -296.167945)
			(xy 56.118151 -296.132604) (xy 56.158586 -296.103227) (xy 56.203119 -296.080537) (xy 56.250653 -296.065094)
			(xy 56.300018 -296.057276) (xy 56.325008 -296.056812) (xy 56.325516 -296.056812) (xy 56.346465 -296.057134)
			(xy 56.388003 -296.062618) (xy 56.40832 -296.067734) (xy 56.411931 -296.06865) (xy 56.419327 -296.069538)
			(xy 56.423052 -296.069512) (xy 56.426608 -296.069512) (xy 56.731408 -296.069512) (xy 56.746466 -296.069933)
			(xy 56.775555 -296.07773) (xy 56.801634 -296.09279) (xy 56.822927 -296.114088) (xy 56.837981 -296.140171)
			(xy 56.845771 -296.169262) (xy 56.846216 -296.18432) (xy 56.846216 -296.399791) (xy 57.907377 -296.399791)
			(xy 57.907377 -296.349809) (xy 57.915196 -296.300442) (xy 57.930642 -296.252907) (xy 57.953335 -296.208373)
			(xy 57.982715 -296.167938) (xy 58.018059 -296.132597) (xy 58.058497 -296.10322) (xy 58.103033 -296.080532)
			(xy 58.15057 -296.06509) (xy 58.199937 -296.057275) (xy 58.224928 -296.056812) (xy 58.245949 -296.05718)
			(xy 58.287615 -296.062789) (xy 58.307986 -296.067988) (xy 58.31459 -296.069512) (xy 58.605928 -296.069512)
			(xy 58.620981 -296.069959) (xy 58.65006 -296.077758) (xy 58.676129 -296.092816) (xy 58.697413 -296.114109)
			(xy 58.712461 -296.140185) (xy 58.720248 -296.169267) (xy 58.720736 -296.18432) (xy 58.720736 -296.56532)
			(xy 58.720235 -296.580369) (xy 58.719503 -296.5831) (xy 60.451492 -296.5831) (xy 60.451492 -296.2021)
			(xy 60.451983 -296.18705) (xy 60.459773 -296.157975) (xy 60.474824 -296.131908) (xy 60.496108 -296.110624)
			(xy 60.522175 -296.095573) (xy 60.55125 -296.087783) (xy 60.5663 -296.087292) (xy 60.8711 -296.087292)
			(xy 60.878749 -296.087435) (xy 60.893912 -296.089467) (xy 60.901326 -296.091356) (xy 60.910234 -296.093468)
			(xy 60.928462 -296.091895) (xy 60.936886 -296.088308) (xy 60.958423 -296.078393) (xy 61.003719 -296.064391)
			(xy 61.050595 -296.057282) (xy 61.0743 -296.056812) (xy 61.074808 -296.056812) (xy 61.100113 -296.057319)
			(xy 61.150083 -296.065353) (xy 61.198153 -296.081187) (xy 61.220858 -296.092372) (xy 61.230641 -296.096777)
			(xy 61.252044 -296.097942) (xy 61.26226 -296.094658) (xy 61.272062 -296.091204) (xy 61.292509 -296.087494)
			(xy 61.3029 -296.087292) (xy 61.6077 -296.087292) (xy 61.62275 -296.087783) (xy 61.651825 -296.095573)
			(xy 61.677892 -296.110624) (xy 61.699176 -296.131908) (xy 61.714227 -296.157975) (xy 61.722017 -296.18705)
			(xy 61.722508 -296.2021) (xy 61.722508 -296.399787) (xy 62.657502 -296.399787) (xy 62.657502 -296.349813)
			(xy 62.665319 -296.300455) (xy 62.680762 -296.252927) (xy 62.703448 -296.2084) (xy 62.732821 -296.16797)
			(xy 62.768157 -296.132633) (xy 62.808585 -296.103258) (xy 62.853111 -296.080568) (xy 62.900638 -296.065124)
			(xy 62.949995 -296.057304) (xy 62.974982 -296.056812) (xy 62.996002 -296.057189) (xy 63.037669 -296.062792)
			(xy 63.05804 -296.067988) (xy 63.064644 -296.069512) (xy 63.355982 -296.069512) (xy 63.371022 -296.07001)
			(xy 63.400076 -296.077801) (xy 63.426118 -296.092855) (xy 63.447369 -296.114143) (xy 63.462377 -296.140212)
			(xy 63.470116 -296.169279) (xy 63.470536 -296.18432) (xy 63.470536 -296.39979) (xy 64.557377 -296.39979)
			(xy 64.557377 -296.34981) (xy 64.565195 -296.300446) (xy 64.58064 -296.252913) (xy 64.60333 -296.208381)
			(xy 64.632707 -296.167947) (xy 64.668048 -296.132606) (xy 64.708483 -296.103229) (xy 64.753015 -296.080539)
			(xy 64.800548 -296.065095) (xy 64.849912 -296.057277) (xy 64.874902 -296.056812) (xy 64.895922 -296.057185)
			(xy 64.937589 -296.062791) (xy 64.95796 -296.067988) (xy 64.964564 -296.069512) (xy 65.255902 -296.069512)
			(xy 65.270943 -296.069993) (xy 65.299997 -296.077788) (xy 65.326039 -296.092846) (xy 65.34729 -296.114138)
			(xy 65.362297 -296.140209) (xy 65.370036 -296.169278) (xy 65.370456 -296.18432) (xy 65.370456 -296.56532)
			(xy 65.369938 -296.580346) (xy 65.362169 -296.609376) (xy 65.347162 -296.635414) (xy 65.325938 -296.65669)
			(xy 65.299938 -296.67176) (xy 65.270927 -296.679601) (xy 65.255902 -296.680128) (xy 64.964564 -296.680128)
			(xy 64.95796 -296.681652) (xy 64.937589 -296.686851) (xy 64.895922 -296.692456) (xy 64.874902 -296.692828)
			(xy 64.849912 -296.692323) (xy 64.800548 -296.684505) (xy 64.753015 -296.669061) (xy 64.708483 -296.646371)
			(xy 64.668048 -296.616994) (xy 64.632707 -296.581653) (xy 64.60333 -296.541219) (xy 64.58064 -296.496687)
			(xy 64.565195 -296.449154) (xy 64.557377 -296.39979) (xy 63.470536 -296.39979) (xy 63.470536 -296.56532)
			(xy 63.470038 -296.580348) (xy 63.462267 -296.609381) (xy 63.447257 -296.63542) (xy 63.426029 -296.656697)
			(xy 63.400024 -296.671766) (xy 63.371008 -296.679603) (xy 63.355982 -296.680128) (xy 63.064644 -296.680128)
			(xy 63.05804 -296.681652) (xy 63.03767 -296.686855) (xy 62.996003 -296.692457) (xy 62.974982 -296.692828)
			(xy 62.949995 -296.692296) (xy 62.900638 -296.684476) (xy 62.853111 -296.669032) (xy 62.808585 -296.646342)
			(xy 62.768157 -296.616967) (xy 62.732821 -296.58163) (xy 62.703448 -296.5412) (xy 62.680762 -296.496673)
			(xy 62.665319 -296.449145) (xy 62.657502 -296.399787) (xy 61.722508 -296.399787) (xy 61.722508 -296.5831)
			(xy 61.722017 -296.59815) (xy 61.714227 -296.627225) (xy 61.699176 -296.653292) (xy 61.677892 -296.674576)
			(xy 61.651825 -296.689627) (xy 61.62275 -296.697417) (xy 61.6077 -296.697908) (xy 61.3029 -296.697908)
			(xy 61.286823 -296.697382) (xy 61.25592 -296.688508) (xy 61.228682 -296.671425) (xy 61.217556 -296.659808)
			(xy 61.216286 -296.659808) (xy 61.194281 -296.670157) (xy 61.147927 -296.68484) (xy 61.099881 -296.69232)
			(xy 61.07557 -296.692828) (xy 61.074808 -296.692828) (xy 61.049009 -296.692344) (xy 60.998082 -296.684045)
			(xy 60.973462 -296.676318) (xy 60.962718 -296.67334) (xy 60.940591 -296.675833) (xy 60.93079 -296.681144)
			(xy 60.917103 -296.688904) (xy 60.886826 -296.697418) (xy 60.8711 -296.697908) (xy 60.5663 -296.697908)
			(xy 60.55125 -296.697417) (xy 60.522175 -296.689627) (xy 60.496108 -296.674576) (xy 60.474824 -296.653292)
			(xy 60.459773 -296.627225) (xy 60.451983 -296.59815) (xy 60.451492 -296.5831) (xy 58.719503 -296.5831)
			(xy 58.712442 -296.60944) (xy 58.697392 -296.635505) (xy 58.676111 -296.656787) (xy 58.650047 -296.671839)
			(xy 58.620977 -296.679634) (xy 58.605928 -296.680128) (xy 58.31459 -296.680128) (xy 58.307986 -296.681652)
			(xy 58.287614 -296.686846) (xy 58.245948 -296.692454) (xy 58.224928 -296.692828) (xy 58.199937 -296.692325)
			(xy 58.15057 -296.68451) (xy 58.103033 -296.669068) (xy 58.058497 -296.64638) (xy 58.018059 -296.617003)
			(xy 57.982715 -296.581662) (xy 57.953335 -296.541227) (xy 57.930642 -296.496693) (xy 57.915196 -296.449158)
			(xy 57.907377 -296.399791) (xy 56.846216 -296.399791) (xy 56.846216 -296.56532) (xy 56.845735 -296.58037)
			(xy 56.83794 -296.609444) (xy 56.822887 -296.635511) (xy 56.801602 -296.656795) (xy 56.775533 -296.671845)
			(xy 56.746458 -296.679636) (xy 56.731408 -296.680128) (xy 56.423052 -296.680128) (xy 56.419326 -296.680088)
			(xy 56.411929 -296.680981) (xy 56.40832 -296.681906) (xy 56.388003 -296.687025) (xy 56.346465 -296.692509)
			(xy 56.325516 -296.692828) (xy 56.325008 -296.692828) (xy 56.300018 -296.692324) (xy 56.250653 -296.684506)
			(xy 56.203119 -296.669063) (xy 56.158586 -296.646373) (xy 56.118151 -296.616996) (xy 56.082809 -296.581655)
			(xy 56.053431 -296.541221) (xy 56.030741 -296.496688) (xy 56.015296 -296.449155) (xy 56.007477 -296.39979)
			(xy 54.945788 -296.39979) (xy 54.945788 -296.56532) (xy 54.945337 -296.580352) (xy 54.937562 -296.609392)
			(xy 54.922545 -296.635436) (xy 54.901307 -296.656714) (xy 54.875291 -296.67178) (xy 54.846265 -296.679609)
			(xy 54.831234 -296.680128) (xy 54.522878 -296.680128) (xy 54.519152 -296.680094) (xy 54.511756 -296.680983)
			(xy 54.508146 -296.681906) (xy 54.487832 -296.68704) (xy 54.446292 -296.692514) (xy 54.425342 -296.692828)
			(xy 54.424834 -296.692828) (xy 54.399843 -296.692326) (xy 54.350475 -296.684511) (xy 54.302937 -296.66907)
			(xy 54.2584 -296.646382) (xy 54.217962 -296.617005) (xy 54.182617 -296.581664) (xy 54.153236 -296.541229)
			(xy 54.130543 -296.496694) (xy 54.115097 -296.449158) (xy 54.107277 -296.399791) (xy 53.045868 -296.399791)
			(xy 53.045868 -296.56532) (xy 53.045437 -296.580353) (xy 53.03766 -296.609397) (xy 53.02264 -296.635443)
			(xy 53.001397 -296.656721) (xy 52.975377 -296.671785) (xy 52.946346 -296.679611) (xy 52.931314 -296.680128)
			(xy 52.622958 -296.680128) (xy 52.619232 -296.680089) (xy 52.611835 -296.680981) (xy 52.608226 -296.681906)
			(xy 52.587909 -296.687024) (xy 52.546371 -296.692509) (xy 52.525422 -296.692828) (xy 52.524914 -296.692828)
			(xy 52.499924 -296.692324) (xy 52.450558 -296.684507) (xy 52.403023 -296.669064) (xy 52.358489 -296.646375)
			(xy 52.318053 -296.616998) (xy 52.282711 -296.581657) (xy 52.253332 -296.541223) (xy 52.230641 -296.49669)
			(xy 52.215196 -296.449156) (xy 52.207377 -296.39979) (xy 51.145948 -296.39979) (xy 51.145948 -296.56532)
			(xy 51.145438 -296.580347) (xy 51.137668 -296.609378) (xy 51.12266 -296.635416) (xy 51.101435 -296.656693)
			(xy 51.075432 -296.671762) (xy 51.046419 -296.679602) (xy 51.031394 -296.680128) (xy 50.723038 -296.680128)
			(xy 50.719312 -296.680085) (xy 50.711915 -296.68098) (xy 50.708306 -296.681906) (xy 50.68799 -296.687028)
			(xy 50.646452 -296.69251) (xy 50.625502 -296.692828) (xy 50.624994 -296.692828) (xy 50.600007 -296.692297)
			(xy 50.550647 -296.684479) (xy 50.503119 -296.669035) (xy 50.458592 -296.646346) (xy 50.418162 -296.616972)
			(xy 50.382825 -296.581634) (xy 50.35345 -296.541203) (xy 50.330763 -296.496675) (xy 50.31532 -296.449147)
			(xy 50.307502 -296.399787) (xy 49.246028 -296.399787) (xy 49.246028 -296.56532) (xy 49.245535 -296.580369)
			(xy 49.237741 -296.609442) (xy 49.22269 -296.635507) (xy 49.201407 -296.65679) (xy 49.175342 -296.671841)
			(xy 49.146269 -296.679635) (xy 49.13122 -296.680128) (xy 48.822864 -296.680128) (xy 48.819138 -296.680091)
			(xy 48.811741 -296.680982) (xy 48.808132 -296.681906) (xy 48.787819 -296.687042) (xy 48.746278 -296.692515)
			(xy 48.725328 -296.692828) (xy 48.72482 -296.692828) (xy 48.699829 -296.692325) (xy 48.650463 -296.684509)
			(xy 48.602927 -296.669066) (xy 48.558393 -296.646377) (xy 48.517956 -296.617) (xy 48.482613 -296.581659)
			(xy 48.453234 -296.541224) (xy 48.430542 -296.496691) (xy 48.415096 -296.449156) (xy 48.407277 -296.399791)
			(xy 48.1076 -296.399791) (xy 48.1076 -297.32478) (xy 49.356772 -297.32478) (xy 49.357262 -297.299791)
			(xy 49.365081 -297.250428) (xy 49.380525 -297.202896) (xy 49.403215 -297.158364) (xy 49.432591 -297.117931)
			(xy 49.467931 -297.082591) (xy 49.508364 -297.053215) (xy 49.552896 -297.030525) (xy 49.600428 -297.015081)
			(xy 49.649791 -297.007262) (xy 49.699769 -297.007262) (xy 49.749132 -297.015081) (xy 49.796664 -297.030525)
			(xy 49.841196 -297.053215) (xy 49.881629 -297.082591) (xy 49.916969 -297.117931) (xy 49.946345 -297.158364)
			(xy 49.969035 -297.202896) (xy 49.984479 -297.250428) (xy 49.992298 -297.299791) (xy 49.992788 -297.32478)
			(xy 51.256946 -297.32478) (xy 51.257436 -297.299791) (xy 51.265255 -297.250428) (xy 51.280699 -297.202896)
			(xy 51.303389 -297.158364) (xy 51.332765 -297.117931) (xy 51.368105 -297.082591) (xy 51.408538 -297.053215)
			(xy 51.45307 -297.030525) (xy 51.500602 -297.015081) (xy 51.549965 -297.007262) (xy 51.599943 -297.007262)
			(xy 51.649306 -297.015081) (xy 51.696838 -297.030525) (xy 51.74137 -297.053215) (xy 51.781803 -297.082591)
			(xy 51.817143 -297.117931) (xy 51.846519 -297.158364) (xy 51.869209 -297.202896) (xy 51.884653 -297.250428)
			(xy 51.892472 -297.299791) (xy 51.892962 -297.32478) (xy 53.156866 -297.32478) (xy 53.157356 -297.299791)
			(xy 53.165175 -297.250428) (xy 53.180619 -297.202896) (xy 53.203309 -297.158364) (xy 53.232685 -297.117931)
			(xy 53.268025 -297.082591) (xy 53.308458 -297.053215) (xy 53.35299 -297.030525) (xy 53.400522 -297.015081)
			(xy 53.449885 -297.007262) (xy 53.499863 -297.007262) (xy 53.549226 -297.015081) (xy 53.596758 -297.030525)
			(xy 53.64129 -297.053215) (xy 53.681723 -297.082591) (xy 53.717063 -297.117931) (xy 53.746439 -297.158364)
			(xy 53.769129 -297.202896) (xy 53.784573 -297.250428) (xy 53.792392 -297.299791) (xy 53.792882 -297.32478)
			(xy 55.056786 -297.32478) (xy 55.057276 -297.299791) (xy 55.065095 -297.250428) (xy 55.080539 -297.202896)
			(xy 55.103229 -297.158364) (xy 55.132605 -297.117931) (xy 55.167945 -297.082591) (xy 55.208378 -297.053215)
			(xy 55.25291 -297.030525) (xy 55.300442 -297.015081) (xy 55.349805 -297.007262) (xy 55.399783 -297.007262)
			(xy 55.449146 -297.015081) (xy 55.496678 -297.030525) (xy 55.54121 -297.053215) (xy 55.581643 -297.082591)
			(xy 55.616983 -297.117931) (xy 55.646359 -297.158364) (xy 55.669049 -297.202896) (xy 55.684493 -297.250428)
			(xy 55.692312 -297.299791) (xy 55.692802 -297.32478) (xy 56.95696 -297.32478) (xy 56.95745 -297.299791)
			(xy 56.965269 -297.250428) (xy 56.980713 -297.202896) (xy 57.003403 -297.158364) (xy 57.032779 -297.117931)
			(xy 57.068119 -297.082591) (xy 57.108552 -297.053215) (xy 57.153084 -297.030525) (xy 57.200616 -297.015081)
			(xy 57.249979 -297.007262) (xy 57.299957 -297.007262) (xy 57.34932 -297.015081) (xy 57.396852 -297.030525)
			(xy 57.441384 -297.053215) (xy 57.481817 -297.082591) (xy 57.517157 -297.117931) (xy 57.546533 -297.158364)
			(xy 57.569223 -297.202896) (xy 57.584667 -297.250428) (xy 57.592486 -297.299791) (xy 57.592976 -297.32478)
			(xy 59.80684 -297.32478) (xy 59.80733 -297.299791) (xy 59.815149 -297.250428) (xy 59.830593 -297.202896)
			(xy 59.853283 -297.158364) (xy 59.882659 -297.117931) (xy 59.917999 -297.082591) (xy 59.958432 -297.053215)
			(xy 60.002964 -297.030525) (xy 60.050496 -297.015081) (xy 60.099859 -297.007262) (xy 60.149837 -297.007262)
			(xy 60.1992 -297.015081) (xy 60.246732 -297.030525) (xy 60.291264 -297.053215) (xy 60.331697 -297.082591)
			(xy 60.367037 -297.117931) (xy 60.396413 -297.158364) (xy 60.419103 -297.202896) (xy 60.434547 -297.250428)
			(xy 60.442366 -297.299791) (xy 60.442856 -297.32478) (xy 61.70676 -297.32478) (xy 61.70725 -297.299791)
			(xy 61.715069 -297.250428) (xy 61.730513 -297.202896) (xy 61.753203 -297.158364) (xy 61.782579 -297.117931)
			(xy 61.817919 -297.082591) (xy 61.858352 -297.053215) (xy 61.902884 -297.030525) (xy 61.950416 -297.015081)
			(xy 61.999779 -297.007262) (xy 62.049757 -297.007262) (xy 62.09912 -297.015081) (xy 62.146652 -297.030525)
			(xy 62.191184 -297.053215) (xy 62.231617 -297.082591) (xy 62.266957 -297.117931) (xy 62.296333 -297.158364)
			(xy 62.319023 -297.202896) (xy 62.334467 -297.250428) (xy 62.342286 -297.299791) (xy 62.342776 -297.32478)
			(xy 63.606934 -297.32478) (xy 63.607424 -297.299791) (xy 63.615243 -297.250428) (xy 63.630687 -297.202896)
			(xy 63.653377 -297.158364) (xy 63.682753 -297.117931) (xy 63.718093 -297.082591) (xy 63.758526 -297.053215)
			(xy 63.803058 -297.030525) (xy 63.85059 -297.015081) (xy 63.899953 -297.007262) (xy 63.949931 -297.007262)
			(xy 63.999294 -297.015081) (xy 64.046826 -297.030525) (xy 64.091358 -297.053215) (xy 64.131791 -297.082591)
			(xy 64.167131 -297.117931) (xy 64.196507 -297.158364) (xy 64.219197 -297.202896) (xy 64.234641 -297.250428)
			(xy 64.24246 -297.299791) (xy 64.24295 -297.32478) (xy 64.242571 -297.3458) (xy 64.236969 -297.387466)
			(xy 64.231774 -297.407838) (xy 64.229996 -297.414442) (xy 64.229996 -297.68546) (xy 64.229485 -297.700488)
			(xy 64.221724 -297.729525) (xy 64.20672 -297.755569) (xy 64.185494 -297.776848) (xy 64.159487 -297.791916)
			(xy 64.130469 -297.799747) (xy 64.115442 -297.800268) (xy 63.734442 -297.800268) (xy 63.719401 -297.799769)
			(xy 63.690346 -297.791982) (xy 63.664301 -297.77693) (xy 63.643049 -297.755641) (xy 63.628042 -297.729571)
			(xy 63.620305 -297.700501) (xy 63.619888 -297.68546) (xy 63.619888 -297.414442) (xy 63.61811 -297.407838)
			(xy 63.612908 -297.387468) (xy 63.607305 -297.345801) (xy 63.606934 -297.32478) (xy 62.342776 -297.32478)
			(xy 62.342399 -297.3458) (xy 62.336796 -297.387467) (xy 62.3316 -297.407838) (xy 62.330076 -297.414442)
			(xy 62.330076 -297.68546) (xy 62.329625 -297.700517) (xy 62.321839 -297.729606) (xy 62.306786 -297.755687)
			(xy 62.285493 -297.776981) (xy 62.259413 -297.792036) (xy 62.230325 -297.799824) (xy 62.215268 -297.800268)
			(xy 61.834268 -297.800268) (xy 61.819207 -297.799889) (xy 61.790114 -297.792084) (xy 61.764033 -297.777015)
			(xy 61.74274 -297.75571) (xy 61.727688 -297.729619) (xy 61.719902 -297.700521) (xy 61.71946 -297.68546)
			(xy 61.71946 -297.414442) (xy 61.717936 -297.407838) (xy 61.712733 -297.387468) (xy 61.70713 -297.345801)
			(xy 61.70676 -297.32478) (xy 60.442856 -297.32478) (xy 60.442476 -297.3458) (xy 60.436875 -297.387466)
			(xy 60.43168 -297.407838) (xy 60.430156 -297.414442) (xy 60.430156 -297.68546) (xy 60.429582 -297.700504)
			(xy 60.421805 -297.72957) (xy 60.406771 -297.755633) (xy 60.385503 -297.776917) (xy 60.359452 -297.791971)
			(xy 60.330392 -297.799771) (xy 60.315348 -297.800268) (xy 59.934348 -297.800268) (xy 59.919291 -297.799818)
			(xy 59.890201 -297.792033) (xy 59.864119 -297.77698) (xy 59.842825 -297.755687) (xy 59.82777 -297.729607)
			(xy 59.819983 -297.700517) (xy 59.81954 -297.68546) (xy 59.81954 -297.414442) (xy 59.818016 -297.407838)
			(xy 59.812812 -297.387468) (xy 59.80721 -297.345801) (xy 59.80684 -297.32478) (xy 57.592976 -297.32478)
			(xy 57.592599 -297.3458) (xy 57.586996 -297.387467) (xy 57.5818 -297.407838) (xy 57.580276 -297.414442)
			(xy 57.580276 -297.68546) (xy 57.579825 -297.700517) (xy 57.572039 -297.729606) (xy 57.556986 -297.755687)
			(xy 57.535693 -297.776981) (xy 57.509613 -297.792036) (xy 57.480525 -297.799824) (xy 57.465468 -297.800268)
			(xy 57.084468 -297.800268) (xy 57.069407 -297.799889) (xy 57.040314 -297.792084) (xy 57.014233 -297.777015)
			(xy 56.99294 -297.75571) (xy 56.977888 -297.729619) (xy 56.970102 -297.700521) (xy 56.96966 -297.68546)
			(xy 56.96966 -297.414442) (xy 56.968136 -297.407838) (xy 56.962933 -297.387468) (xy 56.95733 -297.345801)
			(xy 56.95696 -297.32478) (xy 55.692802 -297.32478) (xy 55.692424 -297.3458) (xy 55.686821 -297.387467)
			(xy 55.681626 -297.407838) (xy 55.679848 -297.414442) (xy 55.679848 -297.68546) (xy 55.679285 -297.700484)
			(xy 55.671529 -297.729513) (xy 55.656534 -297.755552) (xy 55.635318 -297.776829) (xy 55.609323 -297.791901)
			(xy 55.580317 -297.799741) (xy 55.565294 -297.800268) (xy 55.184294 -297.800268) (xy 55.169251 -297.799811)
			(xy 55.140194 -297.792013) (xy 55.11415 -297.776951) (xy 55.092899 -297.755654) (xy 55.077893 -297.729578)
			(xy 55.070157 -297.700504) (xy 55.06974 -297.68546) (xy 55.06974 -297.414442) (xy 55.067962 -297.407838)
			(xy 55.062759 -297.387468) (xy 55.057156 -297.345801) (xy 55.056786 -297.32478) (xy 53.792882 -297.32478)
			(xy 53.792505 -297.3458) (xy 53.786902 -297.387467) (xy 53.781706 -297.407838) (xy 53.779928 -297.414442)
			(xy 53.779928 -297.68546) (xy 53.779385 -297.700486) (xy 53.771627 -297.729518) (xy 53.756629 -297.755558)
			(xy 53.735408 -297.776837) (xy 53.709409 -297.791906) (xy 53.680398 -297.799744) (xy 53.665374 -297.800268)
			(xy 53.284374 -297.800268) (xy 53.26933 -297.799828) (xy 53.240272 -297.792025) (xy 53.214228 -297.776959)
			(xy 53.192978 -297.75566) (xy 53.177973 -297.729581) (xy 53.170237 -297.700505) (xy 53.16982 -297.68546)
			(xy 53.16982 -297.414442) (xy 53.168042 -297.407838) (xy 53.162839 -297.387468) (xy 53.157236 -297.345801)
			(xy 53.156866 -297.32478) (xy 51.892962 -297.32478) (xy 51.892582 -297.3458) (xy 51.88698 -297.387466)
			(xy 51.881786 -297.407838) (xy 51.880008 -297.414442) (xy 51.880008 -297.68546) (xy 51.879485 -297.700487)
			(xy 51.871725 -297.729523) (xy 51.856723 -297.755565) (xy 51.835499 -297.776844) (xy 51.809495 -297.791912)
			(xy 51.78048 -297.799746) (xy 51.765454 -297.800268) (xy 51.384454 -297.800268) (xy 51.369409 -297.799846)
			(xy 51.340351 -297.792038) (xy 51.314307 -297.776968) (xy 51.293057 -297.755665) (xy 51.278052 -297.729584)
			(xy 51.270317 -297.700506) (xy 51.2699 -297.68546) (xy 51.2699 -297.414442) (xy 51.268122 -297.407838)
			(xy 51.262918 -297.387468) (xy 51.257316 -297.345801) (xy 51.256946 -297.32478) (xy 49.992788 -297.32478)
			(xy 49.992411 -297.3458) (xy 49.986808 -297.387467) (xy 49.981612 -297.407838) (xy 49.980088 -297.414442)
			(xy 49.980088 -297.68546) (xy 49.979626 -297.700516) (xy 49.97184 -297.729603) (xy 49.956789 -297.755683)
			(xy 49.935499 -297.776977) (xy 49.909422 -297.792032) (xy 49.880336 -297.799823) (xy 49.86528 -297.800268)
			(xy 49.48428 -297.800268) (xy 49.46922 -297.799878) (xy 49.440127 -297.792077) (xy 49.414046 -297.77701)
			(xy 49.392753 -297.755706) (xy 49.3777 -297.729617) (xy 49.369914 -297.70052) (xy 49.369472 -297.68546)
			(xy 49.369472 -297.414442) (xy 49.367948 -297.407838) (xy 49.362745 -297.387468) (xy 49.357142 -297.345801)
			(xy 49.356772 -297.32478) (xy 48.1076 -297.32478) (xy 48.1076 -298.27474) (xy 48.406812 -298.27474)
			(xy 48.407193 -298.25372) (xy 48.412794 -298.212054) (xy 48.417988 -298.191682) (xy 48.419512 -298.185078)
			(xy 48.419512 -297.91406) (xy 48.419948 -297.899006) (xy 48.42775 -297.869927) (xy 48.442811 -297.843858)
			(xy 48.464106 -297.822575) (xy 48.490183 -297.807527) (xy 48.519266 -297.79974) (xy 48.53432 -297.799252)
			(xy 48.91532 -297.799252) (xy 48.930368 -297.799765) (xy 48.959437 -297.807557) (xy 48.985501 -297.822605)
			(xy 49.006783 -297.843884) (xy 49.021835 -297.869944) (xy 49.029632 -297.899012) (xy 49.030128 -297.91406)
			(xy 49.030128 -298.185078) (xy 49.031652 -298.191682) (xy 49.036859 -298.212051) (xy 49.042459 -298.253719)
			(xy 49.042828 -298.27474) (xy 49.042338 -298.299729) (xy 49.034519 -298.349092) (xy 49.019075 -298.396624)
			(xy 48.996385 -298.441156) (xy 48.967009 -298.481589) (xy 48.931669 -298.516929) (xy 48.891236 -298.546305)
			(xy 48.846704 -298.568995) (xy 48.799172 -298.584439) (xy 48.749809 -298.592258) (xy 48.699831 -298.592258)
			(xy 48.650468 -298.584439) (xy 48.602936 -298.568995) (xy 48.558404 -298.546305) (xy 48.517971 -298.516929)
			(xy 48.482631 -298.481589) (xy 48.453255 -298.441156) (xy 48.430565 -298.396624) (xy 48.415121 -298.349092)
			(xy 48.407302 -298.299729) (xy 48.406812 -298.27474) (xy 48.1076 -298.27474) (xy 48.1076 -300.199891)
			(xy 48.40727 -300.199891) (xy 48.40727 -300.149909) (xy 48.41509 -300.100542) (xy 48.430536 -300.053006)
			(xy 48.453228 -300.008472) (xy 48.482608 -299.968036) (xy 48.517952 -299.932695) (xy 48.558389 -299.903317)
			(xy 48.602925 -299.880628) (xy 48.650462 -299.865185) (xy 48.699829 -299.857369) (xy 48.72482 -299.856906)
			(xy 48.74584 -299.857276) (xy 48.787507 -299.862884) (xy 48.807878 -299.868082) (xy 48.814482 -299.86986)
			(xy 49.0855 -299.86986) (xy 49.100526 -299.870379) (xy 49.129559 -299.878146) (xy 49.155598 -299.89315)
			(xy 49.176875 -299.914375) (xy 49.191944 -299.940376) (xy 49.199783 -299.969389) (xy 49.200308 -299.984414)
			(xy 49.200308 -300.365414) (xy 49.199879 -300.380414) (xy 49.19212 -300.409394) (xy 49.177133 -300.435383)
			(xy 49.155938 -300.456615) (xy 49.129974 -300.471645) (xy 49.101007 -300.479453) (xy 49.086008 -300.479968)
			(xy 48.814482 -300.479968) (xy 48.807878 -300.481746) (xy 48.787506 -300.486941) (xy 48.74584 -300.492549)
			(xy 48.72482 -300.492922) (xy 48.699829 -300.492431) (xy 48.650462 -300.484615) (xy 48.602925 -300.469172)
			(xy 48.558389 -300.446483) (xy 48.517952 -300.417105) (xy 48.482608 -300.381764) (xy 48.453228 -300.341328)
			(xy 48.430536 -300.296794) (xy 48.41509 -300.249258) (xy 48.40727 -300.199891) (xy 48.1076 -300.199891)
			(xy 48.1076 -301.197518) (xy 48.108616 -301.20717) (xy 48.110245 -301.214413) (xy 48.117089 -301.22758)
			(xy 48.122078 -301.233078) (xy 48.19396 -301.30496) (xy 48.201366 -301.311655) (xy 48.219802 -301.319258)
			(xy 48.229774 -301.319692)
		)
		(stroke
			(width 0)
			(type solid)
		)
		(fill yes)
		(layer "B.Cu")
		(net "P0V8_PEX0")
	)
	(gr_poly
		(pts
			(xy 228.919024 -328.912982) (xy 228.929009 -328.91244) (xy 228.947433 -328.904718) (xy 228.954838 -328.897996)
			(xy 229.192582 -328.660506) (xy 229.202488 -328.650854) (xy 229.202742 -328.650346) (xy 229.241858 -328.611484)
			(xy 229.264971 -328.589019) (xy 229.315374 -328.548839) (xy 229.369958 -328.514554) (xy 229.428036 -328.486594)
			(xy 229.488879 -328.465311) (xy 229.551722 -328.450971) (xy 229.615775 -328.443757) (xy 229.648004 -328.443336)
			(xy 232.593388 -328.443336) (xy 232.603458 -328.442913) (xy 232.622059 -328.435195) (xy 232.629456 -328.42835)
			(xy 234.927648 -326.130158) (xy 234.950755 -326.107678) (xy 235.001149 -326.067468) (xy 235.055727 -326.033152)
			(xy 235.113804 -326.005163) (xy 235.174649 -325.98385) (xy 235.237497 -325.969484) (xy 235.301559 -325.962243)
			(xy 235.333794 -325.961756) (xy 244.715538 -325.961756) (xy 244.725571 -325.96132) (xy 244.744146 -325.953744)
			(xy 244.751606 -325.947024) (xy 248.038112 -322.660518) (xy 248.041543 -322.656899) (xy 248.047039 -322.648579)
			(xy 248.049034 -322.644008) (xy 249.56389 -318.986408) (xy 249.565663 -318.98178) (xy 249.567583 -318.972059)
			(xy 249.5677 -318.967104) (xy 249.5677 -300.810422) (xy 249.567262 -300.800358) (xy 249.559528 -300.781774)
			(xy 249.552714 -300.774354) (xy 248.56821 -299.790104) (xy 248.561362 -299.782706) (xy 248.553624 -299.764108)
			(xy 248.553224 -299.754036) (xy 248.553224 -294.626284) (xy 248.552799 -294.616215) (xy 248.545083 -294.597612)
			(xy 248.538238 -294.590216) (xy 248.183146 -294.235124) (xy 248.176034 -294.227758) (xy 248.157238 -294.220138)
			(xy 248.153428 -294.220138) (xy 248.143414 -294.219655) (xy 248.124906 -294.212002) (xy 248.110735 -294.19785)
			(xy 248.103058 -294.179352) (xy 248.102628 -294.169338) (xy 248.102628 -283.030422) (xy 248.102123 -283.020371)
			(xy 248.094402 -283.00181) (xy 248.087642 -282.994354) (xy 247.861074 -282.767532) (xy 247.853676 -282.760686)
			(xy 247.835077 -282.752956) (xy 247.825006 -282.752546) (xy 245.249446 -282.752546) (xy 245.239381 -282.75298)
			(xy 245.220795 -282.760714) (xy 245.213378 -282.767532) (xy 244.986556 -282.994354) (xy 244.979712 -283.001753)
			(xy 244.971988 -283.020352) (xy 244.97157 -283.030422) (xy 244.97157 -293.57447) (xy 244.971133 -293.584534)
			(xy 244.963398 -293.603117) (xy 244.956584 -293.610538) (xy 244.598952 -293.96817) (xy 244.591552 -293.975012)
			(xy 244.572954 -293.982734) (xy 244.562884 -293.983156) (xy 236.508798 -293.983156) (xy 236.498729 -293.982731)
			(xy 236.480129 -293.975011) (xy 236.47273 -293.96817) (xy 235.832142 -293.327582) (xy 235.825294 -293.320185)
			(xy 235.817559 -293.301586) (xy 235.817156 -293.291514) (xy 235.817156 -284.452568) (xy 235.816726 -284.442501)
			(xy 235.808998 -284.42391) (xy 235.80217 -284.4165) (xy 235.643928 -284.258258) (xy 235.636529 -284.251416)
			(xy 235.61793 -284.243699) (xy 235.60786 -284.243272) (xy 233.840782 -284.243272) (xy 233.830714 -284.242845)
			(xy 233.812117 -284.235123) (xy 233.804714 -284.228286) (xy 233.38028 -283.803852) (xy 233.373432 -283.796455)
			(xy 233.365703 -283.777856) (xy 233.365294 -283.767784) (xy 233.365294 -281.200352) (xy 233.365725 -281.190285)
			(xy 233.373451 -281.171693) (xy 233.38028 -281.164284) (xy 233.740452 -280.804112) (xy 233.747853 -280.797272)
			(xy 233.766451 -280.789555) (xy 233.77652 -280.789126) (xy 234.073192 -280.789126) (xy 234.091734 -280.781506)
			(xy 234.098084 -280.775156) (xy 241.43208 -280.775156) (xy 241.442068 -280.774621) (xy 241.460501 -280.766908)
			(xy 241.467894 -280.76017) (xy 241.82197 -280.406094) (xy 241.828819 -280.398697) (xy 241.836556 -280.380098)
			(xy 241.836956 -280.370026) (xy 241.836956 -278.889206) (xy 241.836533 -278.879136) (xy 241.828815 -278.860534)
			(xy 241.82197 -278.853138) (xy 241.74704 -278.778208) (xy 241.739633 -278.771517) (xy 241.721197 -278.763919)
			(xy 241.711226 -278.763476) (xy 241.18062 -278.763476) (xy 241.170658 -278.763964) (xy 241.152235 -278.771552)
			(xy 241.144806 -278.778208) (xy 241.028728 -278.894286) (xy 241.021326 -278.901122) (xy 241.002728 -278.908833)
			(xy 240.99266 -278.909272) (xy 234.243372 -278.909272) (xy 234.233305 -278.908843) (xy 234.21471 -278.901118)
			(xy 234.207304 -278.894286) (xy 234.058968 -278.74595) (xy 234.052122 -278.738552) (xy 234.044395 -278.719953)
			(xy 234.043982 -278.709882) (xy 234.043982 -276.364954) (xy 234.044413 -276.354887) (xy 234.052137 -276.336293)
			(xy 234.058968 -276.328886) (xy 234.317286 -276.070568) (xy 234.324129 -276.063168) (xy 234.331854 -276.04457)
			(xy 234.332272 -276.0345) (xy 234.332272 -272.498058) (xy 234.331776 -272.488058) (xy 234.324108 -272.469585)
			(xy 234.309956 -272.455452) (xy 234.291473 -272.44781) (xy 234.281472 -272.447258) (xy 228.261418 -272.447258)
			(xy 228.251356 -272.447698) (xy 228.232778 -272.45544) (xy 228.22535 -272.462244) (xy 228.131624 -272.55597)
			(xy 228.124786 -272.563371) (xy 228.117073 -272.58197) (xy 228.116638 -272.592038) (xy 228.116638 -273.427698)
			(xy 228.116214 -273.437767) (xy 228.108493 -273.456366) (xy 228.101652 -273.463766) (xy 228.094032 -273.471386)
			(xy 232.53395 -273.471386) (xy 232.538021 -273.415764) (xy 232.550147 -273.361327) (xy 232.57007 -273.309236)
			(xy 232.597366 -273.260601) (xy 232.631452 -273.216458) (xy 232.671601 -273.177749) (xy 232.716959 -273.145298)
			(xy 232.766559 -273.119797) (xy 232.819343 -273.10179) (xy 232.874186 -273.09166) (xy 232.92992 -273.089623)
			(xy 232.985357 -273.095723) (xy 233.039314 -273.109829) (xy 233.090643 -273.131641) (xy 233.138249 -273.160695)
			(xy 233.181117 -273.19637) (xy 233.218334 -273.237907) (xy 233.249107 -273.28442) (xy 233.272779 -273.334917)
			(xy 233.288847 -273.388324) (xy 233.296967 -273.4435) (xy 233.297476 -273.471386) (xy 233.296967 -273.499272)
			(xy 233.288847 -273.554448) (xy 233.272779 -273.607855) (xy 233.249107 -273.658352) (xy 233.218334 -273.704865)
			(xy 233.181117 -273.746402) (xy 233.138249 -273.782077) (xy 233.090643 -273.811131) (xy 233.039314 -273.832943)
			(xy 232.985357 -273.847049) (xy 232.92992 -273.853149) (xy 232.874186 -273.851112) (xy 232.819343 -273.840982)
			(xy 232.766559 -273.822975) (xy 232.716959 -273.797474) (xy 232.671601 -273.765023) (xy 232.631452 -273.726314)
			(xy 232.597366 -273.682171) (xy 232.57007 -273.633536) (xy 232.550147 -273.581445) (xy 232.538021 -273.527008)
			(xy 232.53395 -273.471386) (xy 228.094032 -273.471386) (xy 227.981256 -273.584162) (xy 227.973857 -273.591005)
			(xy 227.955258 -273.59873) (xy 227.945188 -273.599148) (xy 227.012754 -273.599148) (xy 227.002689 -273.599581)
			(xy 226.984101 -273.607312) (xy 226.976686 -273.614134) (xy 225.928178 -274.662642) (xy 226.619798 -274.662642)
			(xy 226.619798 -274.602706) (xy 226.627621 -274.543284) (xy 226.643134 -274.485391) (xy 226.66607 -274.430018)
			(xy 226.696037 -274.378112) (xy 226.732524 -274.330562) (xy 226.774904 -274.288182) (xy 226.822454 -274.251695)
			(xy 226.87436 -274.221728) (xy 226.929733 -274.198792) (xy 226.987626 -274.183279) (xy 227.047048 -274.175456)
			(xy 227.106984 -274.175456) (xy 227.166406 -274.183279) (xy 227.224299 -274.198792) (xy 227.279672 -274.221728)
			(xy 227.331578 -274.251695) (xy 227.379128 -274.288182) (xy 227.421508 -274.330562) (xy 227.457995 -274.378112)
			(xy 227.487962 -274.430018) (xy 227.510898 -274.485391) (xy 227.526411 -274.543284) (xy 227.534234 -274.602706)
			(xy 227.534724 -274.632674) (xy 227.534234 -274.662642) (xy 227.526411 -274.722064) (xy 227.510898 -274.779957)
			(xy 227.503414 -274.798024) (xy 228.749588 -274.798024) (xy 228.749588 -274.738088) (xy 228.757411 -274.678666)
			(xy 228.772924 -274.620773) (xy 228.79586 -274.5654) (xy 228.825827 -274.513494) (xy 228.862314 -274.465944)
			(xy 228.904694 -274.423564) (xy 228.952244 -274.387077) (xy 229.00415 -274.35711) (xy 229.059523 -274.334174)
			(xy 229.117416 -274.318661) (xy 229.176838 -274.310838) (xy 229.236774 -274.310838) (xy 229.296196 -274.318661)
			(xy 229.354089 -274.334174) (xy 229.409462 -274.35711) (xy 229.461368 -274.387077) (xy 229.508918 -274.423564)
			(xy 229.551298 -274.465944) (xy 229.587785 -274.513494) (xy 229.617752 -274.5654) (xy 229.640688 -274.620773)
			(xy 229.656201 -274.678666) (xy 229.664024 -274.738088) (xy 229.664514 -274.768056) (xy 229.664024 -274.798024)
			(xy 229.656201 -274.857446) (xy 229.640688 -274.915339) (xy 229.617752 -274.970712) (xy 229.587785 -275.022618)
			(xy 229.551298 -275.070168) (xy 229.508918 -275.112548) (xy 229.461368 -275.149035) (xy 229.409462 -275.179002)
			(xy 229.354089 -275.201938) (xy 229.296196 -275.217451) (xy 229.236774 -275.225274) (xy 229.176838 -275.225274)
			(xy 229.117416 -275.217451) (xy 229.059523 -275.201938) (xy 229.00415 -275.179002) (xy 228.952244 -275.149035)
			(xy 228.904694 -275.112548) (xy 228.862314 -275.070168) (xy 228.825827 -275.022618) (xy 228.79586 -274.970712)
			(xy 228.772924 -274.915339) (xy 228.757411 -274.857446) (xy 228.749588 -274.798024) (xy 227.503414 -274.798024)
			(xy 227.487962 -274.83533) (xy 227.457995 -274.887236) (xy 227.421508 -274.934786) (xy 227.379128 -274.977166)
			(xy 227.331578 -275.013653) (xy 227.279672 -275.04362) (xy 227.224299 -275.066556) (xy 227.166406 -275.082069)
			(xy 227.106984 -275.089892) (xy 227.047048 -275.089892) (xy 226.987626 -275.082069) (xy 226.929733 -275.066556)
			(xy 226.87436 -275.04362) (xy 226.822454 -275.013653) (xy 226.774904 -274.977166) (xy 226.732524 -274.934786)
			(xy 226.696037 -274.887236) (xy 226.66607 -274.83533) (xy 226.643134 -274.779957) (xy 226.627621 -274.722064)
			(xy 226.619798 -274.662642) (xy 225.928178 -274.662642) (xy 225.355916 -275.234904) (xy 230.245394 -275.234904)
			(xy 230.245394 -275.174968) (xy 230.253217 -275.115546) (xy 230.26873 -275.057653) (xy 230.291666 -275.00228)
			(xy 230.321633 -274.950374) (xy 230.35812 -274.902824) (xy 230.4005 -274.860444) (xy 230.44805 -274.823957)
			(xy 230.499956 -274.79399) (xy 230.555329 -274.771054) (xy 230.613222 -274.755541) (xy 230.672644 -274.747718)
			(xy 230.73258 -274.747718) (xy 230.792002 -274.755541) (xy 230.849895 -274.771054) (xy 230.905268 -274.79399)
			(xy 230.957174 -274.823957) (xy 231.004724 -274.860444) (xy 231.047104 -274.902824) (xy 231.083591 -274.950374)
			(xy 231.113558 -275.00228) (xy 231.136494 -275.057653) (xy 231.152007 -275.115546) (xy 231.15983 -275.174968)
			(xy 231.16032 -275.204936) (xy 231.15983 -275.234904) (xy 231.152007 -275.294326) (xy 231.136494 -275.352219)
			(xy 231.113558 -275.407592) (xy 231.083591 -275.459498) (xy 231.049914 -275.503386) (xy 232.472228 -275.503386)
			(xy 232.476299 -275.447764) (xy 232.488425 -275.393327) (xy 232.508348 -275.341236) (xy 232.535644 -275.292601)
			(xy 232.56973 -275.248458) (xy 232.609879 -275.209749) (xy 232.655237 -275.177298) (xy 232.704837 -275.151797)
			(xy 232.757621 -275.13379) (xy 232.812464 -275.12366) (xy 232.868198 -275.121623) (xy 232.923635 -275.127723)
			(xy 232.977592 -275.141829) (xy 233.028921 -275.163641) (xy 233.076527 -275.192695) (xy 233.119395 -275.22837)
			(xy 233.156612 -275.269907) (xy 233.187385 -275.31642) (xy 233.211057 -275.366917) (xy 233.227125 -275.420324)
			(xy 233.235245 -275.4755) (xy 233.235754 -275.503386) (xy 233.235245 -275.531272) (xy 233.227125 -275.586448)
			(xy 233.211057 -275.639855) (xy 233.187385 -275.690352) (xy 233.156612 -275.736865) (xy 233.119395 -275.778402)
			(xy 233.076527 -275.814077) (xy 233.028921 -275.843131) (xy 232.977592 -275.864943) (xy 232.923635 -275.879049)
			(xy 232.868198 -275.885149) (xy 232.812464 -275.883112) (xy 232.757621 -275.872982) (xy 232.704837 -275.854975)
			(xy 232.655237 -275.829474) (xy 232.609879 -275.797023) (xy 232.56973 -275.758314) (xy 232.535644 -275.714171)
			(xy 232.508348 -275.665536) (xy 232.488425 -275.613445) (xy 232.476299 -275.559008) (xy 232.472228 -275.503386)
			(xy 231.049914 -275.503386) (xy 231.047104 -275.507048) (xy 231.004724 -275.549428) (xy 230.957174 -275.585915)
			(xy 230.905268 -275.615882) (xy 230.849895 -275.638818) (xy 230.792002 -275.654331) (xy 230.73258 -275.662154)
			(xy 230.672644 -275.662154) (xy 230.613222 -275.654331) (xy 230.555329 -275.638818) (xy 230.499956 -275.615882)
			(xy 230.44805 -275.585915) (xy 230.4005 -275.549428) (xy 230.35812 -275.507048) (xy 230.321633 -275.459498)
			(xy 230.291666 -275.407592) (xy 230.26873 -275.352219) (xy 230.253217 -275.294326) (xy 230.245394 -275.234904)
			(xy 225.355916 -275.234904) (xy 224.747582 -275.843238) (xy 224.740733 -275.850635) (xy 224.732999 -275.869234)
			(xy 224.732596 -275.879306) (xy 224.732596 -276.398986) (xy 225.05973 -276.398986) (xy 225.05973 -276.33905)
			(xy 225.067553 -276.279628) (xy 225.083066 -276.221735) (xy 225.106002 -276.166362) (xy 225.135969 -276.114456)
			(xy 225.172456 -276.066906) (xy 225.214836 -276.024526) (xy 225.262386 -275.988039) (xy 225.314292 -275.958072)
			(xy 225.369665 -275.935136) (xy 225.427558 -275.919623) (xy 225.48698 -275.9118) (xy 225.546916 -275.9118)
			(xy 225.606338 -275.919623) (xy 225.664231 -275.935136) (xy 225.719604 -275.958072) (xy 225.77151 -275.988039)
			(xy 225.81906 -276.024526) (xy 225.86144 -276.066906) (xy 225.897927 -276.114456) (xy 225.927894 -276.166362)
			(xy 225.95083 -276.221735) (xy 225.966343 -276.279628) (xy 225.974166 -276.33905) (xy 225.974656 -276.369018)
			(xy 225.974166 -276.398986) (xy 225.966343 -276.458408) (xy 225.95083 -276.516301) (xy 225.937139 -276.549354)
			(xy 230.377728 -276.549354) (xy 230.377728 -276.489418) (xy 230.385551 -276.429996) (xy 230.401064 -276.372103)
			(xy 230.424 -276.31673) (xy 230.453967 -276.264824) (xy 230.490454 -276.217274) (xy 230.532834 -276.174894)
			(xy 230.580384 -276.138407) (xy 230.63229 -276.10844) (xy 230.687663 -276.085504) (xy 230.745556 -276.069991)
			(xy 230.804978 -276.062168) (xy 230.864914 -276.062168) (xy 230.924336 -276.069991) (xy 230.982229 -276.085504)
			(xy 231.037602 -276.10844) (xy 231.089508 -276.138407) (xy 231.137058 -276.174894) (xy 231.179438 -276.217274)
			(xy 231.215925 -276.264824) (xy 231.245892 -276.31673) (xy 231.268828 -276.372103) (xy 231.284341 -276.429996)
			(xy 231.292164 -276.489418) (xy 231.292654 -276.519386) (xy 231.292164 -276.549354) (xy 231.284341 -276.608776)
			(xy 231.268828 -276.666669) (xy 231.245892 -276.722042) (xy 231.215925 -276.773948) (xy 231.179438 -276.821498)
			(xy 231.137058 -276.863878) (xy 231.089508 -276.900365) (xy 231.037602 -276.930332) (xy 230.982229 -276.953268)
			(xy 230.924336 -276.968781) (xy 230.864914 -276.976604) (xy 230.804978 -276.976604) (xy 230.745556 -276.968781)
			(xy 230.687663 -276.953268) (xy 230.63229 -276.930332) (xy 230.580384 -276.900365) (xy 230.532834 -276.863878)
			(xy 230.490454 -276.821498) (xy 230.453967 -276.773948) (xy 230.424 -276.722042) (xy 230.401064 -276.666669)
			(xy 230.385551 -276.608776) (xy 230.377728 -276.549354) (xy 225.937139 -276.549354) (xy 225.927894 -276.571674)
			(xy 225.897927 -276.62358) (xy 225.86144 -276.67113) (xy 225.81906 -276.71351) (xy 225.77151 -276.749997)
			(xy 225.719604 -276.779964) (xy 225.664231 -276.8029) (xy 225.606338 -276.818413) (xy 225.546916 -276.826236)
			(xy 225.48698 -276.826236) (xy 225.427558 -276.818413) (xy 225.369665 -276.8029) (xy 225.314292 -276.779964)
			(xy 225.262386 -276.749997) (xy 225.214836 -276.71351) (xy 225.172456 -276.67113) (xy 225.135969 -276.62358)
			(xy 225.106002 -276.571674) (xy 225.083066 -276.516301) (xy 225.067553 -276.458408) (xy 225.05973 -276.398986)
			(xy 224.732596 -276.398986) (xy 224.732596 -277.789386) (xy 230.377238 -277.789386) (xy 230.377728 -277.759418)
			(xy 230.385551 -277.699996) (xy 230.401064 -277.642103) (xy 230.424 -277.58673) (xy 230.453967 -277.534824)
			(xy 230.490454 -277.487274) (xy 230.532834 -277.444894) (xy 230.580384 -277.408407) (xy 230.63229 -277.37844)
			(xy 230.687663 -277.355504) (xy 230.745556 -277.339991) (xy 230.804978 -277.332168) (xy 230.864914 -277.332168)
			(xy 230.924336 -277.339991) (xy 230.982229 -277.355504) (xy 231.037602 -277.37844) (xy 231.089508 -277.408407)
			(xy 231.137058 -277.444894) (xy 231.179438 -277.487274) (xy 231.215925 -277.534824) (xy 231.234284 -277.566624)
			(xy 232.397028 -277.566624) (xy 232.397028 -277.506688) (xy 232.404851 -277.447266) (xy 232.420364 -277.389373)
			(xy 232.4433 -277.334) (xy 232.473267 -277.282094) (xy 232.509754 -277.234544) (xy 232.552134 -277.192164)
			(xy 232.599684 -277.155677) (xy 232.65159 -277.12571) (xy 232.706963 -277.102774) (xy 232.764856 -277.087261)
			(xy 232.824278 -277.079438) (xy 232.884214 -277.079438) (xy 232.943636 -277.087261) (xy 233.001529 -277.102774)
			(xy 233.056902 -277.12571) (xy 233.108808 -277.155677) (xy 233.156358 -277.192164) (xy 233.198738 -277.234544)
			(xy 233.235225 -277.282094) (xy 233.265192 -277.334) (xy 233.288128 -277.389373) (xy 233.303641 -277.447266)
			(xy 233.311464 -277.506688) (xy 233.311954 -277.536656) (xy 233.311464 -277.566624) (xy 233.303641 -277.626046)
			(xy 233.288128 -277.683939) (xy 233.265192 -277.739312) (xy 233.235225 -277.791218) (xy 233.198738 -277.838768)
			(xy 233.156358 -277.881148) (xy 233.108808 -277.917635) (xy 233.056902 -277.947602) (xy 233.001529 -277.970538)
			(xy 232.943636 -277.986051) (xy 232.884214 -277.993874) (xy 232.824278 -277.993874) (xy 232.764856 -277.986051)
			(xy 232.706963 -277.970538) (xy 232.65159 -277.947602) (xy 232.599684 -277.917635) (xy 232.552134 -277.881148)
			(xy 232.509754 -277.838768) (xy 232.473267 -277.791218) (xy 232.4433 -277.739312) (xy 232.420364 -277.683939)
			(xy 232.404851 -277.626046) (xy 232.397028 -277.566624) (xy 231.234284 -277.566624) (xy 231.245892 -277.58673)
			(xy 231.268828 -277.642103) (xy 231.284341 -277.699996) (xy 231.292164 -277.759418) (xy 231.292654 -277.789386)
			(xy 231.292215 -277.818349) (xy 231.284893 -277.87581) (xy 231.270378 -277.931887) (xy 231.248901 -277.985684)
			(xy 231.220806 -278.03634) (xy 231.186542 -278.083045) (xy 231.146658 -278.125052) (xy 231.124506 -278.143716)
			(xy 231.116378 -278.150574) (xy 231.106726 -278.169116) (xy 231.100122 -278.264112) (xy 231.107234 -278.283924)
			(xy 231.114346 -278.291544) (xy 231.133415 -278.312861) (xy 231.165674 -278.360086) (xy 231.190523 -278.411597)
			(xy 231.207405 -278.46624) (xy 231.215943 -278.52279) (xy 231.216454 -278.551386) (xy 231.215968 -278.578637)
			(xy 231.208212 -278.632585) (xy 231.192857 -278.68488) (xy 231.170215 -278.734457) (xy 231.140749 -278.780307)
			(xy 231.105058 -278.821498) (xy 231.063867 -278.857189) (xy 231.018017 -278.886655) (xy 230.96844 -278.909297)
			(xy 230.916145 -278.924652) (xy 230.862197 -278.932408) (xy 230.807695 -278.932408) (xy 230.753747 -278.924652)
			(xy 230.701452 -278.909297) (xy 230.651875 -278.886655) (xy 230.606025 -278.857189) (xy 230.564834 -278.821498)
			(xy 230.529143 -278.780307) (xy 230.499677 -278.734457) (xy 230.477035 -278.68488) (xy 230.46168 -278.632585)
			(xy 230.453924 -278.578637) (xy 230.453438 -278.551386) (xy 230.453928 -278.522789) (xy 230.462474 -278.466237)
			(xy 230.479358 -278.411591) (xy 230.504203 -278.360075) (xy 230.536452 -278.312839) (xy 230.555546 -278.291544)
			(xy 230.562658 -278.283924) (xy 230.56977 -278.264112) (xy 230.563166 -278.169116) (xy 230.553514 -278.150574)
			(xy 230.545386 -278.143716) (xy 230.523234 -278.125052) (xy 230.483344 -278.083049) (xy 230.449076 -278.036346)
			(xy 230.42098 -277.98569) (xy 230.399505 -277.931891) (xy 230.384996 -277.875812) (xy 230.377683 -277.818349)
			(xy 230.377238 -277.789386) (xy 224.732596 -277.789386) (xy 224.732596 -278.711406) (xy 224.732172 -278.721476)
			(xy 224.724455 -278.740078) (xy 224.71761 -278.747474) (xy 224.409762 -279.055322) (xy 232.504232 -279.055322)
			(xy 232.508303 -278.9997) (xy 232.520429 -278.945263) (xy 232.540352 -278.893172) (xy 232.567648 -278.844537)
			(xy 232.601734 -278.800394) (xy 232.641883 -278.761685) (xy 232.687241 -278.729234) (xy 232.736841 -278.703733)
			(xy 232.789625 -278.685726) (xy 232.844468 -278.675596) (xy 232.900202 -278.673559) (xy 232.955639 -278.679659)
			(xy 233.009596 -278.693765) (xy 233.060925 -278.715577) (xy 233.108531 -278.744631) (xy 233.151399 -278.780306)
			(xy 233.188616 -278.821843) (xy 233.219389 -278.868356) (xy 233.243061 -278.918853) (xy 233.259129 -278.97226)
			(xy 233.267249 -279.027436) (xy 233.267758 -279.055322) (xy 233.267249 -279.083208) (xy 233.259129 -279.138384)
			(xy 233.243061 -279.191791) (xy 233.219389 -279.242288) (xy 233.188616 -279.288801) (xy 233.151399 -279.330338)
			(xy 233.108531 -279.366013) (xy 233.060925 -279.395067) (xy 233.009596 -279.416879) (xy 232.955639 -279.430985)
			(xy 232.900202 -279.437085) (xy 232.844468 -279.435048) (xy 232.789625 -279.424918) (xy 232.736841 -279.406911)
			(xy 232.687241 -279.38141) (xy 232.641883 -279.348959) (xy 232.601734 -279.31025) (xy 232.567648 -279.266107)
			(xy 232.540352 -279.217472) (xy 232.520429 -279.165381) (xy 232.508303 -279.110944) (xy 232.504232 -279.055322)
			(xy 224.409762 -279.055322) (xy 224.229168 -279.235916) (xy 224.22249 -279.243328) (xy 224.214918 -279.261764)
			(xy 224.214436 -279.27173) (xy 224.214436 -279.597354) (xy 230.377728 -279.597354) (xy 230.377728 -279.537418)
			(xy 230.385551 -279.477996) (xy 230.401064 -279.420103) (xy 230.424 -279.36473) (xy 230.453967 -279.312824)
			(xy 230.490454 -279.265274) (xy 230.532834 -279.222894) (xy 230.580384 -279.186407) (xy 230.63229 -279.15644)
			(xy 230.687663 -279.133504) (xy 230.745556 -279.117991) (xy 230.804978 -279.110168) (xy 230.864914 -279.110168)
			(xy 230.924336 -279.117991) (xy 230.982229 -279.133504) (xy 231.037602 -279.15644) (xy 231.089508 -279.186407)
			(xy 231.137058 -279.222894) (xy 231.179438 -279.265274) (xy 231.215925 -279.312824) (xy 231.245892 -279.36473)
			(xy 231.268828 -279.420103) (xy 231.284341 -279.477996) (xy 231.292164 -279.537418) (xy 231.292654 -279.567386)
			(xy 231.292164 -279.597354) (xy 231.284341 -279.656776) (xy 231.268828 -279.714669) (xy 231.245892 -279.770042)
			(xy 231.215925 -279.821948) (xy 231.179438 -279.869498) (xy 231.137058 -279.911878) (xy 231.089508 -279.948365)
			(xy 231.037602 -279.978332) (xy 230.982229 -280.001268) (xy 230.924336 -280.016781) (xy 230.864914 -280.024604)
			(xy 230.804978 -280.024604) (xy 230.745556 -280.016781) (xy 230.687663 -280.001268) (xy 230.63229 -279.978332)
			(xy 230.580384 -279.948365) (xy 230.532834 -279.911878) (xy 230.490454 -279.869498) (xy 230.453967 -279.821948)
			(xy 230.424 -279.770042) (xy 230.401064 -279.714669) (xy 230.385551 -279.656776) (xy 230.377728 -279.597354)
			(xy 224.214436 -279.597354) (xy 224.214436 -279.865074) (xy 224.213904 -279.875064) (xy 224.206201 -279.893507)
			(xy 224.19945 -279.900888) (xy 224.194116 -279.906476) (xy 224.187316 -279.913825) (xy 224.179608 -279.932288)
			(xy 224.17913 -279.94229) (xy 224.17913 -280.246582) (xy 224.179569 -280.256645) (xy 224.187307 -280.275225)
			(xy 224.194116 -280.28265) (xy 224.298256 -280.38679) (xy 224.305657 -280.393629) (xy 224.324255 -280.401345)
			(xy 224.334324 -280.401776) (xy 226.345242 -280.401776) (xy 226.353726 -280.401463) (xy 226.369755 -280.395901)
			(xy 226.383063 -280.385377) (xy 226.387914 -280.378408) (xy 226.441254 -280.295858) (xy 226.443286 -280.270204)
			(xy 226.437952 -280.258266) (xy 226.427225 -280.233456) (xy 226.412085 -280.181569) (xy 226.404414 -280.128065)
			(xy 226.403916 -280.10104) (xy 226.404402 -280.073789) (xy 226.412158 -280.019841) (xy 226.427513 -279.967546)
			(xy 226.450155 -279.917969) (xy 226.479621 -279.872119) (xy 226.515312 -279.830928) (xy 226.556503 -279.795237)
			(xy 226.602353 -279.765771) (xy 226.65193 -279.743129) (xy 226.704225 -279.727774) (xy 226.758173 -279.720018)
			(xy 226.812675 -279.720018) (xy 226.866623 -279.727774) (xy 226.918918 -279.743129) (xy 226.968495 -279.765771)
			(xy 227.014345 -279.795237) (xy 227.055536 -279.830928) (xy 227.091227 -279.872119) (xy 227.120693 -279.917969)
			(xy 227.143335 -279.967546) (xy 227.15869 -280.019841) (xy 227.166446 -280.073789) (xy 227.166932 -280.10104)
			(xy 227.166444 -280.128066) (xy 227.158774 -280.18157) (xy 227.143621 -280.233455) (xy 227.132896 -280.258266)
			(xy 227.127562 -280.270204) (xy 227.129594 -280.295858) (xy 227.182934 -280.378408) (xy 227.187787 -280.385369)
			(xy 227.201112 -280.395861) (xy 227.217127 -280.401443) (xy 227.225606 -280.401776) (xy 228.178614 -280.401776)
			(xy 228.188684 -280.402201) (xy 228.207287 -280.409916) (xy 228.214682 -280.416762) (xy 228.32847 -280.53055)
			(xy 228.740444 -280.53055) (xy 228.740444 -280.470614) (xy 228.748267 -280.411192) (xy 228.76378 -280.353299)
			(xy 228.786716 -280.297926) (xy 228.816683 -280.24602) (xy 228.85317 -280.19847) (xy 228.89555 -280.15609)
			(xy 228.9431 -280.119603) (xy 228.995006 -280.089636) (xy 229.050379 -280.0667) (xy 229.108272 -280.051187)
			(xy 229.167694 -280.043364) (xy 229.22763 -280.043364) (xy 229.287052 -280.051187) (xy 229.344945 -280.0667)
			(xy 229.400318 -280.089636) (xy 229.452224 -280.119603) (xy 229.499774 -280.15609) (xy 229.542154 -280.19847)
			(xy 229.578641 -280.24602) (xy 229.608608 -280.297926) (xy 229.631544 -280.353299) (xy 229.647057 -280.411192)
			(xy 229.65488 -280.470614) (xy 229.65537 -280.500582) (xy 229.65488 -280.53055) (xy 229.647924 -280.583386)
			(xy 232.472228 -280.583386) (xy 232.476299 -280.527764) (xy 232.488425 -280.473327) (xy 232.508348 -280.421236)
			(xy 232.535644 -280.372601) (xy 232.56973 -280.328458) (xy 232.609879 -280.289749) (xy 232.655237 -280.257298)
			(xy 232.704837 -280.231797) (xy 232.757621 -280.21379) (xy 232.812464 -280.20366) (xy 232.868198 -280.201623)
			(xy 232.923635 -280.207723) (xy 232.977592 -280.221829) (xy 233.028921 -280.243641) (xy 233.076527 -280.272695)
			(xy 233.119395 -280.30837) (xy 233.156612 -280.349907) (xy 233.187385 -280.39642) (xy 233.211057 -280.446917)
			(xy 233.227125 -280.500324) (xy 233.235245 -280.5555) (xy 233.235754 -280.583386) (xy 233.235245 -280.611272)
			(xy 233.227125 -280.666448) (xy 233.211057 -280.719855) (xy 233.187385 -280.770352) (xy 233.156612 -280.816865)
			(xy 233.119395 -280.858402) (xy 233.076527 -280.894077) (xy 233.028921 -280.923131) (xy 232.977592 -280.944943)
			(xy 232.923635 -280.959049) (xy 232.868198 -280.965149) (xy 232.812464 -280.963112) (xy 232.757621 -280.952982)
			(xy 232.704837 -280.934975) (xy 232.655237 -280.909474) (xy 232.609879 -280.877023) (xy 232.56973 -280.838314)
			(xy 232.535644 -280.794171) (xy 232.508348 -280.745536) (xy 232.488425 -280.693445) (xy 232.476299 -280.639008)
			(xy 232.472228 -280.583386) (xy 229.647924 -280.583386) (xy 229.647057 -280.589972) (xy 229.631544 -280.647865)
			(xy 229.608608 -280.703238) (xy 229.578641 -280.755144) (xy 229.542154 -280.802694) (xy 229.499774 -280.845074)
			(xy 229.452224 -280.881561) (xy 229.400318 -280.911528) (xy 229.344945 -280.934464) (xy 229.287052 -280.949977)
			(xy 229.22763 -280.9578) (xy 229.167694 -280.9578) (xy 229.108272 -280.949977) (xy 229.050379 -280.934464)
			(xy 228.995006 -280.911528) (xy 228.9431 -280.881561) (xy 228.89555 -280.845074) (xy 228.85317 -280.802694)
			(xy 228.816683 -280.755144) (xy 228.786716 -280.703238) (xy 228.76378 -280.647865) (xy 228.748267 -280.589972)
			(xy 228.740444 -280.53055) (xy 228.32847 -280.53055) (xy 228.706426 -280.908506) (xy 228.713279 -280.915901)
			(xy 228.721023 -280.9345) (xy 228.721412 -280.944574) (xy 228.721412 -293.57447) (xy 228.720977 -293.584535)
			(xy 228.713246 -293.603122) (xy 228.706426 -293.610538) (xy 228.348794 -293.96817) (xy 228.341397 -293.975019)
			(xy 228.322798 -293.982756) (xy 228.312726 -293.983156) (xy 220.25864 -293.983156) (xy 220.248576 -293.982721)
			(xy 220.229991 -293.974986) (xy 220.222572 -293.96817) (xy 219.581984 -293.327582) (xy 219.575131 -293.320187)
			(xy 219.56739 -293.301588) (xy 219.566998 -293.291514) (xy 219.566998 -284.452568) (xy 219.566569 -284.4425)
			(xy 219.558846 -284.423905) (xy 219.552012 -284.4165) (xy 219.39377 -284.258258) (xy 219.386373 -284.25141)
			(xy 219.367774 -284.243677) (xy 219.357702 -284.243272) (xy 213.844378 -284.243272) (xy 213.834309 -284.243698)
			(xy 213.815708 -284.251415) (xy 213.80831 -284.258258) (xy 213.135718 -284.93085) (xy 213.128877 -284.93825)
			(xy 213.121158 -284.956849) (xy 213.120732 -284.966918) (xy 213.120732 -295.619678) (xy 213.113112 -295.63822)
			(xy 213.107778 -295.643554) (xy 213.107778 -306.744116) (xy 221.82328 -306.744116) (xy 221.823808 -306.710836)
			(xy 221.832483 -306.644845) (xy 221.849701 -306.580551) (xy 221.875166 -306.519056) (xy 221.908442 -306.461412)
			(xy 221.94896 -306.408606) (xy 221.972124 -306.384706) (xy 222.527114 -305.829716) (xy 222.551053 -305.806596)
			(xy 222.603857 -305.766086) (xy 222.661495 -305.732812) (xy 222.722981 -305.707343) (xy 222.787265 -305.690114)
			(xy 222.853248 -305.68142) (xy 222.886524 -305.680872) (xy 227.759006 -305.680872) (xy 227.792286 -305.681388)
			(xy 227.858278 -305.690066) (xy 227.922572 -305.707286) (xy 227.984067 -305.732753) (xy 228.041711 -305.766032)
			(xy 228.094516 -305.806551) (xy 228.118416 -305.829716) (xy 228.995478 -306.706778) (xy 229.001963 -306.712809)
			(xy 229.01798 -306.720338) (xy 229.035606 -306.721929) (xy 229.044246 -306.719986) (xy 229.14229 -306.694332)
			(xy 229.16134 -306.675536) (xy 229.16515 -306.662582) (xy 229.173682 -306.634176) (xy 229.197044 -306.57966)
			(xy 229.227252 -306.528619) (xy 229.263801 -306.481907) (xy 229.306079 -306.440309) (xy 229.353375 -306.404521)
			(xy 229.404899 -306.375142) (xy 229.459786 -306.352666) (xy 229.517117 -306.337468) (xy 229.575931 -306.329805)
			(xy 229.605586 -306.329334) (xy 229.635556 -306.329774) (xy 229.694985 -306.337597) (xy 229.752883 -306.35311)
			(xy 229.808261 -306.376049) (xy 229.860171 -306.40602) (xy 229.907725 -306.44251) (xy 229.950108 -306.484896)
			(xy 229.986596 -306.532452) (xy 230.016564 -306.584364) (xy 230.039499 -306.639743) (xy 230.055009 -306.697643)
			(xy 230.061123 -306.744116) (xy 238.073184 -306.744116) (xy 238.073767 -306.710832) (xy 238.0825 -306.644838)
			(xy 238.099767 -306.580546) (xy 238.125273 -306.519057) (xy 238.158582 -306.46142) (xy 238.199124 -306.40862)
			(xy 238.222282 -306.384706) (xy 238.777272 -305.829716) (xy 238.801185 -305.806568) (xy 238.853995 -305.76606)
			(xy 238.911638 -305.73279) (xy 238.973129 -305.707326) (xy 239.037418 -305.690104) (xy 239.103404 -305.681417)
			(xy 239.136682 -305.680872) (xy 244.009164 -305.680872) (xy 244.042443 -305.681415) (xy 244.108434 -305.690088)
			(xy 244.172727 -305.707303) (xy 244.234223 -305.732765) (xy 244.291867 -305.766038) (xy 244.344673 -305.806553)
			(xy 244.368574 -305.829716) (xy 245.245636 -306.706778) (xy 245.25209 -306.712847) (xy 245.268123 -306.720366)
			(xy 245.285761 -306.72194) (xy 245.294404 -306.719986) (xy 245.392448 -306.694332) (xy 245.411498 -306.675536)
			(xy 245.415308 -306.662582) (xy 245.423788 -306.634159) (xy 245.447154 -306.57964) (xy 245.477367 -306.528597)
			(xy 245.513922 -306.481884) (xy 245.556205 -306.440286) (xy 245.603508 -306.404499) (xy 245.655038 -306.375123)
			(xy 245.709931 -306.352651) (xy 245.767268 -306.337459) (xy 245.826086 -306.329801) (xy 245.855744 -306.329334)
			(xy 245.885714 -306.329741) (xy 245.945142 -306.337571) (xy 246.003039 -306.35309) (xy 246.058415 -306.376034)
			(xy 246.110322 -306.406009) (xy 246.157873 -306.442503) (xy 246.200254 -306.484892) (xy 246.236739 -306.532449)
			(xy 246.266705 -306.584363) (xy 246.289638 -306.639743) (xy 246.305146 -306.697643) (xy 246.312965 -306.757072)
			(xy 246.313452 -306.787042) (xy 246.312986 -306.817761) (xy 246.304774 -306.878648) (xy 246.288491 -306.937888)
			(xy 246.26443 -306.994418) (xy 246.233021 -307.047221) (xy 246.194832 -307.095347) (xy 246.150547 -307.137932)
			(xy 246.100963 -307.17421) (xy 246.046972 -307.203528) (xy 245.989544 -307.22536) (xy 245.929712 -307.239312)
			(xy 245.899178 -307.242718) (xy 245.890542 -307.24348) (xy 245.87454 -307.2511) (xy 245.86819 -307.257196)
			(xy 245.861436 -307.2646) (xy 245.853805 -307.283114) (xy 245.853815 -307.303138) (xy 245.861466 -307.321644)
			(xy 245.86819 -307.329078) (xy 245.885716 -307.346858) (xy 245.908863 -307.370772) (xy 245.949369 -307.423582)
			(xy 245.982639 -307.481225) (xy 245.983901 -307.484272) (xy 248.185684 -307.484272) (xy 248.189757 -307.428613)
			(xy 248.201892 -307.37414) (xy 248.221828 -307.322014) (xy 248.249142 -307.273346) (xy 248.28325 -307.229174)
			(xy 248.323427 -307.190439) (xy 248.368815 -307.157967) (xy 248.418447 -307.132449) (xy 248.471267 -307.11443)
			(xy 248.526146 -307.104293) (xy 248.581917 -307.102255) (xy 248.637391 -307.108358) (xy 248.691384 -307.122474)
			(xy 248.742747 -307.144301) (xy 248.790385 -307.173374) (xy 248.833281 -307.209073) (xy 248.870523 -307.250637)
			(xy 248.901317 -307.297181) (xy 248.925005 -307.347712) (xy 248.941083 -307.401154) (xy 248.949209 -307.456368)
			(xy 248.949718 -307.484272) (xy 248.949209 -307.512176) (xy 248.941083 -307.56739) (xy 248.925005 -307.620832)
			(xy 248.901317 -307.671363) (xy 248.870523 -307.717907) (xy 248.833281 -307.759471) (xy 248.790385 -307.79517)
			(xy 248.742747 -307.824243) (xy 248.691384 -307.84607) (xy 248.637391 -307.860186) (xy 248.581917 -307.866289)
			(xy 248.526146 -307.864251) (xy 248.471267 -307.854114) (xy 248.418447 -307.836095) (xy 248.368815 -307.810577)
			(xy 248.323427 -307.778105) (xy 248.28325 -307.73937) (xy 248.249142 -307.695198) (xy 248.221828 -307.64653)
			(xy 248.201892 -307.594404) (xy 248.189757 -307.539931) (xy 248.185684 -307.484272) (xy 245.983901 -307.484272)
			(xy 246.008103 -307.542716) (xy 246.025326 -307.607005) (xy 246.034014 -307.67299) (xy 246.03456 -307.706268)
			(xy 246.03456 -308.669182) (xy 246.035078 -308.679686) (xy 246.043455 -308.698949) (xy 246.058851 -308.713238)
			(xy 246.068596 -308.717188) (xy 246.174514 -308.754018) (xy 246.205502 -308.745128) (xy 246.215662 -308.732428)
			(xy 246.234354 -308.709826) (xy 246.276527 -308.669064) (xy 246.323559 -308.634022) (xy 246.374682 -308.605273)
			(xy 246.429058 -308.583289) (xy 246.485797 -308.56843) (xy 246.543968 -308.560938) (xy 246.573294 -308.56047)
			(xy 246.603262 -308.560983) (xy 246.662685 -308.568805) (xy 246.66286 -308.568852) (xy 248.185684 -308.568852)
			(xy 248.189757 -308.513193) (xy 248.201892 -308.45872) (xy 248.221828 -308.406594) (xy 248.249142 -308.357926)
			(xy 248.28325 -308.313754) (xy 248.323427 -308.275019) (xy 248.368815 -308.242547) (xy 248.418447 -308.217029)
			(xy 248.471267 -308.19901) (xy 248.526146 -308.188873) (xy 248.581917 -308.186835) (xy 248.637391 -308.192938)
			(xy 248.691384 -308.207054) (xy 248.742747 -308.228881) (xy 248.790385 -308.257954) (xy 248.833281 -308.293653)
			(xy 248.870523 -308.335217) (xy 248.901317 -308.381761) (xy 248.925005 -308.432292) (xy 248.941083 -308.485734)
			(xy 248.949209 -308.540948) (xy 248.949718 -308.568852) (xy 248.949209 -308.596756) (xy 248.941083 -308.65197)
			(xy 248.925005 -308.705412) (xy 248.901317 -308.755943) (xy 248.870523 -308.802487) (xy 248.833281 -308.844051)
			(xy 248.790385 -308.87975) (xy 248.742747 -308.908823) (xy 248.691384 -308.93065) (xy 248.637391 -308.944766)
			(xy 248.581917 -308.950869) (xy 248.526146 -308.948831) (xy 248.471267 -308.938694) (xy 248.418447 -308.920675)
			(xy 248.368815 -308.895157) (xy 248.323427 -308.862685) (xy 248.28325 -308.82395) (xy 248.249142 -308.779778)
			(xy 248.221828 -308.73111) (xy 248.201892 -308.678984) (xy 248.189757 -308.624511) (xy 248.185684 -308.568852)
			(xy 246.66286 -308.568852) (xy 246.720578 -308.584317) (xy 246.775952 -308.607253) (xy 246.827858 -308.63722)
			(xy 246.875408 -308.673706) (xy 246.91779 -308.716087) (xy 246.954276 -308.763637) (xy 246.984245 -308.815543)
			(xy 247.007181 -308.870916) (xy 247.022694 -308.928809) (xy 247.030517 -308.988232) (xy 247.030517 -309.048168)
			(xy 247.022694 -309.107591) (xy 247.007181 -309.165484) (xy 246.984245 -309.220857) (xy 246.954276 -309.272763)
			(xy 246.91779 -309.320313) (xy 246.875408 -309.362694) (xy 246.827858 -309.39918) (xy 246.775952 -309.429147)
			(xy 246.720578 -309.452083) (xy 246.662685 -309.467595) (xy 246.603262 -309.475417) (xy 246.573294 -309.475886)
			(xy 246.543969 -309.475415) (xy 246.485799 -309.467915) (xy 246.429062 -309.453052) (xy 246.374687 -309.431069)
			(xy 246.323562 -309.402324) (xy 246.276525 -309.36729) (xy 246.234344 -309.326538) (xy 246.215662 -309.303928)
			(xy 246.205502 -309.291228) (xy 246.174514 -309.282338) (xy 246.068596 -309.319168) (xy 246.058854 -309.323119)
			(xy 246.043472 -309.33742) (xy 246.035078 -309.356673) (xy 246.03456 -309.367174) (xy 246.03456 -309.589424)
			(xy 246.035129 -309.599404) (xy 246.042846 -309.617822) (xy 246.056964 -309.631945) (xy 246.07538 -309.639667)
			(xy 246.08536 -309.640224) (xy 246.798592 -309.640224) (xy 246.829314 -309.640663) (xy 246.890311 -309.648066)
			(xy 246.949972 -309.662766) (xy 247.007426 -309.684548) (xy 247.061836 -309.713095) (xy 247.11241 -309.747991)
			(xy 247.158411 -309.788726) (xy 247.199167 -309.834708) (xy 247.234086 -309.885267) (xy 247.262657 -309.939664)
			(xy 247.284465 -309.997109) (xy 247.299192 -310.056762) (xy 247.306623 -310.117756) (xy 247.3071 -310.148478)
			(xy 247.306587 -310.179423) (xy 247.299053 -310.240852) (xy 247.284119 -310.300913) (xy 247.262004 -310.358717)
			(xy 247.233037 -310.41341) (xy 247.197646 -310.464182) (xy 247.156353 -310.510283) (xy 247.133364 -310.531002)
			(xy 247.125485 -310.538557) (xy 247.116541 -310.558448) (xy 247.116092 -310.569356) (xy 247.116092 -310.811164)
			(xy 247.125236 -310.811164) (xy 247.135242 -310.811658) (xy 247.153727 -310.819322) (xy 247.167878 -310.833473)
			(xy 247.175542 -310.851958) (xy 247.176036 -310.861964) (xy 247.176036 -311.078626) (xy 247.175399 -311.10181)
			(xy 247.165887 -311.147194) (xy 247.147329 -311.189688) (xy 247.13438 -311.208928) (xy 247.13011 -311.21553)
			(xy 247.125447 -311.230533) (xy 247.125236 -311.238392) (xy 247.125236 -311.736486) (xy 247.125612 -311.744758)
			(xy 247.130907 -311.760434) (xy 247.13565 -311.76722) (xy 247.150095 -311.787139) (xy 247.170829 -311.831753)
			(xy 247.18148 -311.879783) (xy 247.182132 -311.90438) (xy 247.182132 -312.172096) (xy 247.172988 -312.172096)
			(xy 247.16298 -312.172578) (xy 247.144489 -312.180241) (xy 247.130337 -312.194396) (xy 247.122677 -312.212888)
			(xy 247.122188 -312.222896) (xy 247.122188 -312.46318) (xy 247.122735 -312.473173) (xy 247.130414 -312.491628)
			(xy 247.144545 -312.505767) (xy 247.162995 -312.513458) (xy 247.172988 -312.51398) (xy 247.952768 -312.51398)
			(xy 247.96279 -312.513554) (xy 247.98131 -312.505891) (xy 247.995484 -312.49172) (xy 248.003151 -312.473202)
			(xy 248.003568 -312.46318) (xy 248.003568 -310.333136) (xy 248.004126 -310.305971) (xy 248.013301 -310.252421)
			(xy 248.031378 -310.201187) (xy 248.057838 -310.153735) (xy 248.074434 -310.132222) (xy 248.077794 -310.127716)
			(xy 248.082673 -310.117595) (xy 248.084086 -310.112156) (xy 248.091234 -310.084804) (xy 248.11254 -310.03244)
			(xy 248.141336 -309.983791) (xy 248.176992 -309.939921) (xy 248.218728 -309.901789) (xy 248.265632 -309.87023)
			(xy 248.316677 -309.845932) (xy 248.370747 -309.829429) (xy 248.42666 -309.821081) (xy 248.454926 -309.820564)
			(xy 248.482177 -309.821054) (xy 248.536123 -309.828813) (xy 248.588416 -309.84417) (xy 248.637991 -309.866812)
			(xy 248.68384 -309.896278) (xy 248.725029 -309.931969) (xy 248.76072 -309.973158) (xy 248.790187 -310.019007)
			(xy 248.812829 -310.068582) (xy 248.828187 -310.120875) (xy 248.835946 -310.174821) (xy 248.836434 -310.202072)
			(xy 248.835944 -310.228842) (xy 248.828449 -310.281856) (xy 248.813618 -310.333302) (xy 248.791742 -310.38217)
			(xy 248.763249 -310.4275) (xy 248.7287 -310.468402) (xy 248.688772 -310.504073) (xy 248.666762 -310.519318)
			(xy 248.65667 -310.52681) (xy 248.644804 -310.54893) (xy 248.644156 -310.561482) (xy 248.644156 -312.674254)
			(xy 248.64365 -312.699426) (xy 248.635789 -312.749152) (xy 248.620254 -312.797038) (xy 248.597425 -312.841908)
			(xy 248.567864 -312.882659) (xy 248.55043 -312.900822) (xy 248.390156 -313.061096) (xy 248.372017 -313.078571)
			(xy 248.331273 -313.10818) (xy 248.286404 -313.131059) (xy 248.238511 -313.146647) (xy 248.188771 -313.154561)
			(xy 248.163588 -313.155076) (xy 247.08485 -313.155076) (xy 247.072658 -313.158124) (xy 247.066816 -313.161426)
			(xy 247.049538 -313.170705) (xy 247.01257 -313.18379) (xy 246.973904 -313.190326) (xy 246.954294 -313.190636)
			(xy 246.655082 -313.190636) (xy 246.632752 -313.190306) (xy 246.588896 -313.181896) (xy 246.547541 -313.16505)
			(xy 246.510292 -313.140424) (xy 246.478594 -313.108971) (xy 246.453678 -313.071914) (xy 246.436512 -313.030692)
			(xy 246.427761 -312.986903) (xy 246.427244 -312.964576) (xy 246.427244 -312.69686) (xy 246.436388 -312.69686)
			(xy 246.446425 -312.696501) (xy 246.464984 -312.688857) (xy 246.479172 -312.67466) (xy 246.486807 -312.656098)
			(xy 246.487188 -312.64606) (xy 246.487188 -312.172096) (xy 246.478044 -312.172096) (xy 246.468007 -312.171758)
			(xy 246.449454 -312.164098) (xy 246.435269 -312.149896) (xy 246.42763 -312.131334) (xy 246.427244 -312.121296)
			(xy 246.427244 -311.90438) (xy 246.427851 -311.879778) (xy 246.438491 -311.831737) (xy 246.459263 -311.787132)
			(xy 246.473726 -311.76722) (xy 246.478521 -311.76046) (xy 246.483826 -311.744769) (xy 246.48414 -311.736486)
			(xy 246.48414 -311.319672) (xy 246.483636 -311.309667) (xy 246.475975 -311.291183) (xy 246.461827 -311.277032)
			(xy 246.443344 -311.269366) (xy 246.43334 -311.268872) (xy 244.610636 -311.268872) (xy 244.58295 -311.291732)
			(xy 244.57914 -311.309512) (xy 244.572161 -311.339968) (xy 244.551161 -311.398812) (xy 244.522353 -311.454254)
			(xy 244.486273 -311.505263) (xy 244.443591 -311.55089) (xy 244.395099 -311.590289) (xy 244.3417 -311.622727)
			(xy 244.284386 -311.647601) (xy 244.224221 -311.664449) (xy 244.162324 -311.672957) (xy 244.131084 -311.673494)
			(xy 244.101115 -311.673033) (xy 244.041691 -311.665207) (xy 243.983797 -311.649693) (xy 243.928423 -311.626754)
			(xy 243.876517 -311.596783) (xy 243.828967 -311.560294) (xy 243.786586 -311.517911) (xy 243.7501 -311.470358)
			(xy 243.720133 -311.41845) (xy 243.697198 -311.363075) (xy 243.681687 -311.305179) (xy 243.673865 -311.245755)
			(xy 243.673376 -311.215786) (xy 243.673856 -311.186444) (xy 243.681359 -311.128243) (xy 243.696239 -311.071477)
			(xy 243.718252 -311.017079) (xy 243.747038 -310.965941) (xy 243.782123 -310.918902) (xy 243.822933 -310.876732)
			(xy 243.868799 -310.840125) (xy 243.918967 -310.809681) (xy 243.972615 -310.785898) (xy 244.028863 -310.769167)
			(xy 244.086788 -310.759763) (xy 244.116098 -310.758332) (xy 244.126004 -310.758078) (xy 244.143276 -310.750458)
			(xy 244.171724 -310.72201) (xy 244.189874 -310.704555) (xy 244.230611 -310.674959) (xy 244.275481 -310.652111)
			(xy 244.323377 -310.636574) (xy 244.373115 -310.628731) (xy 244.398292 -310.628284) (xy 245.420134 -310.628284)
			(xy 245.430529 -310.627739) (xy 245.449615 -310.619491) (xy 245.463873 -310.604359) (xy 245.467886 -310.594756)
			(xy 245.476776 -310.570626) (xy 245.479619 -310.561195) (xy 245.478789 -310.541537) (xy 245.470646 -310.523625)
			(xy 245.463822 -310.516524) (xy 245.455186 -310.507888) (xy 245.166896 -310.219598) (xy 245.147387 -310.199608)
			(xy 245.112381 -310.156077) (xy 245.097046 -310.13273) (xy 245.091458 -310.123586) (xy 245.073678 -310.111902)
			(xy 244.978428 -310.095138) (xy 244.9576 -310.100218) (xy 244.949218 -310.106822) (xy 244.925065 -310.124951)
			(xy 244.87289 -310.155365) (xy 244.817167 -310.178651) (xy 244.758866 -310.194404) (xy 244.698998 -310.202349)
			(xy 244.668802 -310.202834) (xy 244.638835 -310.202313) (xy 244.579413 -310.19449) (xy 244.52152 -310.178978)
			(xy 244.466147 -310.156042) (xy 244.414242 -310.126075) (xy 244.366693 -310.089589) (xy 244.324312 -310.047209)
			(xy 244.287826 -309.99966) (xy 244.257859 -309.947755) (xy 244.234922 -309.892382) (xy 244.21941 -309.834489)
			(xy 244.211587 -309.775067) (xy 244.211587 -309.715133) (xy 244.21941 -309.655711) (xy 244.234922 -309.597818)
			(xy 244.257859 -309.542445) (xy 244.287826 -309.49054) (xy 244.324312 -309.442991) (xy 244.366693 -309.400611)
			(xy 244.414242 -309.364125) (xy 244.466147 -309.334158) (xy 244.52152 -309.311222) (xy 244.579413 -309.29571)
			(xy 244.638835 -309.287887) (xy 244.668802 -309.287418) (xy 244.703812 -309.288075) (xy 244.773018 -309.298724)
			(xy 244.8398 -309.319775) (xy 244.871494 -309.334662) (xy 244.883178 -309.340504) (xy 244.90934 -309.339234)
			(xy 244.993922 -309.286656) (xy 245.001099 -309.281837) (xy 245.011956 -309.268401) (xy 245.01771 -309.252113)
			(xy 245.018052 -309.243476) (xy 245.018052 -308.837584) (xy 245.017675 -308.827987) (xy 245.010688 -308.810114)
			(xy 244.997593 -308.796086) (xy 244.989096 -308.79161) (xy 244.893084 -308.74589) (xy 244.864128 -308.749192)
			(xy 244.852444 -308.75859) (xy 244.827917 -308.777664) (xy 244.77471 -308.809749) (xy 244.717654 -308.834346)
			(xy 244.657796 -308.851002) (xy 244.596236 -308.859413) (xy 244.56517 -308.859936) (xy 244.535205 -308.859388)
			(xy 244.47579 -308.851562) (xy 244.417903 -308.836048) (xy 244.362537 -308.813112) (xy 244.310638 -308.783145)
			(xy 244.263095 -308.74666) (xy 244.22072 -308.704283) (xy 244.184238 -308.656737) (xy 244.154275 -308.604836)
			(xy 244.131342 -308.549468) (xy 244.115832 -308.491581) (xy 244.10801 -308.432165) (xy 244.10801 -308.372235)
			(xy 244.115832 -308.312819) (xy 244.131342 -308.254932) (xy 244.154275 -308.199564) (xy 244.184238 -308.147663)
			(xy 244.22072 -308.100117) (xy 244.263095 -308.05774) (xy 244.310638 -308.021255) (xy 244.362537 -307.991288)
			(xy 244.417903 -307.968352) (xy 244.475789 -307.952838) (xy 244.535205 -307.945012) (xy 244.56517 -307.94452)
			(xy 244.596238 -307.945037) (xy 244.657804 -307.95343) (xy 244.717668 -307.970078) (xy 244.774727 -307.994676)
			(xy 244.827932 -308.026771) (xy 244.852444 -308.045866) (xy 244.864128 -308.055264) (xy 244.893084 -308.058566)
			(xy 244.989096 -308.012846) (xy 244.997576 -308.008357) (xy 245.010622 -307.994304) (xy 245.017642 -307.976459)
			(xy 245.018052 -307.966872) (xy 245.018052 -307.937916) (xy 245.017631 -307.927846) (xy 245.009908 -307.909248)
			(xy 245.003066 -307.901848) (xy 243.813584 -306.712366) (xy 243.806188 -306.705522) (xy 243.787585 -306.697805)
			(xy 243.777516 -306.69738) (xy 239.36833 -306.69738) (xy 239.35826 -306.6978) (xy 239.339661 -306.705522)
			(xy 239.332262 -306.712366) (xy 238.941102 -307.103526) (xy 238.917214 -307.126716) (xy 238.86442 -307.167278)
			(xy 238.806781 -307.2006) (xy 238.745285 -307.22611) (xy 238.680985 -307.243372) (xy 238.61498 -307.25209)
			(xy 238.581692 -307.252624) (xy 238.550961 -307.252151) (xy 238.489949 -307.244742) (xy 238.430274 -307.230033)
			(xy 238.372806 -307.208239) (xy 238.318385 -307.179676) (xy 238.267804 -307.144762) (xy 238.221799 -307.104006)
			(xy 238.181043 -307.058002) (xy 238.146128 -307.007421) (xy 238.117565 -306.953001) (xy 238.095769 -306.895534)
			(xy 238.081059 -306.835859) (xy 238.073649 -306.774847) (xy 238.073184 -306.744116) (xy 230.061123 -306.744116)
			(xy 230.062828 -306.757072) (xy 230.063294 -306.787042) (xy 230.06279 -306.817759) (xy 230.054579 -306.878643)
			(xy 230.038298 -306.937881) (xy 230.014239 -306.994408) (xy 229.982834 -307.047209) (xy 229.944649 -307.095335)
			(xy 229.900368 -307.137919) (xy 229.85079 -307.174198) (xy 229.796803 -307.203518) (xy 229.73938 -307.225353)
			(xy 229.679552 -307.23931) (xy 229.64902 -307.242718) (xy 229.640384 -307.24348) (xy 229.624382 -307.2511)
			(xy 229.618032 -307.257196) (xy 229.611285 -307.264603) (xy 229.603662 -307.283116) (xy 229.603673 -307.303136)
			(xy 229.611314 -307.321641) (xy 229.618032 -307.329078) (xy 229.635558 -307.346858) (xy 229.658735 -307.370758)
			(xy 229.699297 -307.42355) (xy 229.73262 -307.481186) (xy 229.7339 -307.484272) (xy 231.935526 -307.484272)
			(xy 231.939599 -307.428613) (xy 231.951734 -307.37414) (xy 231.97167 -307.322014) (xy 231.998984 -307.273346)
			(xy 232.033092 -307.229174) (xy 232.073269 -307.190439) (xy 232.118657 -307.157967) (xy 232.168289 -307.132449)
			(xy 232.221109 -307.11443) (xy 232.275988 -307.104293) (xy 232.331759 -307.102255) (xy 232.387233 -307.108358)
			(xy 232.441226 -307.122474) (xy 232.492589 -307.144301) (xy 232.540227 -307.173374) (xy 232.583123 -307.209073)
			(xy 232.620365 -307.250637) (xy 232.651159 -307.297181) (xy 232.674847 -307.347712) (xy 232.690925 -307.401154)
			(xy 232.699051 -307.456368) (xy 232.699416 -307.476394) (xy 243.050042 -307.476394) (xy 243.050042 -307.416458)
			(xy 243.057865 -307.357036) (xy 243.073378 -307.299143) (xy 243.096314 -307.24377) (xy 243.126281 -307.191864)
			(xy 243.162768 -307.144314) (xy 243.205148 -307.101934) (xy 243.252698 -307.065447) (xy 243.304604 -307.03548)
			(xy 243.359977 -307.012544) (xy 243.41787 -306.997031) (xy 243.477292 -306.989208) (xy 243.537228 -306.989208)
			(xy 243.59665 -306.997031) (xy 243.654543 -307.012544) (xy 243.709916 -307.03548) (xy 243.761822 -307.065447)
			(xy 243.809372 -307.101934) (xy 243.851752 -307.144314) (xy 243.888239 -307.191864) (xy 243.918206 -307.24377)
			(xy 243.941142 -307.299143) (xy 243.956655 -307.357036) (xy 243.964478 -307.416458) (xy 243.964968 -307.446426)
			(xy 243.964478 -307.476394) (xy 243.956655 -307.535816) (xy 243.941142 -307.593709) (xy 243.918206 -307.649082)
			(xy 243.888239 -307.700988) (xy 243.851752 -307.748538) (xy 243.809372 -307.790918) (xy 243.761822 -307.827405)
			(xy 243.709916 -307.857372) (xy 243.654543 -307.880308) (xy 243.59665 -307.895821) (xy 243.537228 -307.903644)
			(xy 243.477292 -307.903644) (xy 243.41787 -307.895821) (xy 243.359977 -307.880308) (xy 243.304604 -307.857372)
			(xy 243.252698 -307.827405) (xy 243.205148 -307.790918) (xy 243.162768 -307.748538) (xy 243.126281 -307.700988)
			(xy 243.096314 -307.649082) (xy 243.073378 -307.593709) (xy 243.057865 -307.535816) (xy 243.050042 -307.476394)
			(xy 232.699416 -307.476394) (xy 232.69956 -307.484272) (xy 232.699051 -307.512176) (xy 232.690925 -307.56739)
			(xy 232.674847 -307.620832) (xy 232.651159 -307.671363) (xy 232.620365 -307.717907) (xy 232.583123 -307.759471)
			(xy 232.540227 -307.79517) (xy 232.492589 -307.824243) (xy 232.441226 -307.84607) (xy 232.387233 -307.860186)
			(xy 232.331759 -307.866289) (xy 232.275988 -307.864251) (xy 232.221109 -307.854114) (xy 232.168289 -307.836095)
			(xy 232.118657 -307.810577) (xy 232.073269 -307.778105) (xy 232.033092 -307.73937) (xy 231.998984 -307.695198)
			(xy 231.97167 -307.64653) (xy 231.951734 -307.594404) (xy 231.939599 -307.539931) (xy 231.935526 -307.484272)
			(xy 229.7339 -307.484272) (xy 229.758132 -307.54268) (xy 229.775397 -307.606978) (xy 229.78412 -307.67298)
			(xy 229.784656 -307.706268) (xy 229.784656 -308.669182) (xy 229.785137 -308.679653) (xy 229.793464 -308.69887)
			(xy 229.808749 -308.713186) (xy 229.818438 -308.717188) (xy 229.924356 -308.754018) (xy 229.955344 -308.745128)
			(xy 229.965504 -308.732428) (xy 229.984173 -308.709806) (xy 230.026349 -308.669045) (xy 230.073386 -308.634004)
			(xy 230.124513 -308.605258) (xy 230.178893 -308.583278) (xy 230.235635 -308.568422) (xy 230.293809 -308.560935)
			(xy 230.323136 -308.56047) (xy 230.353101 -308.561006) (xy 230.412517 -308.568833) (xy 230.412588 -308.568852)
			(xy 231.935526 -308.568852) (xy 231.939599 -308.513193) (xy 231.951734 -308.45872) (xy 231.97167 -308.406594)
			(xy 231.998984 -308.357926) (xy 232.033092 -308.313754) (xy 232.073269 -308.275019) (xy 232.118657 -308.242547)
			(xy 232.168289 -308.217029) (xy 232.221109 -308.19901) (xy 232.275988 -308.188873) (xy 232.331759 -308.186835)
			(xy 232.387233 -308.192938) (xy 232.441226 -308.207054) (xy 232.492589 -308.228881) (xy 232.540227 -308.257954)
			(xy 232.583123 -308.293653) (xy 232.620365 -308.335217) (xy 232.651159 -308.381761) (xy 232.674847 -308.432292)
			(xy 232.690925 -308.485734) (xy 232.699051 -308.540948) (xy 232.69956 -308.568852) (xy 232.699051 -308.596756)
			(xy 232.690925 -308.65197) (xy 232.674847 -308.705412) (xy 232.651159 -308.755943) (xy 232.620365 -308.802487)
			(xy 232.583123 -308.844051) (xy 232.540227 -308.87975) (xy 232.492589 -308.908823) (xy 232.441226 -308.93065)
			(xy 232.387233 -308.944766) (xy 232.331759 -308.950869) (xy 232.275988 -308.948831) (xy 232.221109 -308.938694)
			(xy 232.168289 -308.920675) (xy 232.118657 -308.895157) (xy 232.073269 -308.862685) (xy 232.033092 -308.82395)
			(xy 231.998984 -308.779778) (xy 231.97167 -308.73111) (xy 231.951734 -308.678984) (xy 231.939599 -308.624511)
			(xy 231.935526 -308.568852) (xy 230.412588 -308.568852) (xy 230.470403 -308.584348) (xy 230.525769 -308.607285)
			(xy 230.577668 -308.637252) (xy 230.625212 -308.673737) (xy 230.667587 -308.716115) (xy 230.704068 -308.763662)
			(xy 230.734031 -308.815563) (xy 230.756964 -308.870931) (xy 230.772474 -308.928819) (xy 230.780296 -308.988235)
			(xy 230.780296 -309.048165) (xy 230.772474 -309.107581) (xy 230.756964 -309.165469) (xy 230.734031 -309.220837)
			(xy 230.704068 -309.272738) (xy 230.667587 -309.320285) (xy 230.625212 -309.362663) (xy 230.577668 -309.399148)
			(xy 230.525769 -309.429115) (xy 230.470403 -309.452052) (xy 230.412517 -309.467567) (xy 230.353101 -309.475394)
			(xy 230.323136 -309.475886) (xy 230.293811 -309.475385) (xy 230.235643 -309.467891) (xy 230.178907 -309.453033)
			(xy 230.124532 -309.431054) (xy 230.073407 -309.402314) (xy 230.026369 -309.367284) (xy 229.984187 -309.326536)
			(xy 229.965504 -309.303928) (xy 229.955344 -309.291228) (xy 229.924356 -309.282338) (xy 229.818438 -309.319168)
			(xy 229.808703 -309.323095) (xy 229.793382 -309.337416) (xy 229.785101 -309.356684) (xy 229.784656 -309.367174)
			(xy 229.784656 -309.62854) (xy 229.785016 -309.638587) (xy 229.792611 -309.657183) (xy 229.799388 -309.664608)
			(xy 230.202486 -310.067706) (xy 230.209896 -310.074533) (xy 230.228488 -310.08226) (xy 230.238554 -310.082692)
			(xy 231.300782 -310.082692) (xy 231.336261 -310.083261) (xy 231.406537 -310.093069) (xy 231.474762 -310.112568)
			(xy 231.539608 -310.141377) (xy 231.570022 -310.159654) (xy 231.580944 -310.166512) (xy 231.606344 -310.16829)
			(xy 231.706928 -310.122316) (xy 231.722168 -310.101996) (xy 231.7242 -310.089296) (xy 231.728864 -310.062693)
			(xy 231.744696 -310.011056) (xy 231.767649 -309.962167) (xy 231.797266 -309.917002) (xy 231.832954 -309.876464)
			(xy 231.874002 -309.841363) (xy 231.919588 -309.812399) (xy 231.968803 -309.790152) (xy 232.020663 -309.775066)
			(xy 232.074131 -309.767442) (xy 232.101136 -309.76697) (xy 232.128384 -309.767503) (xy 232.182325 -309.775263)
			(xy 232.234612 -309.79062) (xy 232.284182 -309.813262) (xy 232.330025 -309.842728) (xy 232.371208 -309.878417)
			(xy 232.406894 -309.919604) (xy 232.418983 -309.938416) (xy 242.496068 -309.938416) (xy 242.496068 -309.87848)
			(xy 242.503891 -309.819058) (xy 242.519404 -309.761165) (xy 242.54234 -309.705792) (xy 242.572307 -309.653886)
			(xy 242.608794 -309.606336) (xy 242.651174 -309.563956) (xy 242.698724 -309.527469) (xy 242.75063 -309.497502)
			(xy 242.806003 -309.474566) (xy 242.863896 -309.459053) (xy 242.923318 -309.45123) (xy 242.983254 -309.45123)
			(xy 243.042676 -309.459053) (xy 243.100569 -309.474566) (xy 243.155942 -309.497502) (xy 243.207848 -309.527469)
			(xy 243.255398 -309.563956) (xy 243.297778 -309.606336) (xy 243.334265 -309.653886) (xy 243.364232 -309.705792)
			(xy 243.387168 -309.761165) (xy 243.402681 -309.819058) (xy 243.410504 -309.87848) (xy 243.410994 -309.908448)
			(xy 243.410504 -309.938416) (xy 243.402681 -309.997838) (xy 243.387168 -310.055731) (xy 243.364232 -310.111104)
			(xy 243.334265 -310.16301) (xy 243.297778 -310.21056) (xy 243.255398 -310.25294) (xy 243.207848 -310.289427)
			(xy 243.155942 -310.319394) (xy 243.100569 -310.34233) (xy 243.042676 -310.357843) (xy 242.983254 -310.365666)
			(xy 242.923318 -310.365666) (xy 242.863896 -310.357843) (xy 242.806003 -310.34233) (xy 242.75063 -310.319394)
			(xy 242.698724 -310.289427) (xy 242.651174 -310.25294) (xy 242.608794 -310.21056) (xy 242.572307 -310.16301)
			(xy 242.54234 -310.111104) (xy 242.519404 -310.055731) (xy 242.503891 -309.997838) (xy 242.496068 -309.938416)
			(xy 232.418983 -309.938416) (xy 232.436355 -309.96545) (xy 232.458992 -310.015022) (xy 232.474345 -310.067311)
			(xy 232.4821 -310.121252) (xy 232.4821 -310.175748) (xy 232.474345 -310.229689) (xy 232.458992 -310.281978)
			(xy 232.436355 -310.33155) (xy 232.406894 -310.377396) (xy 232.371208 -310.418583) (xy 232.330025 -310.454272)
			(xy 232.284182 -310.483738) (xy 232.234612 -310.50638) (xy 232.182325 -310.521737) (xy 232.128384 -310.529497)
			(xy 232.101136 -310.529986) (xy 232.075361 -310.52956) (xy 232.024286 -310.522582) (xy 231.974616 -310.508787)
			(xy 231.950768 -310.498998) (xy 231.939084 -310.494172) (xy 231.913684 -310.496204) (xy 231.821228 -310.55691)
			(xy 231.80929 -310.579516) (xy 231.809036 -310.592216) (xy 231.808472 -310.625441) (xy 231.799642 -310.691304)
			(xy 231.782304 -310.755454) (xy 231.756754 -310.816798) (xy 231.723428 -310.874289) (xy 231.682894 -310.926948)
			(xy 231.635844 -310.973875) (xy 231.583079 -311.01427) (xy 231.5255 -311.047445) (xy 231.46409 -311.072834)
			(xy 231.399894 -311.090003) (xy 231.334008 -311.098661) (xy 231.300782 -311.0992) (xy 230.516176 -311.0992)
			(xy 230.505802 -311.099692) (xy 230.48673 -311.107852) (xy 230.472456 -311.122905) (xy 230.468424 -311.132474)
			(xy 230.43007 -311.237122) (xy 230.437944 -311.267602) (xy 230.450136 -311.27827) (xy 230.47075 -311.296453)
			(xy 230.507018 -311.337758) (xy 230.536976 -311.383844) (xy 230.560005 -311.433755) (xy 230.575626 -311.486456)
			(xy 230.583516 -311.540854) (xy 230.583994 -311.568338) (xy 230.583557 -311.595591) (xy 230.575795 -311.649541)
			(xy 230.560435 -311.701838) (xy 230.537788 -311.751416) (xy 230.508317 -311.797267) (xy 230.47262 -311.838457)
			(xy 230.431425 -311.874148) (xy 230.38557 -311.903613) (xy 230.335989 -311.926253) (xy 230.28369 -311.941607)
			(xy 230.229739 -311.949361) (xy 230.202486 -311.949846) (xy 230.174428 -311.949368) (xy 230.11892 -311.941133)
			(xy 230.065217 -311.924857) (xy 230.014477 -311.90089) (xy 229.967794 -311.869751) (xy 229.926175 -311.83211)
			(xy 229.890518 -311.78878) (xy 229.861591 -311.740694) (xy 229.840019 -311.688891) (xy 229.832662 -311.66181)
			(xy 229.830884 -311.654952) (xy 229.824026 -311.643014) (xy 229.732078 -311.551066) (xy 229.724698 -311.544312)
			(xy 229.706255 -311.53661) (xy 229.696264 -311.53608) (xy 228.228398 -311.53608) (xy 228.21885 -311.536531)
			(xy 228.201095 -311.543559) (xy 228.193854 -311.549796) (xy 228.172565 -311.569083) (xy 228.126064 -311.602812)
			(xy 228.075707 -311.630456) (xy 228.022286 -311.651579) (xy 227.966642 -311.66585) (xy 227.909649 -311.673043)
			(xy 227.880926 -311.673494) (xy 227.850955 -311.673055) (xy 227.791525 -311.665234) (xy 227.733625 -311.649722)
			(xy 227.678245 -311.626786) (xy 227.626332 -311.596817) (xy 227.578776 -311.560328) (xy 227.536389 -311.517944)
			(xy 227.499898 -311.470389) (xy 227.469926 -311.418479) (xy 227.446986 -311.3631) (xy 227.431471 -311.3052)
			(xy 227.423647 -311.245771) (xy 227.423647 -311.185829) (xy 227.431471 -311.1264) (xy 227.446986 -311.0685)
			(xy 227.469926 -311.013121) (xy 227.499898 -310.961211) (xy 227.536389 -310.913656) (xy 227.578776 -310.871272)
			(xy 227.626332 -310.834783) (xy 227.678245 -310.804814) (xy 227.733625 -310.781878) (xy 227.791525 -310.766366)
			(xy 227.850955 -310.758545) (xy 227.880926 -310.758078) (xy 227.90965 -310.758525) (xy 227.966645 -310.765717)
			(xy 228.022292 -310.779985) (xy 228.075717 -310.801104) (xy 228.126079 -310.828742) (xy 228.172586 -310.862465)
			(xy 228.193854 -310.881776) (xy 228.201098 -310.888009) (xy 228.218851 -310.895048) (xy 228.228398 -310.895492)
			(xy 229.485444 -310.895492) (xy 229.510844 -310.878474) (xy 229.516686 -310.863996) (xy 229.52002 -310.854557)
			(xy 229.520044 -310.834564) (xy 229.512453 -310.816068) (xy 229.505764 -310.808624) (xy 228.916738 -310.219598)
			(xy 228.897225 -310.199611) (xy 228.862222 -310.156078) (xy 228.846888 -310.13273) (xy 228.8413 -310.123586)
			(xy 228.82352 -310.111902) (xy 228.72827 -310.095138) (xy 228.707442 -310.100218) (xy 228.69906 -310.106822)
			(xy 228.674893 -310.124932) (xy 228.622722 -310.155349) (xy 228.567003 -310.178639) (xy 228.508704 -310.194396)
			(xy 228.448839 -310.202347) (xy 228.418644 -310.202834) (xy 228.388675 -310.202316) (xy 228.329249 -310.194497)
			(xy 228.271351 -310.178989) (xy 228.215974 -310.156056) (xy 228.164064 -310.12609) (xy 228.11651 -310.089604)
			(xy 228.074125 -310.047223) (xy 228.037635 -309.999673) (xy 228.007664 -309.947766) (xy 227.984725 -309.89239)
			(xy 227.969211 -309.834495) (xy 227.961387 -309.775069) (xy 227.961387 -309.715131) (xy 227.969211 -309.655705)
			(xy 227.984725 -309.59781) (xy 228.007664 -309.542434) (xy 228.037635 -309.490527) (xy 228.074125 -309.442977)
			(xy 228.11651 -309.400596) (xy 228.164064 -309.36411) (xy 228.215974 -309.334144) (xy 228.271351 -309.311211)
			(xy 228.329249 -309.295703) (xy 228.388675 -309.287884) (xy 228.418644 -309.287418) (xy 228.453653 -309.288096)
			(xy 228.522859 -309.298737) (xy 228.589641 -309.319779) (xy 228.621336 -309.334662) (xy 228.63302 -309.340504)
			(xy 228.659182 -309.339234) (xy 228.743764 -309.286656) (xy 228.750944 -309.281869) (xy 228.761721 -309.268402)
			(xy 228.767363 -309.252103) (xy 228.76764 -309.243476) (xy 228.76764 -308.837584) (xy 228.767294 -308.828017)
			(xy 228.760357 -308.810188) (xy 228.747376 -308.796134) (xy 228.738938 -308.79161) (xy 228.642926 -308.74589)
			(xy 228.61397 -308.749192) (xy 228.602286 -308.75859) (xy 228.577779 -308.77769) (xy 228.524567 -308.809771)
			(xy 228.467505 -308.834363) (xy 228.407643 -308.851013) (xy 228.346079 -308.859416) (xy 228.315012 -308.859936)
			(xy 228.285044 -308.859412) (xy 228.225621 -308.85159) (xy 228.167728 -308.836079) (xy 228.112354 -308.813144)
			(xy 228.060448 -308.783177) (xy 228.012898 -308.746691) (xy 227.970517 -308.704311) (xy 227.93403 -308.656762)
			(xy 227.904062 -308.604856) (xy 227.881125 -308.549483) (xy 227.865612 -308.49159) (xy 227.857789 -308.432168)
			(xy 227.857789 -308.372232) (xy 227.865612 -308.31281) (xy 227.881125 -308.254917) (xy 227.904062 -308.199544)
			(xy 227.93403 -308.147638) (xy 227.970517 -308.100089) (xy 228.012898 -308.057709) (xy 228.060448 -308.021223)
			(xy 228.112354 -307.991256) (xy 228.167728 -307.968321) (xy 228.225621 -307.95281) (xy 228.285044 -307.944988)
			(xy 228.315012 -307.94452) (xy 228.346081 -307.945013) (xy 228.407648 -307.953412) (xy 228.467512 -307.970066)
			(xy 228.524571 -307.994669) (xy 228.577774 -308.026768) (xy 228.602286 -308.045866) (xy 228.61397 -308.055264)
			(xy 228.642926 -308.058566) (xy 228.738938 -308.012846) (xy 228.747362 -308.008299) (xy 228.760347 -307.994259)
			(xy 228.76728 -307.976436) (xy 228.76764 -307.966872) (xy 228.76764 -307.937916) (xy 228.767304 -307.927867)
			(xy 228.759693 -307.90927) (xy 228.752908 -307.901848) (xy 227.563426 -306.712366) (xy 227.556015 -306.70554)
			(xy 227.537424 -306.697813) (xy 227.527358 -306.69738) (xy 223.118172 -306.69738) (xy 223.108098 -306.697769)
			(xy 223.089499 -306.705513) (xy 223.082104 -306.712366) (xy 222.690944 -307.103526) (xy 222.667038 -307.126696)
			(xy 222.614247 -307.16726) (xy 222.556613 -307.200584) (xy 222.49512 -307.226098) (xy 222.430823 -307.243364)
			(xy 222.364821 -307.252087) (xy 222.331534 -307.252624) (xy 222.300807 -307.252176) (xy 222.239801 -307.24477)
			(xy 222.180133 -307.230061) (xy 222.122675 -307.208265) (xy 222.068263 -307.179699) (xy 222.017694 -307.144781)
			(xy 221.971704 -307.104019) (xy 221.930965 -307.058009) (xy 221.896071 -307.007422) (xy 221.867532 -306.952997)
			(xy 221.845764 -306.895528) (xy 221.831085 -306.835853) (xy 221.823709 -306.774843) (xy 221.82328 -306.744116)
			(xy 213.107778 -306.744116) (xy 213.107778 -307.476394) (xy 226.799884 -307.476394) (xy 226.799884 -307.416458)
			(xy 226.807707 -307.357036) (xy 226.82322 -307.299143) (xy 226.846156 -307.24377) (xy 226.876123 -307.191864)
			(xy 226.91261 -307.144314) (xy 226.95499 -307.101934) (xy 227.00254 -307.065447) (xy 227.054446 -307.03548)
			(xy 227.109819 -307.012544) (xy 227.167712 -306.997031) (xy 227.227134 -306.989208) (xy 227.28707 -306.989208)
			(xy 227.346492 -306.997031) (xy 227.404385 -307.012544) (xy 227.459758 -307.03548) (xy 227.511664 -307.065447)
			(xy 227.559214 -307.101934) (xy 227.601594 -307.144314) (xy 227.638081 -307.191864) (xy 227.668048 -307.24377)
			(xy 227.690984 -307.299143) (xy 227.706497 -307.357036) (xy 227.71432 -307.416458) (xy 227.71481 -307.446426)
			(xy 227.71432 -307.476394) (xy 227.706497 -307.535816) (xy 227.690984 -307.593709) (xy 227.668048 -307.649082)
			(xy 227.638081 -307.700988) (xy 227.601594 -307.748538) (xy 227.559214 -307.790918) (xy 227.511664 -307.827405)
			(xy 227.459758 -307.857372) (xy 227.404385 -307.880308) (xy 227.346492 -307.895821) (xy 227.28707 -307.903644)
			(xy 227.227134 -307.903644) (xy 227.167712 -307.895821) (xy 227.109819 -307.880308) (xy 227.054446 -307.857372)
			(xy 227.00254 -307.827405) (xy 226.95499 -307.790918) (xy 226.91261 -307.748538) (xy 226.876123 -307.700988)
			(xy 226.846156 -307.649082) (xy 226.82322 -307.593709) (xy 226.807707 -307.535816) (xy 226.799884 -307.476394)
			(xy 213.107778 -307.476394) (xy 213.107778 -311.265644) (xy 213.336372 -311.265644) (xy 213.336372 -311.0943)
			(xy 213.344404 -310.923144) (xy 213.360449 -310.752553) (xy 213.384472 -310.582902) (xy 213.416421 -310.414563)
			(xy 213.456225 -310.247906) (xy 213.503797 -310.083299) (xy 213.559032 -309.921102) (xy 213.621809 -309.761672)
			(xy 213.69199 -309.605361) (xy 213.76942 -309.45251) (xy 213.85393 -309.303457) (xy 213.945333 -309.158529)
			(xy 214.043429 -309.018044) (xy 214.148002 -308.882312) (xy 214.258822 -308.75163) (xy 214.375646 -308.626287)
			(xy 214.498216 -308.506557) (xy 214.626264 -308.392704) (xy 214.759507 -308.284978) (xy 214.897653 -308.183615)
			(xy 215.040399 -308.08884) (xy 215.18743 -308.000859) (xy 215.338424 -307.919867) (xy 215.493047 -307.846041)
			(xy 215.650961 -307.779544) (xy 215.811819 -307.720521) (xy 215.975266 -307.669104) (xy 216.140943 -307.625404)
			(xy 216.308487 -307.589517) (xy 216.477529 -307.561524) (xy 216.647697 -307.541484) (xy 216.818617 -307.529443)
			(xy 216.989914 -307.525426) (xy 217.161211 -307.529443) (xy 217.332131 -307.541484) (xy 217.502299 -307.561524)
			(xy 217.671341 -307.589517) (xy 217.838885 -307.625404) (xy 218.004562 -307.669104) (xy 218.168009 -307.720521)
			(xy 218.328867 -307.779544) (xy 218.486781 -307.846041) (xy 218.641404 -307.919867) (xy 218.792398 -308.000859)
			(xy 218.939429 -308.08884) (xy 219.082175 -308.183615) (xy 219.220321 -308.284978) (xy 219.353564 -308.392704)
			(xy 219.481612 -308.506557) (xy 219.604182 -308.626287) (xy 219.721006 -308.75163) (xy 219.831826 -308.882312)
			(xy 219.936399 -309.018044) (xy 220.034495 -309.158529) (xy 220.125898 -309.303457) (xy 220.210408 -309.45251)
			(xy 220.287838 -309.605361) (xy 220.358019 -309.761672) (xy 220.420796 -309.921102) (xy 220.426692 -309.938416)
			(xy 226.24591 -309.938416) (xy 226.24591 -309.87848) (xy 226.253733 -309.819058) (xy 226.269246 -309.761165)
			(xy 226.292182 -309.705792) (xy 226.322149 -309.653886) (xy 226.358636 -309.606336) (xy 226.401016 -309.563956)
			(xy 226.448566 -309.527469) (xy 226.500472 -309.497502) (xy 226.555845 -309.474566) (xy 226.613738 -309.459053)
			(xy 226.67316 -309.45123) (xy 226.733096 -309.45123) (xy 226.792518 -309.459053) (xy 226.850411 -309.474566)
			(xy 226.905784 -309.497502) (xy 226.95769 -309.527469) (xy 227.00524 -309.563956) (xy 227.04762 -309.606336)
			(xy 227.084107 -309.653886) (xy 227.114074 -309.705792) (xy 227.13701 -309.761165) (xy 227.152523 -309.819058)
			(xy 227.160346 -309.87848) (xy 227.160836 -309.908448) (xy 227.160346 -309.938416) (xy 227.152523 -309.997838)
			(xy 227.13701 -310.055731) (xy 227.114074 -310.111104) (xy 227.084107 -310.16301) (xy 227.04762 -310.21056)
			(xy 227.00524 -310.25294) (xy 226.95769 -310.289427) (xy 226.905784 -310.319394) (xy 226.850411 -310.34233)
			(xy 226.792518 -310.357843) (xy 226.733096 -310.365666) (xy 226.67316 -310.365666) (xy 226.613738 -310.357843)
			(xy 226.555845 -310.34233) (xy 226.500472 -310.319394) (xy 226.448566 -310.289427) (xy 226.401016 -310.25294)
			(xy 226.358636 -310.21056) (xy 226.322149 -310.16301) (xy 226.292182 -310.111104) (xy 226.269246 -310.055731)
			(xy 226.253733 -309.997838) (xy 226.24591 -309.938416) (xy 220.426692 -309.938416) (xy 220.476031 -310.083299)
			(xy 220.523603 -310.247906) (xy 220.563407 -310.414563) (xy 220.595356 -310.582902) (xy 220.619379 -310.752553)
			(xy 220.635424 -310.923144) (xy 220.643456 -311.0943) (xy 220.643958 -311.179972) (xy 220.643456 -311.265644)
			(xy 220.635424 -311.4368) (xy 220.619379 -311.607391) (xy 220.595356 -311.777042) (xy 220.563407 -311.945381)
			(xy 220.523603 -312.112038) (xy 220.476031 -312.276645) (xy 220.420796 -312.438842) (xy 220.358019 -312.598272)
			(xy 220.287838 -312.754583) (xy 220.210408 -312.907434) (xy 220.125898 -313.056487) (xy 220.090953 -313.111896)
			(xy 230.52354 -313.111896) (xy 230.527611 -313.056274) (xy 230.539737 -313.001837) (xy 230.55966 -312.949746)
			(xy 230.586956 -312.901111) (xy 230.621042 -312.856968) (xy 230.661191 -312.818259) (xy 230.706549 -312.785808)
			(xy 230.756149 -312.760307) (xy 230.808933 -312.7423) (xy 230.863776 -312.73217) (xy 230.91951 -312.730133)
			(xy 230.974947 -312.736233) (xy 231.028904 -312.750339) (xy 231.080233 -312.772151) (xy 231.127839 -312.801205)
			(xy 231.170707 -312.83688) (xy 231.207924 -312.878417) (xy 231.238697 -312.92493) (xy 231.262369 -312.975427)
			(xy 231.278437 -313.028834) (xy 231.286557 -313.08401) (xy 231.287066 -313.111896) (xy 231.286557 -313.139782)
			(xy 231.278437 -313.194958) (xy 231.262369 -313.248365) (xy 231.238697 -313.298862) (xy 231.207924 -313.345375)
			(xy 231.170707 -313.386912) (xy 231.127839 -313.422587) (xy 231.080233 -313.451641) (xy 231.028904 -313.473453)
			(xy 230.974947 -313.487559) (xy 230.91951 -313.493659) (xy 230.863776 -313.491622) (xy 230.808933 -313.481492)
			(xy 230.756149 -313.463485) (xy 230.706549 -313.437984) (xy 230.661191 -313.405533) (xy 230.621042 -313.366824)
			(xy 230.586956 -313.322681) (xy 230.55966 -313.274046) (xy 230.539737 -313.221955) (xy 230.527611 -313.167518)
			(xy 230.52354 -313.111896) (xy 220.090953 -313.111896) (xy 220.034495 -313.201415) (xy 219.936399 -313.3419)
			(xy 219.831826 -313.477632) (xy 219.721006 -313.608314) (xy 219.604182 -313.733657) (xy 219.481612 -313.853387)
			(xy 219.353564 -313.96724) (xy 219.220321 -314.074966) (xy 219.082175 -314.176329) (xy 218.939429 -314.271104)
			(xy 218.792398 -314.359085) (xy 218.641404 -314.440077) (xy 218.486781 -314.513903) (xy 218.328867 -314.5804)
			(xy 218.168009 -314.639423) (xy 218.004562 -314.69084) (xy 217.838885 -314.73454) (xy 217.671341 -314.770427)
			(xy 217.502299 -314.79842) (xy 217.332131 -314.81846) (xy 217.161211 -314.830501) (xy 216.989914 -314.834518)
			(xy 216.818617 -314.830501) (xy 216.647697 -314.81846) (xy 216.477529 -314.79842) (xy 216.308487 -314.770427)
			(xy 216.140943 -314.73454) (xy 215.975266 -314.69084) (xy 215.811819 -314.639423) (xy 215.650961 -314.5804)
			(xy 215.493047 -314.513903) (xy 215.338424 -314.440077) (xy 215.18743 -314.359085) (xy 215.040399 -314.271104)
			(xy 214.897653 -314.176329) (xy 214.759507 -314.074966) (xy 214.626264 -313.96724) (xy 214.498216 -313.853387)
			(xy 214.375646 -313.733657) (xy 214.258822 -313.608314) (xy 214.148002 -313.477632) (xy 214.043429 -313.3419)
			(xy 213.945333 -313.201415) (xy 213.85393 -313.056487) (xy 213.76942 -312.907434) (xy 213.69199 -312.754583)
			(xy 213.621809 -312.598272) (xy 213.559032 -312.438842) (xy 213.503797 -312.276645) (xy 213.456225 -312.112038)
			(xy 213.416421 -311.945381) (xy 213.384472 -311.777042) (xy 213.360449 -311.607391) (xy 213.344404 -311.4368)
			(xy 213.336372 -311.265644) (xy 213.107778 -311.265644) (xy 213.107778 -315.777626) (xy 213.108205 -315.787695)
			(xy 213.115924 -315.806294) (xy 213.122764 -315.813694) (xy 218.125802 -320.816732) (xy 224.888044 -320.816732)
			(xy 224.888518 -320.789362) (xy 224.896332 -320.735183) (xy 224.911819 -320.682679) (xy 224.934659 -320.632932)
			(xy 224.964383 -320.586966) (xy 224.982024 -320.566034) (xy 224.98812 -320.558922) (xy 224.99447 -320.541904)
			(xy 224.99447 -320.45656) (xy 224.98812 -320.439542) (xy 224.982024 -320.43243) (xy 224.964389 -320.411494)
			(xy 224.934676 -320.365523) (xy 224.911839 -320.315776) (xy 224.896347 -320.263276) (xy 224.888518 -320.209101)
			(xy 224.888044 -320.181732) (xy 224.888608 -320.154484) (xy 224.896359 -320.100541) (xy 224.911707 -320.048251)
			(xy 224.934341 -319.998677) (xy 224.9638 -319.952829) (xy 224.999483 -319.91164) (xy 225.040665 -319.875948)
			(xy 225.086507 -319.84648) (xy 225.136076 -319.823835) (xy 225.188363 -319.808476) (xy 225.242304 -319.800714)
			(xy 225.269552 -319.800224) (xy 225.296921 -319.800712) (xy 225.3511 -319.808524) (xy 225.403603 -319.824007)
			(xy 225.45335 -319.846844) (xy 225.499318 -319.876565) (xy 225.52025 -319.894204) (xy 225.527362 -319.9003)
			(xy 225.54438 -319.90665) (xy 225.629724 -319.90665) (xy 225.646742 -319.9003) (xy 225.653854 -319.894204)
			(xy 225.674787 -319.876563) (xy 225.720755 -319.846839) (xy 225.770501 -319.823993) (xy 225.823003 -319.808497)
			(xy 225.877181 -319.800668) (xy 225.931923 -319.800668) (xy 225.986101 -319.808497) (xy 226.038603 -319.823993)
			(xy 226.088349 -319.846839) (xy 226.134317 -319.876563) (xy 226.15525 -319.894204) (xy 226.162362 -319.9003)
			(xy 226.17938 -319.90665) (xy 226.264724 -319.90665) (xy 226.281742 -319.9003) (xy 226.288854 -319.894204)
			(xy 226.309793 -319.876574) (xy 226.355764 -319.84686) (xy 226.40551 -319.824023) (xy 226.458009 -319.80853)
			(xy 226.512183 -319.800699) (xy 226.539552 -319.800224) (xy 226.566805 -319.8007) (xy 226.620757 -319.808451)
			(xy 226.673057 -319.823803) (xy 226.722639 -319.846442) (xy 226.768494 -319.875908) (xy 226.809688 -319.911601)
			(xy 226.845382 -319.952793) (xy 226.87485 -319.998647) (xy 226.897492 -320.048228) (xy 226.912845 -320.100527)
			(xy 226.920599 -320.154479) (xy 226.92106 -320.181732) (xy 226.920622 -320.209103) (xy 226.912799 -320.263284)
			(xy 226.897304 -320.315788) (xy 226.874456 -320.365534) (xy 226.844725 -320.4115) (xy 226.82708 -320.43243)
			(xy 226.820984 -320.439542) (xy 226.814634 -320.45656) (xy 226.814634 -320.541904) (xy 226.820984 -320.558922)
			(xy 226.82708 -320.566034) (xy 226.844699 -320.586983) (xy 226.874414 -320.632951) (xy 226.897254 -320.682694)
			(xy 226.91275 -320.735191) (xy 226.920583 -320.789364) (xy 226.92106 -320.816732) (xy 241.138202 -320.816732)
			(xy 241.138686 -320.789362) (xy 241.1465 -320.735184) (xy 241.161984 -320.682681) (xy 241.184822 -320.632934)
			(xy 241.214543 -320.586966) (xy 241.232182 -320.566034) (xy 241.238278 -320.558922) (xy 241.244628 -320.541904)
			(xy 241.244628 -320.45656) (xy 241.238278 -320.439542) (xy 241.232182 -320.43243) (xy 241.214541 -320.4115)
			(xy 241.18483 -320.365526) (xy 241.161995 -320.315778) (xy 241.146504 -320.263277) (xy 241.138676 -320.209101)
			(xy 241.138202 -320.181732) (xy 241.138685 -320.154479) (xy 241.146438 -320.100529) (xy 241.16179 -320.048231)
			(xy 241.18443 -319.99865) (xy 241.213896 -319.952796) (xy 241.249587 -319.911603) (xy 241.290779 -319.875909)
			(xy 241.336631 -319.846441) (xy 241.38621 -319.823798) (xy 241.438507 -319.808443) (xy 241.492458 -319.800687)
			(xy 241.51971 -319.800224) (xy 241.547081 -319.800678) (xy 241.601261 -319.808498) (xy 241.653764 -319.82399)
			(xy 241.703511 -319.846834) (xy 241.749477 -319.876561) (xy 241.770408 -319.894204) (xy 241.77752 -319.9003)
			(xy 241.794538 -319.90665) (xy 241.879882 -319.90665) (xy 241.8969 -319.9003) (xy 241.904012 -319.894204)
			(xy 241.924945 -319.876563) (xy 241.970913 -319.846839) (xy 242.020659 -319.823993) (xy 242.073161 -319.808497)
			(xy 242.127339 -319.800668) (xy 242.182081 -319.800668) (xy 242.236259 -319.808497) (xy 242.288761 -319.823993)
			(xy 242.338507 -319.846839) (xy 242.384475 -319.876563) (xy 242.405408 -319.894204) (xy 242.41252 -319.9003)
			(xy 242.429538 -319.90665) (xy 242.514882 -319.90665) (xy 242.5319 -319.9003) (xy 242.539012 -319.894204)
			(xy 242.559967 -319.876593) (xy 242.605933 -319.846877) (xy 242.655675 -319.824036) (xy 242.708171 -319.808538)
			(xy 242.762342 -319.800702) (xy 242.78971 -319.800224) (xy 242.816965 -319.800646) (xy 242.870919 -319.808405)
			(xy 242.923219 -319.823764) (xy 242.972802 -319.84641) (xy 243.018656 -319.875882) (xy 243.05985 -319.91158)
			(xy 243.095543 -319.952777) (xy 243.12501 -319.998635) (xy 243.147651 -320.04822) (xy 243.163004 -320.100522)
			(xy 243.170757 -320.154477) (xy 243.171218 -320.181732) (xy 243.170791 -320.209104) (xy 243.162967 -320.263285)
			(xy 243.14747 -320.31579) (xy 243.124619 -320.365536) (xy 243.094884 -320.4115) (xy 243.077238 -320.43243)
			(xy 243.071142 -320.439542) (xy 243.064792 -320.45656) (xy 243.064792 -320.541904) (xy 243.071142 -320.558922)
			(xy 243.077238 -320.566034) (xy 243.094866 -320.586975) (xy 243.124578 -320.632946) (xy 243.147416 -320.682691)
			(xy 243.16291 -320.73519) (xy 243.170742 -320.789364) (xy 243.171218 -320.816732) (xy 243.170752 -320.843984)
			(xy 243.162991 -320.897931) (xy 243.147633 -320.950226) (xy 243.124989 -320.999803) (xy 243.09552 -321.045652)
			(xy 243.059826 -321.086842) (xy 243.018635 -321.122533) (xy 242.972783 -321.151999) (xy 242.923205 -321.17464)
			(xy 242.87091 -321.189996) (xy 242.816962 -321.197754) (xy 242.78971 -321.19824) (xy 242.762339 -321.197783)
			(xy 242.708159 -321.189965) (xy 242.655655 -321.174475) (xy 242.605909 -321.151631) (xy 242.559943 -321.121903)
			(xy 242.539012 -321.10426) (xy 242.5319 -321.098164) (xy 242.514882 -321.091814) (xy 242.429538 -321.091814)
			(xy 242.41252 -321.098164) (xy 242.405408 -321.10426) (xy 242.384475 -321.121901) (xy 242.338507 -321.151625)
			(xy 242.288761 -321.174471) (xy 242.236259 -321.189967) (xy 242.182081 -321.197796) (xy 242.127339 -321.197796)
			(xy 242.073161 -321.189967) (xy 242.020659 -321.174471) (xy 241.970913 -321.151625) (xy 241.924945 -321.121901)
			(xy 241.904012 -321.10426) (xy 241.8969 -321.098164) (xy 241.879882 -321.091814) (xy 241.794538 -321.091814)
			(xy 241.77752 -321.098164) (xy 241.770408 -321.10426) (xy 241.749479 -321.121903) (xy 241.703506 -321.151615)
			(xy 241.653758 -321.174451) (xy 241.601256 -321.189941) (xy 241.547079 -321.197767) (xy 241.51971 -321.19824)
			(xy 241.49246 -321.197713) (xy 241.438516 -321.189958) (xy 241.386224 -321.174606) (xy 241.336649 -321.151968)
			(xy 241.2908 -321.122506) (xy 241.249611 -321.086819) (xy 241.213919 -321.045634) (xy 241.184452 -320.999788)
			(xy 241.161809 -320.950215) (xy 241.146451 -320.897925) (xy 241.13869 -320.843981) (xy 241.138202 -320.816732)
			(xy 226.92106 -320.816732) (xy 226.920675 -320.843988) (xy 226.912912 -320.897944) (xy 226.89755 -320.950246)
			(xy 226.8749 -320.99983) (xy 226.845424 -321.045685) (xy 226.809722 -321.086879) (xy 226.768521 -321.122572)
			(xy 226.72266 -321.152038) (xy 226.673071 -321.174678) (xy 226.620766 -321.190029) (xy 226.566808 -321.19778)
			(xy 226.539552 -321.19824) (xy 226.512182 -321.197758) (xy 226.458003 -321.189946) (xy 226.4055 -321.174462)
			(xy 226.355752 -321.151623) (xy 226.309786 -321.121901) (xy 226.288854 -321.10426) (xy 226.281742 -321.098164)
			(xy 226.264724 -321.091814) (xy 226.17938 -321.091814) (xy 226.162362 -321.098164) (xy 226.15525 -321.10426)
			(xy 226.134317 -321.121901) (xy 226.088349 -321.151625) (xy 226.038603 -321.174471) (xy 225.986101 -321.189967)
			(xy 225.931923 -321.197796) (xy 225.877181 -321.197796) (xy 225.823003 -321.189967) (xy 225.770501 -321.174471)
			(xy 225.720755 -321.151625) (xy 225.674787 -321.121901) (xy 225.653854 -321.10426) (xy 225.646742 -321.098164)
			(xy 225.629724 -321.091814) (xy 225.54438 -321.091814) (xy 225.527362 -321.098164) (xy 225.52025 -321.10426)
			(xy 225.499305 -321.121883) (xy 225.453336 -321.151599) (xy 225.403592 -321.174438) (xy 225.351094 -321.189933)
			(xy 225.29692 -321.197764) (xy 225.269552 -321.19824) (xy 225.242301 -321.197767) (xy 225.188355 -321.190005)
			(xy 225.136062 -321.174645) (xy 225.086486 -321.152001) (xy 225.040638 -321.122532) (xy 224.999449 -321.08684)
			(xy 224.963758 -321.04565) (xy 224.934292 -320.9998) (xy 224.911649 -320.950223) (xy 224.896292 -320.89793)
			(xy 224.888532 -320.843983) (xy 224.888044 -320.816732) (xy 218.125802 -320.816732) (xy 223.412558 -326.103488)
			(xy 228.141528 -326.103488) (xy 228.145599 -326.047866) (xy 228.157725 -325.993429) (xy 228.177648 -325.941338)
			(xy 228.204944 -325.892703) (xy 228.23903 -325.84856) (xy 228.279179 -325.809851) (xy 228.324537 -325.7774)
			(xy 228.374137 -325.751899) (xy 228.426921 -325.733892) (xy 228.481764 -325.723762) (xy 228.537498 -325.721725)
			(xy 228.592935 -325.727825) (xy 228.646892 -325.741931) (xy 228.698221 -325.763743) (xy 228.745827 -325.792797)
			(xy 228.788695 -325.828472) (xy 228.825912 -325.870009) (xy 228.856685 -325.916522) (xy 228.880357 -325.967019)
			(xy 228.896425 -326.020426) (xy 228.904545 -326.075602) (xy 228.905054 -326.103488) (xy 228.904545 -326.131374)
			(xy 228.896425 -326.18655) (xy 228.880357 -326.239957) (xy 228.856685 -326.290454) (xy 228.825912 -326.336967)
			(xy 228.788695 -326.378504) (xy 228.745827 -326.414179) (xy 228.698221 -326.443233) (xy 228.646892 -326.465045)
			(xy 228.592935 -326.479151) (xy 228.537498 -326.485251) (xy 228.481764 -326.483214) (xy 228.426921 -326.473084)
			(xy 228.374137 -326.455077) (xy 228.324537 -326.429576) (xy 228.279179 -326.397125) (xy 228.23903 -326.358416)
			(xy 228.204944 -326.314273) (xy 228.177648 -326.265638) (xy 228.157725 -326.213547) (xy 228.145599 -326.15911)
			(xy 228.141528 -326.103488) (xy 223.412558 -326.103488) (xy 225.981006 -328.671936) (xy 225.998278 -328.679556)
			(xy 226.00793 -328.67981) (xy 226.036488 -328.681575) (xy 226.092633 -328.69259) (xy 226.146504 -328.711865)
			(xy 226.196893 -328.738968) (xy 226.24267 -328.77329) (xy 226.28281 -328.814063) (xy 226.316412 -328.860372)
			(xy 226.330002 -328.88555) (xy 226.336606 -328.89825) (xy 226.360736 -328.912982)
		)
		(stroke
			(width 0)
			(type solid)
		)
		(fill yes)
		(layer "B.Cu")
		(net "GND")
	)
	(gr_poly
		(pts
			(xy 98.214688 -44.24807) (xy 98.224862 -44.247618) (xy 98.243606 -44.239703) (xy 98.257792 -44.225117)
			(xy 98.261932 -44.215812) (xy 98.302318 -44.112942) (xy 98.29546 -44.082716) (xy 98.283776 -44.072048)
			(xy 98.261086 -44.0503) (xy 98.221276 -44.001665) (xy 98.188489 -43.948044) (xy 98.163343 -43.890443)
			(xy 98.146309 -43.829944) (xy 98.137707 -43.767685) (xy 98.137218 -43.73626) (xy 98.137708 -43.706292)
			(xy 98.145531 -43.64687) (xy 98.161044 -43.588977) (xy 98.18398 -43.533604) (xy 98.213947 -43.481698)
			(xy 98.250434 -43.434148) (xy 98.292814 -43.391768) (xy 98.340364 -43.355281) (xy 98.39227 -43.325314)
			(xy 98.447643 -43.302378) (xy 98.505536 -43.286865) (xy 98.564958 -43.279042) (xy 98.624894 -43.279042)
			(xy 98.684316 -43.286865) (xy 98.742209 -43.302378) (xy 98.797582 -43.325314) (xy 98.849488 -43.355281)
			(xy 98.897038 -43.391768) (xy 98.939418 -43.434148) (xy 98.975905 -43.481698) (xy 99.005872 -43.533604)
			(xy 99.028808 -43.588977) (xy 99.044321 -43.64687) (xy 99.052144 -43.706292) (xy 99.052634 -43.73626)
			(xy 99.052118 -43.767685) (xy 99.043528 -43.829946) (xy 99.026504 -43.890447) (xy 99.001366 -43.948052)
			(xy 98.968586 -44.001677) (xy 98.928781 -44.050316) (xy 98.906076 -44.072048) (xy 98.894392 -44.082716)
			(xy 98.887534 -44.112942) (xy 98.92792 -44.215812) (xy 98.932056 -44.225118) (xy 98.946254 -44.239695)
			(xy 98.964991 -44.24763) (xy 98.975164 -44.24807) (xy 99.877372 -44.24807) (xy 99.887244 -44.2476)
			(xy 99.905526 -44.240139) (xy 99.912932 -44.233592) (xy 99.913186 -44.233338) (xy 100.472494 -43.67403)
			(xy 100.473002 -43.673522) (xy 100.479586 -43.666142) (xy 100.487035 -43.647842) (xy 100.48748 -43.637962)
			(xy 100.48748 -35.109658) (xy 100.468938 -35.083496) (xy 100.453698 -35.078162) (xy 100.427426 -35.068318)
			(xy 100.377866 -35.042027) (xy 100.332687 -35.008764) (xy 100.292864 -34.969248) (xy 100.275644 -34.947098)
			(xy 100.27031 -34.939986) (xy 100.248212 -34.925254) (xy 100.244262 -34.922819) (xy 100.235704 -34.919233)
			(xy 100.231194 -34.918142) (xy 100.200968 -34.911284) (xy 100.182172 -34.914078) (xy 100.17379 -34.91865)
			(xy 100.155408 -34.928876) (xy 100.11712 -34.946302) (xy 100.097336 -34.953448) (xy 100.073135 -34.96149)
			(xy 100.023401 -34.97278) (xy 99.972721 -34.978478) (xy 99.947222 -34.978848) (xy 99.921722 -34.978488)
			(xy 99.87104 -34.972797) (xy 99.821305 -34.961505) (xy 99.797108 -34.953448) (xy 99.777323 -34.946304)
			(xy 99.739034 -34.928881) (xy 99.720654 -34.91865) (xy 99.712272 -34.914078) (xy 99.693476 -34.911284)
			(xy 99.66325 -34.918142) (xy 99.65873 -34.919205) (xy 99.650164 -34.922784) (xy 99.646232 -34.925254)
			(xy 99.62388 -34.94024) (xy 99.6188 -34.947352) (xy 99.600648 -34.970649) (xy 99.558367 -35.011882)
			(xy 99.510234 -35.046102) (xy 99.457401 -35.072491) (xy 99.40113 -35.090417) (xy 99.342767 -35.099453)
			(xy 99.313238 -35.100006) (xy 99.302316 -35.100006) (xy 99.302062 -35.099752) (xy 99.275347 -35.098515)
			(xy 99.222634 -35.089493) (xy 99.171697 -35.073198) (xy 99.123534 -35.049952) (xy 99.079088 -35.020209)
			(xy 99.039231 -34.984552) (xy 99.004742 -34.943679) (xy 98.976297 -34.898392) (xy 98.954454 -34.849576)
			(xy 98.93964 -34.79819) (xy 98.932146 -34.745238) (xy 98.93173 -34.718498) (xy 98.932194 -34.691246)
			(xy 98.939951 -34.637298) (xy 98.955308 -34.585002) (xy 98.977951 -34.535425) (xy 99.007419 -34.489575)
			(xy 99.043114 -34.448385) (xy 99.084307 -34.412695) (xy 99.13016 -34.383231) (xy 99.17974 -34.360594)
			(xy 99.232037 -34.345242) (xy 99.285986 -34.337491) (xy 99.313238 -34.33699) (xy 99.328031 -34.337134)
			(xy 99.357528 -34.339422) (xy 99.372166 -34.341562) (xy 99.383088 -34.34334) (xy 99.404424 -34.337244)
			(xy 99.480116 -34.272728) (xy 99.48926 -34.252662) (xy 99.48926 -33.93694) (xy 99.48926 -33.92551)
			(xy 99.480116 -33.905444) (xy 99.404424 -33.840928) (xy 99.383088 -33.834832) (xy 99.372166 -33.83661)
			(xy 99.35734 -33.838784) (xy 99.32746 -33.841076) (xy 99.312476 -33.841182) (xy 99.312222 -33.841182)
			(xy 99.285017 -33.840629) (xy 99.231177 -33.83276) (xy 99.179001 -33.81732) (xy 99.129548 -33.794623)
			(xy 99.083822 -33.765129) (xy 99.042751 -33.729438) (xy 99.007168 -33.688273) (xy 98.977795 -33.64247)
			(xy 98.955228 -33.592958) (xy 98.939926 -33.540741) (xy 98.932198 -33.48688) (xy 98.93173 -33.459674)
			(xy 98.932195 -33.432423) (xy 98.939955 -33.378477) (xy 98.955314 -33.326185) (xy 98.977958 -33.27661)
			(xy 99.007428 -33.230763) (xy 99.043122 -33.189577) (xy 99.084314 -33.153889) (xy 99.130167 -33.124428)
			(xy 99.179745 -33.101792) (xy 99.23204 -33.086442) (xy 99.285987 -33.078691) (xy 99.313238 -33.078166)
			(xy 99.313492 -33.078166) (xy 99.342997 -33.078723) (xy 99.401301 -33.087818) (xy 99.457512 -33.105777)
			(xy 99.51029 -33.132171) (xy 99.558377 -33.166373) (xy 99.600628 -33.207568) (xy 99.6188 -33.23082)
			(xy 99.62388 -33.237932) (xy 99.646232 -33.252918) (xy 99.650183 -33.255351) (xy 99.658742 -33.258931)
			(xy 99.66325 -33.26003) (xy 99.693476 -33.266888) (xy 99.712272 -33.264094) (xy 99.720654 -33.259522)
			(xy 99.739035 -33.249295) (xy 99.777322 -33.231865) (xy 99.797108 -33.224724) (xy 99.821308 -33.216679)
			(xy 99.871042 -33.205384) (xy 99.921722 -33.19968) (xy 99.947222 -33.199324) (xy 99.972722 -33.199686)
			(xy 100.023403 -33.205382) (xy 100.073136 -33.216678) (xy 100.097336 -33.224724) (xy 100.11712 -33.231869)
			(xy 100.155409 -33.249295) (xy 100.17379 -33.259522) (xy 100.182172 -33.264094) (xy 100.200968 -33.266888)
			(xy 100.231194 -33.26003) (xy 100.235716 -33.258971) (xy 100.244286 -33.255398) (xy 100.248212 -33.252918)
			(xy 100.27031 -33.238186) (xy 100.275644 -33.231074) (xy 100.292846 -33.20891) (xy 100.332673 -33.169394)
			(xy 100.377857 -33.136137) (xy 100.427426 -33.109857) (xy 100.453698 -33.10001) (xy 100.468938 -33.094676)
			(xy 100.48748 -33.068514) (xy 100.48748 -31.509462) (xy 100.468938 -31.4833) (xy 100.453698 -31.477966)
			(xy 100.427426 -31.468122) (xy 100.377865 -31.441831) (xy 100.332687 -31.408569) (xy 100.292863 -31.369052)
			(xy 100.275644 -31.346902) (xy 100.27031 -31.33979) (xy 100.248212 -31.325058) (xy 100.244262 -31.322623)
			(xy 100.235704 -31.319037) (xy 100.231194 -31.317946) (xy 100.200968 -31.311088) (xy 100.182172 -31.313882)
			(xy 100.17379 -31.318454) (xy 100.155408 -31.32868) (xy 100.11712 -31.346106) (xy 100.097336 -31.353252)
			(xy 100.073135 -31.361294) (xy 100.023401 -31.372584) (xy 99.972721 -31.378282) (xy 99.947222 -31.378652)
			(xy 99.921722 -31.378292) (xy 99.87104 -31.372601) (xy 99.821305 -31.361309) (xy 99.797108 -31.353252)
			(xy 99.777323 -31.346108) (xy 99.739033 -31.328685) (xy 99.720654 -31.318454) (xy 99.712272 -31.313882)
			(xy 99.693476 -31.311088) (xy 99.66325 -31.317946) (xy 99.65873 -31.319009) (xy 99.650164 -31.322589)
			(xy 99.646232 -31.325058) (xy 99.62388 -31.340044) (xy 99.6188 -31.347156) (xy 99.600648 -31.370453)
			(xy 99.558367 -31.411685) (xy 99.510234 -31.445905) (xy 99.4574 -31.472293) (xy 99.401129 -31.49022)
			(xy 99.342767 -31.499255) (xy 99.313238 -31.49981) (xy 99.302316 -31.49981) (xy 99.302062 -31.499556)
			(xy 99.275347 -31.498319) (xy 99.222634 -31.489297) (xy 99.171697 -31.473002) (xy 99.123533 -31.449756)
			(xy 99.079087 -31.420013) (xy 99.039229 -31.384356) (xy 99.00474 -31.343484) (xy 98.976295 -31.298196)
			(xy 98.954451 -31.249381) (xy 98.939637 -31.197994) (xy 98.932142 -31.145042) (xy 98.93173 -31.118302)
			(xy 98.932193 -31.09105) (xy 98.93995 -31.037101) (xy 98.955306 -30.984805) (xy 98.977949 -30.935227)
			(xy 99.007418 -30.889376) (xy 99.043112 -30.848187) (xy 99.084305 -30.812496) (xy 99.130159 -30.783032)
			(xy 99.179739 -30.760394) (xy 99.232036 -30.745043) (xy 99.285986 -30.737291) (xy 99.313238 -30.736794)
			(xy 99.328031 -30.736938) (xy 99.357528 -30.739226) (xy 99.372166 -30.741366) (xy 99.383088 -30.743144)
			(xy 99.404424 -30.737048) (xy 99.480116 -30.672532) (xy 99.48926 -30.652466) (xy 99.48926 -30.336744)
			(xy 99.48926 -30.325314) (xy 99.480116 -30.305248) (xy 99.404424 -30.240732) (xy 99.383088 -30.234636)
			(xy 99.372166 -30.236414) (xy 99.35734 -30.238588) (xy 99.32746 -30.24088) (xy 99.312476 -30.240986)
			(xy 99.312222 -30.240986) (xy 99.285017 -30.240433) (xy 99.231176 -30.232564) (xy 99.179 -30.217124)
			(xy 99.129547 -30.194427) (xy 99.083821 -30.164934) (xy 99.04275 -30.129242) (xy 99.007166 -30.088077)
			(xy 98.977793 -30.042274) (xy 98.955226 -29.992762) (xy 98.939923 -29.940545) (xy 98.932194 -29.886684)
			(xy 98.93173 -29.859478) (xy 98.932195 -29.832227) (xy 98.939955 -29.778281) (xy 98.955313 -29.725988)
			(xy 98.977957 -29.676413) (xy 99.007426 -29.630565) (xy 99.043121 -29.589378) (xy 99.084313 -29.55369)
			(xy 99.130165 -29.524228) (xy 99.179744 -29.501592) (xy 99.232039 -29.486242) (xy 99.285987 -29.478491)
			(xy 99.313238 -29.47797) (xy 99.313492 -29.47797) (xy 99.342997 -29.478527) (xy 99.401301 -29.487622)
			(xy 99.457512 -29.505581) (xy 99.510289 -29.531976) (xy 99.558376 -29.566178) (xy 99.600627 -29.607373)
			(xy 99.6188 -29.630624) (xy 99.62388 -29.637736) (xy 99.646232 -29.652722) (xy 99.650183 -29.655155)
			(xy 99.658742 -29.658735) (xy 99.66325 -29.659834) (xy 99.693476 -29.666692) (xy 99.712272 -29.663898)
			(xy 99.720654 -29.659326) (xy 99.739035 -29.649099) (xy 99.777322 -29.631669) (xy 99.797108 -29.624528)
			(xy 99.821308 -29.616483) (xy 99.871042 -29.605188) (xy 99.921722 -29.599484) (xy 99.947222 -29.599128)
			(xy 99.972722 -29.59949) (xy 100.023403 -29.605186) (xy 100.073136 -29.616482) (xy 100.097336 -29.624528)
			(xy 100.11712 -29.631673) (xy 100.155408 -29.649099) (xy 100.17379 -29.659326) (xy 100.182172 -29.663898)
			(xy 100.200968 -29.666692) (xy 100.231194 -29.659834) (xy 100.235716 -29.658775) (xy 100.244286 -29.655203)
			(xy 100.248212 -29.652722) (xy 100.27031 -29.63799) (xy 100.275644 -29.630878) (xy 100.292846 -29.608714)
			(xy 100.332672 -29.569197) (xy 100.377857 -29.53594) (xy 100.427426 -29.50966) (xy 100.453698 -29.499814)
			(xy 100.468938 -29.49448) (xy 100.48748 -29.468318) (xy 100.48748 -19.255994) (xy 100.487055 -19.245925)
			(xy 100.479337 -19.227324) (xy 100.472494 -19.219926) (xy 100.39858 -19.146012) (xy 100.389973 -19.138252)
			(xy 100.368068 -19.130757) (xy 100.345088 -19.133568) (xy 100.33508 -19.139408) (xy 100.31984 -19.149568)
			(xy 100.308918 -19.183604) (xy 100.315522 -19.200622) (xy 100.323862 -19.222954) (xy 100.335553 -19.269171)
			(xy 100.341379 -19.316485) (xy 100.341684 -19.340322) (xy 100.341684 -19.343878) (xy 100.340909 -19.370929)
			(xy 100.332661 -19.424413) (xy 100.316938 -19.476195) (xy 100.294056 -19.525236) (xy 100.264474 -19.57055)
			(xy 100.228784 -19.61123) (xy 100.187705 -19.646459) (xy 100.142059 -19.675528) (xy 100.092764 -19.697856)
			(xy 100.040808 -19.712994) (xy 99.987234 -19.720638) (xy 99.960176 -19.721068) (xy 99.932929 -19.72058)
			(xy 99.878989 -19.712822) (xy 99.826703 -19.697466) (xy 99.777134 -19.674826) (xy 99.731292 -19.645362)
			(xy 99.690109 -19.609674) (xy 99.654423 -19.568489) (xy 99.624962 -19.522645) (xy 99.602325 -19.473074)
			(xy 99.586973 -19.420787) (xy 99.579218 -19.366847) (xy 99.579218 -19.312353) (xy 99.586973 -19.258413)
			(xy 99.602325 -19.206126) (xy 99.624962 -19.156555) (xy 99.654423 -19.110711) (xy 99.690109 -19.069526)
			(xy 99.731292 -19.033838) (xy 99.777134 -19.004374) (xy 99.826703 -18.981734) (xy 99.878989 -18.966378)
			(xy 99.932929 -18.95862) (xy 99.960176 -18.958052) (xy 99.96424 -18.958052) (xy 99.97948 -18.958306)
			(xy 100.005642 -18.941288) (xy 100.04806 -18.840196) (xy 100.051611 -18.830751) (xy 100.05172 -18.81059)
			(xy 100.044004 -18.791964) (xy 100.037138 -18.78457) (xy 99.667822 -18.415254) (xy 99.66071 -18.407888)
			(xy 99.641914 -18.400268) (xy 87.929212 -18.400268) (xy 87.91914 -18.400688) (xy 87.90053 -18.408396)
			(xy 87.893144 -18.415254) (xy 87.55888 -18.749518) (xy 87.551514 -18.75663) (xy 87.543894 -18.775426)
			(xy 87.543894 -21.738336) (xy 89.416636 -21.738336) (xy 89.417138 -21.709596) (xy 89.425768 -21.652769)
			(xy 89.442825 -21.597879) (xy 89.46792 -21.546167) (xy 89.500488 -21.498805) (xy 89.51976 -21.477478)
			(xy 89.526364 -21.470366) (xy 89.533476 -21.45284) (xy 89.533476 -21.363432) (xy 89.526364 -21.345906)
			(xy 89.51976 -21.338794) (xy 89.500523 -21.317437) (xy 89.467954 -21.270081) (xy 89.442858 -21.218374)
			(xy 89.425803 -21.163488) (xy 89.417177 -21.106664) (xy 89.417173 -21.049189) (xy 89.425792 -20.992364)
			(xy 89.442839 -20.937475) (xy 89.467927 -20.885765) (xy 89.50049 -20.838404) (xy 89.51976 -20.817078)
			(xy 89.526364 -20.809966) (xy 89.533476 -20.79244) (xy 89.533476 -20.703032) (xy 89.526364 -20.685506)
			(xy 89.51976 -20.678394) (xy 89.500523 -20.657037) (xy 89.467954 -20.609681) (xy 89.442858 -20.557974)
			(xy 89.425803 -20.503088) (xy 89.417177 -20.446264) (xy 89.417173 -20.388789) (xy 89.425792 -20.331964)
			(xy 89.442839 -20.277075) (xy 89.467927 -20.225365) (xy 89.50049 -20.178004) (xy 89.51976 -20.156678)
			(xy 89.526364 -20.149566) (xy 89.533476 -20.13204) (xy 89.533476 -20.042632) (xy 89.526364 -20.025106)
			(xy 89.51976 -20.017994) (xy 89.500523 -19.996637) (xy 89.467954 -19.949281) (xy 89.442858 -19.897574)
			(xy 89.425803 -19.842688) (xy 89.417177 -19.785864) (xy 89.417173 -19.728389) (xy 89.425792 -19.671564)
			(xy 89.442839 -19.616675) (xy 89.467927 -19.564965) (xy 89.50049 -19.517604) (xy 89.51976 -19.496278)
			(xy 89.526364 -19.489166) (xy 89.533476 -19.47164) (xy 89.533476 -19.382232) (xy 89.526364 -19.364706)
			(xy 89.51976 -19.357594) (xy 89.50051 -19.336249) (xy 89.46794 -19.288892) (xy 89.442843 -19.237185)
			(xy 89.425788 -19.182298) (xy 89.41716 -19.125474) (xy 89.416636 -19.096736) (xy 89.417122 -19.069485)
			(xy 89.424878 -19.015537) (xy 89.440233 -18.963242) (xy 89.462875 -18.913665) (xy 89.492341 -18.867815)
			(xy 89.528032 -18.826624) (xy 89.569223 -18.790933) (xy 89.615073 -18.761467) (xy 89.66465 -18.738825)
			(xy 89.716945 -18.72347) (xy 89.770893 -18.715714) (xy 89.825395 -18.715714) (xy 89.879343 -18.72347)
			(xy 89.931638 -18.738825) (xy 89.981215 -18.761467) (xy 90.027065 -18.790933) (xy 90.068256 -18.826624)
			(xy 90.103947 -18.867815) (xy 90.133413 -18.913665) (xy 90.156055 -18.963242) (xy 90.17141 -19.015537)
			(xy 90.179166 -19.069485) (xy 90.179652 -19.096736) (xy 90.179136 -19.125475) (xy 90.17051 -19.182302)
			(xy 90.153457 -19.237192) (xy 90.128364 -19.288904) (xy 90.095799 -19.336267) (xy 90.076528 -19.357594)
			(xy 90.069924 -19.364706) (xy 90.062812 -19.382232) (xy 90.062812 -19.47164) (xy 90.069924 -19.489166)
			(xy 90.076528 -19.496278) (xy 90.095832 -19.517575) (xy 90.128392 -19.564944) (xy 90.153478 -19.616661)
			(xy 90.170523 -19.671556) (xy 90.179141 -19.728386) (xy 90.179137 -19.785866) (xy 90.170511 -19.842695)
			(xy 90.153459 -19.897588) (xy 90.128365 -19.949301) (xy 90.095799 -19.996666) (xy 90.076528 -20.017994)
			(xy 90.069924 -20.025106) (xy 90.062812 -20.042632) (xy 90.062812 -20.13204) (xy 90.069924 -20.149566)
			(xy 90.076528 -20.156678) (xy 90.095832 -20.177975) (xy 90.128392 -20.225344) (xy 90.153478 -20.277061)
			(xy 90.170523 -20.331956) (xy 90.174102 -20.35556) (xy 99.578158 -20.35556) (xy 99.582229 -20.299938)
			(xy 99.594355 -20.245501) (xy 99.614278 -20.19341) (xy 99.641574 -20.144775) (xy 99.67566 -20.100632)
			(xy 99.715809 -20.061923) (xy 99.761167 -20.029472) (xy 99.810767 -20.003971) (xy 99.863551 -19.985964)
			(xy 99.918394 -19.975834) (xy 99.974128 -19.973797) (xy 100.029565 -19.979897) (xy 100.083522 -19.994003)
			(xy 100.134851 -20.015815) (xy 100.182457 -20.044869) (xy 100.225325 -20.080544) (xy 100.262542 -20.122081)
			(xy 100.293315 -20.168594) (xy 100.316987 -20.219091) (xy 100.333055 -20.272498) (xy 100.341175 -20.327674)
			(xy 100.341684 -20.35556) (xy 100.341175 -20.383446) (xy 100.333055 -20.438622) (xy 100.316987 -20.492029)
			(xy 100.293315 -20.542526) (xy 100.262542 -20.589039) (xy 100.225325 -20.630576) (xy 100.182457 -20.666251)
			(xy 100.134851 -20.695305) (xy 100.083522 -20.717117) (xy 100.029565 -20.731223) (xy 99.974128 -20.737323)
			(xy 99.918394 -20.735286) (xy 99.863551 -20.725156) (xy 99.810767 -20.707149) (xy 99.761167 -20.681648)
			(xy 99.715809 -20.649197) (xy 99.67566 -20.610488) (xy 99.641574 -20.566345) (xy 99.614278 -20.51771)
			(xy 99.594355 -20.465619) (xy 99.582229 -20.411182) (xy 99.578158 -20.35556) (xy 90.174102 -20.35556)
			(xy 90.179141 -20.388786) (xy 90.179137 -20.446266) (xy 90.170511 -20.503095) (xy 90.153459 -20.557988)
			(xy 90.128365 -20.609701) (xy 90.095799 -20.657066) (xy 90.076528 -20.678394) (xy 90.069924 -20.685506)
			(xy 90.062812 -20.703032) (xy 90.062812 -20.79244) (xy 90.069924 -20.809966) (xy 90.076528 -20.817078)
			(xy 90.095832 -20.838375) (xy 90.128392 -20.885744) (xy 90.153478 -20.937461) (xy 90.170523 -20.992356)
			(xy 90.179141 -21.049186) (xy 90.179137 -21.106666) (xy 90.170511 -21.163495) (xy 90.153459 -21.218388)
			(xy 90.128365 -21.270101) (xy 90.095799 -21.317466) (xy 90.076528 -21.338794) (xy 90.069924 -21.345906)
			(xy 90.062812 -21.363432) (xy 90.062812 -21.37156) (xy 99.578158 -21.37156) (xy 99.582229 -21.315938)
			(xy 99.594355 -21.261501) (xy 99.614278 -21.20941) (xy 99.641574 -21.160775) (xy 99.67566 -21.116632)
			(xy 99.715809 -21.077923) (xy 99.761167 -21.045472) (xy 99.810767 -21.019971) (xy 99.863551 -21.001964)
			(xy 99.918394 -20.991834) (xy 99.974128 -20.989797) (xy 100.029565 -20.995897) (xy 100.083522 -21.010003)
			(xy 100.134851 -21.031815) (xy 100.182457 -21.060869) (xy 100.225325 -21.096544) (xy 100.262542 -21.138081)
			(xy 100.293315 -21.184594) (xy 100.316987 -21.235091) (xy 100.333055 -21.288498) (xy 100.341175 -21.343674)
			(xy 100.341684 -21.37156) (xy 100.341175 -21.399446) (xy 100.333055 -21.454622) (xy 100.316987 -21.508029)
			(xy 100.293315 -21.558526) (xy 100.262542 -21.605039) (xy 100.225325 -21.646576) (xy 100.182457 -21.682251)
			(xy 100.134851 -21.711305) (xy 100.083522 -21.733117) (xy 100.029565 -21.747223) (xy 99.974128 -21.753323)
			(xy 99.918394 -21.751286) (xy 99.863551 -21.741156) (xy 99.810767 -21.723149) (xy 99.761167 -21.697648)
			(xy 99.715809 -21.665197) (xy 99.67566 -21.626488) (xy 99.641574 -21.582345) (xy 99.614278 -21.53371)
			(xy 99.594355 -21.481619) (xy 99.582229 -21.427182) (xy 99.578158 -21.37156) (xy 90.062812 -21.37156)
			(xy 90.062812 -21.45284) (xy 90.069924 -21.470366) (xy 90.076528 -21.477478) (xy 90.09581 -21.498795)
			(xy 90.128376 -21.546159) (xy 90.153467 -21.597873) (xy 90.170515 -21.652767) (xy 90.179134 -21.709596)
			(xy 90.179652 -21.738336) (xy 90.179166 -21.765587) (xy 90.17141 -21.819535) (xy 90.156055 -21.87183)
			(xy 90.133413 -21.921407) (xy 90.103947 -21.967257) (xy 90.068256 -22.008448) (xy 90.027065 -22.044139)
			(xy 89.981215 -22.073605) (xy 89.931638 -22.096247) (xy 89.879343 -22.111602) (xy 89.825395 -22.119358)
			(xy 89.770893 -22.119358) (xy 89.716945 -22.111602) (xy 89.66465 -22.096247) (xy 89.615073 -22.073605)
			(xy 89.569223 -22.044139) (xy 89.528032 -22.008448) (xy 89.492341 -21.967257) (xy 89.462875 -21.921407)
			(xy 89.440233 -21.87183) (xy 89.424878 -21.819535) (xy 89.417122 -21.765587) (xy 89.416636 -21.738336)
			(xy 87.543894 -21.738336) (xy 87.543894 -23.055065) (xy 89.287086 -23.055065) (xy 89.287086 -22.99513)
			(xy 89.29491 -22.935708) (xy 89.310422 -22.877816) (xy 89.333358 -22.822443) (xy 89.363326 -22.770539)
			(xy 89.399812 -22.722989) (xy 89.442193 -22.680609) (xy 89.489742 -22.644124) (xy 89.541647 -22.614157)
			(xy 89.59702 -22.591221) (xy 89.654912 -22.575709) (xy 89.714334 -22.567886) (xy 89.774269 -22.567886)
			(xy 89.833691 -22.575709) (xy 89.891583 -22.591222) (xy 89.946955 -22.614158) (xy 89.99886 -22.644125)
			(xy 90.046409 -22.680611) (xy 90.08879 -22.722992) (xy 90.125275 -22.770541) (xy 90.155243 -22.822446)
			(xy 90.178179 -22.877818) (xy 90.193691 -22.935711) (xy 90.201514 -22.995133) (xy 90.202004 -23.0251)
			(xy 90.20178 -23.045661) (xy 90.198091 -23.086618) (xy 90.194638 -23.106888) (xy 90.192098 -23.120604)
			(xy 90.200988 -23.145496) (xy 90.287602 -23.22068) (xy 90.31351 -23.226014) (xy 90.326718 -23.221696)
			(xy 90.355919 -23.212602) (xy 90.416282 -23.202782) (xy 90.44686 -23.202138) (xy 90.465787 -23.202399)
			(xy 90.503449 -23.206217) (xy 90.522044 -23.209758) (xy 90.534744 -23.212044) (xy 90.558366 -23.205186)
			(xy 90.636852 -23.128986) (xy 90.644472 -23.105618) (xy 90.64244 -23.092918) (xy 90.63938 -23.073888)
			(xy 90.636069 -23.035483) (xy 90.635836 -23.01621) (xy 90.636271 -22.986242) (xy 90.644093 -22.926819)
			(xy 90.659604 -22.868925) (xy 90.682539 -22.813551) (xy 90.712505 -22.761645) (xy 90.74899 -22.714093)
			(xy 90.79137 -22.671711) (xy 90.838918 -22.635223) (xy 90.890823 -22.605253) (xy 90.946196 -22.582314)
			(xy 91.004088 -22.566799) (xy 91.063511 -22.558973) (xy 91.123447 -22.558971) (xy 91.18287 -22.566791)
			(xy 91.240764 -22.5823) (xy 91.296139 -22.605234) (xy 91.348046 -22.635199) (xy 91.395598 -22.671683)
			(xy 91.437982 -22.714061) (xy 91.474471 -22.761609) (xy 91.504442 -22.813513) (xy 91.527382 -22.868885)
			(xy 91.542899 -22.926777) (xy 91.550726 -22.9862) (xy 91.55073 -23.046135) (xy 91.542911 -23.105559)
			(xy 91.527403 -23.163453) (xy 91.504471 -23.218828) (xy 91.474507 -23.270737) (xy 91.438025 -23.31829)
			(xy 91.395647 -23.360674) (xy 91.3481 -23.397165) (xy 91.296197 -23.427137) (xy 91.240826 -23.450079)
			(xy 91.182934 -23.465596) (xy 91.123512 -23.473425) (xy 91.093544 -23.473918) (xy 91.059299 -23.473311)
			(xy 90.991573 -23.463108) (xy 90.95867 -23.453598) (xy 90.946478 -23.449788) (xy 90.922348 -23.45436)
			(xy 90.836496 -23.522178) (xy 90.82659 -23.544784) (xy 90.827606 -23.557738) (xy 90.828368 -23.583646)
			(xy 90.827882 -23.610897) (xy 90.826578 -23.619964) (xy 94.009192 -23.619964) (xy 94.009192 -23.560028)
			(xy 94.017015 -23.500606) (xy 94.032528 -23.442713) (xy 94.055464 -23.38734) (xy 94.085431 -23.335434)
			(xy 94.121918 -23.287884) (xy 94.164298 -23.245504) (xy 94.211848 -23.209017) (xy 94.263754 -23.17905)
			(xy 94.319127 -23.156114) (xy 94.37702 -23.140601) (xy 94.436442 -23.132778) (xy 94.496378 -23.132778)
			(xy 94.5558 -23.140601) (xy 94.613693 -23.156114) (xy 94.669066 -23.17905) (xy 94.720972 -23.209017)
			(xy 94.768522 -23.245504) (xy 94.810902 -23.287884) (xy 94.847389 -23.335434) (xy 94.877356 -23.38734)
			(xy 94.900292 -23.442713) (xy 94.915805 -23.500606) (xy 94.923628 -23.560028) (xy 94.924118 -23.589996)
			(xy 94.923628 -23.619964) (xy 94.915805 -23.679386) (xy 94.900292 -23.737279) (xy 94.877356 -23.792652)
			(xy 94.847389 -23.844558) (xy 94.819949 -23.880318) (xy 95.2406 -23.880318) (xy 95.244671 -23.824696)
			(xy 95.256797 -23.770259) (xy 95.27672 -23.718168) (xy 95.304016 -23.669533) (xy 95.338102 -23.62539)
			(xy 95.378251 -23.586681) (xy 95.423609 -23.55423) (xy 95.473209 -23.528729) (xy 95.525993 -23.510722)
			(xy 95.580836 -23.500592) (xy 95.63657 -23.498555) (xy 95.692007 -23.504655) (xy 95.745964 -23.518761)
			(xy 95.797293 -23.540573) (xy 95.844899 -23.569627) (xy 95.887767 -23.605302) (xy 95.924984 -23.646839)
			(xy 95.955757 -23.693352) (xy 95.979429 -23.743849) (xy 95.995497 -23.797256) (xy 96.003617 -23.852432)
			(xy 96.004126 -23.880318) (xy 96.2566 -23.880318) (xy 96.260671 -23.824696) (xy 96.272797 -23.770259)
			(xy 96.29272 -23.718168) (xy 96.320016 -23.669533) (xy 96.354102 -23.62539) (xy 96.394251 -23.586681)
			(xy 96.439609 -23.55423) (xy 96.489209 -23.528729) (xy 96.541993 -23.510722) (xy 96.596836 -23.500592)
			(xy 96.65257 -23.498555) (xy 96.708007 -23.504655) (xy 96.761964 -23.518761) (xy 96.813293 -23.540573)
			(xy 96.860899 -23.569627) (xy 96.903767 -23.605302) (xy 96.940984 -23.646839) (xy 96.971757 -23.693352)
			(xy 96.995429 -23.743849) (xy 97.011497 -23.797256) (xy 97.019617 -23.852432) (xy 97.020126 -23.880318)
			(xy 97.2726 -23.880318) (xy 97.276671 -23.824696) (xy 97.288797 -23.770259) (xy 97.30872 -23.718168)
			(xy 97.336016 -23.669533) (xy 97.370102 -23.62539) (xy 97.410251 -23.586681) (xy 97.455609 -23.55423)
			(xy 97.505209 -23.528729) (xy 97.557993 -23.510722) (xy 97.612836 -23.500592) (xy 97.66857 -23.498555)
			(xy 97.724007 -23.504655) (xy 97.777964 -23.518761) (xy 97.829293 -23.540573) (xy 97.876899 -23.569627)
			(xy 97.919767 -23.605302) (xy 97.956984 -23.646839) (xy 97.987757 -23.693352) (xy 98.011429 -23.743849)
			(xy 98.027497 -23.797256) (xy 98.035617 -23.852432) (xy 98.036126 -23.880318) (xy 98.290886 -23.880318)
			(xy 98.294957 -23.824696) (xy 98.307083 -23.770259) (xy 98.327006 -23.718168) (xy 98.354302 -23.669533)
			(xy 98.388388 -23.62539) (xy 98.428537 -23.586681) (xy 98.473895 -23.55423) (xy 98.523495 -23.528729)
			(xy 98.576279 -23.510722) (xy 98.631122 -23.500592) (xy 98.686856 -23.498555) (xy 98.742293 -23.504655)
			(xy 98.79625 -23.518761) (xy 98.847579 -23.540573) (xy 98.895185 -23.569627) (xy 98.938053 -23.605302)
			(xy 98.97527 -23.646839) (xy 99.006043 -23.693352) (xy 99.029715 -23.743849) (xy 99.045783 -23.797256)
			(xy 99.053903 -23.852432) (xy 99.054412 -23.880318) (xy 99.053903 -23.908204) (xy 99.045783 -23.96338)
			(xy 99.029715 -24.016787) (xy 99.006043 -24.067284) (xy 98.97527 -24.113797) (xy 98.938053 -24.155334)
			(xy 98.895185 -24.191009) (xy 98.847579 -24.220063) (xy 98.79625 -24.241875) (xy 98.742293 -24.255981)
			(xy 98.686856 -24.262081) (xy 98.631122 -24.260044) (xy 98.576279 -24.249914) (xy 98.523495 -24.231907)
			(xy 98.473895 -24.206406) (xy 98.428537 -24.173955) (xy 98.388388 -24.135246) (xy 98.354302 -24.091103)
			(xy 98.327006 -24.042468) (xy 98.307083 -23.990377) (xy 98.294957 -23.93594) (xy 98.290886 -23.880318)
			(xy 98.036126 -23.880318) (xy 98.035617 -23.908204) (xy 98.027497 -23.96338) (xy 98.011429 -24.016787)
			(xy 97.987757 -24.067284) (xy 97.956984 -24.113797) (xy 97.919767 -24.155334) (xy 97.876899 -24.191009)
			(xy 97.829293 -24.220063) (xy 97.777964 -24.241875) (xy 97.724007 -24.255981) (xy 97.66857 -24.262081)
			(xy 97.612836 -24.260044) (xy 97.557993 -24.249914) (xy 97.505209 -24.231907) (xy 97.455609 -24.206406)
			(xy 97.410251 -24.173955) (xy 97.370102 -24.135246) (xy 97.336016 -24.091103) (xy 97.30872 -24.042468)
			(xy 97.288797 -23.990377) (xy 97.276671 -23.93594) (xy 97.2726 -23.880318) (xy 97.020126 -23.880318)
			(xy 97.019617 -23.908204) (xy 97.011497 -23.96338) (xy 96.995429 -24.016787) (xy 96.971757 -24.067284)
			(xy 96.940984 -24.113797) (xy 96.903767 -24.155334) (xy 96.860899 -24.191009) (xy 96.813293 -24.220063)
			(xy 96.761964 -24.241875) (xy 96.708007 -24.255981) (xy 96.65257 -24.262081) (xy 96.596836 -24.260044)
			(xy 96.541993 -24.249914) (xy 96.489209 -24.231907) (xy 96.439609 -24.206406) (xy 96.394251 -24.173955)
			(xy 96.354102 -24.135246) (xy 96.320016 -24.091103) (xy 96.29272 -24.042468) (xy 96.272797 -23.990377)
			(xy 96.260671 -23.93594) (xy 96.2566 -23.880318) (xy 96.004126 -23.880318) (xy 96.003617 -23.908204)
			(xy 95.995497 -23.96338) (xy 95.979429 -24.016787) (xy 95.955757 -24.067284) (xy 95.924984 -24.113797)
			(xy 95.887767 -24.155334) (xy 95.844899 -24.191009) (xy 95.797293 -24.220063) (xy 95.745964 -24.241875)
			(xy 95.692007 -24.255981) (xy 95.63657 -24.262081) (xy 95.580836 -24.260044) (xy 95.525993 -24.249914)
			(xy 95.473209 -24.231907) (xy 95.423609 -24.206406) (xy 95.378251 -24.173955) (xy 95.338102 -24.135246)
			(xy 95.304016 -24.091103) (xy 95.27672 -24.042468) (xy 95.256797 -23.990377) (xy 95.244671 -23.93594)
			(xy 95.2406 -23.880318) (xy 94.819949 -23.880318) (xy 94.810902 -23.892108) (xy 94.768522 -23.934488)
			(xy 94.720972 -23.970975) (xy 94.669066 -24.000942) (xy 94.613693 -24.023878) (xy 94.5558 -24.039391)
			(xy 94.496378 -24.047214) (xy 94.436442 -24.047214) (xy 94.37702 -24.039391) (xy 94.319127 -24.023878)
			(xy 94.263754 -24.000942) (xy 94.211848 -23.970975) (xy 94.164298 -23.934488) (xy 94.121918 -23.892108)
			(xy 94.085431 -23.844558) (xy 94.055464 -23.792652) (xy 94.032528 -23.737279) (xy 94.017015 -23.679386)
			(xy 94.009192 -23.619964) (xy 90.826578 -23.619964) (xy 90.820126 -23.664845) (xy 90.804771 -23.71714)
			(xy 90.782129 -23.766717) (xy 90.752663 -23.812567) (xy 90.716972 -23.853758) (xy 90.675781 -23.889449)
			(xy 90.629931 -23.918915) (xy 90.580354 -23.941557) (xy 90.528059 -23.956912) (xy 90.474111 -23.964668)
			(xy 90.419609 -23.964668) (xy 90.365661 -23.956912) (xy 90.313366 -23.941557) (xy 90.263789 -23.918915)
			(xy 90.217939 -23.889449) (xy 90.176748 -23.853758) (xy 90.141057 -23.812567) (xy 90.111591 -23.766717)
			(xy 90.088949 -23.71714) (xy 90.073594 -23.664845) (xy 90.065838 -23.610897) (xy 90.065352 -23.583646)
			(xy 90.06713 -23.548086) (xy 90.0684 -23.53437) (xy 90.057478 -23.51024) (xy 89.964514 -23.44293)
			(xy 89.938098 -23.439882) (xy 89.925652 -23.44547) (xy 89.896892 -23.45728) (xy 89.836987 -23.473919)
			(xy 89.775382 -23.482302) (xy 89.744296 -23.482808) (xy 89.714329 -23.482314) (xy 89.654907 -23.47449)
			(xy 89.597015 -23.458977) (xy 89.541642 -23.436041) (xy 89.489738 -23.406073) (xy 89.442188 -23.369587)
			(xy 89.399809 -23.327206) (xy 89.363323 -23.279657) (xy 89.333356 -23.227752) (xy 89.31042 -23.172379)
			(xy 89.294909 -23.114487) (xy 89.287086 -23.055065) (xy 87.543894 -23.055065) (xy 87.543894 -24.189944)
			(xy 89.298778 -24.189944) (xy 89.302849 -24.134322) (xy 89.314975 -24.079885) (xy 89.334898 -24.027794)
			(xy 89.362194 -23.979159) (xy 89.39628 -23.935016) (xy 89.436429 -23.896307) (xy 89.481787 -23.863856)
			(xy 89.531387 -23.838355) (xy 89.584171 -23.820348) (xy 89.639014 -23.810218) (xy 89.694748 -23.808181)
			(xy 89.750185 -23.814281) (xy 89.804142 -23.828387) (xy 89.855471 -23.850199) (xy 89.903077 -23.879253)
			(xy 89.945945 -23.914928) (xy 89.983162 -23.956465) (xy 90.013935 -24.002978) (xy 90.037607 -24.053475)
			(xy 90.053675 -24.106882) (xy 90.061795 -24.162058) (xy 90.062304 -24.189944) (xy 91.82176 -24.189944)
			(xy 91.825831 -24.134322) (xy 91.837957 -24.079885) (xy 91.85788 -24.027794) (xy 91.885176 -23.979159)
			(xy 91.919262 -23.935016) (xy 91.959411 -23.896307) (xy 92.004769 -23.863856) (xy 92.054369 -23.838355)
			(xy 92.107153 -23.820348) (xy 92.161996 -23.810218) (xy 92.21773 -23.808181) (xy 92.273167 -23.814281)
			(xy 92.327124 -23.828387) (xy 92.378453 -23.850199) (xy 92.426059 -23.879253) (xy 92.468927 -23.914928)
			(xy 92.506144 -23.956465) (xy 92.536917 -24.002978) (xy 92.560589 -24.053475) (xy 92.576657 -24.106882)
			(xy 92.584777 -24.162058) (xy 92.585286 -24.189944) (xy 92.584777 -24.21783) (xy 92.576657 -24.273006)
			(xy 92.560589 -24.326413) (xy 92.536917 -24.37691) (xy 92.506144 -24.423423) (xy 92.468927 -24.46496)
			(xy 92.426059 -24.500635) (xy 92.378453 -24.529689) (xy 92.327124 -24.551501) (xy 92.273167 -24.565607)
			(xy 92.21773 -24.571707) (xy 92.161996 -24.56967) (xy 92.107153 -24.55954) (xy 92.054369 -24.541533)
			(xy 92.004769 -24.516032) (xy 91.959411 -24.483581) (xy 91.919262 -24.444872) (xy 91.885176 -24.400729)
			(xy 91.85788 -24.352094) (xy 91.837957 -24.300003) (xy 91.825831 -24.245566) (xy 91.82176 -24.189944)
			(xy 90.062304 -24.189944) (xy 90.061795 -24.21783) (xy 90.053675 -24.273006) (xy 90.037607 -24.326413)
			(xy 90.013935 -24.37691) (xy 89.983162 -24.423423) (xy 89.945945 -24.46496) (xy 89.903077 -24.500635)
			(xy 89.855471 -24.529689) (xy 89.804142 -24.551501) (xy 89.750185 -24.565607) (xy 89.694748 -24.571707)
			(xy 89.639014 -24.56967) (xy 89.584171 -24.55954) (xy 89.531387 -24.541533) (xy 89.481787 -24.516032)
			(xy 89.436429 -24.483581) (xy 89.39628 -24.444872) (xy 89.362194 -24.400729) (xy 89.334898 -24.352094)
			(xy 89.314975 -24.300003) (xy 89.302849 -24.245566) (xy 89.298778 -24.189944) (xy 87.543894 -24.189944)
			(xy 87.543894 -25.390094) (xy 91.73337 -25.390094) (xy 91.73386 -25.360126) (xy 91.741683 -25.300704)
			(xy 91.757196 -25.242811) (xy 91.780132 -25.187438) (xy 91.810099 -25.135532) (xy 91.846586 -25.087982)
			(xy 91.888966 -25.045602) (xy 91.936516 -25.009115) (xy 91.988422 -24.979148) (xy 92.043795 -24.956212)
			(xy 92.101688 -24.940699) (xy 92.16111 -24.932876) (xy 92.221046 -24.932876) (xy 92.280468 -24.940699)
			(xy 92.338361 -24.956212) (xy 92.393734 -24.979148) (xy 92.44564 -25.009115) (xy 92.49319 -25.045602)
			(xy 92.53557 -25.087982) (xy 92.572057 -25.135532) (xy 92.602024 -25.187438) (xy 92.62496 -25.242811)
			(xy 92.640473 -25.300704) (xy 92.648296 -25.360126) (xy 92.648786 -25.390094) (xy 92.648357 -25.418879)
			(xy 92.641138 -25.475994) (xy 92.626814 -25.531753) (xy 92.605611 -25.585275) (xy 92.577863 -25.635716)
			(xy 92.544008 -25.682278) (xy 92.504581 -25.724228) (xy 92.48267 -25.7429) (xy 92.474288 -25.749758)
			(xy 92.464636 -25.769316) (xy 92.461334 -25.867106) (xy 92.469462 -25.887172) (xy 92.47759 -25.894792)
			(xy 92.495996 -25.912862) (xy 92.528232 -25.953131) (xy 92.554754 -25.997373) (xy 92.57508 -26.044781)
			(xy 92.58884 -26.094494) (xy 92.595783 -26.145607) (xy 92.596208 -26.171398) (xy 92.595722 -26.198649)
			(xy 92.587966 -26.252597) (xy 92.572611 -26.304892) (xy 92.549969 -26.354469) (xy 92.520503 -26.400319)
			(xy 92.484812 -26.44151) (xy 92.443621 -26.477201) (xy 92.397771 -26.506667) (xy 92.348194 -26.529309)
			(xy 92.295899 -26.544664) (xy 92.241951 -26.55242) (xy 92.187449 -26.55242) (xy 92.133501 -26.544664)
			(xy 92.081206 -26.529309) (xy 92.031629 -26.506667) (xy 91.985779 -26.477201) (xy 91.944588 -26.44151)
			(xy 91.908897 -26.400319) (xy 91.879431 -26.354469) (xy 91.856789 -26.304892) (xy 91.841434 -26.252597)
			(xy 91.833678 -26.198649) (xy 91.833192 -26.171398) (xy 91.833711 -26.142755) (xy 91.842309 -26.086116)
			(xy 91.85928 -26.031401) (xy 91.884243 -25.979839) (xy 91.916636 -25.93259) (xy 91.935808 -25.911302)
			(xy 91.943174 -25.903174) (xy 91.950032 -25.8826) (xy 91.940888 -25.785064) (xy 91.93022 -25.766268)
			(xy 91.92133 -25.759918) (xy 91.896789 -25.741359) (xy 91.852393 -25.69876) (xy 91.814102 -25.650599)
			(xy 91.782604 -25.597744) (xy 91.758467 -25.541148) (xy 91.742126 -25.48183) (xy 91.733875 -25.420858)
			(xy 91.73337 -25.390094) (xy 87.543894 -25.390094) (xy 87.543894 -25.506934) (xy 87.544323 -25.517002)
			(xy 87.552045 -25.535598) (xy 87.55888 -25.543002) (xy 87.610188 -25.593802) (xy 87.617597 -25.600488)
			(xy 87.636033 -25.608074) (xy 87.646002 -25.608534) (xy 87.648796 -25.608534) (xy 87.676046 -25.608997)
			(xy 87.729991 -25.616753) (xy 87.782284 -25.632107) (xy 87.831859 -25.654746) (xy 87.877708 -25.684211)
			(xy 87.918896 -25.719901) (xy 87.954587 -25.761089) (xy 87.984052 -25.806937) (xy 88.006692 -25.856512)
			(xy 88.022047 -25.908805) (xy 88.029803 -25.96275) (xy 88.029803 -25.990042) (xy 89.298778 -25.990042)
			(xy 89.302849 -25.93442) (xy 89.314975 -25.879983) (xy 89.334898 -25.827892) (xy 89.362194 -25.779257)
			(xy 89.39628 -25.735114) (xy 89.436429 -25.696405) (xy 89.481787 -25.663954) (xy 89.531387 -25.638453)
			(xy 89.584171 -25.620446) (xy 89.639014 -25.610316) (xy 89.694748 -25.608279) (xy 89.750185 -25.614379)
			(xy 89.804142 -25.628485) (xy 89.855471 -25.650297) (xy 89.903077 -25.679351) (xy 89.945945 -25.715026)
			(xy 89.983162 -25.756563) (xy 90.013935 -25.803076) (xy 90.037607 -25.853573) (xy 90.053675 -25.90698)
			(xy 90.061795 -25.962156) (xy 90.062304 -25.990042) (xy 90.061795 -26.017928) (xy 90.053675 -26.073104)
			(xy 90.037607 -26.126511) (xy 90.013935 -26.177008) (xy 89.983162 -26.223521) (xy 89.945945 -26.265058)
			(xy 89.903077 -26.300733) (xy 89.855471 -26.329787) (xy 89.804142 -26.351599) (xy 89.750185 -26.365705)
			(xy 89.694748 -26.371805) (xy 89.639014 -26.369768) (xy 89.584171 -26.359638) (xy 89.531387 -26.341631)
			(xy 89.481787 -26.31613) (xy 89.436429 -26.283679) (xy 89.39628 -26.24497) (xy 89.362194 -26.200827)
			(xy 89.334898 -26.152192) (xy 89.314975 -26.100101) (xy 89.302849 -26.045664) (xy 89.298778 -25.990042)
			(xy 88.029803 -25.990042) (xy 88.029803 -26.01725) (xy 88.022047 -26.071195) (xy 88.006692 -26.123488)
			(xy 87.984052 -26.173063) (xy 87.954587 -26.218911) (xy 87.918896 -26.260099) (xy 87.877708 -26.295789)
			(xy 87.831859 -26.325254) (xy 87.782284 -26.347893) (xy 87.729991 -26.363247) (xy 87.676046 -26.371003)
			(xy 87.648796 -26.37155) (xy 87.646002 -26.37155) (xy 87.636035 -26.372025) (xy 87.617598 -26.379601)
			(xy 87.610188 -26.386282) (xy 87.55888 -26.437082) (xy 87.552038 -26.444481) (xy 87.544321 -26.46308)
			(xy 87.543894 -26.47315) (xy 87.543894 -27.307032) (xy 87.544323 -27.3171) (xy 87.552044 -27.335696)
			(xy 87.55888 -27.3431) (xy 87.610188 -27.3939) (xy 87.617597 -27.400586) (xy 87.636033 -27.408172)
			(xy 87.646002 -27.408632) (xy 87.648796 -27.408632) (xy 87.676046 -27.409095) (xy 87.729992 -27.416851)
			(xy 87.782285 -27.432205) (xy 87.83186 -27.454845) (xy 87.877709 -27.484309) (xy 87.918898 -27.519999)
			(xy 87.954588 -27.561188) (xy 87.984053 -27.607036) (xy 88.006694 -27.656612) (xy 88.022048 -27.708904)
			(xy 88.029805 -27.76285) (xy 88.029805 -27.79014) (xy 89.362786 -27.79014) (xy 89.366857 -27.734518)
			(xy 89.378983 -27.680081) (xy 89.398906 -27.62799) (xy 89.426202 -27.579355) (xy 89.460288 -27.535212)
			(xy 89.500437 -27.496503) (xy 89.545795 -27.464052) (xy 89.595395 -27.438551) (xy 89.648179 -27.420544)
			(xy 89.703022 -27.410414) (xy 89.758756 -27.408377) (xy 89.814193 -27.414477) (xy 89.86815 -27.428583)
			(xy 89.919479 -27.450395) (xy 89.967085 -27.479449) (xy 90.009953 -27.515124) (xy 90.04717 -27.556661)
			(xy 90.077943 -27.603174) (xy 90.101615 -27.653671) (xy 90.117683 -27.707078) (xy 90.125803 -27.762254)
			(xy 90.126312 -27.79014) (xy 91.866718 -27.79014) (xy 91.870789 -27.734518) (xy 91.882915 -27.680081)
			(xy 91.902838 -27.62799) (xy 91.930134 -27.579355) (xy 91.96422 -27.535212) (xy 92.004369 -27.496503)
			(xy 92.049727 -27.464052) (xy 92.099327 -27.438551) (xy 92.152111 -27.420544) (xy 92.206954 -27.410414)
			(xy 92.262688 -27.408377) (xy 92.318125 -27.414477) (xy 92.372082 -27.428583) (xy 92.423411 -27.450395)
			(xy 92.471017 -27.479449) (xy 92.513885 -27.515124) (xy 92.551102 -27.556661) (xy 92.581875 -27.603174)
			(xy 92.605547 -27.653671) (xy 92.621615 -27.707078) (xy 92.629735 -27.762254) (xy 92.630244 -27.79014)
			(xy 92.629747 -27.817352) (xy 93.899695 -27.817352) (xy 93.899695 -27.762848) (xy 93.907452 -27.7089)
			(xy 93.922809 -27.656605) (xy 93.945451 -27.607027) (xy 93.97492 -27.561177) (xy 94.010614 -27.519988)
			(xy 94.051806 -27.484298) (xy 94.097659 -27.454834) (xy 94.147238 -27.432196) (xy 94.199535 -27.416845)
			(xy 94.253484 -27.409093) (xy 94.280736 -27.408632) (xy 94.306042 -27.409051) (xy 94.356214 -27.415714)
			(xy 94.405067 -27.428945) (xy 94.428564 -27.43835) (xy 94.436563 -27.441399) (xy 94.453639 -27.442482)
			(xy 94.470121 -27.437885) (xy 94.477332 -27.43327) (xy 94.502732 -27.41549) (xy 94.509608 -27.410203)
			(xy 94.519689 -27.396107) (xy 94.52449 -27.379456) (xy 94.524322 -27.370786) (xy 94.52356 -27.342846)
			(xy 94.52356 -26.479246) (xy 94.524068 -26.456894) (xy 94.524576 -26.444448) (xy 94.514162 -26.421842)
			(xy 94.429072 -26.355548) (xy 94.404688 -26.350976) (xy 94.39275 -26.354786) (xy 94.365415 -26.362634)
			(xy 94.309171 -26.371048) (xy 94.280736 -26.37155) (xy 94.253484 -26.371005) (xy 94.199536 -26.363253)
			(xy 94.147239 -26.347902) (xy 94.09766 -26.325264) (xy 94.051807 -26.2958) (xy 94.010615 -26.260111)
			(xy 93.974921 -26.218921) (xy 93.945453 -26.173072) (xy 93.922811 -26.123495) (xy 93.907454 -26.0712)
			(xy 93.899697 -26.017251) (xy 93.899697 -25.962749) (xy 93.907454 -25.9088) (xy 93.922811 -25.856505)
			(xy 93.945453 -25.806928) (xy 93.974921 -25.761079) (xy 94.010615 -25.719889) (xy 94.051807 -25.6842)
			(xy 94.09766 -25.654736) (xy 94.147239 -25.632098) (xy 94.199536 -25.616747) (xy 94.253484 -25.608995)
			(xy 94.280736 -25.608534) (xy 94.309689 -25.609043) (xy 94.366931 -25.617785) (xy 94.422195 -25.635078)
			(xy 94.474211 -25.660523) (xy 94.521783 -25.693538) (xy 94.563819 -25.733363) (xy 94.599354 -25.779084)
			(xy 94.627571 -25.82965) (xy 94.628468 -25.832054) (xy 96.188276 -25.832054) (xy 96.188733 -25.80545)
			(xy 96.196109 -25.752756) (xy 96.210739 -25.701599) (xy 96.23234 -25.652973) (xy 96.260491 -25.607822)
			(xy 96.294646 -25.567023) (xy 96.334141 -25.531369) (xy 96.355916 -25.516078) (xy 96.367391 -25.507738)
			(xy 96.385591 -25.485994) (xy 96.397106 -25.460082) (xy 96.401046 -25.432002) (xy 96.397107 -25.403922)
			(xy 96.385594 -25.378009) (xy 96.367394 -25.356265) (xy 96.355916 -25.34793) (xy 96.334146 -25.332636)
			(xy 96.294668 -25.296968) (xy 96.260525 -25.256164) (xy 96.23238 -25.211014) (xy 96.210778 -25.162393)
			(xy 96.196137 -25.111243) (xy 96.188741 -25.058556) (xy 96.188276 -25.031954) (xy 96.188762 -25.004703)
			(xy 96.196518 -24.950755) (xy 96.211873 -24.89846) (xy 96.234515 -24.848883) (xy 96.263981 -24.803033)
			(xy 96.299672 -24.761842) (xy 96.340863 -24.726151) (xy 96.386713 -24.696685) (xy 96.43629 -24.674043)
			(xy 96.488585 -24.658688) (xy 96.542533 -24.650932) (xy 96.597035 -24.650932) (xy 96.650983 -24.658688)
			(xy 96.703278 -24.674043) (xy 96.752855 -24.696685) (xy 96.798705 -24.726151) (xy 96.839896 -24.761842)
			(xy 96.863097 -24.788618) (xy 98.793282 -24.788618) (xy 98.793282 -24.728682) (xy 98.801105 -24.66926)
			(xy 98.816618 -24.611367) (xy 98.839554 -24.555994) (xy 98.869521 -24.504088) (xy 98.906008 -24.456538)
			(xy 98.948388 -24.414158) (xy 98.995938 -24.377671) (xy 99.047844 -24.347704) (xy 99.103217 -24.324768)
			(xy 99.16111 -24.309255) (xy 99.220532 -24.301432) (xy 99.280468 -24.301432) (xy 99.33989 -24.309255)
			(xy 99.397783 -24.324768) (xy 99.453156 -24.347704) (xy 99.505062 -24.377671) (xy 99.552612 -24.414158)
			(xy 99.594992 -24.456538) (xy 99.631479 -24.504088) (xy 99.661446 -24.555994) (xy 99.684382 -24.611367)
			(xy 99.699895 -24.66926) (xy 99.707718 -24.728682) (xy 99.708208 -24.75865) (xy 99.707718 -24.788618)
			(xy 99.699895 -24.84804) (xy 99.684382 -24.905933) (xy 99.661446 -24.961306) (xy 99.631479 -25.013212)
			(xy 99.594992 -25.060762) (xy 99.552612 -25.103142) (xy 99.505062 -25.139629) (xy 99.453156 -25.169596)
			(xy 99.397783 -25.192532) (xy 99.33989 -25.208045) (xy 99.280468 -25.215868) (xy 99.220532 -25.215868)
			(xy 99.16111 -25.208045) (xy 99.103217 -25.192532) (xy 99.047844 -25.169596) (xy 98.995938 -25.139629)
			(xy 98.948388 -25.103142) (xy 98.906008 -25.060762) (xy 98.869521 -25.013212) (xy 98.839554 -24.961306)
			(xy 98.816618 -24.905933) (xy 98.801105 -24.84804) (xy 98.793282 -24.788618) (xy 96.863097 -24.788618)
			(xy 96.875587 -24.803033) (xy 96.905053 -24.848883) (xy 96.927695 -24.89846) (xy 96.94305 -24.950755)
			(xy 96.950806 -25.004703) (xy 96.951292 -25.031954) (xy 96.950812 -25.058557) (xy 96.943436 -25.111249)
			(xy 96.928808 -25.162404) (xy 96.90721 -25.211029) (xy 96.879063 -25.25618) (xy 96.844914 -25.29698)
			(xy 96.805424 -25.332636) (xy 96.783652 -25.34793) (xy 96.772163 -25.356256) (xy 96.75395 -25.377999)
			(xy 96.742427 -25.403915) (xy 96.738485 -25.432002) (xy 96.742428 -25.460089) (xy 96.753953 -25.486005)
			(xy 96.772166 -25.507747) (xy 96.783652 -25.516078) (xy 96.805419 -25.531377) (xy 96.844899 -25.567043)
			(xy 96.879042 -25.607845) (xy 96.907188 -25.652994) (xy 96.928791 -25.701615) (xy 96.943432 -25.752765)
			(xy 96.950828 -25.805452) (xy 96.951292 -25.832054) (xy 96.950806 -25.859305) (xy 96.94305 -25.913253)
			(xy 96.927695 -25.965548) (xy 96.905053 -26.015125) (xy 96.875587 -26.060975) (xy 96.839896 -26.102166)
			(xy 96.798705 -26.137857) (xy 96.752855 -26.167323) (xy 96.703278 -26.189965) (xy 96.650983 -26.20532)
			(xy 96.597035 -26.213076) (xy 96.542533 -26.213076) (xy 96.488585 -26.20532) (xy 96.43629 -26.189965)
			(xy 96.386713 -26.167323) (xy 96.340863 -26.137857) (xy 96.299672 -26.102166) (xy 96.263981 -26.060975)
			(xy 96.234515 -26.015125) (xy 96.211873 -25.965548) (xy 96.196518 -25.913253) (xy 96.188762 -25.859305)
			(xy 96.188276 -25.832054) (xy 94.628468 -25.832054) (xy 94.647822 -25.883899) (xy 94.659641 -25.940586)
			(xy 94.661736 -25.969468) (xy 94.662244 -25.981914) (xy 94.674944 -26.00325) (xy 94.766638 -26.060654)
			(xy 94.791276 -26.062432) (xy 94.802706 -26.057606) (xy 94.831066 -26.046144) (xy 94.890063 -26.029986)
			(xy 94.950684 -26.021812) (xy 94.981268 -26.021284) (xy 95.011247 -26.021792) (xy 95.070691 -26.029616)
			(xy 95.128604 -26.045136) (xy 95.183995 -26.068085) (xy 95.235916 -26.098071) (xy 95.283476 -26.134579)
			(xy 95.325862 -26.176985) (xy 95.362348 -26.224562) (xy 95.392309 -26.276497) (xy 95.415233 -26.331899)
			(xy 95.422985 -26.360882) (xy 97.089466 -26.360882) (xy 97.093537 -26.30526) (xy 97.105663 -26.250823)
			(xy 97.125586 -26.198732) (xy 97.152882 -26.150097) (xy 97.186968 -26.105954) (xy 97.227117 -26.067245)
			(xy 97.272475 -26.034794) (xy 97.322075 -26.009293) (xy 97.374859 -25.991286) (xy 97.429702 -25.981156)
			(xy 97.485436 -25.979119) (xy 97.540873 -25.985219) (xy 97.59483 -25.999325) (xy 97.646159 -26.021137)
			(xy 97.693765 -26.050191) (xy 97.736633 -26.085866) (xy 97.77385 -26.127403) (xy 97.804623 -26.173916)
			(xy 97.828295 -26.224413) (xy 97.844363 -26.27782) (xy 97.852483 -26.332996) (xy 97.852992 -26.360882)
			(xy 98.105466 -26.360882) (xy 98.109537 -26.30526) (xy 98.121663 -26.250823) (xy 98.141586 -26.198732)
			(xy 98.168882 -26.150097) (xy 98.202968 -26.105954) (xy 98.243117 -26.067245) (xy 98.288475 -26.034794)
			(xy 98.338075 -26.009293) (xy 98.390859 -25.991286) (xy 98.445702 -25.981156) (xy 98.501436 -25.979119)
			(xy 98.556873 -25.985219) (xy 98.61083 -25.999325) (xy 98.662159 -26.021137) (xy 98.709765 -26.050191)
			(xy 98.752633 -26.085866) (xy 98.78985 -26.127403) (xy 98.820623 -26.173916) (xy 98.844295 -26.224413)
			(xy 98.860363 -26.27782) (xy 98.868483 -26.332996) (xy 98.868992 -26.360882) (xy 98.868483 -26.388768)
			(xy 98.860363 -26.443944) (xy 98.844295 -26.497351) (xy 98.820623 -26.547848) (xy 98.78985 -26.594361)
			(xy 98.752633 -26.635898) (xy 98.709765 -26.671573) (xy 98.662159 -26.700627) (xy 98.61083 -26.722439)
			(xy 98.556873 -26.736545) (xy 98.501436 -26.742645) (xy 98.445702 -26.740608) (xy 98.390859 -26.730478)
			(xy 98.338075 -26.712471) (xy 98.288475 -26.68697) (xy 98.243117 -26.654519) (xy 98.202968 -26.61581)
			(xy 98.168882 -26.571667) (xy 98.141586 -26.523032) (xy 98.121663 -26.470941) (xy 98.109537 -26.416504)
			(xy 98.105466 -26.360882) (xy 97.852992 -26.360882) (xy 97.852483 -26.388768) (xy 97.844363 -26.443944)
			(xy 97.828295 -26.497351) (xy 97.804623 -26.547848) (xy 97.77385 -26.594361) (xy 97.736633 -26.635898)
			(xy 97.693765 -26.671573) (xy 97.646159 -26.700627) (xy 97.59483 -26.722439) (xy 97.540873 -26.736545)
			(xy 97.485436 -26.742645) (xy 97.429702 -26.740608) (xy 97.374859 -26.730478) (xy 97.322075 -26.712471)
			(xy 97.272475 -26.68697) (xy 97.227117 -26.654519) (xy 97.186968 -26.61581) (xy 97.152882 -26.571667)
			(xy 97.125586 -26.523032) (xy 97.105663 -26.470941) (xy 97.093537 -26.416504) (xy 97.089466 -26.360882)
			(xy 95.422985 -26.360882) (xy 95.430725 -26.389819) (xy 95.438522 -26.449267) (xy 95.438976 -26.479246)
			(xy 95.438976 -26.971244) (xy 98.850956 -26.971244) (xy 98.855027 -26.915622) (xy 98.867153 -26.861185)
			(xy 98.887076 -26.809094) (xy 98.914372 -26.760459) (xy 98.948458 -26.716316) (xy 98.988607 -26.677607)
			(xy 99.033965 -26.645156) (xy 99.083565 -26.619655) (xy 99.136349 -26.601648) (xy 99.191192 -26.591518)
			(xy 99.246926 -26.589481) (xy 99.302363 -26.595581) (xy 99.35632 -26.609687) (xy 99.407649 -26.631499)
			(xy 99.455255 -26.660553) (xy 99.498123 -26.696228) (xy 99.53534 -26.737765) (xy 99.566113 -26.784278)
			(xy 99.589785 -26.834775) (xy 99.605853 -26.888182) (xy 99.613973 -26.943358) (xy 99.614482 -26.971244)
			(xy 99.613973 -26.99913) (xy 99.605853 -27.054306) (xy 99.589785 -27.107713) (xy 99.566113 -27.15821)
			(xy 99.53534 -27.204723) (xy 99.498123 -27.24626) (xy 99.455255 -27.281935) (xy 99.407649 -27.310989)
			(xy 99.35632 -27.332801) (xy 99.302363 -27.346907) (xy 99.246926 -27.353007) (xy 99.191192 -27.35097)
			(xy 99.136349 -27.34084) (xy 99.083565 -27.322833) (xy 99.033965 -27.297332) (xy 98.988607 -27.264881)
			(xy 98.948458 -27.226172) (xy 98.914372 -27.182029) (xy 98.887076 -27.133394) (xy 98.867153 -27.081303)
			(xy 98.855027 -27.026866) (xy 98.850956 -26.971244) (xy 95.438976 -26.971244) (xy 95.438976 -27.342846)
			(xy 95.438516 -27.37282) (xy 95.430688 -27.432255) (xy 95.415173 -27.490161) (xy 95.392236 -27.545548)
			(xy 95.362268 -27.597469) (xy 95.325783 -27.645036) (xy 95.283403 -27.687436) (xy 95.235854 -27.723945)
			(xy 95.183948 -27.753938) (xy 95.128572 -27.776902) (xy 95.070673 -27.792445) (xy 95.011242 -27.800301)
			(xy 94.981268 -27.800808) (xy 94.950131 -27.80028) (xy 94.888435 -27.791814) (xy 94.82845 -27.775083)
			(xy 94.799658 -27.763216) (xy 94.788482 -27.75839) (xy 94.76486 -27.75966) (xy 94.673674 -27.810968)
			(xy 94.660212 -27.830526) (xy 94.658688 -27.842464) (xy 94.654498 -27.869499) (xy 94.639316 -27.922058)
			(xy 94.616785 -27.971912) (xy 94.587366 -28.018037) (xy 94.551663 -28.059489) (xy 94.510407 -28.095418)
			(xy 94.464443 -28.125088) (xy 94.414713 -28.147891) (xy 94.362237 -28.163359) (xy 94.30809 -28.171176)
			(xy 94.280736 -28.171648) (xy 94.253484 -28.171107) (xy 94.199535 -28.163355) (xy 94.147238 -28.148004)
			(xy 94.097659 -28.125366) (xy 94.051806 -28.095902) (xy 94.010614 -28.060212) (xy 93.97492 -28.019023)
			(xy 93.945451 -27.973173) (xy 93.922809 -27.923595) (xy 93.907452 -27.8713) (xy 93.899695 -27.817352)
			(xy 92.629747 -27.817352) (xy 92.629735 -27.818026) (xy 92.621615 -27.873202) (xy 92.605547 -27.926609)
			(xy 92.581875 -27.977106) (xy 92.551102 -28.023619) (xy 92.513885 -28.065156) (xy 92.471017 -28.100831)
			(xy 92.423411 -28.129885) (xy 92.372082 -28.151697) (xy 92.318125 -28.165803) (xy 92.262688 -28.171903)
			(xy 92.206954 -28.169866) (xy 92.152111 -28.159736) (xy 92.099327 -28.141729) (xy 92.049727 -28.116228)
			(xy 92.004369 -28.083777) (xy 91.96422 -28.045068) (xy 91.930134 -28.000925) (xy 91.902838 -27.95229)
			(xy 91.882915 -27.900199) (xy 91.870789 -27.845762) (xy 91.866718 -27.79014) (xy 90.126312 -27.79014)
			(xy 90.125803 -27.818026) (xy 90.117683 -27.873202) (xy 90.101615 -27.926609) (xy 90.077943 -27.977106)
			(xy 90.04717 -28.023619) (xy 90.009953 -28.065156) (xy 89.967085 -28.100831) (xy 89.919479 -28.129885)
			(xy 89.86815 -28.151697) (xy 89.814193 -28.165803) (xy 89.758756 -28.171903) (xy 89.703022 -28.169866)
			(xy 89.648179 -28.159736) (xy 89.595395 -28.141729) (xy 89.545795 -28.116228) (xy 89.500437 -28.083777)
			(xy 89.460288 -28.045068) (xy 89.426202 -28.000925) (xy 89.398906 -27.95229) (xy 89.378983 -27.900199)
			(xy 89.366857 -27.845762) (xy 89.362786 -27.79014) (xy 88.029805 -27.79014) (xy 88.029805 -27.81735)
			(xy 88.022048 -27.871296) (xy 88.006694 -27.923588) (xy 87.984053 -27.973164) (xy 87.954588 -28.019012)
			(xy 87.918898 -28.060201) (xy 87.877709 -28.095891) (xy 87.83186 -28.125355) (xy 87.782285 -28.147995)
			(xy 87.729992 -28.163349) (xy 87.676046 -28.171105) (xy 87.648796 -28.171648) (xy 87.646002 -28.171648)
			(xy 87.636035 -28.172123) (xy 87.617598 -28.179699) (xy 87.610188 -28.18638) (xy 87.55888 -28.23718)
			(xy 87.552038 -28.244579) (xy 87.54432 -28.263178) (xy 87.543894 -28.273248) (xy 87.543894 -29.106876)
			(xy 87.544331 -29.11694) (xy 87.552064 -29.135525) (xy 87.55888 -29.142944) (xy 87.610188 -29.193744)
			(xy 87.617599 -29.200425) (xy 87.636035 -29.208005) (xy 87.646002 -29.208476) (xy 87.648796 -29.208476)
			(xy 87.67605 -29.208939) (xy 87.730004 -29.216695) (xy 87.782304 -29.232052) (xy 87.831887 -29.254695)
			(xy 87.877743 -29.284164) (xy 87.918938 -29.319859) (xy 87.954633 -29.361054) (xy 87.984103 -29.406909)
			(xy 88.006747 -29.456492) (xy 88.022104 -29.508792) (xy 88.029861 -29.562746) (xy 88.029861 -29.589984)
			(xy 89.362786 -29.589984) (xy 89.366857 -29.534362) (xy 89.378983 -29.479925) (xy 89.398906 -29.427834)
			(xy 89.426202 -29.379199) (xy 89.460288 -29.335056) (xy 89.500437 -29.296347) (xy 89.545795 -29.263896)
			(xy 89.595395 -29.238395) (xy 89.648179 -29.220388) (xy 89.703022 -29.210258) (xy 89.758756 -29.208221)
			(xy 89.814193 -29.214321) (xy 89.86815 -29.228427) (xy 89.919479 -29.250239) (xy 89.967085 -29.279293)
			(xy 90.009953 -29.314968) (xy 90.04717 -29.356505) (xy 90.077943 -29.403018) (xy 90.101615 -29.453515)
			(xy 90.117683 -29.506922) (xy 90.125803 -29.562098) (xy 90.126312 -29.589984) (xy 91.866718 -29.589984)
			(xy 91.870789 -29.534362) (xy 91.882915 -29.479925) (xy 91.902838 -29.427834) (xy 91.930134 -29.379199)
			(xy 91.96422 -29.335056) (xy 92.004369 -29.296347) (xy 92.049727 -29.263896) (xy 92.099327 -29.238395)
			(xy 92.152111 -29.220388) (xy 92.206954 -29.210258) (xy 92.262688 -29.208221) (xy 92.318125 -29.214321)
			(xy 92.372082 -29.228427) (xy 92.423411 -29.250239) (xy 92.471017 -29.279293) (xy 92.513885 -29.314968)
			(xy 92.551102 -29.356505) (xy 92.581875 -29.403018) (xy 92.605547 -29.453515) (xy 92.621615 -29.506922)
			(xy 92.629735 -29.562098) (xy 92.630244 -29.589984) (xy 93.898718 -29.589984) (xy 93.902789 -29.534362)
			(xy 93.914915 -29.479925) (xy 93.934838 -29.427834) (xy 93.962134 -29.379199) (xy 93.99622 -29.335056)
			(xy 94.036369 -29.296347) (xy 94.081727 -29.263896) (xy 94.131327 -29.238395) (xy 94.184111 -29.220388)
			(xy 94.238954 -29.210258) (xy 94.294688 -29.208221) (xy 94.350125 -29.214321) (xy 94.404082 -29.228427)
			(xy 94.455411 -29.250239) (xy 94.503017 -29.279293) (xy 94.545885 -29.314968) (xy 94.567559 -29.339158)
			(xy 96.290009 -29.339158) (xy 96.290009 -29.284642) (xy 96.297768 -29.230682) (xy 96.313127 -29.178376)
			(xy 96.335775 -29.128788) (xy 96.365249 -29.082927) (xy 96.40095 -29.041729) (xy 96.442151 -29.006031)
			(xy 96.488014 -28.97656) (xy 96.537604 -28.953917) (xy 96.589912 -28.938561) (xy 96.643872 -28.930807)
			(xy 96.67113 -28.930346) (xy 96.685923 -28.930487) (xy 96.715421 -28.932772) (xy 96.730058 -28.934918)
			(xy 96.74098 -28.936696) (xy 96.762316 -28.9306) (xy 96.829626 -28.873196) (xy 96.837599 -28.865609)
			(xy 96.84668 -28.845585) (xy 96.847152 -28.834588) (xy 96.847152 -28.530296) (xy 96.846632 -28.519309)
			(xy 96.837565 -28.499298) (xy 96.829626 -28.491688) (xy 96.762316 -28.434284) (xy 96.74098 -28.428188)
			(xy 96.730058 -28.429966) (xy 96.71542 -28.432106) (xy 96.685923 -28.434395) (xy 96.67113 -28.434538)
			(xy 96.643878 -28.434017) (xy 96.589928 -28.426264) (xy 96.537631 -28.410912) (xy 96.488051 -28.388273)
			(xy 96.442197 -28.358808) (xy 96.401004 -28.323117) (xy 96.36531 -28.281927) (xy 96.335842 -28.236076)
			(xy 96.313199 -28.186498) (xy 96.297842 -28.134201) (xy 96.290085 -28.080252) (xy 96.290085 -28.025748)
			(xy 96.297842 -27.971799) (xy 96.313199 -27.919502) (xy 96.335842 -27.869924) (xy 96.36531 -27.824073)
			(xy 96.401004 -27.782883) (xy 96.442197 -27.747192) (xy 96.488051 -27.717727) (xy 96.537631 -27.695088)
			(xy 96.589928 -27.679736) (xy 96.643878 -27.671983) (xy 96.67113 -27.671522) (xy 96.697058 -27.671923)
			(xy 96.748436 -27.678934) (xy 96.798393 -27.692836) (xy 96.846008 -27.713372) (xy 96.890404 -27.740166)
			(xy 96.930764 -27.772723) (xy 96.966345 -27.810445) (xy 96.981772 -27.831288) (xy 96.987512 -27.838619)
			(xy 97.003015 -27.848904) (xy 97.011998 -27.851354) (xy 97.042224 -27.858212) (xy 97.051502 -27.859949)
			(xy 97.070163 -27.857216) (xy 97.078546 -27.852878) (xy 97.104513 -27.838566) (xy 97.159369 -27.81606)
			(xy 97.216674 -27.800838) (xy 97.275468 -27.793157) (xy 97.305114 -27.79268) (xy 97.334756 -27.793203)
			(xy 97.393537 -27.800917) (xy 97.450835 -27.816136) (xy 97.505697 -27.838607) (xy 97.531682 -27.852878)
			(xy 97.540094 -27.857126) (xy 97.558725 -27.859858) (xy 97.568004 -27.858212) (xy 97.59823 -27.851354)
			(xy 97.607224 -27.84893) (xy 97.622729 -27.838635) (xy 97.628456 -27.831288) (xy 97.643883 -27.810443)
			(xy 97.679452 -27.772708) (xy 97.719807 -27.740142) (xy 97.764204 -27.713346) (xy 97.811823 -27.692814)
			(xy 97.861786 -27.678926) (xy 97.913169 -27.671938) (xy 97.939098 -27.671522) (xy 97.966353 -27.671925)
			(xy 98.020309 -27.679682) (xy 98.072611 -27.695039) (xy 98.122195 -27.717683) (xy 98.168052 -27.747154)
			(xy 98.209248 -27.78285) (xy 98.244945 -27.824046) (xy 98.274416 -27.869903) (xy 98.29706 -27.919487)
			(xy 98.312417 -27.971789) (xy 98.320175 -28.025745) (xy 98.320175 -28.080255) (xy 98.312417 -28.134211)
			(xy 98.29706 -28.186513) (xy 98.274416 -28.236097) (xy 98.244945 -28.281954) (xy 98.209248 -28.32315)
			(xy 98.168052 -28.358846) (xy 98.122195 -28.388317) (xy 98.072611 -28.410961) (xy 98.020309 -28.426318)
			(xy 97.966353 -28.434075) (xy 97.939098 -28.434538) (xy 97.924305 -28.434405) (xy 97.894807 -28.432115)
			(xy 97.88017 -28.429966) (xy 97.869248 -28.428188) (xy 97.847912 -28.434284) (xy 97.780602 -28.491688)
			(xy 97.772641 -28.499286) (xy 97.763553 -28.519302) (xy 97.763076 -28.530296) (xy 97.763076 -28.834588)
			(xy 97.763595 -28.845575) (xy 97.772661 -28.865587) (xy 97.780602 -28.873196) (xy 97.847912 -28.9306)
			(xy 97.869248 -28.936696) (xy 97.88017 -28.934918) (xy 97.894808 -28.932774) (xy 97.924305 -28.930488)
			(xy 97.939098 -28.930346) (xy 97.966348 -28.930901) (xy 98.020292 -28.938657) (xy 98.072584 -28.954011)
			(xy 98.122158 -28.976651) (xy 98.168006 -29.006115) (xy 98.209194 -29.041804) (xy 98.244884 -29.082992)
			(xy 98.274348 -29.12884) (xy 98.296988 -29.178414) (xy 98.312343 -29.230706) (xy 98.320099 -29.28465)
			(xy 98.320099 -29.33915) (xy 98.312343 -29.393094) (xy 98.296988 -29.445386) (xy 98.274348 -29.49496)
			(xy 98.244884 -29.540808) (xy 98.209194 -29.581996) (xy 98.168006 -29.617685) (xy 98.122158 -29.647149)
			(xy 98.072584 -29.669789) (xy 98.020292 -29.685143) (xy 97.966348 -29.692899) (xy 97.939098 -29.693362)
			(xy 97.913171 -29.692947) (xy 97.861792 -29.685939) (xy 97.811836 -29.672041) (xy 97.764221 -29.651506)
			(xy 97.719824 -29.624715) (xy 97.679464 -29.592159) (xy 97.643883 -29.554438) (xy 97.628456 -29.533596)
			(xy 97.62269 -29.526289) (xy 97.607206 -29.515988) (xy 97.59823 -29.51353) (xy 97.568004 -29.506672)
			(xy 97.558724 -29.504952) (xy 97.540065 -29.507674) (xy 97.531682 -29.512006) (xy 97.505708 -29.526305)
			(xy 97.450855 -29.548815) (xy 97.393552 -29.56404) (xy 97.33476 -29.571725) (xy 97.305114 -29.572204)
			(xy 97.275471 -29.571714) (xy 97.216689 -29.563991) (xy 97.15939 -29.548762) (xy 97.10453 -29.526281)
			(xy 97.078546 -29.512006) (xy 97.070128 -29.507771) (xy 97.051502 -29.505031) (xy 97.042224 -29.506672)
			(xy 97.011998 -29.51353) (xy 97.002996 -29.515929) (xy 96.987495 -29.526243) (xy 96.981772 -29.533596)
			(xy 96.966323 -29.554424) (xy 96.930759 -29.59216) (xy 96.890407 -29.624728) (xy 96.846014 -29.651527)
			(xy 96.798398 -29.672061) (xy 96.748439 -29.685953) (xy 96.697058 -29.692944) (xy 96.67113 -29.693362)
			(xy 96.643872 -29.692993) (xy 96.589912 -29.685239) (xy 96.537604 -29.669883) (xy 96.488014 -29.64724)
			(xy 96.442151 -29.617769) (xy 96.40095 -29.582071) (xy 96.365249 -29.540873) (xy 96.335775 -29.495012)
			(xy 96.313127 -29.445424) (xy 96.297768 -29.393118) (xy 96.290009 -29.339158) (xy 94.567559 -29.339158)
			(xy 94.583102 -29.356505) (xy 94.613875 -29.403018) (xy 94.637547 -29.453515) (xy 94.653615 -29.506922)
			(xy 94.661735 -29.562098) (xy 94.662244 -29.589984) (xy 94.661735 -29.61787) (xy 94.653615 -29.673046)
			(xy 94.637547 -29.726453) (xy 94.613875 -29.77695) (xy 94.583102 -29.823463) (xy 94.545885 -29.865)
			(xy 94.503017 -29.900675) (xy 94.455411 -29.929729) (xy 94.404082 -29.951541) (xy 94.350125 -29.965647)
			(xy 94.294688 -29.971747) (xy 94.238954 -29.96971) (xy 94.184111 -29.95958) (xy 94.131327 -29.941573)
			(xy 94.081727 -29.916072) (xy 94.036369 -29.883621) (xy 93.99622 -29.844912) (xy 93.962134 -29.800769)
			(xy 93.934838 -29.752134) (xy 93.914915 -29.700043) (xy 93.902789 -29.645606) (xy 93.898718 -29.589984)
			(xy 92.630244 -29.589984) (xy 92.629735 -29.61787) (xy 92.621615 -29.673046) (xy 92.605547 -29.726453)
			(xy 92.581875 -29.77695) (xy 92.551102 -29.823463) (xy 92.513885 -29.865) (xy 92.471017 -29.900675)
			(xy 92.423411 -29.929729) (xy 92.372082 -29.951541) (xy 92.318125 -29.965647) (xy 92.262688 -29.971747)
			(xy 92.206954 -29.96971) (xy 92.152111 -29.95958) (xy 92.099327 -29.941573) (xy 92.049727 -29.916072)
			(xy 92.004369 -29.883621) (xy 91.96422 -29.844912) (xy 91.930134 -29.800769) (xy 91.902838 -29.752134)
			(xy 91.882915 -29.700043) (xy 91.870789 -29.645606) (xy 91.866718 -29.589984) (xy 90.126312 -29.589984)
			(xy 90.125803 -29.61787) (xy 90.117683 -29.673046) (xy 90.101615 -29.726453) (xy 90.077943 -29.77695)
			(xy 90.04717 -29.823463) (xy 90.009953 -29.865) (xy 89.967085 -29.900675) (xy 89.919479 -29.929729)
			(xy 89.86815 -29.951541) (xy 89.814193 -29.965647) (xy 89.758756 -29.971747) (xy 89.703022 -29.96971)
			(xy 89.648179 -29.95958) (xy 89.595395 -29.941573) (xy 89.545795 -29.916072) (xy 89.500437 -29.883621)
			(xy 89.460288 -29.844912) (xy 89.426202 -29.800769) (xy 89.398906 -29.752134) (xy 89.378983 -29.700043)
			(xy 89.366857 -29.645606) (xy 89.362786 -29.589984) (xy 88.029861 -29.589984) (xy 88.029861 -29.617254)
			(xy 88.022104 -29.671208) (xy 88.006747 -29.723508) (xy 87.984103 -29.773091) (xy 87.954633 -29.818946)
			(xy 87.918938 -29.860141) (xy 87.877743 -29.895836) (xy 87.831887 -29.925305) (xy 87.782304 -29.947948)
			(xy 87.730004 -29.963305) (xy 87.67605 -29.971061) (xy 87.648796 -29.971492) (xy 87.646002 -29.971492)
			(xy 87.636034 -29.971966) (xy 87.617591 -29.979535) (xy 87.610188 -29.986224) (xy 87.55888 -30.037024)
			(xy 87.552029 -30.04442) (xy 87.54429 -30.063019) (xy 87.543894 -30.073092) (xy 87.543894 -30.906974)
			(xy 87.54433 -30.917038) (xy 87.552063 -30.935624) (xy 87.55888 -30.943042) (xy 87.610188 -30.993842)
			(xy 87.617599 -31.000524) (xy 87.636034 -31.008104) (xy 87.646002 -31.008574) (xy 87.648796 -31.008574)
			(xy 87.67605 -31.009037) (xy 87.730004 -31.016793) (xy 87.782305 -31.03215) (xy 87.831888 -31.054793)
			(xy 87.877744 -31.084263) (xy 87.918939 -31.119958) (xy 87.954635 -31.161153) (xy 87.984105 -31.207008)
			(xy 88.006749 -31.256591) (xy 88.022106 -31.308892) (xy 88.029863 -31.362846) (xy 88.029863 -31.417354)
			(xy 88.022106 -31.471308) (xy 88.006749 -31.523609) (xy 87.984105 -31.573192) (xy 87.954635 -31.619047)
			(xy 87.934483 -31.642304) (xy 89.406474 -31.642304) (xy 89.410545 -31.586682) (xy 89.422671 -31.532245)
			(xy 89.442594 -31.480154) (xy 89.46989 -31.431519) (xy 89.503976 -31.387376) (xy 89.544125 -31.348667)
			(xy 89.589483 -31.316216) (xy 89.639083 -31.290715) (xy 89.691867 -31.272708) (xy 89.74671 -31.262578)
			(xy 89.802444 -31.260541) (xy 89.857881 -31.266641) (xy 89.911838 -31.280747) (xy 89.963167 -31.302559)
			(xy 90.010773 -31.331613) (xy 90.053641 -31.367288) (xy 90.074064 -31.390082) (xy 91.866718 -31.390082)
			(xy 91.870789 -31.33446) (xy 91.882915 -31.280023) (xy 91.902838 -31.227932) (xy 91.930134 -31.179297)
			(xy 91.96422 -31.135154) (xy 92.004369 -31.096445) (xy 92.049727 -31.063994) (xy 92.099327 -31.038493)
			(xy 92.152111 -31.020486) (xy 92.206954 -31.010356) (xy 92.262688 -31.008319) (xy 92.318125 -31.014419)
			(xy 92.372082 -31.028525) (xy 92.423411 -31.050337) (xy 92.471017 -31.079391) (xy 92.513885 -31.115066)
			(xy 92.551102 -31.156603) (xy 92.581875 -31.203116) (xy 92.605547 -31.253613) (xy 92.621615 -31.30702)
			(xy 92.629735 -31.362196) (xy 92.630244 -31.390082) (xy 93.898718 -31.390082) (xy 93.902789 -31.33446)
			(xy 93.914915 -31.280023) (xy 93.934838 -31.227932) (xy 93.962134 -31.179297) (xy 93.99622 -31.135154)
			(xy 94.036369 -31.096445) (xy 94.081727 -31.063994) (xy 94.131327 -31.038493) (xy 94.184111 -31.020486)
			(xy 94.238954 -31.010356) (xy 94.294688 -31.008319) (xy 94.350125 -31.014419) (xy 94.404082 -31.028525)
			(xy 94.455411 -31.050337) (xy 94.503017 -31.079391) (xy 94.545885 -31.115066) (xy 94.583102 -31.156603)
			(xy 94.613875 -31.203116) (xy 94.637547 -31.253613) (xy 94.653615 -31.30702) (xy 94.661735 -31.362196)
			(xy 94.662244 -31.390082) (xy 94.661735 -31.417968) (xy 94.653615 -31.473144) (xy 94.637547 -31.526551)
			(xy 94.613875 -31.577048) (xy 94.583102 -31.623561) (xy 94.545885 -31.665098) (xy 94.527671 -31.680256)
			(xy 96.290027 -31.680256) (xy 96.290027 -31.625744) (xy 96.297785 -31.571786) (xy 96.313144 -31.519482)
			(xy 96.33579 -31.469896) (xy 96.365263 -31.424038) (xy 96.400963 -31.382842) (xy 96.442162 -31.347145)
			(xy 96.488023 -31.317676) (xy 96.53761 -31.295034) (xy 96.589916 -31.279679) (xy 96.643874 -31.271925)
			(xy 96.67113 -31.271464) (xy 96.697058 -31.271848) (xy 96.748438 -31.278859) (xy 96.798396 -31.292763)
			(xy 96.846012 -31.313302) (xy 96.890408 -31.340099) (xy 96.930767 -31.37266) (xy 96.966346 -31.410385)
			(xy 96.981772 -31.43123) (xy 96.987523 -31.438551) (xy 97.003018 -31.448843) (xy 97.011998 -31.451296)
			(xy 97.042224 -31.458154) (xy 97.051502 -31.459886) (xy 97.070163 -31.457155) (xy 97.078546 -31.45282)
			(xy 97.10453 -31.438561) (xy 97.159401 -31.416149) (xy 97.216702 -31.400994) (xy 97.275478 -31.393347)
			(xy 97.305114 -31.392876) (xy 97.334752 -31.39331) (xy 97.393536 -31.400938) (xy 97.450839 -31.416104)
			(xy 97.5057 -31.438552) (xy 97.531682 -31.45282) (xy 97.540095 -31.457066) (xy 97.558725 -31.459801)
			(xy 97.568004 -31.458154) (xy 97.59823 -31.451296) (xy 97.60722 -31.448859) (xy 97.622726 -31.438572)
			(xy 97.628456 -31.43123) (xy 97.643866 -31.410373) (xy 97.67944 -31.37264) (xy 97.719799 -31.340077)
			(xy 97.764199 -31.313283) (xy 97.81182 -31.292754) (xy 97.861784 -31.278867) (xy 97.913169 -31.27188)
			(xy 97.939098 -31.271464) (xy 97.966349 -31.271983) (xy 98.020296 -31.279739) (xy 98.07259 -31.295094)
			(xy 98.122167 -31.317735) (xy 98.168017 -31.347201) (xy 98.209207 -31.382892) (xy 98.244898 -31.424081)
			(xy 98.274364 -31.469931) (xy 98.297005 -31.519508) (xy 98.31236 -31.571802) (xy 98.320117 -31.625749)
			(xy 98.320117 -31.680251) (xy 98.31236 -31.734198) (xy 98.297005 -31.786492) (xy 98.274364 -31.836069)
			(xy 98.244898 -31.881919) (xy 98.209207 -31.923108) (xy 98.168017 -31.958799) (xy 98.122167 -31.988265)
			(xy 98.07259 -32.010906) (xy 98.020296 -32.026261) (xy 97.966349 -32.034017) (xy 97.939098 -32.03448)
			(xy 97.924305 -32.034347) (xy 97.894807 -32.032056) (xy 97.88017 -32.029908) (xy 97.869248 -32.02813)
			(xy 97.847912 -32.034226) (xy 97.780602 -32.09163) (xy 97.772667 -32.099251) (xy 97.763564 -32.119249)
			(xy 97.763076 -32.130238) (xy 97.763076 -32.43453) (xy 97.763572 -32.44552) (xy 97.772654 -32.465532)
			(xy 97.780602 -32.473138) (xy 97.847912 -32.530542) (xy 97.869248 -32.536638) (xy 97.88017 -32.53486)
			(xy 97.894807 -32.532716) (xy 97.924305 -32.53043) (xy 97.939098 -32.530288) (xy 97.966351 -32.530759)
			(xy 98.020301 -32.538516) (xy 98.072599 -32.553872) (xy 98.122179 -32.576514) (xy 98.168032 -32.605981)
			(xy 98.209224 -32.641675) (xy 98.244917 -32.682867) (xy 98.274385 -32.72872) (xy 98.297028 -32.778299)
			(xy 98.312384 -32.830597) (xy 98.320141 -32.884547) (xy 98.320141 -32.939053) (xy 98.312384 -32.993003)
			(xy 98.297028 -33.045301) (xy 98.274385 -33.09488) (xy 98.244917 -33.140733) (xy 98.209224 -33.181925)
			(xy 98.168032 -33.217619) (xy 98.122179 -33.247086) (xy 98.072599 -33.269728) (xy 98.020301 -33.285084)
			(xy 97.966351 -33.292841) (xy 97.939098 -33.293304) (xy 97.913172 -33.292871) (xy 97.861795 -33.285865)
			(xy 97.811839 -33.271968) (xy 97.764225 -33.251436) (xy 97.719828 -33.224647) (xy 97.679467 -33.192095)
			(xy 97.643884 -33.154379) (xy 97.628456 -33.133538) (xy 97.622701 -33.12622) (xy 97.607209 -33.115927)
			(xy 97.59823 -33.113472) (xy 97.568004 -33.106614) (xy 97.558725 -33.104889) (xy 97.540065 -33.107613)
			(xy 97.531682 -33.111948) (xy 97.505691 -33.126194) (xy 97.450823 -33.148609) (xy 97.393524 -33.163768)
			(xy 97.334749 -33.171419) (xy 97.305114 -33.171892) (xy 97.275476 -33.17145) (xy 97.216693 -33.163825)
			(xy 97.159389 -33.148662) (xy 97.104528 -33.126215) (xy 97.078546 -33.111948) (xy 97.070127 -33.107715)
			(xy 97.051502 -33.104973) (xy 97.042224 -33.106614) (xy 97.011998 -33.113472) (xy 97.003002 -33.11589)
			(xy 96.9875 -33.126191) (xy 96.981772 -33.133538) (xy 96.966336 -33.154375) (xy 96.930767 -33.192109)
			(xy 96.890413 -33.224675) (xy 96.846018 -33.251472) (xy 96.798401 -33.272005) (xy 96.74844 -33.285895)
			(xy 96.697058 -33.292886) (xy 96.67113 -33.293304) (xy 96.643875 -33.292851) (xy 96.589921 -33.285097)
			(xy 96.537619 -33.269744) (xy 96.488034 -33.247102) (xy 96.442177 -33.217635) (xy 96.40098 -33.181941)
			(xy 96.365283 -33.140747) (xy 96.335812 -33.094892) (xy 96.313167 -33.045309) (xy 96.297809 -32.993009)
			(xy 96.290051 -32.939054) (xy 96.290051 -32.884546) (xy 96.297809 -32.830591) (xy 96.313167 -32.778291)
			(xy 96.335812 -32.728708) (xy 96.365283 -32.682853) (xy 96.40098 -32.641659) (xy 96.442177 -32.605965)
			(xy 96.488034 -32.576498) (xy 96.537619 -32.553856) (xy 96.589921 -32.538503) (xy 96.643875 -32.530749)
			(xy 96.67113 -32.530288) (xy 96.685923 -32.53043) (xy 96.715421 -32.532715) (xy 96.730058 -32.53486)
			(xy 96.74098 -32.536638) (xy 96.762316 -32.530542) (xy 96.829626 -32.473138) (xy 96.83758 -32.465534)
			(xy 96.846671 -32.445523) (xy 96.847152 -32.43453) (xy 96.847152 -32.130238) (xy 96.846665 -32.119247)
			(xy 96.837575 -32.099236) (xy 96.829626 -32.09163) (xy 96.762316 -32.034226) (xy 96.74098 -32.02813)
			(xy 96.730058 -32.029908) (xy 96.71542 -32.032048) (xy 96.685923 -32.034337) (xy 96.67113 -32.03448)
			(xy 96.643874 -32.034075) (xy 96.589916 -32.026321) (xy 96.53761 -32.010966) (xy 96.488023 -31.988324)
			(xy 96.442162 -31.958855) (xy 96.400963 -31.923158) (xy 96.365263 -31.881962) (xy 96.33579 -31.836104)
			(xy 96.313144 -31.786518) (xy 96.297785 -31.734214) (xy 96.290027 -31.680256) (xy 94.527671 -31.680256)
			(xy 94.503017 -31.700773) (xy 94.455411 -31.729827) (xy 94.404082 -31.751639) (xy 94.350125 -31.765745)
			(xy 94.294688 -31.771845) (xy 94.238954 -31.769808) (xy 94.184111 -31.759678) (xy 94.131327 -31.741671)
			(xy 94.081727 -31.71617) (xy 94.036369 -31.683719) (xy 93.99622 -31.64501) (xy 93.962134 -31.600867)
			(xy 93.934838 -31.552232) (xy 93.914915 -31.500141) (xy 93.902789 -31.445704) (xy 93.898718 -31.390082)
			(xy 92.630244 -31.390082) (xy 92.629735 -31.417968) (xy 92.621615 -31.473144) (xy 92.605547 -31.526551)
			(xy 92.581875 -31.577048) (xy 92.551102 -31.623561) (xy 92.513885 -31.665098) (xy 92.471017 -31.700773)
			(xy 92.423411 -31.729827) (xy 92.372082 -31.751639) (xy 92.318125 -31.765745) (xy 92.262688 -31.771845)
			(xy 92.206954 -31.769808) (xy 92.152111 -31.759678) (xy 92.099327 -31.741671) (xy 92.049727 -31.71617)
			(xy 92.004369 -31.683719) (xy 91.96422 -31.64501) (xy 91.930134 -31.600867) (xy 91.902838 -31.552232)
			(xy 91.882915 -31.500141) (xy 91.870789 -31.445704) (xy 91.866718 -31.390082) (xy 90.074064 -31.390082)
			(xy 90.090858 -31.408825) (xy 90.121631 -31.455338) (xy 90.145303 -31.505835) (xy 90.161371 -31.559242)
			(xy 90.169491 -31.614418) (xy 90.17 -31.642304) (xy 90.169491 -31.67019) (xy 90.161371 -31.725366)
			(xy 90.145303 -31.778773) (xy 90.121631 -31.82927) (xy 90.090858 -31.875783) (xy 90.053641 -31.91732)
			(xy 90.010773 -31.952995) (xy 89.963167 -31.982049) (xy 89.911838 -32.003861) (xy 89.857881 -32.017967)
			(xy 89.802444 -32.024067) (xy 89.74671 -32.02203) (xy 89.691867 -32.0119) (xy 89.639083 -31.993893)
			(xy 89.589483 -31.968392) (xy 89.544125 -31.935941) (xy 89.503976 -31.897232) (xy 89.46989 -31.853089)
			(xy 89.442594 -31.804454) (xy 89.422671 -31.752363) (xy 89.410545 -31.697926) (xy 89.406474 -31.642304)
			(xy 87.934483 -31.642304) (xy 87.918939 -31.660242) (xy 87.877744 -31.695937) (xy 87.831888 -31.725407)
			(xy 87.782305 -31.74805) (xy 87.730004 -31.763407) (xy 87.67605 -31.771163) (xy 87.648796 -31.77159)
			(xy 87.646002 -31.77159) (xy 87.636034 -31.772064) (xy 87.617591 -31.779633) (xy 87.610188 -31.786322)
			(xy 87.55888 -31.837122) (xy 87.552028 -31.844518) (xy 87.544289 -31.863117) (xy 87.543894 -31.87319)
			(xy 87.543894 -32.707072) (xy 87.54433 -32.717137) (xy 87.552062 -32.735723) (xy 87.55888 -32.74314)
			(xy 87.610188 -32.79394) (xy 87.617599 -32.800622) (xy 87.636034 -32.808202) (xy 87.646002 -32.808672)
			(xy 87.648796 -32.808672) (xy 87.676051 -32.809135) (xy 87.730005 -32.816892) (xy 87.782306 -32.832248)
			(xy 87.831889 -32.854892) (xy 87.877745 -32.884361) (xy 87.918941 -32.920057) (xy 87.954637 -32.961252)
			(xy 87.984107 -33.007107) (xy 88.006751 -33.05669) (xy 88.022108 -33.108991) (xy 88.029865 -33.162946)
			(xy 88.029865 -33.19018) (xy 89.673936 -33.19018) (xy 89.678007 -33.134558) (xy 89.690133 -33.080121)
			(xy 89.710056 -33.02803) (xy 89.737352 -32.979395) (xy 89.771438 -32.935252) (xy 89.811587 -32.896543)
			(xy 89.856945 -32.864092) (xy 89.906545 -32.838591) (xy 89.959329 -32.820584) (xy 90.014172 -32.810454)
			(xy 90.069906 -32.808417) (xy 90.125343 -32.814517) (xy 90.1793 -32.828623) (xy 90.230629 -32.850435)
			(xy 90.278235 -32.879489) (xy 90.321103 -32.915164) (xy 90.35832 -32.956701) (xy 90.389093 -33.003214)
			(xy 90.412765 -33.053711) (xy 90.428833 -33.107118) (xy 90.436953 -33.162294) (xy 90.437462 -33.19018)
			(xy 91.866718 -33.19018) (xy 91.870789 -33.134558) (xy 91.882915 -33.080121) (xy 91.902838 -33.02803)
			(xy 91.930134 -32.979395) (xy 91.96422 -32.935252) (xy 92.004369 -32.896543) (xy 92.049727 -32.864092)
			(xy 92.099327 -32.838591) (xy 92.152111 -32.820584) (xy 92.206954 -32.810454) (xy 92.262688 -32.808417)
			(xy 92.318125 -32.814517) (xy 92.372082 -32.828623) (xy 92.423411 -32.850435) (xy 92.471017 -32.879489)
			(xy 92.513885 -32.915164) (xy 92.551102 -32.956701) (xy 92.581875 -33.003214) (xy 92.605547 -33.053711)
			(xy 92.621615 -33.107118) (xy 92.629735 -33.162294) (xy 92.630244 -33.19018) (xy 93.898718 -33.19018)
			(xy 93.902789 -33.134558) (xy 93.914915 -33.080121) (xy 93.934838 -33.02803) (xy 93.962134 -32.979395)
			(xy 93.99622 -32.935252) (xy 94.036369 -32.896543) (xy 94.081727 -32.864092) (xy 94.131327 -32.838591)
			(xy 94.184111 -32.820584) (xy 94.238954 -32.810454) (xy 94.294688 -32.808417) (xy 94.350125 -32.814517)
			(xy 94.404082 -32.828623) (xy 94.455411 -32.850435) (xy 94.503017 -32.879489) (xy 94.545885 -32.915164)
			(xy 94.583102 -32.956701) (xy 94.613875 -33.003214) (xy 94.637547 -33.053711) (xy 94.653615 -33.107118)
			(xy 94.661735 -33.162294) (xy 94.662244 -33.19018) (xy 94.661735 -33.218066) (xy 94.653615 -33.273242)
			(xy 94.637547 -33.326649) (xy 94.613875 -33.377146) (xy 94.583102 -33.423659) (xy 94.545885 -33.465196)
			(xy 94.503017 -33.500871) (xy 94.455411 -33.529925) (xy 94.404082 -33.551737) (xy 94.350125 -33.565843)
			(xy 94.294688 -33.571943) (xy 94.238954 -33.569906) (xy 94.184111 -33.559776) (xy 94.131327 -33.541769)
			(xy 94.081727 -33.516268) (xy 94.036369 -33.483817) (xy 93.99622 -33.445108) (xy 93.962134 -33.400965)
			(xy 93.934838 -33.35233) (xy 93.914915 -33.300239) (xy 93.902789 -33.245802) (xy 93.898718 -33.19018)
			(xy 92.630244 -33.19018) (xy 92.629735 -33.218066) (xy 92.621615 -33.273242) (xy 92.605547 -33.326649)
			(xy 92.581875 -33.377146) (xy 92.551102 -33.423659) (xy 92.513885 -33.465196) (xy 92.471017 -33.500871)
			(xy 92.423411 -33.529925) (xy 92.372082 -33.551737) (xy 92.318125 -33.565843) (xy 92.262688 -33.571943)
			(xy 92.206954 -33.569906) (xy 92.152111 -33.559776) (xy 92.099327 -33.541769) (xy 92.049727 -33.516268)
			(xy 92.004369 -33.483817) (xy 91.96422 -33.445108) (xy 91.930134 -33.400965) (xy 91.902838 -33.35233)
			(xy 91.882915 -33.300239) (xy 91.870789 -33.245802) (xy 91.866718 -33.19018) (xy 90.437462 -33.19018)
			(xy 90.436953 -33.218066) (xy 90.428833 -33.273242) (xy 90.412765 -33.326649) (xy 90.389093 -33.377146)
			(xy 90.35832 -33.423659) (xy 90.321103 -33.465196) (xy 90.278235 -33.500871) (xy 90.230629 -33.529925)
			(xy 90.1793 -33.551737) (xy 90.125343 -33.565843) (xy 90.069906 -33.571943) (xy 90.014172 -33.569906)
			(xy 89.959329 -33.559776) (xy 89.906545 -33.541769) (xy 89.856945 -33.516268) (xy 89.811587 -33.483817)
			(xy 89.771438 -33.445108) (xy 89.737352 -33.400965) (xy 89.710056 -33.35233) (xy 89.690133 -33.300239)
			(xy 89.678007 -33.245802) (xy 89.673936 -33.19018) (xy 88.029865 -33.19018) (xy 88.029865 -33.217454)
			(xy 88.022108 -33.271409) (xy 88.006751 -33.32371) (xy 87.984107 -33.373293) (xy 87.954637 -33.419148)
			(xy 87.918941 -33.460343) (xy 87.877745 -33.496039) (xy 87.831889 -33.525508) (xy 87.782306 -33.548152)
			(xy 87.730005 -33.563508) (xy 87.676051 -33.571265) (xy 87.648796 -33.571688) (xy 87.646002 -33.571688)
			(xy 87.636034 -33.572162) (xy 87.617591 -33.579731) (xy 87.610188 -33.58642) (xy 87.55888 -33.63722)
			(xy 87.552028 -33.644616) (xy 87.544288 -33.663215) (xy 87.543894 -33.673288) (xy 87.543894 -34.506916)
			(xy 87.54432 -34.516985) (xy 87.552037 -34.535586) (xy 87.55888 -34.542984) (xy 87.610188 -34.593784)
			(xy 87.617596 -34.600472) (xy 87.636032 -34.608061) (xy 87.646002 -34.608516) (xy 87.648796 -34.608516)
			(xy 87.676047 -34.608979) (xy 87.729995 -34.616735) (xy 87.78229 -34.63209) (xy 87.831868 -34.654731)
			(xy 87.877719 -34.684197) (xy 87.918909 -34.719888) (xy 87.954601 -34.761078) (xy 87.984067 -34.806929)
			(xy 88.006709 -34.856506) (xy 88.022064 -34.908801) (xy 88.029821 -34.962749) (xy 88.029821 -34.990024)
			(xy 89.672666 -34.990024) (xy 89.676737 -34.934402) (xy 89.688863 -34.879965) (xy 89.708786 -34.827874)
			(xy 89.736082 -34.779239) (xy 89.770168 -34.735096) (xy 89.810317 -34.696387) (xy 89.855675 -34.663936)
			(xy 89.905275 -34.638435) (xy 89.958059 -34.620428) (xy 90.012902 -34.610298) (xy 90.068636 -34.608261)
			(xy 90.124073 -34.614361) (xy 90.17803 -34.628467) (xy 90.229359 -34.650279) (xy 90.276965 -34.679333)
			(xy 90.319833 -34.715008) (xy 90.35705 -34.756545) (xy 90.387823 -34.803058) (xy 90.411495 -34.853555)
			(xy 90.427563 -34.906962) (xy 90.435683 -34.962138) (xy 90.436192 -34.990024) (xy 90.937332 -34.990024)
			(xy 90.941403 -34.934402) (xy 90.953529 -34.879965) (xy 90.973452 -34.827874) (xy 91.000748 -34.779239)
			(xy 91.034834 -34.735096) (xy 91.074983 -34.696387) (xy 91.120341 -34.663936) (xy 91.169941 -34.638435)
			(xy 91.222725 -34.620428) (xy 91.277568 -34.610298) (xy 91.333302 -34.608261) (xy 91.388739 -34.614361)
			(xy 91.442696 -34.628467) (xy 91.494025 -34.650279) (xy 91.541631 -34.679333) (xy 91.584499 -34.715008)
			(xy 91.621716 -34.756545) (xy 91.652489 -34.803058) (xy 91.676161 -34.853555) (xy 91.692229 -34.906962)
			(xy 91.700349 -34.962138) (xy 91.700858 -34.990024) (xy 93.898718 -34.990024) (xy 93.902789 -34.934402)
			(xy 93.914915 -34.879965) (xy 93.934838 -34.827874) (xy 93.962134 -34.779239) (xy 93.99622 -34.735096)
			(xy 94.036369 -34.696387) (xy 94.081727 -34.663936) (xy 94.131327 -34.638435) (xy 94.184111 -34.620428)
			(xy 94.238954 -34.610298) (xy 94.294688 -34.608261) (xy 94.350125 -34.614361) (xy 94.404082 -34.628467)
			(xy 94.455411 -34.650279) (xy 94.503017 -34.679333) (xy 94.545885 -34.715008) (xy 94.583102 -34.756545)
			(xy 94.613875 -34.803058) (xy 94.637547 -34.853555) (xy 94.653615 -34.906962) (xy 94.661735 -34.962138)
			(xy 94.662244 -34.990024) (xy 94.661735 -35.01791) (xy 94.653615 -35.073086) (xy 94.637547 -35.126493)
			(xy 94.613875 -35.17699) (xy 94.583102 -35.223503) (xy 94.545885 -35.26504) (xy 94.503017 -35.300715)
			(xy 94.455411 -35.329769) (xy 94.404082 -35.351581) (xy 94.350125 -35.365687) (xy 94.294688 -35.371787)
			(xy 94.238954 -35.36975) (xy 94.184111 -35.35962) (xy 94.131327 -35.341613) (xy 94.081727 -35.316112)
			(xy 94.036369 -35.283661) (xy 93.99622 -35.244952) (xy 93.962134 -35.200809) (xy 93.934838 -35.152174)
			(xy 93.914915 -35.100083) (xy 93.902789 -35.045646) (xy 93.898718 -34.990024) (xy 91.700858 -34.990024)
			(xy 91.700349 -35.01791) (xy 91.692229 -35.073086) (xy 91.676161 -35.126493) (xy 91.652489 -35.17699)
			(xy 91.621716 -35.223503) (xy 91.584499 -35.26504) (xy 91.541631 -35.300715) (xy 91.494025 -35.329769)
			(xy 91.442696 -35.351581) (xy 91.388739 -35.365687) (xy 91.333302 -35.371787) (xy 91.277568 -35.36975)
			(xy 91.222725 -35.35962) (xy 91.169941 -35.341613) (xy 91.120341 -35.316112) (xy 91.074983 -35.283661)
			(xy 91.034834 -35.244952) (xy 91.000748 -35.200809) (xy 90.973452 -35.152174) (xy 90.953529 -35.100083)
			(xy 90.941403 -35.045646) (xy 90.937332 -34.990024) (xy 90.436192 -34.990024) (xy 90.435683 -35.01791)
			(xy 90.427563 -35.073086) (xy 90.411495 -35.126493) (xy 90.387823 -35.17699) (xy 90.35705 -35.223503)
			(xy 90.319833 -35.26504) (xy 90.276965 -35.300715) (xy 90.229359 -35.329769) (xy 90.17803 -35.351581)
			(xy 90.124073 -35.365687) (xy 90.068636 -35.371787) (xy 90.012902 -35.36975) (xy 89.958059 -35.35962)
			(xy 89.905275 -35.341613) (xy 89.855675 -35.316112) (xy 89.810317 -35.283661) (xy 89.770168 -35.244952)
			(xy 89.736082 -35.200809) (xy 89.708786 -35.152174) (xy 89.688863 -35.100083) (xy 89.676737 -35.045646)
			(xy 89.672666 -34.990024) (xy 88.029821 -34.990024) (xy 88.029821 -35.017251) (xy 88.022064 -35.071199)
			(xy 88.006709 -35.123494) (xy 87.984067 -35.173071) (xy 87.954601 -35.218922) (xy 87.918909 -35.260112)
			(xy 87.877719 -35.295803) (xy 87.831868 -35.325269) (xy 87.78229 -35.34791) (xy 87.729995 -35.363265)
			(xy 87.676047 -35.371021) (xy 87.648796 -35.371532) (xy 87.646002 -35.371532) (xy 87.636035 -35.372006)
			(xy 87.617596 -35.37958) (xy 87.610188 -35.386264) (xy 87.55888 -35.437064) (xy 87.552035 -35.444462)
			(xy 87.544311 -35.463061) (xy 87.543894 -35.473132) (xy 87.543894 -38.193435) (xy 89.098186 -38.193435)
			(xy 89.098186 -38.106565) (xy 89.106201 -38.020064) (xy 89.122163 -37.934673) (xy 89.145936 -37.851118)
			(xy 89.177316 -37.770113) (xy 89.216037 -37.692349) (xy 89.261768 -37.61849) (xy 89.314118 -37.549165)
			(xy 89.372641 -37.484965) (xy 89.436838 -37.42644) (xy 89.506162 -37.374087) (xy 89.58002 -37.328354)
			(xy 89.657782 -37.28963) (xy 89.738786 -37.258246) (xy 89.82234 -37.234471) (xy 89.907731 -37.218505)
			(xy 89.994231 -37.210487) (xy 90.037666 -37.209984) (xy 90.115644 -37.209984) (xy 90.125656 -37.209547)
			(xy 90.144152 -37.20187) (xy 90.158304 -37.187702) (xy 90.165959 -37.169197) (xy 90.166444 -37.159184)
			(xy 90.166444 -37.151564) (xy 90.162126 -37.137594) (xy 90.158062 -37.131244) (xy 90.134143 -37.094009)
			(xy 90.092442 -37.015944) (xy 90.058057 -36.93439) (xy 90.031279 -36.850033) (xy 90.01233 -36.76358)
			(xy 90.00137 -36.675755) (xy 89.998492 -36.587297) (xy 90.003719 -36.498946) (xy 90.017007 -36.411443)
			(xy 90.038245 -36.325524) (xy 90.067254 -36.241908) (xy 90.103792 -36.161296) (xy 90.147553 -36.084366)
			(xy 90.198167 -36.011762) (xy 90.255213 -35.944093) (xy 90.31821 -35.881927) (xy 90.38663 -35.825786)
			(xy 90.4599 -35.776139) (xy 90.537405 -35.733405) (xy 90.618494 -35.69794) (xy 90.702488 -35.670044)
			(xy 90.788682 -35.649948) (xy 90.876353 -35.637824) (xy 90.964766 -35.633771) (xy 91.053179 -35.637824)
			(xy 91.14085 -35.649948) (xy 91.227044 -35.670044) (xy 91.311038 -35.69794) (xy 91.392127 -35.733405)
			(xy 91.469632 -35.776139) (xy 91.542902 -35.825786) (xy 91.611322 -35.881927) (xy 91.674319 -35.944093)
			(xy 91.731365 -36.011762) (xy 91.781979 -36.084366) (xy 91.82574 -36.161296) (xy 91.862278 -36.241908)
			(xy 91.891287 -36.325524) (xy 91.912525 -36.411443) (xy 91.925813 -36.498946) (xy 91.93104 -36.587297)
			(xy 91.928162 -36.675755) (xy 91.917202 -36.76358) (xy 91.898253 -36.850033) (xy 91.871475 -36.93439)
			(xy 91.83709 -37.015944) (xy 91.795389 -37.094009) (xy 91.77147 -37.131244) (xy 91.763088 -37.143944)
			(xy 91.763088 -37.159184) (xy 91.763532 -37.169203) (xy 91.771195 -37.187717) (xy 91.785359 -37.20189)
			(xy 91.803869 -37.209562) (xy 91.813888 -37.209984) (xy 91.891866 -37.209984) (xy 91.935308 -37.210393)
			(xy 92.02182 -37.218407) (xy 92.107225 -37.234369) (xy 92.190792 -37.258143) (xy 92.271809 -37.289527)
			(xy 92.349584 -37.328252) (xy 92.423455 -37.373988) (xy 92.49279 -37.426345) (xy 92.556999 -37.484877)
			(xy 92.615533 -37.549083) (xy 92.667893 -37.618417) (xy 92.713632 -37.692286) (xy 92.75236 -37.77006)
			(xy 92.783746 -37.851076) (xy 92.807523 -37.934642) (xy 92.823489 -38.020046) (xy 92.831505 -38.106558)
			(xy 92.831505 -38.193442) (xy 92.823489 -38.279954) (xy 92.807523 -38.365358) (xy 92.783746 -38.448924)
			(xy 92.75236 -38.52994) (xy 92.713632 -38.607714) (xy 92.667893 -38.681583) (xy 92.615533 -38.750917)
			(xy 92.556999 -38.815123) (xy 92.49279 -38.873655) (xy 92.423455 -38.926012) (xy 92.349584 -38.971748)
			(xy 92.271809 -39.010473) (xy 92.190792 -39.041857) (xy 92.107225 -39.065631) (xy 92.02182 -39.081593)
			(xy 91.935308 -39.089607) (xy 91.891866 -39.090092) (xy 90.037666 -39.090092) (xy 89.994231 -39.089513)
			(xy 89.907731 -39.081495) (xy 89.82234 -39.065529) (xy 89.738786 -39.041754) (xy 89.657782 -39.01037)
			(xy 89.58002 -38.971646) (xy 89.506162 -38.925913) (xy 89.436838 -38.87356) (xy 89.372641 -38.815035)
			(xy 89.314118 -38.750835) (xy 89.261768 -38.68151) (xy 89.216037 -38.607651) (xy 89.177316 -38.529887)
			(xy 89.145936 -38.448882) (xy 89.122163 -38.365327) (xy 89.106201 -38.279936) (xy 89.098186 -38.193435)
			(xy 87.543894 -38.193435) (xy 87.543894 -42.849038) (xy 98.89185 -42.849038) (xy 98.895921 -42.793416)
			(xy 98.908047 -42.738979) (xy 98.92797 -42.686888) (xy 98.955266 -42.638253) (xy 98.989352 -42.59411)
			(xy 99.029501 -42.555401) (xy 99.074859 -42.52295) (xy 99.124459 -42.497449) (xy 99.177243 -42.479442)
			(xy 99.232086 -42.469312) (xy 99.28782 -42.467275) (xy 99.343257 -42.473375) (xy 99.397214 -42.487481)
			(xy 99.448543 -42.509293) (xy 99.496149 -42.538347) (xy 99.539017 -42.574022) (xy 99.576234 -42.615559)
			(xy 99.607007 -42.662072) (xy 99.630679 -42.712569) (xy 99.646747 -42.765976) (xy 99.654867 -42.821152)
			(xy 99.655376 -42.849038) (xy 99.654867 -42.876924) (xy 99.646747 -42.9321) (xy 99.630679 -42.985507)
			(xy 99.607007 -43.036004) (xy 99.576234 -43.082517) (xy 99.539017 -43.124054) (xy 99.496149 -43.159729)
			(xy 99.448543 -43.188783) (xy 99.397214 -43.210595) (xy 99.343257 -43.224701) (xy 99.28782 -43.230801)
			(xy 99.232086 -43.228764) (xy 99.177243 -43.218634) (xy 99.124459 -43.200627) (xy 99.074859 -43.175126)
			(xy 99.029501 -43.142675) (xy 98.989352 -43.103966) (xy 98.955266 -43.059823) (xy 98.92797 -43.011188)
			(xy 98.908047 -42.959097) (xy 98.895921 -42.90466) (xy 98.89185 -42.849038) (xy 87.543894 -42.849038)
			(xy 87.543894 -43.719242) (xy 87.544358 -43.729117) (xy 87.551807 -43.74741) (xy 87.558372 -43.754802)
			(xy 87.558626 -43.755056) (xy 88.036654 -44.233084) (xy 88.037162 -44.233592) (xy 88.044546 -44.240169)
			(xy 88.062844 -44.24761) (xy 88.072722 -44.24807)
		)
		(stroke
			(width 0)
			(type solid)
		)
		(fill yes)
		(layer "B.Cu")
		(net "P12V_SSD3")
	)
	(gr_poly
		(pts
			(xy 332.077314 -44.335954) (xy 332.087192 -44.335496) (xy 332.105497 -44.32806) (xy 332.112874 -44.321476)
			(xy 332.113128 -44.321222) (xy 332.672436 -43.761914) (xy 332.672944 -43.761406) (xy 332.679521 -43.754023)
			(xy 332.686958 -43.735724) (xy 332.687422 -43.725846) (xy 332.687422 -35.109658) (xy 332.66888 -35.083496)
			(xy 332.65364 -35.078162) (xy 332.627366 -35.06832) (xy 332.577802 -35.042033) (xy 332.53262 -35.008774)
			(xy 332.492792 -34.969259) (xy 332.475586 -34.947098) (xy 332.470252 -34.939986) (xy 332.448154 -34.925254)
			(xy 332.444202 -34.922823) (xy 332.435642 -34.919247) (xy 332.431136 -34.918142) (xy 332.40091 -34.911284)
			(xy 332.382114 -34.914078) (xy 332.373732 -34.91865) (xy 332.355351 -34.928877) (xy 332.317064 -34.946307)
			(xy 332.297278 -34.953448) (xy 332.273078 -34.961492) (xy 332.223344 -34.972787) (xy 332.172664 -34.97849)
			(xy 332.147164 -34.978848) (xy 332.121664 -34.978485) (xy 332.070984 -34.972787) (xy 332.021251 -34.961489)
			(xy 331.99705 -34.953448) (xy 331.977266 -34.946302) (xy 331.938979 -34.928874) (xy 331.920596 -34.91865)
			(xy 331.912214 -34.914078) (xy 331.893418 -34.911284) (xy 331.863192 -34.918142) (xy 331.858671 -34.919202)
			(xy 331.8501 -34.922775) (xy 331.846174 -34.925254) (xy 331.823822 -34.94024) (xy 331.818742 -34.947352)
			(xy 331.800591 -34.970651) (xy 331.758311 -35.011889) (xy 331.710179 -35.046114) (xy 331.657346 -35.072509)
			(xy 331.601074 -35.090441) (xy 331.542711 -35.099483) (xy 331.51318 -35.100006) (xy 331.502258 -35.100006)
			(xy 331.502004 -35.099752) (xy 331.475287 -35.098518) (xy 331.42257 -35.0895) (xy 331.371628 -35.073209)
			(xy 331.32346 -35.049965) (xy 331.279009 -35.020223) (xy 331.239146 -34.984566) (xy 331.204653 -34.943693)
			(xy 331.176204 -34.898403) (xy 331.154358 -34.849585) (xy 331.139542 -34.798195) (xy 331.132047 -34.745239)
			(xy 331.131672 -34.718498) (xy 331.132158 -34.691246) (xy 331.139915 -34.637298) (xy 331.15527 -34.585002)
			(xy 331.177911 -34.535424) (xy 331.207377 -34.489572) (xy 331.243068 -34.448381) (xy 331.284258 -34.412687)
			(xy 331.330108 -34.383219) (xy 331.379685 -34.360576) (xy 331.43198 -34.345218) (xy 331.485928 -34.337459)
			(xy 331.51318 -34.33699) (xy 331.527973 -34.337135) (xy 331.557469 -34.339427) (xy 331.572108 -34.341562)
			(xy 331.58303 -34.34334) (xy 331.604366 -34.337244) (xy 331.671422 -34.280094) (xy 331.679565 -34.272507)
			(xy 331.688936 -34.252348) (xy 331.689456 -34.241232) (xy 331.689456 -33.93694) (xy 331.688889 -33.925835)
			(xy 331.679529 -33.90569) (xy 331.671422 -33.898078) (xy 331.604366 -33.840928) (xy 331.58303 -33.834832)
			(xy 331.572108 -33.83661) (xy 331.557282 -33.838782) (xy 331.527402 -33.841069) (xy 331.512418 -33.841182)
			(xy 331.512164 -33.841182) (xy 331.484962 -33.840625) (xy 331.431128 -33.832749) (xy 331.378959 -33.817304)
			(xy 331.329513 -33.794604) (xy 331.283795 -33.765109) (xy 331.24273 -33.729418) (xy 331.207154 -33.688254)
			(xy 331.177786 -33.642454) (xy 331.155224 -33.592945) (xy 331.139924 -33.540733) (xy 331.132198 -33.486878)
			(xy 331.131672 -33.459674) (xy 331.13216 -33.432423) (xy 331.139919 -33.378477) (xy 331.155276 -33.326185)
			(xy 331.177918 -33.276609) (xy 331.207385 -33.230761) (xy 331.243076 -33.189572) (xy 331.284266 -33.153882)
			(xy 331.330115 -33.124416) (xy 331.37969 -33.101774) (xy 331.431983 -33.086418) (xy 331.485929 -33.078659)
			(xy 331.51318 -33.078166) (xy 331.513434 -33.078166) (xy 331.542941 -33.078719) (xy 331.601251 -33.087806)
			(xy 331.657467 -33.105758) (xy 331.710252 -33.132148) (xy 331.758346 -33.166347) (xy 331.800604 -33.20754)
			(xy 331.818742 -33.23082) (xy 331.823822 -33.237932) (xy 331.846174 -33.252918) (xy 331.850126 -33.255348)
			(xy 331.858687 -33.258921) (xy 331.863192 -33.26003) (xy 331.893418 -33.266888) (xy 331.912214 -33.264094)
			(xy 331.920596 -33.259522) (xy 331.938978 -33.249296) (xy 331.977266 -33.23187) (xy 331.99705 -33.224724)
			(xy 332.021251 -33.216682) (xy 332.070985 -33.205391) (xy 332.121665 -33.199691) (xy 332.147164 -33.199324)
			(xy 332.172663 -33.199689) (xy 332.223343 -33.205389) (xy 332.273075 -33.216689) (xy 332.297278 -33.224724)
			(xy 332.317061 -33.231871) (xy 332.355348 -33.2493) (xy 332.373732 -33.259522) (xy 332.382114 -33.264094)
			(xy 332.40091 -33.266888) (xy 332.431136 -33.26003) (xy 332.435656 -33.258967) (xy 332.444223 -33.255389)
			(xy 332.448154 -33.252918) (xy 332.470252 -33.238186) (xy 332.475586 -33.231074) (xy 332.492789 -33.208911)
			(xy 332.532618 -33.169399) (xy 332.577804 -33.136147) (xy 332.627374 -33.109872) (xy 332.65364 -33.10001)
			(xy 332.66888 -33.094676) (xy 332.687422 -33.068514) (xy 332.687422 -31.509462) (xy 332.66888 -31.4833)
			(xy 332.65364 -31.477966) (xy 332.627366 -31.468124) (xy 332.577802 -31.441837) (xy 332.532619 -31.408578)
			(xy 332.492792 -31.369063) (xy 332.475586 -31.346902) (xy 332.470252 -31.33979) (xy 332.448154 -31.325058)
			(xy 332.444202 -31.322627) (xy 332.435642 -31.319051) (xy 332.431136 -31.317946) (xy 332.40091 -31.311088)
			(xy 332.382114 -31.313882) (xy 332.373732 -31.318454) (xy 332.355351 -31.328681) (xy 332.317064 -31.34611)
			(xy 332.297278 -31.353252) (xy 332.273078 -31.361296) (xy 332.223344 -31.372591) (xy 332.172664 -31.378294)
			(xy 332.147164 -31.378652) (xy 332.121664 -31.378289) (xy 332.070984 -31.372591) (xy 332.021251 -31.361294)
			(xy 331.99705 -31.353252) (xy 331.977266 -31.346106) (xy 331.938979 -31.328678) (xy 331.920596 -31.318454)
			(xy 331.912214 -31.313882) (xy 331.893418 -31.311088) (xy 331.863192 -31.317946) (xy 331.858671 -31.319006)
			(xy 331.8501 -31.322579) (xy 331.846174 -31.325058) (xy 331.823822 -31.340044) (xy 331.818742 -31.347156)
			(xy 331.800591 -31.370455) (xy 331.758311 -31.411692) (xy 331.710179 -31.445917) (xy 331.657345 -31.472311)
			(xy 331.601074 -31.490244) (xy 331.54271 -31.499286) (xy 331.51318 -31.49981) (xy 331.502258 -31.49981)
			(xy 331.502004 -31.499556) (xy 331.475287 -31.498322) (xy 331.422569 -31.489304) (xy 331.371627 -31.473013)
			(xy 331.323459 -31.449769) (xy 331.279008 -31.420028) (xy 331.239145 -31.384371) (xy 331.204651 -31.343497)
			(xy 331.176202 -31.298207) (xy 331.154355 -31.249389) (xy 331.139539 -31.197999) (xy 331.132043 -31.145044)
			(xy 331.131672 -31.118302) (xy 331.132158 -31.09105) (xy 331.139914 -31.037101) (xy 331.155269 -30.984805)
			(xy 331.177909 -30.935226) (xy 331.207375 -30.889374) (xy 331.243066 -30.848182) (xy 331.284257 -30.812488)
			(xy 331.330107 -30.78302) (xy 331.379684 -30.760376) (xy 331.43198 -30.745018) (xy 331.485928 -30.737259)
			(xy 331.51318 -30.736794) (xy 331.527973 -30.736939) (xy 331.557469 -30.739231) (xy 331.572108 -30.741366)
			(xy 331.58303 -30.743144) (xy 331.604366 -30.737048) (xy 331.671422 -30.679898) (xy 331.679566 -30.672311)
			(xy 331.688938 -30.652152) (xy 331.689456 -30.641036) (xy 331.689456 -30.336744) (xy 331.68889 -30.325638)
			(xy 331.679531 -30.305493) (xy 331.671422 -30.297882) (xy 331.604366 -30.240732) (xy 331.58303 -30.234636)
			(xy 331.572108 -30.236414) (xy 331.557282 -30.238586) (xy 331.527402 -30.240873) (xy 331.512418 -30.240986)
			(xy 331.512164 -30.240986) (xy 331.484962 -30.240429) (xy 331.431127 -30.232553) (xy 331.378958 -30.217108)
			(xy 331.329513 -30.194408) (xy 331.283794 -30.164913) (xy 331.242729 -30.129222) (xy 331.207152 -30.088058)
			(xy 331.177784 -30.042258) (xy 331.155221 -29.99275) (xy 331.139921 -29.940538) (xy 331.132194 -29.886682)
			(xy 331.131672 -29.859478) (xy 331.132159 -29.832227) (xy 331.139918 -29.778281) (xy 331.155275 -29.725988)
			(xy 331.177917 -29.676412) (xy 331.207384 -29.630563) (xy 331.243075 -29.589374) (xy 331.284264 -29.553683)
			(xy 331.330114 -29.524216) (xy 331.379689 -29.501574) (xy 331.431983 -29.486218) (xy 331.485929 -29.478459)
			(xy 331.51318 -29.47797) (xy 331.513434 -29.47797) (xy 331.542941 -29.478523) (xy 331.60125 -29.48761)
			(xy 331.657467 -29.505563) (xy 331.710251 -29.531953) (xy 331.758345 -29.566152) (xy 331.800603 -29.607345)
			(xy 331.818742 -29.630624) (xy 331.823822 -29.637736) (xy 331.846174 -29.652722) (xy 331.850126 -29.655152)
			(xy 331.858687 -29.658725) (xy 331.863192 -29.659834) (xy 331.893418 -29.666692) (xy 331.912214 -29.663898)
			(xy 331.920596 -29.659326) (xy 331.938978 -29.6491) (xy 331.977266 -29.631674) (xy 331.99705 -29.624528)
			(xy 332.021251 -29.616486) (xy 332.070985 -29.605195) (xy 332.121665 -29.599495) (xy 332.147164 -29.599128)
			(xy 332.172663 -29.599493) (xy 332.223343 -29.605193) (xy 332.273075 -29.616493) (xy 332.297278 -29.624528)
			(xy 332.317061 -29.631675) (xy 332.355348 -29.649104) (xy 332.373732 -29.659326) (xy 332.382114 -29.663898)
			(xy 332.40091 -29.666692) (xy 332.431136 -29.659834) (xy 332.435656 -29.658771) (xy 332.444223 -29.655193)
			(xy 332.448154 -29.652722) (xy 332.470252 -29.63799) (xy 332.475586 -29.630878) (xy 332.492789 -29.608715)
			(xy 332.532617 -29.569203) (xy 332.577804 -29.53595) (xy 332.627374 -29.509675) (xy 332.65364 -29.499814)
			(xy 332.66888 -29.49448) (xy 332.687422 -29.468318) (xy 332.687422 -19.343878) (xy 332.686996 -19.333809)
			(xy 332.679278 -19.315208) (xy 332.672436 -19.30781) (xy 332.626208 -19.261582) (xy 332.618796 -19.254898)
			(xy 332.600363 -19.247301) (xy 332.580425 -19.247301) (xy 332.561992 -19.254898) (xy 332.55458 -19.261582)
			(xy 332.546198 -19.269964) (xy 332.538832 -19.291046) (xy 332.539848 -19.302476) (xy 332.541626 -19.337274)
			(xy 332.541626 -19.340576) (xy 332.541074 -19.367782) (xy 332.533205 -19.421625) (xy 332.517765 -19.473804)
			(xy 332.495069 -19.52326) (xy 332.465577 -19.568989) (xy 332.429886 -19.610064) (xy 332.388721 -19.645652)
			(xy 332.342918 -19.675029) (xy 332.293405 -19.697601) (xy 332.241188 -19.71291) (xy 332.187325 -19.720643)
			(xy 332.160118 -19.721068) (xy 332.132865 -19.720606) (xy 332.078915 -19.712851) (xy 332.026617 -19.697496)
			(xy 331.977037 -19.674854) (xy 331.931185 -19.645386) (xy 331.889993 -19.609691) (xy 331.854301 -19.568498)
			(xy 331.824836 -19.522644) (xy 331.802196 -19.473062) (xy 331.786845 -19.420764) (xy 331.779093 -19.366813)
			(xy 331.77861 -19.33956) (xy 331.779077 -19.312622) (xy 331.786663 -19.259283) (xy 331.801677 -19.207541)
			(xy 331.823822 -19.158427) (xy 331.852657 -19.112916) (xy 331.887609 -19.071916) (xy 331.927981 -19.03624)
			(xy 331.972971 -19.0066) (xy 332.021683 -18.983584) (xy 332.073149 -18.967651) (xy 332.099666 -18.962878)
			(xy 332.11389 -18.960592) (xy 332.13548 -18.94205) (xy 332.167738 -18.842228) (xy 332.170181 -18.833221)
			(xy 332.169156 -18.814601) (xy 332.16158 -18.797562) (xy 332.155292 -18.790666) (xy 331.867764 -18.503138)
			(xy 331.860652 -18.495772) (xy 331.841856 -18.488152) (xy 320.129154 -18.488152) (xy 320.119089 -18.488585)
			(xy 320.100501 -18.496317) (xy 320.093086 -18.503138) (xy 319.758822 -18.837402) (xy 319.751456 -18.844514)
			(xy 319.743836 -18.86331) (xy 319.743836 -21.738336) (xy 321.616578 -21.738336) (xy 321.617069 -21.709596)
			(xy 321.6257 -21.652767) (xy 321.642758 -21.597876) (xy 321.667857 -21.546165) (xy 321.700428 -21.498804)
			(xy 321.719702 -21.477478) (xy 321.726306 -21.470366) (xy 321.733418 -21.45284) (xy 321.733418 -21.363432)
			(xy 321.726306 -21.345906) (xy 321.719702 -21.338794) (xy 321.700468 -21.317436) (xy 321.667903 -21.270078)
			(xy 321.642811 -21.218371) (xy 321.62576 -21.163486) (xy 321.617134 -21.106663) (xy 321.61713 -21.049189)
			(xy 321.625748 -20.992366) (xy 321.642792 -20.937478) (xy 321.667877 -20.885767) (xy 321.700435 -20.838405)
			(xy 321.719702 -20.817078) (xy 321.726306 -20.809966) (xy 321.733418 -20.79244) (xy 321.733418 -20.703032)
			(xy 321.726306 -20.685506) (xy 321.719702 -20.678394) (xy 321.700468 -20.657036) (xy 321.667903 -20.609678)
			(xy 321.642811 -20.557971) (xy 321.62576 -20.503086) (xy 321.617134 -20.446263) (xy 321.61713 -20.388789)
			(xy 321.625748 -20.331966) (xy 321.642792 -20.277078) (xy 321.667877 -20.225367) (xy 321.700435 -20.178005)
			(xy 321.719702 -20.156678) (xy 321.726306 -20.149566) (xy 321.733418 -20.13204) (xy 321.733418 -20.042632)
			(xy 321.726306 -20.025106) (xy 321.719702 -20.017994) (xy 321.700468 -19.996636) (xy 321.667903 -19.949278)
			(xy 321.642811 -19.897571) (xy 321.62576 -19.842686) (xy 321.617134 -19.785863) (xy 321.61713 -19.728389)
			(xy 321.625748 -19.671566) (xy 321.642792 -19.616678) (xy 321.667877 -19.564967) (xy 321.700435 -19.517605)
			(xy 321.719702 -19.496278) (xy 321.726306 -19.489166) (xy 321.733418 -19.47164) (xy 321.733418 -19.382232)
			(xy 321.726306 -19.364706) (xy 321.719702 -19.357594) (xy 321.700459 -19.336242) (xy 321.667887 -19.288888)
			(xy 321.642788 -19.237183) (xy 321.625731 -19.182297) (xy 321.617102 -19.125474) (xy 321.616578 -19.096736)
			(xy 321.617064 -19.069485) (xy 321.62482 -19.015537) (xy 321.640175 -18.963242) (xy 321.662817 -18.913665)
			(xy 321.692283 -18.867815) (xy 321.727974 -18.826624) (xy 321.769165 -18.790933) (xy 321.815015 -18.761467)
			(xy 321.864592 -18.738825) (xy 321.916887 -18.72347) (xy 321.970835 -18.715714) (xy 322.025337 -18.715714)
			(xy 322.079285 -18.72347) (xy 322.13158 -18.738825) (xy 322.181157 -18.761467) (xy 322.227007 -18.790933)
			(xy 322.268198 -18.826624) (xy 322.303889 -18.867815) (xy 322.333355 -18.913665) (xy 322.355997 -18.963242)
			(xy 322.371352 -19.015537) (xy 322.379108 -19.069485) (xy 322.379594 -19.096736) (xy 322.379094 -19.125476)
			(xy 322.370466 -19.182304) (xy 322.35341 -19.237195) (xy 322.328313 -19.288907) (xy 322.295743 -19.336268)
			(xy 322.27647 -19.357594) (xy 322.269866 -19.364706) (xy 322.262754 -19.382232) (xy 322.262754 -19.47164)
			(xy 322.269866 -19.489166) (xy 322.27647 -19.496278) (xy 322.295777 -19.517574) (xy 322.328341 -19.564941)
			(xy 322.353431 -19.616658) (xy 322.370479 -19.671554) (xy 322.379098 -19.728385) (xy 322.379094 -19.785867)
			(xy 322.370467 -19.842698) (xy 322.353412 -19.897591) (xy 322.328315 -19.949304) (xy 322.295744 -19.996667)
			(xy 322.27647 -20.017994) (xy 322.269866 -20.025106) (xy 322.262754 -20.042632) (xy 322.262754 -20.13204)
			(xy 322.269866 -20.149566) (xy 322.27647 -20.156678) (xy 322.295777 -20.177974) (xy 322.328341 -20.225341)
			(xy 322.353431 -20.277058) (xy 322.370479 -20.331954) (xy 322.374059 -20.35556) (xy 331.7781 -20.35556)
			(xy 331.782171 -20.299938) (xy 331.794297 -20.245501) (xy 331.81422 -20.19341) (xy 331.841516 -20.144775)
			(xy 331.875602 -20.100632) (xy 331.915751 -20.061923) (xy 331.961109 -20.029472) (xy 332.010709 -20.003971)
			(xy 332.063493 -19.985964) (xy 332.118336 -19.975834) (xy 332.17407 -19.973797) (xy 332.229507 -19.979897)
			(xy 332.283464 -19.994003) (xy 332.334793 -20.015815) (xy 332.382399 -20.044869) (xy 332.425267 -20.080544)
			(xy 332.462484 -20.122081) (xy 332.493257 -20.168594) (xy 332.516929 -20.219091) (xy 332.532997 -20.272498)
			(xy 332.541117 -20.327674) (xy 332.541626 -20.35556) (xy 332.541117 -20.383446) (xy 332.532997 -20.438622)
			(xy 332.516929 -20.492029) (xy 332.493257 -20.542526) (xy 332.462484 -20.589039) (xy 332.425267 -20.630576)
			(xy 332.382399 -20.666251) (xy 332.334793 -20.695305) (xy 332.283464 -20.717117) (xy 332.229507 -20.731223)
			(xy 332.17407 -20.737323) (xy 332.118336 -20.735286) (xy 332.063493 -20.725156) (xy 332.010709 -20.707149)
			(xy 331.961109 -20.681648) (xy 331.915751 -20.649197) (xy 331.875602 -20.610488) (xy 331.841516 -20.566345)
			(xy 331.81422 -20.51771) (xy 331.794297 -20.465619) (xy 331.782171 -20.411182) (xy 331.7781 -20.35556)
			(xy 322.374059 -20.35556) (xy 322.379098 -20.388785) (xy 322.379094 -20.446267) (xy 322.370467 -20.503098)
			(xy 322.353412 -20.557991) (xy 322.328315 -20.609704) (xy 322.295744 -20.657067) (xy 322.27647 -20.678394)
			(xy 322.269866 -20.685506) (xy 322.262754 -20.703032) (xy 322.262754 -20.79244) (xy 322.269866 -20.809966)
			(xy 322.27647 -20.817078) (xy 322.295777 -20.838374) (xy 322.328341 -20.885741) (xy 322.353431 -20.937458)
			(xy 322.370479 -20.992354) (xy 322.379098 -21.049185) (xy 322.379094 -21.106667) (xy 322.370467 -21.163498)
			(xy 322.353412 -21.218391) (xy 322.328315 -21.270104) (xy 322.295744 -21.317467) (xy 322.27647 -21.338794)
			(xy 322.269866 -21.345906) (xy 322.262754 -21.363432) (xy 322.262754 -21.37156) (xy 331.7781 -21.37156)
			(xy 331.782171 -21.315938) (xy 331.794297 -21.261501) (xy 331.81422 -21.20941) (xy 331.841516 -21.160775)
			(xy 331.875602 -21.116632) (xy 331.915751 -21.077923) (xy 331.961109 -21.045472) (xy 332.010709 -21.019971)
			(xy 332.063493 -21.001964) (xy 332.118336 -20.991834) (xy 332.17407 -20.989797) (xy 332.229507 -20.995897)
			(xy 332.283464 -21.010003) (xy 332.334793 -21.031815) (xy 332.382399 -21.060869) (xy 332.425267 -21.096544)
			(xy 332.462484 -21.138081) (xy 332.493257 -21.184594) (xy 332.516929 -21.235091) (xy 332.532997 -21.288498)
			(xy 332.541117 -21.343674) (xy 332.541626 -21.37156) (xy 332.541117 -21.399446) (xy 332.532997 -21.454622)
			(xy 332.516929 -21.508029) (xy 332.493257 -21.558526) (xy 332.462484 -21.605039) (xy 332.425267 -21.646576)
			(xy 332.382399 -21.682251) (xy 332.334793 -21.711305) (xy 332.283464 -21.733117) (xy 332.229507 -21.747223)
			(xy 332.17407 -21.753323) (xy 332.118336 -21.751286) (xy 332.063493 -21.741156) (xy 332.010709 -21.723149)
			(xy 331.961109 -21.697648) (xy 331.915751 -21.665197) (xy 331.875602 -21.626488) (xy 331.841516 -21.582345)
			(xy 331.81422 -21.53371) (xy 331.794297 -21.481619) (xy 331.782171 -21.427182) (xy 331.7781 -21.37156)
			(xy 322.262754 -21.37156) (xy 322.262754 -21.45284) (xy 322.269866 -21.470366) (xy 322.27647 -21.477478)
			(xy 322.295759 -21.498789) (xy 322.328323 -21.546156) (xy 322.353411 -21.597871) (xy 322.370458 -21.652766)
			(xy 322.379076 -21.709596) (xy 322.379594 -21.738336) (xy 322.379108 -21.765587) (xy 322.371352 -21.819535)
			(xy 322.355997 -21.87183) (xy 322.333355 -21.921407) (xy 322.303889 -21.967257) (xy 322.268198 -22.008448)
			(xy 322.227007 -22.044139) (xy 322.181157 -22.073605) (xy 322.13158 -22.096247) (xy 322.079285 -22.111602)
			(xy 322.025337 -22.119358) (xy 321.970835 -22.119358) (xy 321.916887 -22.111602) (xy 321.864592 -22.096247)
			(xy 321.815015 -22.073605) (xy 321.769165 -22.044139) (xy 321.727974 -22.008448) (xy 321.692283 -21.967257)
			(xy 321.662817 -21.921407) (xy 321.640175 -21.87183) (xy 321.62482 -21.819535) (xy 321.617064 -21.765587)
			(xy 321.616578 -21.738336) (xy 319.743836 -21.738336) (xy 319.743836 -22.995153) (xy 321.486922 -22.995153)
			(xy 321.494743 -22.935722) (xy 321.510254 -22.877819) (xy 321.533191 -22.822437) (xy 321.563161 -22.770523)
			(xy 321.599651 -22.722964) (xy 321.642036 -22.680576) (xy 321.689591 -22.644082) (xy 321.741503 -22.614108)
			(xy 321.796883 -22.591167) (xy 321.854784 -22.57565) (xy 321.914215 -22.567824) (xy 321.974159 -22.567822)
			(xy 322.033591 -22.575645) (xy 322.091493 -22.591158) (xy 322.146874 -22.614097) (xy 322.198788 -22.644068)
			(xy 322.246345 -22.680559) (xy 322.288733 -22.722945) (xy 322.325225 -22.770502) (xy 322.355197 -22.822414)
			(xy 322.378137 -22.877795) (xy 322.393652 -22.935697) (xy 322.401477 -22.995128) (xy 322.401946 -23.0251)
			(xy 322.401723 -23.045661) (xy 322.398034 -23.086618) (xy 322.39458 -23.106888) (xy 322.39204 -23.120604)
			(xy 322.40093 -23.145496) (xy 322.487544 -23.22068) (xy 322.513452 -23.226014) (xy 322.52666 -23.221696)
			(xy 322.555865 -23.212615) (xy 322.616225 -23.202786) (xy 322.646802 -23.202138) (xy 322.670831 -23.202515)
			(xy 322.718509 -23.208553) (xy 322.76505 -23.220534) (xy 322.787518 -23.229062) (xy 322.80098 -23.234396)
			(xy 322.829174 -23.22957) (xy 322.918582 -23.15083) (xy 322.927218 -23.123652) (xy 322.923662 -23.109682)
			(xy 322.918211 -23.086699) (xy 322.91235 -23.039828) (xy 322.911978 -23.01621) (xy 322.912444 -22.988956)
			(xy 322.9202 -22.935003) (xy 322.935556 -22.882702) (xy 322.958198 -22.83312) (xy 322.987666 -22.787264)
			(xy 323.023361 -22.746069) (xy 323.064555 -22.710374) (xy 323.110409 -22.680904) (xy 323.159991 -22.65826)
			(xy 323.212291 -22.642903) (xy 323.266244 -22.635145) (xy 323.320752 -22.635145) (xy 323.374705 -22.642902)
			(xy 323.427005 -22.658258) (xy 323.476587 -22.680902) (xy 323.522442 -22.710371) (xy 323.563636 -22.746066)
			(xy 323.599331 -22.787261) (xy 323.6288 -22.833116) (xy 323.651443 -22.882699) (xy 323.666799 -22.934999)
			(xy 323.674556 -22.988952) (xy 323.674555 -23.04346) (xy 323.666796 -23.097413) (xy 323.651439 -23.149713)
			(xy 323.628794 -23.199294) (xy 323.599324 -23.245149) (xy 323.563628 -23.286342) (xy 323.522433 -23.322036)
			(xy 323.476577 -23.351504) (xy 323.426994 -23.374146) (xy 323.374693 -23.389501) (xy 323.32074 -23.397256)
			(xy 323.293486 -23.397718) (xy 323.269457 -23.397341) (xy 323.221779 -23.391302) (xy 323.175238 -23.379322)
			(xy 323.15277 -23.370794) (xy 323.139308 -23.36546) (xy 323.111114 -23.370286) (xy 323.021706 -23.449026)
			(xy 323.01307 -23.476204) (xy 323.016626 -23.490174) (xy 323.022086 -23.513155) (xy 323.027942 -23.560028)
			(xy 323.02831 -23.583646) (xy 323.027824 -23.610897) (xy 323.02652 -23.619964) (xy 326.209134 -23.619964)
			(xy 326.209134 -23.560028) (xy 326.216957 -23.500606) (xy 326.23247 -23.442713) (xy 326.255406 -23.38734)
			(xy 326.285373 -23.335434) (xy 326.32186 -23.287884) (xy 326.36424 -23.245504) (xy 326.41179 -23.209017)
			(xy 326.463696 -23.17905) (xy 326.519069 -23.156114) (xy 326.576962 -23.140601) (xy 326.636384 -23.132778)
			(xy 326.69632 -23.132778) (xy 326.755742 -23.140601) (xy 326.813635 -23.156114) (xy 326.869008 -23.17905)
			(xy 326.920914 -23.209017) (xy 326.968464 -23.245504) (xy 327.010844 -23.287884) (xy 327.047331 -23.335434)
			(xy 327.077298 -23.38734) (xy 327.100234 -23.442713) (xy 327.115747 -23.500606) (xy 327.12357 -23.560028)
			(xy 327.12406 -23.589996) (xy 327.12357 -23.619964) (xy 327.115747 -23.679386) (xy 327.100234 -23.737279)
			(xy 327.077298 -23.792652) (xy 327.047331 -23.844558) (xy 327.019891 -23.880318) (xy 327.440542 -23.880318)
			(xy 327.444613 -23.824696) (xy 327.456739 -23.770259) (xy 327.476662 -23.718168) (xy 327.503958 -23.669533)
			(xy 327.538044 -23.62539) (xy 327.578193 -23.586681) (xy 327.623551 -23.55423) (xy 327.673151 -23.528729)
			(xy 327.725935 -23.510722) (xy 327.780778 -23.500592) (xy 327.836512 -23.498555) (xy 327.891949 -23.504655)
			(xy 327.945906 -23.518761) (xy 327.997235 -23.540573) (xy 328.044841 -23.569627) (xy 328.087709 -23.605302)
			(xy 328.124926 -23.646839) (xy 328.155699 -23.693352) (xy 328.179371 -23.743849) (xy 328.195439 -23.797256)
			(xy 328.203559 -23.852432) (xy 328.204068 -23.880318) (xy 328.456542 -23.880318) (xy 328.460613 -23.824696)
			(xy 328.472739 -23.770259) (xy 328.492662 -23.718168) (xy 328.519958 -23.669533) (xy 328.554044 -23.62539)
			(xy 328.594193 -23.586681) (xy 328.639551 -23.55423) (xy 328.689151 -23.528729) (xy 328.741935 -23.510722)
			(xy 328.796778 -23.500592) (xy 328.852512 -23.498555) (xy 328.907949 -23.504655) (xy 328.961906 -23.518761)
			(xy 329.013235 -23.540573) (xy 329.060841 -23.569627) (xy 329.103709 -23.605302) (xy 329.140926 -23.646839)
			(xy 329.171699 -23.693352) (xy 329.195371 -23.743849) (xy 329.211439 -23.797256) (xy 329.219559 -23.852432)
			(xy 329.220068 -23.880318) (xy 329.472542 -23.880318) (xy 329.476613 -23.824696) (xy 329.488739 -23.770259)
			(xy 329.508662 -23.718168) (xy 329.535958 -23.669533) (xy 329.570044 -23.62539) (xy 329.610193 -23.586681)
			(xy 329.655551 -23.55423) (xy 329.705151 -23.528729) (xy 329.757935 -23.510722) (xy 329.812778 -23.500592)
			(xy 329.868512 -23.498555) (xy 329.923949 -23.504655) (xy 329.977906 -23.518761) (xy 330.029235 -23.540573)
			(xy 330.076841 -23.569627) (xy 330.119709 -23.605302) (xy 330.156926 -23.646839) (xy 330.187699 -23.693352)
			(xy 330.211371 -23.743849) (xy 330.227439 -23.797256) (xy 330.235559 -23.852432) (xy 330.236068 -23.880318)
			(xy 330.490828 -23.880318) (xy 330.494899 -23.824696) (xy 330.507025 -23.770259) (xy 330.526948 -23.718168)
			(xy 330.554244 -23.669533) (xy 330.58833 -23.62539) (xy 330.628479 -23.586681) (xy 330.673837 -23.55423)
			(xy 330.723437 -23.528729) (xy 330.776221 -23.510722) (xy 330.831064 -23.500592) (xy 330.886798 -23.498555)
			(xy 330.942235 -23.504655) (xy 330.996192 -23.518761) (xy 331.047521 -23.540573) (xy 331.095127 -23.569627)
			(xy 331.137995 -23.605302) (xy 331.175212 -23.646839) (xy 331.205985 -23.693352) (xy 331.229657 -23.743849)
			(xy 331.245725 -23.797256) (xy 331.253845 -23.852432) (xy 331.254354 -23.880318) (xy 331.253845 -23.908204)
			(xy 331.245725 -23.96338) (xy 331.229657 -24.016787) (xy 331.205985 -24.067284) (xy 331.175212 -24.113797)
			(xy 331.137995 -24.155334) (xy 331.095127 -24.191009) (xy 331.047521 -24.220063) (xy 330.996192 -24.241875)
			(xy 330.942235 -24.255981) (xy 330.886798 -24.262081) (xy 330.831064 -24.260044) (xy 330.776221 -24.249914)
			(xy 330.723437 -24.231907) (xy 330.673837 -24.206406) (xy 330.628479 -24.173955) (xy 330.58833 -24.135246)
			(xy 330.554244 -24.091103) (xy 330.526948 -24.042468) (xy 330.507025 -23.990377) (xy 330.494899 -23.93594)
			(xy 330.490828 -23.880318) (xy 330.236068 -23.880318) (xy 330.235559 -23.908204) (xy 330.227439 -23.96338)
			(xy 330.211371 -24.016787) (xy 330.187699 -24.067284) (xy 330.156926 -24.113797) (xy 330.119709 -24.155334)
			(xy 330.076841 -24.191009) (xy 330.029235 -24.220063) (xy 329.977906 -24.241875) (xy 329.923949 -24.255981)
			(xy 329.868512 -24.262081) (xy 329.812778 -24.260044) (xy 329.757935 -24.249914) (xy 329.705151 -24.231907)
			(xy 329.655551 -24.206406) (xy 329.610193 -24.173955) (xy 329.570044 -24.135246) (xy 329.535958 -24.091103)
			(xy 329.508662 -24.042468) (xy 329.488739 -23.990377) (xy 329.476613 -23.93594) (xy 329.472542 -23.880318)
			(xy 329.220068 -23.880318) (xy 329.219559 -23.908204) (xy 329.211439 -23.96338) (xy 329.195371 -24.016787)
			(xy 329.171699 -24.067284) (xy 329.140926 -24.113797) (xy 329.103709 -24.155334) (xy 329.060841 -24.191009)
			(xy 329.013235 -24.220063) (xy 328.961906 -24.241875) (xy 328.907949 -24.255981) (xy 328.852512 -24.262081)
			(xy 328.796778 -24.260044) (xy 328.741935 -24.249914) (xy 328.689151 -24.231907) (xy 328.639551 -24.206406)
			(xy 328.594193 -24.173955) (xy 328.554044 -24.135246) (xy 328.519958 -24.091103) (xy 328.492662 -24.042468)
			(xy 328.472739 -23.990377) (xy 328.460613 -23.93594) (xy 328.456542 -23.880318) (xy 328.204068 -23.880318)
			(xy 328.203559 -23.908204) (xy 328.195439 -23.96338) (xy 328.179371 -24.016787) (xy 328.155699 -24.067284)
			(xy 328.124926 -24.113797) (xy 328.087709 -24.155334) (xy 328.044841 -24.191009) (xy 327.997235 -24.220063)
			(xy 327.945906 -24.241875) (xy 327.891949 -24.255981) (xy 327.836512 -24.262081) (xy 327.780778 -24.260044)
			(xy 327.725935 -24.249914) (xy 327.673151 -24.231907) (xy 327.623551 -24.206406) (xy 327.578193 -24.173955)
			(xy 327.538044 -24.135246) (xy 327.503958 -24.091103) (xy 327.476662 -24.042468) (xy 327.456739 -23.990377)
			(xy 327.444613 -23.93594) (xy 327.440542 -23.880318) (xy 327.019891 -23.880318) (xy 327.010844 -23.892108)
			(xy 326.968464 -23.934488) (xy 326.920914 -23.970975) (xy 326.869008 -24.000942) (xy 326.813635 -24.023878)
			(xy 326.755742 -24.039391) (xy 326.69632 -24.047214) (xy 326.636384 -24.047214) (xy 326.576962 -24.039391)
			(xy 326.519069 -24.023878) (xy 326.463696 -24.000942) (xy 326.41179 -23.970975) (xy 326.36424 -23.934488)
			(xy 326.32186 -23.892108) (xy 326.285373 -23.844558) (xy 326.255406 -23.792652) (xy 326.23247 -23.737279)
			(xy 326.216957 -23.679386) (xy 326.209134 -23.619964) (xy 323.02652 -23.619964) (xy 323.020068 -23.664845)
			(xy 323.004713 -23.71714) (xy 322.982071 -23.766717) (xy 322.952605 -23.812567) (xy 322.916914 -23.853758)
			(xy 322.875723 -23.889449) (xy 322.829873 -23.918915) (xy 322.780296 -23.941557) (xy 322.728001 -23.956912)
			(xy 322.674053 -23.964668) (xy 322.619551 -23.964668) (xy 322.565603 -23.956912) (xy 322.513308 -23.941557)
			(xy 322.463731 -23.918915) (xy 322.417881 -23.889449) (xy 322.37669 -23.853758) (xy 322.340999 -23.812567)
			(xy 322.311533 -23.766717) (xy 322.288891 -23.71714) (xy 322.273536 -23.664845) (xy 322.26578 -23.610897)
			(xy 322.265294 -23.583646) (xy 322.267072 -23.548086) (xy 322.268342 -23.53437) (xy 322.25742 -23.51024)
			(xy 322.164456 -23.44293) (xy 322.13804 -23.439882) (xy 322.125594 -23.44547) (xy 322.09684 -23.457298)
			(xy 322.036933 -23.47393) (xy 321.975325 -23.482306) (xy 321.944238 -23.482808) (xy 321.914266 -23.482379)
			(xy 321.854834 -23.47456) (xy 321.796931 -23.45905) (xy 321.741548 -23.436114) (xy 321.689633 -23.406146)
			(xy 321.642074 -23.369658) (xy 321.599684 -23.327274) (xy 321.563189 -23.27972) (xy 321.533214 -23.227808)
			(xy 321.510271 -23.172429) (xy 321.494753 -23.114528) (xy 321.486925 -23.055097) (xy 321.486922 -22.995153)
			(xy 319.743836 -22.995153) (xy 319.743836 -24.189944) (xy 321.49872 -24.189944) (xy 321.502791 -24.134322)
			(xy 321.514917 -24.079885) (xy 321.53484 -24.027794) (xy 321.562136 -23.979159) (xy 321.596222 -23.935016)
			(xy 321.636371 -23.896307) (xy 321.681729 -23.863856) (xy 321.731329 -23.838355) (xy 321.784113 -23.820348)
			(xy 321.838956 -23.810218) (xy 321.89469 -23.808181) (xy 321.950127 -23.814281) (xy 322.004084 -23.828387)
			(xy 322.055413 -23.850199) (xy 322.103019 -23.879253) (xy 322.145887 -23.914928) (xy 322.183104 -23.956465)
			(xy 322.213877 -24.002978) (xy 322.237549 -24.053475) (xy 322.253617 -24.106882) (xy 322.261737 -24.162058)
			(xy 322.262246 -24.189944) (xy 324.021702 -24.189944) (xy 324.025773 -24.134322) (xy 324.037899 -24.079885)
			(xy 324.057822 -24.027794) (xy 324.085118 -23.979159) (xy 324.119204 -23.935016) (xy 324.159353 -23.896307)
			(xy 324.204711 -23.863856) (xy 324.254311 -23.838355) (xy 324.307095 -23.820348) (xy 324.361938 -23.810218)
			(xy 324.417672 -23.808181) (xy 324.473109 -23.814281) (xy 324.527066 -23.828387) (xy 324.578395 -23.850199)
			(xy 324.626001 -23.879253) (xy 324.668869 -23.914928) (xy 324.706086 -23.956465) (xy 324.736859 -24.002978)
			(xy 324.760531 -24.053475) (xy 324.776599 -24.106882) (xy 324.784719 -24.162058) (xy 324.785228 -24.189944)
			(xy 324.784719 -24.21783) (xy 324.776599 -24.273006) (xy 324.760531 -24.326413) (xy 324.736859 -24.37691)
			(xy 324.706086 -24.423423) (xy 324.668869 -24.46496) (xy 324.626001 -24.500635) (xy 324.578395 -24.529689)
			(xy 324.527066 -24.551501) (xy 324.473109 -24.565607) (xy 324.417672 -24.571707) (xy 324.361938 -24.56967)
			(xy 324.307095 -24.55954) (xy 324.254311 -24.541533) (xy 324.204711 -24.516032) (xy 324.159353 -24.483581)
			(xy 324.119204 -24.444872) (xy 324.085118 -24.400729) (xy 324.057822 -24.352094) (xy 324.037899 -24.300003)
			(xy 324.025773 -24.245566) (xy 324.021702 -24.189944) (xy 322.262246 -24.189944) (xy 322.261737 -24.21783)
			(xy 322.253617 -24.273006) (xy 322.237549 -24.326413) (xy 322.213877 -24.37691) (xy 322.183104 -24.423423)
			(xy 322.145887 -24.46496) (xy 322.103019 -24.500635) (xy 322.055413 -24.529689) (xy 322.004084 -24.551501)
			(xy 321.950127 -24.565607) (xy 321.89469 -24.571707) (xy 321.838956 -24.56967) (xy 321.784113 -24.55954)
			(xy 321.731329 -24.541533) (xy 321.681729 -24.516032) (xy 321.636371 -24.483581) (xy 321.596222 -24.444872)
			(xy 321.562136 -24.400729) (xy 321.53484 -24.352094) (xy 321.514917 -24.300003) (xy 321.502791 -24.245566)
			(xy 321.49872 -24.189944) (xy 319.743836 -24.189944) (xy 319.743836 -25.390094) (xy 323.933312 -25.390094)
			(xy 323.933802 -25.360126) (xy 323.941625 -25.300704) (xy 323.957138 -25.242811) (xy 323.980074 -25.187438)
			(xy 324.010041 -25.135532) (xy 324.046528 -25.087982) (xy 324.088908 -25.045602) (xy 324.136458 -25.009115)
			(xy 324.188364 -24.979148) (xy 324.243737 -24.956212) (xy 324.30163 -24.940699) (xy 324.361052 -24.932876)
			(xy 324.420988 -24.932876) (xy 324.48041 -24.940699) (xy 324.538303 -24.956212) (xy 324.593676 -24.979148)
			(xy 324.645582 -25.009115) (xy 324.693132 -25.045602) (xy 324.735512 -25.087982) (xy 324.771999 -25.135532)
			(xy 324.801966 -25.187438) (xy 324.824902 -25.242811) (xy 324.840415 -25.300704) (xy 324.848238 -25.360126)
			(xy 324.848728 -25.390094) (xy 324.848284 -25.418878) (xy 324.841066 -25.475992) (xy 324.826743 -25.53175)
			(xy 324.805542 -25.585272) (xy 324.777796 -25.635712) (xy 324.743945 -25.682276) (xy 324.704522 -25.724227)
			(xy 324.682612 -25.7429) (xy 324.67423 -25.749758) (xy 324.664578 -25.769316) (xy 324.661276 -25.867106)
			(xy 324.669404 -25.887172) (xy 324.677532 -25.894792) (xy 324.695928 -25.912873) (xy 324.728166 -25.953138)
			(xy 324.754691 -25.997377) (xy 324.77502 -26.044784) (xy 324.788781 -26.094496) (xy 324.795725 -26.145607)
			(xy 324.79615 -26.171398) (xy 324.795664 -26.198649) (xy 324.787908 -26.252597) (xy 324.772553 -26.304892)
			(xy 324.749911 -26.354469) (xy 324.720445 -26.400319) (xy 324.684754 -26.44151) (xy 324.643563 -26.477201)
			(xy 324.597713 -26.506667) (xy 324.548136 -26.529309) (xy 324.495841 -26.544664) (xy 324.441893 -26.55242)
			(xy 324.387391 -26.55242) (xy 324.333443 -26.544664) (xy 324.281148 -26.529309) (xy 324.231571 -26.506667)
			(xy 324.185721 -26.477201) (xy 324.14453 -26.44151) (xy 324.108839 -26.400319) (xy 324.079373 -26.354469)
			(xy 324.056731 -26.304892) (xy 324.041376 -26.252597) (xy 324.03362 -26.198649) (xy 324.033134 -26.171398)
			(xy 324.033642 -26.142754) (xy 324.04224 -26.086115) (xy 324.059214 -26.031399) (xy 324.084179 -25.979837)
			(xy 324.116576 -25.932589) (xy 324.13575 -25.911302) (xy 324.143116 -25.903174) (xy 324.149974 -25.8826)
			(xy 324.14083 -25.785064) (xy 324.130162 -25.766268) (xy 324.121272 -25.759918) (xy 324.09674 -25.741347)
			(xy 324.052342 -25.698751) (xy 324.014049 -25.650593) (xy 323.982549 -25.597741) (xy 323.958411 -25.541146)
			(xy 323.942068 -25.481829) (xy 323.933817 -25.420858) (xy 323.933312 -25.390094) (xy 319.743836 -25.390094)
			(xy 319.743836 -25.506934) (xy 319.744266 -25.517001) (xy 319.751993 -25.535593) (xy 319.758822 -25.543002)
			(xy 319.81013 -25.593802) (xy 319.817541 -25.600481) (xy 319.835978 -25.608052) (xy 319.845944 -25.608534)
			(xy 319.848738 -25.608534) (xy 319.875984 -25.609023) (xy 319.929922 -25.616783) (xy 319.982206 -25.63214)
			(xy 320.031773 -25.65478) (xy 320.077614 -25.684244) (xy 320.118795 -25.719932) (xy 320.154478 -25.761117)
			(xy 320.183938 -25.80696) (xy 320.206574 -25.856529) (xy 320.221925 -25.908815) (xy 320.22968 -25.962754)
			(xy 320.22968 -25.990042) (xy 321.49872 -25.990042) (xy 321.502791 -25.93442) (xy 321.514917 -25.879983)
			(xy 321.53484 -25.827892) (xy 321.562136 -25.779257) (xy 321.596222 -25.735114) (xy 321.636371 -25.696405)
			(xy 321.681729 -25.663954) (xy 321.731329 -25.638453) (xy 321.784113 -25.620446) (xy 321.838956 -25.610316)
			(xy 321.89469 -25.608279) (xy 321.950127 -25.614379) (xy 322.004084 -25.628485) (xy 322.055413 -25.650297)
			(xy 322.103019 -25.679351) (xy 322.145887 -25.715026) (xy 322.183104 -25.756563) (xy 322.213877 -25.803076)
			(xy 322.237549 -25.853573) (xy 322.253617 -25.90698) (xy 322.261737 -25.962156) (xy 322.262246 -25.990042)
			(xy 322.261737 -26.017928) (xy 322.253617 -26.073104) (xy 322.237549 -26.126511) (xy 322.213877 -26.177008)
			(xy 322.183104 -26.223521) (xy 322.145887 -26.265058) (xy 322.103019 -26.300733) (xy 322.055413 -26.329787)
			(xy 322.004084 -26.351599) (xy 321.950127 -26.365705) (xy 321.89469 -26.371805) (xy 321.838956 -26.369768)
			(xy 321.784113 -26.359638) (xy 321.731329 -26.341631) (xy 321.681729 -26.31613) (xy 321.636371 -26.283679)
			(xy 321.596222 -26.24497) (xy 321.562136 -26.200827) (xy 321.53484 -26.152192) (xy 321.514917 -26.100101)
			(xy 321.502791 -26.045664) (xy 321.49872 -25.990042) (xy 320.22968 -25.990042) (xy 320.22968 -26.017246)
			(xy 320.221925 -26.071185) (xy 320.206574 -26.123471) (xy 320.183938 -26.17304) (xy 320.154478 -26.218883)
			(xy 320.118795 -26.260068) (xy 320.077614 -26.295756) (xy 320.031773 -26.32522) (xy 319.982206 -26.34786)
			(xy 319.929922 -26.363217) (xy 319.875984 -26.370977) (xy 319.848738 -26.37155) (xy 319.845944 -26.37155)
			(xy 319.835982 -26.372036) (xy 319.81756 -26.379626) (xy 319.81013 -26.386282) (xy 319.758822 -26.437082)
			(xy 319.751986 -26.444484) (xy 319.744278 -26.463082) (xy 319.743836 -26.47315) (xy 319.743836 -27.307032)
			(xy 319.744266 -27.317099) (xy 319.751992 -27.335692) (xy 319.758822 -27.3431) (xy 319.81013 -27.3939)
			(xy 319.817541 -27.400579) (xy 319.835977 -27.408151) (xy 319.845944 -27.408632) (xy 319.848738 -27.408632)
			(xy 319.875985 -27.409121) (xy 319.929922 -27.416881) (xy 319.982207 -27.432238) (xy 320.031774 -27.454879)
			(xy 320.077615 -27.484343) (xy 320.118796 -27.52003) (xy 320.15448 -27.561215) (xy 320.18394 -27.607059)
			(xy 320.206576 -27.656629) (xy 320.221927 -27.708915) (xy 320.229682 -27.762853) (xy 320.229682 -27.79014)
			(xy 321.562728 -27.79014) (xy 321.566799 -27.734518) (xy 321.578925 -27.680081) (xy 321.598848 -27.62799)
			(xy 321.626144 -27.579355) (xy 321.66023 -27.535212) (xy 321.700379 -27.496503) (xy 321.745737 -27.464052)
			(xy 321.795337 -27.438551) (xy 321.848121 -27.420544) (xy 321.902964 -27.410414) (xy 321.958698 -27.408377)
			(xy 322.014135 -27.414477) (xy 322.068092 -27.428583) (xy 322.119421 -27.450395) (xy 322.167027 -27.479449)
			(xy 322.209895 -27.515124) (xy 322.247112 -27.556661) (xy 322.277885 -27.603174) (xy 322.301557 -27.653671)
			(xy 322.317625 -27.707078) (xy 322.325745 -27.762254) (xy 322.326254 -27.79014) (xy 324.06666 -27.79014)
			(xy 324.070731 -27.734518) (xy 324.082857 -27.680081) (xy 324.10278 -27.62799) (xy 324.130076 -27.579355)
			(xy 324.164162 -27.535212) (xy 324.204311 -27.496503) (xy 324.249669 -27.464052) (xy 324.299269 -27.438551)
			(xy 324.352053 -27.420544) (xy 324.406896 -27.410414) (xy 324.46263 -27.408377) (xy 324.518067 -27.414477)
			(xy 324.572024 -27.428583) (xy 324.623353 -27.450395) (xy 324.670959 -27.479449) (xy 324.713827 -27.515124)
			(xy 324.751044 -27.556661) (xy 324.781817 -27.603174) (xy 324.805489 -27.653671) (xy 324.821557 -27.707078)
			(xy 324.829677 -27.762254) (xy 324.830186 -27.79014) (xy 324.829689 -27.817347) (xy 326.099718 -27.817347)
			(xy 326.099718 -27.762853) (xy 326.107473 -27.708913) (xy 326.122826 -27.656625) (xy 326.145463 -27.607055)
			(xy 326.174924 -27.56121) (xy 326.210609 -27.520025) (xy 326.251792 -27.484337) (xy 326.297635 -27.454873)
			(xy 326.347204 -27.432233) (xy 326.399491 -27.416878) (xy 326.453431 -27.40912) (xy 326.480678 -27.408632)
			(xy 326.505985 -27.409038) (xy 326.556157 -27.415706) (xy 326.605009 -27.428943) (xy 326.628506 -27.43835)
			(xy 326.636519 -27.441354) (xy 326.653585 -27.442454) (xy 326.670062 -27.437875) (xy 326.677274 -27.43327)
			(xy 326.702674 -27.41549) (xy 326.709558 -27.410213) (xy 326.719634 -27.396111) (xy 326.724432 -27.379457)
			(xy 326.724264 -27.370786) (xy 326.723248 -27.342846) (xy 326.723248 -26.479246) (xy 326.72401 -26.456894)
			(xy 326.724518 -26.444448) (xy 326.714104 -26.421842) (xy 326.629014 -26.355548) (xy 326.60463 -26.350976)
			(xy 326.592692 -26.354786) (xy 326.565354 -26.362625) (xy 326.509113 -26.371045) (xy 326.480678 -26.37155)
			(xy 326.453431 -26.370978) (xy 326.399491 -26.36322) (xy 326.347205 -26.347865) (xy 326.297636 -26.325225)
			(xy 326.251794 -26.295761) (xy 326.210611 -26.260074) (xy 326.174925 -26.218889) (xy 326.145465 -26.173044)
			(xy 326.122827 -26.123474) (xy 326.107475 -26.071187) (xy 326.09972 -26.017247) (xy 326.09972 -25.962753)
			(xy 326.107475 -25.908813) (xy 326.122827 -25.856526) (xy 326.145465 -25.806956) (xy 326.174925 -25.761111)
			(xy 326.210611 -25.719926) (xy 326.251794 -25.684239) (xy 326.297636 -25.654775) (xy 326.347205 -25.632135)
			(xy 326.399491 -25.61678) (xy 326.453431 -25.609022) (xy 326.480678 -25.608534) (xy 326.509629 -25.609097)
			(xy 326.56687 -25.617831) (xy 326.622132 -25.635115) (xy 326.674147 -25.660554) (xy 326.72172 -25.693562)
			(xy 326.763757 -25.733382) (xy 326.799293 -25.779097) (xy 326.827511 -25.829659) (xy 326.828405 -25.832054)
			(xy 328.388218 -25.832054) (xy 328.3887 -25.805451) (xy 328.396075 -25.752759) (xy 328.410703 -25.701604)
			(xy 328.4323 -25.652979) (xy 328.460446 -25.607828) (xy 328.494596 -25.567028) (xy 328.534086 -25.531371)
			(xy 328.555858 -25.516078) (xy 328.567338 -25.507741) (xy 328.585549 -25.486001) (xy 328.597071 -25.460087)
			(xy 328.601014 -25.432002) (xy 328.597072 -25.403918) (xy 328.585552 -25.378003) (xy 328.567342 -25.356262)
			(xy 328.555858 -25.34793) (xy 328.534097 -25.332622) (xy 328.494617 -25.296959) (xy 328.460472 -25.256158)
			(xy 328.432325 -25.21101) (xy 328.410721 -25.162391) (xy 328.396079 -25.111242) (xy 328.388683 -25.058556)
			(xy 328.388218 -25.031954) (xy 328.388704 -25.004703) (xy 328.39646 -24.950755) (xy 328.411815 -24.89846)
			(xy 328.434457 -24.848883) (xy 328.463923 -24.803033) (xy 328.499614 -24.761842) (xy 328.540805 -24.726151)
			(xy 328.586655 -24.696685) (xy 328.636232 -24.674043) (xy 328.688527 -24.658688) (xy 328.742475 -24.650932)
			(xy 328.796977 -24.650932) (xy 328.850925 -24.658688) (xy 328.90322 -24.674043) (xy 328.952797 -24.696685)
			(xy 328.998647 -24.726151) (xy 329.039838 -24.761842) (xy 329.063039 -24.788618) (xy 330.993224 -24.788618)
			(xy 330.993224 -24.728682) (xy 331.001047 -24.66926) (xy 331.01656 -24.611367) (xy 331.039496 -24.555994)
			(xy 331.069463 -24.504088) (xy 331.10595 -24.456538) (xy 331.14833 -24.414158) (xy 331.19588 -24.377671)
			(xy 331.247786 -24.347704) (xy 331.303159 -24.324768) (xy 331.361052 -24.309255) (xy 331.420474 -24.301432)
			(xy 331.48041 -24.301432) (xy 331.539832 -24.309255) (xy 331.597725 -24.324768) (xy 331.653098 -24.347704)
			(xy 331.705004 -24.377671) (xy 331.752554 -24.414158) (xy 331.794934 -24.456538) (xy 331.831421 -24.504088)
			(xy 331.861388 -24.555994) (xy 331.884324 -24.611367) (xy 331.899837 -24.66926) (xy 331.90766 -24.728682)
			(xy 331.90815 -24.75865) (xy 331.90766 -24.788618) (xy 331.899837 -24.84804) (xy 331.884324 -24.905933)
			(xy 331.861388 -24.961306) (xy 331.831421 -25.013212) (xy 331.794934 -25.060762) (xy 331.752554 -25.103142)
			(xy 331.705004 -25.139629) (xy 331.653098 -25.169596) (xy 331.597725 -25.192532) (xy 331.539832 -25.208045)
			(xy 331.48041 -25.215868) (xy 331.420474 -25.215868) (xy 331.361052 -25.208045) (xy 331.303159 -25.192532)
			(xy 331.247786 -25.169596) (xy 331.19588 -25.139629) (xy 331.14833 -25.103142) (xy 331.10595 -25.060762)
			(xy 331.069463 -25.013212) (xy 331.039496 -24.961306) (xy 331.01656 -24.905933) (xy 331.001047 -24.84804)
			(xy 330.993224 -24.788618) (xy 329.063039 -24.788618) (xy 329.075529 -24.803033) (xy 329.104995 -24.848883)
			(xy 329.127637 -24.89846) (xy 329.142992 -24.950755) (xy 329.150748 -25.004703) (xy 329.151234 -25.031954)
			(xy 329.150779 -25.058558) (xy 329.143402 -25.111252) (xy 329.128771 -25.162409) (xy 329.10717 -25.211035)
			(xy 329.079019 -25.256186) (xy 329.044864 -25.296984) (xy 329.005369 -25.332638) (xy 328.983594 -25.34793)
			(xy 328.972111 -25.35626) (xy 328.953908 -25.378005) (xy 328.942392 -25.403919) (xy 328.938453 -25.432002)
			(xy 328.942393 -25.460085) (xy 328.95391 -25.485999) (xy 328.972114 -25.507743) (xy 328.983594 -25.516078)
			(xy 329.00537 -25.531364) (xy 329.044848 -25.567033) (xy 329.078989 -25.607839) (xy 329.107134 -25.65299)
			(xy 329.128735 -25.701612) (xy 329.143375 -25.752763) (xy 329.15077 -25.805452) (xy 329.151234 -25.832054)
			(xy 329.150748 -25.859305) (xy 329.142992 -25.913253) (xy 329.127637 -25.965548) (xy 329.104995 -26.015125)
			(xy 329.075529 -26.060975) (xy 329.039838 -26.102166) (xy 328.998647 -26.137857) (xy 328.952797 -26.167323)
			(xy 328.90322 -26.189965) (xy 328.850925 -26.20532) (xy 328.796977 -26.213076) (xy 328.742475 -26.213076)
			(xy 328.688527 -26.20532) (xy 328.636232 -26.189965) (xy 328.586655 -26.167323) (xy 328.540805 -26.137857)
			(xy 328.499614 -26.102166) (xy 328.463923 -26.060975) (xy 328.434457 -26.015125) (xy 328.411815 -25.965548)
			(xy 328.39646 -25.913253) (xy 328.388704 -25.859305) (xy 328.388218 -25.832054) (xy 326.828405 -25.832054)
			(xy 326.847763 -25.883904) (xy 326.859583 -25.940588) (xy 326.861678 -25.969468) (xy 326.862186 -25.981914)
			(xy 326.874886 -26.00325) (xy 326.96658 -26.060654) (xy 326.991218 -26.062432) (xy 327.002648 -26.057606)
			(xy 327.031003 -26.046131) (xy 327.090002 -26.029978) (xy 327.150625 -26.021809) (xy 327.18121 -26.021284)
			(xy 327.211198 -26.021698) (xy 327.27066 -26.029528) (xy 327.328592 -26.045053) (xy 327.384001 -26.068007)
			(xy 327.43594 -26.097997) (xy 327.48352 -26.134511) (xy 327.525926 -26.176922) (xy 327.562434 -26.224507)
			(xy 327.592418 -26.276449) (xy 327.615365 -26.331861) (xy 327.623138 -26.360882) (xy 329.289408 -26.360882)
			(xy 329.293479 -26.30526) (xy 329.305605 -26.250823) (xy 329.325528 -26.198732) (xy 329.352824 -26.150097)
			(xy 329.38691 -26.105954) (xy 329.427059 -26.067245) (xy 329.472417 -26.034794) (xy 329.522017 -26.009293)
			(xy 329.574801 -25.991286) (xy 329.629644 -25.981156) (xy 329.685378 -25.979119) (xy 329.740815 -25.985219)
			(xy 329.794772 -25.999325) (xy 329.846101 -26.021137) (xy 329.893707 -26.050191) (xy 329.936575 -26.085866)
			(xy 329.973792 -26.127403) (xy 330.004565 -26.173916) (xy 330.028237 -26.224413) (xy 330.044305 -26.27782)
			(xy 330.052425 -26.332996) (xy 330.052934 -26.360882) (xy 330.305408 -26.360882) (xy 330.309479 -26.30526)
			(xy 330.321605 -26.250823) (xy 330.341528 -26.198732) (xy 330.368824 -26.150097) (xy 330.40291 -26.105954)
			(xy 330.443059 -26.067245) (xy 330.488417 -26.034794) (xy 330.538017 -26.009293) (xy 330.590801 -25.991286)
			(xy 330.645644 -25.981156) (xy 330.701378 -25.979119) (xy 330.756815 -25.985219) (xy 330.810772 -25.999325)
			(xy 330.862101 -26.021137) (xy 330.909707 -26.050191) (xy 330.952575 -26.085866) (xy 330.989792 -26.127403)
			(xy 331.020565 -26.173916) (xy 331.044237 -26.224413) (xy 331.060305 -26.27782) (xy 331.068425 -26.332996)
			(xy 331.068934 -26.360882) (xy 331.068425 -26.388768) (xy 331.060305 -26.443944) (xy 331.044237 -26.497351)
			(xy 331.020565 -26.547848) (xy 330.989792 -26.594361) (xy 330.952575 -26.635898) (xy 330.909707 -26.671573)
			(xy 330.862101 -26.700627) (xy 330.810772 -26.722439) (xy 330.756815 -26.736545) (xy 330.701378 -26.742645)
			(xy 330.645644 -26.740608) (xy 330.590801 -26.730478) (xy 330.538017 -26.712471) (xy 330.488417 -26.68697)
			(xy 330.443059 -26.654519) (xy 330.40291 -26.61581) (xy 330.368824 -26.571667) (xy 330.341528 -26.523032)
			(xy 330.321605 -26.470941) (xy 330.309479 -26.416504) (xy 330.305408 -26.360882) (xy 330.052934 -26.360882)
			(xy 330.052425 -26.388768) (xy 330.044305 -26.443944) (xy 330.028237 -26.497351) (xy 330.004565 -26.547848)
			(xy 329.973792 -26.594361) (xy 329.936575 -26.635898) (xy 329.893707 -26.671573) (xy 329.846101 -26.700627)
			(xy 329.794772 -26.722439) (xy 329.740815 -26.736545) (xy 329.685378 -26.742645) (xy 329.629644 -26.740608)
			(xy 329.574801 -26.730478) (xy 329.522017 -26.712471) (xy 329.472417 -26.68697) (xy 329.427059 -26.654519)
			(xy 329.38691 -26.61581) (xy 329.352824 -26.571667) (xy 329.325528 -26.523032) (xy 329.305605 -26.470941)
			(xy 329.293479 -26.416504) (xy 329.289408 -26.360882) (xy 327.623138 -26.360882) (xy 327.630883 -26.389795)
			(xy 327.638706 -26.449258) (xy 327.639172 -26.479246) (xy 327.639172 -26.971244) (xy 331.050898 -26.971244)
			(xy 331.054969 -26.915622) (xy 331.067095 -26.861185) (xy 331.087018 -26.809094) (xy 331.114314 -26.760459)
			(xy 331.1484 -26.716316) (xy 331.188549 -26.677607) (xy 331.233907 -26.645156) (xy 331.283507 -26.619655)
			(xy 331.336291 -26.601648) (xy 331.391134 -26.591518) (xy 331.446868 -26.589481) (xy 331.502305 -26.595581)
			(xy 331.556262 -26.609687) (xy 331.607591 -26.631499) (xy 331.655197 -26.660553) (xy 331.698065 -26.696228)
			(xy 331.735282 -26.737765) (xy 331.766055 -26.784278) (xy 331.789727 -26.834775) (xy 331.805795 -26.888182)
			(xy 331.813915 -26.943358) (xy 331.814424 -26.971244) (xy 331.813915 -26.99913) (xy 331.805795 -27.054306)
			(xy 331.789727 -27.107713) (xy 331.766055 -27.15821) (xy 331.735282 -27.204723) (xy 331.698065 -27.24626)
			(xy 331.655197 -27.281935) (xy 331.607591 -27.310989) (xy 331.556262 -27.332801) (xy 331.502305 -27.346907)
			(xy 331.446868 -27.353007) (xy 331.391134 -27.35097) (xy 331.336291 -27.34084) (xy 331.283507 -27.322833)
			(xy 331.233907 -27.297332) (xy 331.188549 -27.264881) (xy 331.1484 -27.226172) (xy 331.114314 -27.182029)
			(xy 331.087018 -27.133394) (xy 331.067095 -27.081303) (xy 331.054969 -27.026866) (xy 331.050898 -26.971244)
			(xy 327.639172 -26.971244) (xy 327.639172 -27.342846) (xy 327.638715 -27.372831) (xy 327.630882 -27.432287)
			(xy 327.615356 -27.490212) (xy 327.592403 -27.545616) (xy 327.562414 -27.597549) (xy 327.525905 -27.645125)
			(xy 327.483498 -27.687529) (xy 327.43592 -27.724035) (xy 327.383983 -27.754019) (xy 327.328578 -27.776968)
			(xy 327.270652 -27.792489) (xy 327.211195 -27.800317) (xy 327.18121 -27.800808) (xy 327.150074 -27.800266)
			(xy 327.088378 -27.791806) (xy 327.028392 -27.77508) (xy 326.9996 -27.763216) (xy 326.988424 -27.75839)
			(xy 326.964802 -27.75966) (xy 326.873616 -27.810968) (xy 326.860154 -27.830526) (xy 326.85863 -27.842464)
			(xy 326.8544 -27.869491) (xy 326.83922 -27.922048) (xy 326.816692 -27.971899) (xy 326.787278 -28.018022)
			(xy 326.751579 -28.059473) (xy 326.710327 -28.095402) (xy 326.664368 -28.125074) (xy 326.614644 -28.147879)
			(xy 326.562173 -28.163351) (xy 326.50803 -28.171173) (xy 326.480678 -28.171648) (xy 326.453431 -28.17108)
			(xy 326.399491 -28.163322) (xy 326.347204 -28.147967) (xy 326.297635 -28.125327) (xy 326.251792 -28.095863)
			(xy 326.210609 -28.060175) (xy 326.174924 -28.01899) (xy 326.145463 -27.973145) (xy 326.122826 -27.923575)
			(xy 326.107473 -27.871287) (xy 326.099718 -27.817347) (xy 324.829689 -27.817347) (xy 324.829677 -27.818026)
			(xy 324.821557 -27.873202) (xy 324.805489 -27.926609) (xy 324.781817 -27.977106) (xy 324.751044 -28.023619)
			(xy 324.713827 -28.065156) (xy 324.670959 -28.100831) (xy 324.623353 -28.129885) (xy 324.572024 -28.151697)
			(xy 324.518067 -28.165803) (xy 324.46263 -28.171903) (xy 324.406896 -28.169866) (xy 324.352053 -28.159736)
			(xy 324.299269 -28.141729) (xy 324.249669 -28.116228) (xy 324.204311 -28.083777) (xy 324.164162 -28.045068)
			(xy 324.130076 -28.000925) (xy 324.10278 -27.95229) (xy 324.082857 -27.900199) (xy 324.070731 -27.845762)
			(xy 324.06666 -27.79014) (xy 322.326254 -27.79014) (xy 322.325745 -27.818026) (xy 322.317625 -27.873202)
			(xy 322.301557 -27.926609) (xy 322.277885 -27.977106) (xy 322.247112 -28.023619) (xy 322.209895 -28.065156)
			(xy 322.167027 -28.100831) (xy 322.119421 -28.129885) (xy 322.068092 -28.151697) (xy 322.014135 -28.165803)
			(xy 321.958698 -28.171903) (xy 321.902964 -28.169866) (xy 321.848121 -28.159736) (xy 321.795337 -28.141729)
			(xy 321.745737 -28.116228) (xy 321.700379 -28.083777) (xy 321.66023 -28.045068) (xy 321.626144 -28.000925)
			(xy 321.598848 -27.95229) (xy 321.578925 -27.900199) (xy 321.566799 -27.845762) (xy 321.562728 -27.79014)
			(xy 320.229682 -27.79014) (xy 320.229682 -27.817347) (xy 320.221927 -27.871285) (xy 320.206576 -27.923571)
			(xy 320.18394 -27.973141) (xy 320.15448 -28.018985) (xy 320.118796 -28.06017) (xy 320.077615 -28.095857)
			(xy 320.031774 -28.125321) (xy 319.982207 -28.147962) (xy 319.929922 -28.163319) (xy 319.875985 -28.171079)
			(xy 319.848738 -28.171648) (xy 319.845944 -28.171648) (xy 319.835982 -28.172134) (xy 319.81756 -28.179724)
			(xy 319.81013 -28.18638) (xy 319.758822 -28.23718) (xy 319.751986 -28.244582) (xy 319.744277 -28.26318)
			(xy 319.743836 -28.273248) (xy 319.743836 -29.106876) (xy 319.744274 -29.116939) (xy 319.752012 -29.13552)
			(xy 319.758822 -29.142944) (xy 319.81013 -29.193744) (xy 319.817543 -29.200419) (xy 319.835979 -29.207983)
			(xy 319.845944 -29.208476) (xy 319.848738 -29.208476) (xy 319.875989 -29.208964) (xy 319.929934 -29.216726)
			(xy 319.982227 -29.232085) (xy 320.031801 -29.254729) (xy 320.077649 -29.284198) (xy 320.118836 -29.319891)
			(xy 320.154525 -29.361081) (xy 320.183989 -29.406932) (xy 320.206629 -29.456509) (xy 320.221982 -29.508803)
			(xy 320.229738 -29.562749) (xy 320.229738 -29.589984) (xy 321.562728 -29.589984) (xy 321.566799 -29.534362)
			(xy 321.578925 -29.479925) (xy 321.598848 -29.427834) (xy 321.626144 -29.379199) (xy 321.66023 -29.335056)
			(xy 321.700379 -29.296347) (xy 321.745737 -29.263896) (xy 321.795337 -29.238395) (xy 321.848121 -29.220388)
			(xy 321.902964 -29.210258) (xy 321.958698 -29.208221) (xy 322.014135 -29.214321) (xy 322.068092 -29.228427)
			(xy 322.119421 -29.250239) (xy 322.167027 -29.279293) (xy 322.209895 -29.314968) (xy 322.247112 -29.356505)
			(xy 322.277885 -29.403018) (xy 322.301557 -29.453515) (xy 322.317625 -29.506922) (xy 322.325745 -29.562098)
			(xy 322.326254 -29.589984) (xy 324.06666 -29.589984) (xy 324.070731 -29.534362) (xy 324.082857 -29.479925)
			(xy 324.10278 -29.427834) (xy 324.130076 -29.379199) (xy 324.164162 -29.335056) (xy 324.204311 -29.296347)
			(xy 324.249669 -29.263896) (xy 324.299269 -29.238395) (xy 324.352053 -29.220388) (xy 324.406896 -29.210258)
			(xy 324.46263 -29.208221) (xy 324.518067 -29.214321) (xy 324.572024 -29.228427) (xy 324.623353 -29.250239)
			(xy 324.670959 -29.279293) (xy 324.713827 -29.314968) (xy 324.751044 -29.356505) (xy 324.781817 -29.403018)
			(xy 324.805489 -29.453515) (xy 324.821557 -29.506922) (xy 324.829677 -29.562098) (xy 324.830186 -29.589984)
			(xy 326.09866 -29.589984) (xy 326.102731 -29.534362) (xy 326.114857 -29.479925) (xy 326.13478 -29.427834)
			(xy 326.162076 -29.379199) (xy 326.196162 -29.335056) (xy 326.236311 -29.296347) (xy 326.281669 -29.263896)
			(xy 326.331269 -29.238395) (xy 326.384053 -29.220388) (xy 326.438896 -29.210258) (xy 326.49463 -29.208221)
			(xy 326.550067 -29.214321) (xy 326.604024 -29.228427) (xy 326.655353 -29.250239) (xy 326.702959 -29.279293)
			(xy 326.745827 -29.314968) (xy 326.767497 -29.339153) (xy 328.490032 -29.339153) (xy 328.490032 -29.284647)
			(xy 328.497789 -29.230695) (xy 328.513144 -29.178396) (xy 328.535786 -29.128815) (xy 328.565253 -29.08296)
			(xy 328.600946 -29.041766) (xy 328.642138 -29.00607) (xy 328.68799 -28.976599) (xy 328.73757 -28.953954)
			(xy 328.789868 -28.938594) (xy 328.843819 -28.930834) (xy 328.871072 -28.930346) (xy 328.885865 -28.930482)
			(xy 328.915363 -28.932771) (xy 328.93 -28.934918) (xy 328.940922 -28.936696) (xy 328.962258 -28.9306)
			(xy 329.029568 -28.873196) (xy 329.037602 -28.865634) (xy 329.046812 -28.845609) (xy 329.047348 -28.834588)
			(xy 329.047348 -28.530296) (xy 329.046829 -28.519274) (xy 329.037598 -28.499257) (xy 329.029568 -28.491688)
			(xy 328.962258 -28.434284) (xy 328.940922 -28.428188) (xy 328.93 -28.429966) (xy 328.915361 -28.432101)
			(xy 328.885865 -28.434393) (xy 328.871072 -28.434538) (xy 328.843824 -28.43399) (xy 328.789884 -28.426231)
			(xy 328.737597 -28.410874) (xy 328.688027 -28.388233) (xy 328.642184 -28.358769) (xy 328.601 -28.32308)
			(xy 328.565314 -28.281894) (xy 328.535853 -28.236049) (xy 328.513216 -28.186477) (xy 328.497863 -28.134189)
			(xy 328.490108 -28.080248) (xy 328.490108 -28.025752) (xy 328.497863 -27.971811) (xy 328.513216 -27.919523)
			(xy 328.535853 -27.869951) (xy 328.565314 -27.824106) (xy 328.601 -27.78292) (xy 328.642184 -27.747231)
			(xy 328.688027 -27.717767) (xy 328.737597 -27.695126) (xy 328.789884 -27.679769) (xy 328.843824 -27.67201)
			(xy 328.871072 -27.671522) (xy 328.896998 -27.671967) (xy 328.948375 -27.678969) (xy 328.998331 -27.692864)
			(xy 329.045945 -27.713393) (xy 329.090342 -27.74018) (xy 329.130703 -27.772732) (xy 329.166286 -27.810448)
			(xy 329.181714 -27.831288) (xy 329.187439 -27.838632) (xy 329.202953 -27.84891) (xy 329.21194 -27.851354)
			(xy 329.242166 -27.858212) (xy 329.251441 -27.859972) (xy 329.270106 -27.857224) (xy 329.278488 -27.852878)
			(xy 329.304467 -27.838589) (xy 329.359318 -27.816077) (xy 329.41662 -27.800849) (xy 329.475411 -27.793161)
			(xy 329.505056 -27.79268) (xy 329.534699 -27.793185) (xy 329.59348 -27.800904) (xy 329.650779 -27.816128)
			(xy 329.705639 -27.838605) (xy 329.731624 -27.852878) (xy 329.740027 -27.857147) (xy 329.758665 -27.859866)
			(xy 329.767946 -27.858212) (xy 329.798172 -27.851354) (xy 329.807172 -27.848948) (xy 329.822674 -27.83864)
			(xy 329.828398 -27.831288) (xy 329.843799 -27.810424) (xy 329.879373 -27.772689) (xy 329.919732 -27.740124)
			(xy 329.964134 -27.71333) (xy 330.011757 -27.692802) (xy 330.061723 -27.678918) (xy 330.11311 -27.671935)
			(xy 330.13904 -27.671522) (xy 330.166292 -27.671951) (xy 330.220239 -27.679712) (xy 330.272533 -27.695072)
			(xy 330.322109 -27.717717) (xy 330.367958 -27.747187) (xy 330.409147 -27.782881) (xy 330.444837 -27.824074)
			(xy 330.474302 -27.869926) (xy 330.496942 -27.919504) (xy 330.512296 -27.9718) (xy 330.520052 -28.025748)
			(xy 330.520052 -28.080252) (xy 330.512296 -28.1342) (xy 330.496942 -28.186496) (xy 330.474302 -28.236074)
			(xy 330.444837 -28.281926) (xy 330.409147 -28.323119) (xy 330.367958 -28.358813) (xy 330.322109 -28.388283)
			(xy 330.272533 -28.410928) (xy 330.220239 -28.426288) (xy 330.166292 -28.434049) (xy 330.13904 -28.434538)
			(xy 330.124247 -28.4344) (xy 330.094749 -28.432113) (xy 330.080112 -28.429966) (xy 330.06919 -28.428188)
			(xy 330.047854 -28.434284) (xy 329.980544 -28.491688) (xy 329.97252 -28.499258) (xy 329.963304 -28.519277)
			(xy 329.962764 -28.530296) (xy 329.962764 -28.834588) (xy 329.96332 -28.845604) (xy 329.972528 -28.86562)
			(xy 329.980544 -28.873196) (xy 330.047854 -28.9306) (xy 330.06919 -28.936696) (xy 330.080112 -28.934918)
			(xy 330.09475 -28.932781) (xy 330.124247 -28.93049) (xy 330.13904 -28.930346) (xy 330.166286 -28.930927)
			(xy 330.220223 -28.938687) (xy 330.272506 -28.954044) (xy 330.322073 -28.976684) (xy 330.367912 -29.006148)
			(xy 330.409093 -29.041835) (xy 330.444776 -29.08302) (xy 330.474235 -29.128863) (xy 330.49687 -29.178431)
			(xy 330.512221 -29.230716) (xy 330.519976 -29.284654) (xy 330.519976 -29.339146) (xy 330.512221 -29.393084)
			(xy 330.49687 -29.445369) (xy 330.474235 -29.494937) (xy 330.444776 -29.54078) (xy 330.409093 -29.581965)
			(xy 330.367912 -29.617652) (xy 330.322073 -29.647116) (xy 330.272506 -29.669756) (xy 330.220223 -29.685113)
			(xy 330.166286 -29.692873) (xy 330.13904 -29.693362) (xy 330.113114 -29.692915) (xy 330.061737 -29.685914)
			(xy 330.011781 -29.67202) (xy 329.964166 -29.651491) (xy 329.919769 -29.624704) (xy 329.879408 -29.592153)
			(xy 329.843826 -29.554437) (xy 329.828398 -29.533596) (xy 329.822652 -29.52627) (xy 329.807154 -29.51598)
			(xy 329.798172 -29.51353) (xy 329.767946 -29.506672) (xy 329.75867 -29.504921) (xy 329.740006 -29.507664)
			(xy 329.731624 -29.512006) (xy 329.705642 -29.526289) (xy 329.650792 -29.548803) (xy 329.593491 -29.564033)
			(xy 329.534701 -29.571722) (xy 329.505056 -29.572204) (xy 329.475414 -29.571696) (xy 329.416632 -29.563978)
			(xy 329.359333 -29.548755) (xy 329.304473 -29.526279) (xy 329.278488 -29.512006) (xy 329.270083 -29.507743)
			(xy 329.251446 -29.50502) (xy 329.242166 -29.506672) (xy 329.21194 -29.51353) (xy 329.202943 -29.515946)
			(xy 329.18744 -29.526247) (xy 329.181714 -29.533596) (xy 329.166301 -29.554451) (xy 329.13073 -29.592187)
			(xy 329.090372 -29.624753) (xy 329.045973 -29.651548) (xy 328.998352 -29.672078) (xy 328.948387 -29.685963)
			(xy 328.897001 -29.692948) (xy 328.871072 -29.693362) (xy 328.843819 -29.692966) (xy 328.789868 -29.685206)
			(xy 328.73757 -29.669846) (xy 328.68799 -29.647201) (xy 328.642138 -29.61773) (xy 328.600946 -29.582034)
			(xy 328.565253 -29.54084) (xy 328.535786 -29.494985) (xy 328.513144 -29.445404) (xy 328.497789 -29.393105)
			(xy 328.490032 -29.339153) (xy 326.767497 -29.339153) (xy 326.783044 -29.356505) (xy 326.813817 -29.403018)
			(xy 326.837489 -29.453515) (xy 326.853557 -29.506922) (xy 326.861677 -29.562098) (xy 326.862186 -29.589984)
			(xy 326.861677 -29.61787) (xy 326.853557 -29.673046) (xy 326.837489 -29.726453) (xy 326.813817 -29.77695)
			(xy 326.783044 -29.823463) (xy 326.745827 -29.865) (xy 326.702959 -29.900675) (xy 326.655353 -29.929729)
			(xy 326.604024 -29.951541) (xy 326.550067 -29.965647) (xy 326.49463 -29.971747) (xy 326.438896 -29.96971)
			(xy 326.384053 -29.95958) (xy 326.331269 -29.941573) (xy 326.281669 -29.916072) (xy 326.236311 -29.883621)
			(xy 326.196162 -29.844912) (xy 326.162076 -29.800769) (xy 326.13478 -29.752134) (xy 326.114857 -29.700043)
			(xy 326.102731 -29.645606) (xy 326.09866 -29.589984) (xy 324.830186 -29.589984) (xy 324.829677 -29.61787)
			(xy 324.821557 -29.673046) (xy 324.805489 -29.726453) (xy 324.781817 -29.77695) (xy 324.751044 -29.823463)
			(xy 324.713827 -29.865) (xy 324.670959 -29.900675) (xy 324.623353 -29.929729) (xy 324.572024 -29.951541)
			(xy 324.518067 -29.965647) (xy 324.46263 -29.971747) (xy 324.406896 -29.96971) (xy 324.352053 -29.95958)
			(xy 324.299269 -29.941573) (xy 324.249669 -29.916072) (xy 324.204311 -29.883621) (xy 324.164162 -29.844912)
			(xy 324.130076 -29.800769) (xy 324.10278 -29.752134) (xy 324.082857 -29.700043) (xy 324.070731 -29.645606)
			(xy 324.06666 -29.589984) (xy 322.326254 -29.589984) (xy 322.325745 -29.61787) (xy 322.317625 -29.673046)
			(xy 322.301557 -29.726453) (xy 322.277885 -29.77695) (xy 322.247112 -29.823463) (xy 322.209895 -29.865)
			(xy 322.167027 -29.900675) (xy 322.119421 -29.929729) (xy 322.068092 -29.951541) (xy 322.014135 -29.965647)
			(xy 321.958698 -29.971747) (xy 321.902964 -29.96971) (xy 321.848121 -29.95958) (xy 321.795337 -29.941573)
			(xy 321.745737 -29.916072) (xy 321.700379 -29.883621) (xy 321.66023 -29.844912) (xy 321.626144 -29.800769)
			(xy 321.598848 -29.752134) (xy 321.578925 -29.700043) (xy 321.566799 -29.645606) (xy 321.562728 -29.589984)
			(xy 320.229738 -29.589984) (xy 320.229738 -29.617251) (xy 320.221982 -29.671197) (xy 320.206629 -29.723491)
			(xy 320.183989 -29.773068) (xy 320.154525 -29.818918) (xy 320.118836 -29.860109) (xy 320.077649 -29.895802)
			(xy 320.031801 -29.925271) (xy 319.982227 -29.947915) (xy 319.929934 -29.963274) (xy 319.875989 -29.971036)
			(xy 319.848738 -29.971492) (xy 319.845944 -29.971492) (xy 319.835981 -29.971976) (xy 319.817553 -29.97956)
			(xy 319.81013 -29.986224) (xy 319.758822 -30.037024) (xy 319.751977 -30.044423) (xy 319.744248 -30.063021)
			(xy 319.743836 -30.073092) (xy 319.743836 -30.906974) (xy 319.744273 -30.917037) (xy 319.752011 -30.935619)
			(xy 319.758822 -30.943042) (xy 319.81013 -30.993842) (xy 319.817543 -31.000517) (xy 319.835979 -31.008082)
			(xy 319.845944 -31.008574) (xy 319.848738 -31.008574) (xy 319.875989 -31.009062) (xy 319.929935 -31.016824)
			(xy 319.982228 -31.032183) (xy 320.031802 -31.054827) (xy 320.07765 -31.084296) (xy 320.118838 -31.119989)
			(xy 320.154527 -31.16118) (xy 320.183991 -31.207031) (xy 320.20663 -31.256608) (xy 320.221984 -31.308902)
			(xy 320.22974 -31.362849) (xy 320.22974 -31.417351) (xy 320.221984 -31.471298) (xy 320.20663 -31.523592)
			(xy 320.183991 -31.573169) (xy 320.154527 -31.61902) (xy 320.134353 -31.642304) (xy 321.606416 -31.642304)
			(xy 321.610487 -31.586682) (xy 321.622613 -31.532245) (xy 321.642536 -31.480154) (xy 321.669832 -31.431519)
			(xy 321.703918 -31.387376) (xy 321.744067 -31.348667) (xy 321.789425 -31.316216) (xy 321.839025 -31.290715)
			(xy 321.891809 -31.272708) (xy 321.946652 -31.262578) (xy 322.002386 -31.260541) (xy 322.057823 -31.266641)
			(xy 322.11178 -31.280747) (xy 322.163109 -31.302559) (xy 322.210715 -31.331613) (xy 322.253583 -31.367288)
			(xy 322.274006 -31.390082) (xy 324.06666 -31.390082) (xy 324.070731 -31.33446) (xy 324.082857 -31.280023)
			(xy 324.10278 -31.227932) (xy 324.130076 -31.179297) (xy 324.164162 -31.135154) (xy 324.204311 -31.096445)
			(xy 324.249669 -31.063994) (xy 324.299269 -31.038493) (xy 324.352053 -31.020486) (xy 324.406896 -31.010356)
			(xy 324.46263 -31.008319) (xy 324.518067 -31.014419) (xy 324.572024 -31.028525) (xy 324.623353 -31.050337)
			(xy 324.670959 -31.079391) (xy 324.713827 -31.115066) (xy 324.751044 -31.156603) (xy 324.781817 -31.203116)
			(xy 324.805489 -31.253613) (xy 324.821557 -31.30702) (xy 324.829677 -31.362196) (xy 324.830186 -31.390082)
			(xy 326.09866 -31.390082) (xy 326.102731 -31.33446) (xy 326.114857 -31.280023) (xy 326.13478 -31.227932)
			(xy 326.162076 -31.179297) (xy 326.196162 -31.135154) (xy 326.236311 -31.096445) (xy 326.281669 -31.063994)
			(xy 326.331269 -31.038493) (xy 326.384053 -31.020486) (xy 326.438896 -31.010356) (xy 326.49463 -31.008319)
			(xy 326.550067 -31.014419) (xy 326.604024 -31.028525) (xy 326.655353 -31.050337) (xy 326.702959 -31.079391)
			(xy 326.745827 -31.115066) (xy 326.783044 -31.156603) (xy 326.813817 -31.203116) (xy 326.837489 -31.253613)
			(xy 326.853557 -31.30702) (xy 326.861677 -31.362196) (xy 326.862186 -31.390082) (xy 326.861677 -31.417968)
			(xy 326.853557 -31.473144) (xy 326.837489 -31.526551) (xy 326.813817 -31.577048) (xy 326.783044 -31.623561)
			(xy 326.745827 -31.665098) (xy 326.727618 -31.680252) (xy 328.49005 -31.680252) (xy 328.49005 -31.625748)
			(xy 328.497806 -31.571799) (xy 328.513161 -31.519502) (xy 328.535802 -31.469923) (xy 328.565268 -31.424071)
			(xy 328.600959 -31.382879) (xy 328.642149 -31.347184) (xy 328.687999 -31.317715) (xy 328.737576 -31.295071)
			(xy 328.789871 -31.279712) (xy 328.84382 -31.271952) (xy 328.871072 -31.271464) (xy 328.896999 -31.271891)
			(xy 328.948377 -31.278895) (xy 328.998334 -31.292791) (xy 329.045949 -31.313323) (xy 329.090346 -31.340113)
			(xy 329.130707 -31.372668) (xy 329.166287 -31.410388) (xy 329.181714 -31.43123) (xy 329.187451 -31.438564)
			(xy 329.202956 -31.448849) (xy 329.21194 -31.451296) (xy 329.242166 -31.458154) (xy 329.251442 -31.459909)
			(xy 329.270106 -31.457163) (xy 329.278488 -31.45282) (xy 329.304483 -31.438583) (xy 329.35935 -31.416166)
			(xy 329.416648 -31.401005) (xy 329.475421 -31.393351) (xy 329.505056 -31.392876) (xy 329.534694 -31.393335)
			(xy 329.593476 -31.400956) (xy 329.650779 -31.416114) (xy 329.705641 -31.438556) (xy 329.731624 -31.45282)
			(xy 329.740028 -31.457087) (xy 329.758666 -31.459809) (xy 329.767946 -31.458154) (xy 329.798172 -31.451296)
			(xy 329.807167 -31.448876) (xy 329.822671 -31.438577) (xy 329.828398 -31.43123) (xy 329.843782 -31.410353)
			(xy 329.87936 -31.372621) (xy 329.919724 -31.340059) (xy 329.964128 -31.313268) (xy 330.011754 -31.292742)
			(xy 330.061721 -31.278859) (xy 330.113109 -31.271877) (xy 330.13904 -31.271464) (xy 330.166287 -31.272009)
			(xy 330.220227 -31.279769) (xy 330.272513 -31.295127) (xy 330.322081 -31.317769) (xy 330.367923 -31.347234)
			(xy 330.409106 -31.382923) (xy 330.44479 -31.424109) (xy 330.474251 -31.469954) (xy 330.496887 -31.519525)
			(xy 330.512239 -31.571812) (xy 330.519994 -31.625753) (xy 330.519994 -31.680247) (xy 330.512239 -31.734188)
			(xy 330.496887 -31.786475) (xy 330.474251 -31.836046) (xy 330.44479 -31.881891) (xy 330.409106 -31.923077)
			(xy 330.367923 -31.958766) (xy 330.322081 -31.988231) (xy 330.272513 -32.010873) (xy 330.220227 -32.026231)
			(xy 330.166287 -32.033991) (xy 330.13904 -32.03448) (xy 330.124247 -32.034342) (xy 330.094749 -32.032055)
			(xy 330.080112 -32.029908) (xy 330.06919 -32.02813) (xy 330.047854 -32.034226) (xy 329.980544 -32.09163)
			(xy 329.972501 -32.099183) (xy 329.963296 -32.119215) (xy 329.962764 -32.130238) (xy 329.962764 -32.43453)
			(xy 329.963296 -32.445549) (xy 329.972521 -32.465565) (xy 329.980544 -32.473138) (xy 330.047854 -32.530542)
			(xy 330.06919 -32.536638) (xy 330.080112 -32.53486) (xy 330.09475 -32.532723) (xy 330.124247 -32.530432)
			(xy 330.13904 -32.530288) (xy 330.166289 -32.530784) (xy 330.220232 -32.538546) (xy 330.272521 -32.553904)
			(xy 330.322093 -32.576547) (xy 330.367938 -32.606014) (xy 330.409123 -32.641705) (xy 330.44481 -32.682894)
			(xy 330.474272 -32.728742) (xy 330.49691 -32.778316) (xy 330.512263 -32.830607) (xy 330.520018 -32.884551)
			(xy 330.520018 -32.939049) (xy 330.512263 -32.992993) (xy 330.49691 -33.045284) (xy 330.474272 -33.094858)
			(xy 330.44481 -33.140706) (xy 330.409123 -33.181895) (xy 330.367938 -33.217586) (xy 330.322093 -33.247053)
			(xy 330.272521 -33.269696) (xy 330.220232 -33.285054) (xy 330.166289 -33.292816) (xy 330.13904 -33.293304)
			(xy 330.113115 -33.29284) (xy 330.061739 -33.285839) (xy 330.011784 -33.271947) (xy 329.96417 -33.251421)
			(xy 329.919773 -33.224637) (xy 329.879411 -33.192089) (xy 329.843827 -33.154377) (xy 329.828398 -33.133538)
			(xy 329.822664 -33.126202) (xy 329.807157 -33.115919) (xy 329.798172 -33.113472) (xy 329.767946 -33.106614)
			(xy 329.75867 -33.104858) (xy 329.740006 -33.107603) (xy 329.731624 -33.111948) (xy 329.705625 -33.126177)
			(xy 329.650759 -33.148597) (xy 329.593463 -33.163761) (xy 329.53469 -33.171416) (xy 329.505056 -33.171892)
			(xy 329.475418 -33.171432) (xy 329.416636 -33.163812) (xy 329.359333 -33.148654) (xy 329.304471 -33.126213)
			(xy 329.278488 -33.111948) (xy 329.270082 -33.107686) (xy 329.251446 -33.104962) (xy 329.242166 -33.106614)
			(xy 329.21194 -33.113472) (xy 329.20295 -33.115907) (xy 329.187445 -33.126196) (xy 329.181714 -33.133538)
			(xy 329.166313 -33.154402) (xy 329.130739 -33.192136) (xy 329.090379 -33.2247) (xy 329.045977 -33.251493)
			(xy 328.998354 -33.272021) (xy 328.948388 -33.285906) (xy 328.897002 -33.29289) (xy 328.871072 -33.293304)
			(xy 328.843822 -33.292824) (xy 328.789877 -33.285064) (xy 328.737585 -33.269707) (xy 328.68801 -33.247064)
			(xy 328.642163 -33.217596) (xy 328.600976 -33.181905) (xy 328.565287 -33.140715) (xy 328.535823 -33.094865)
			(xy 328.513183 -33.045289) (xy 328.49783 -32.992996) (xy 328.490074 -32.93905) (xy 328.490074 -32.88455)
			(xy 328.49783 -32.830604) (xy 328.513183 -32.778311) (xy 328.535823 -32.728735) (xy 328.565287 -32.682885)
			(xy 328.600976 -32.641695) (xy 328.642163 -32.606004) (xy 328.68801 -32.576536) (xy 328.737585 -32.553893)
			(xy 328.789877 -32.538536) (xy 328.843822 -32.530776) (xy 328.871072 -32.530288) (xy 328.885865 -32.530425)
			(xy 328.915363 -32.532713) (xy 328.93 -32.53486) (xy 328.940922 -32.536638) (xy 328.962258 -32.530542)
			(xy 329.029568 -32.473138) (xy 329.037583 -32.465559) (xy 329.046803 -32.445547) (xy 329.047348 -32.43453)
			(xy 329.047348 -32.130238) (xy 329.046806 -32.119219) (xy 329.037591 -32.099202) (xy 329.029568 -32.09163)
			(xy 328.962258 -32.034226) (xy 328.940922 -32.02813) (xy 328.93 -32.029908) (xy 328.915361 -32.032044)
			(xy 328.885865 -32.034335) (xy 328.871072 -32.03448) (xy 328.84382 -32.034048) (xy 328.789871 -32.026288)
			(xy 328.737576 -32.010929) (xy 328.687999 -31.988285) (xy 328.642149 -31.958816) (xy 328.600959 -31.923121)
			(xy 328.565268 -31.881929) (xy 328.535802 -31.836077) (xy 328.513161 -31.786498) (xy 328.497806 -31.734201)
			(xy 328.49005 -31.680252) (xy 326.727618 -31.680252) (xy 326.702959 -31.700773) (xy 326.655353 -31.729827)
			(xy 326.604024 -31.751639) (xy 326.550067 -31.765745) (xy 326.49463 -31.771845) (xy 326.438896 -31.769808)
			(xy 326.384053 -31.759678) (xy 326.331269 -31.741671) (xy 326.281669 -31.71617) (xy 326.236311 -31.683719)
			(xy 326.196162 -31.64501) (xy 326.162076 -31.600867) (xy 326.13478 -31.552232) (xy 326.114857 -31.500141)
			(xy 326.102731 -31.445704) (xy 326.09866 -31.390082) (xy 324.830186 -31.390082) (xy 324.829677 -31.417968)
			(xy 324.821557 -31.473144) (xy 324.805489 -31.526551) (xy 324.781817 -31.577048) (xy 324.751044 -31.623561)
			(xy 324.713827 -31.665098) (xy 324.670959 -31.700773) (xy 324.623353 -31.729827) (xy 324.572024 -31.751639)
			(xy 324.518067 -31.765745) (xy 324.46263 -31.771845) (xy 324.406896 -31.769808) (xy 324.352053 -31.759678)
			(xy 324.299269 -31.741671) (xy 324.249669 -31.71617) (xy 324.204311 -31.683719) (xy 324.164162 -31.64501)
			(xy 324.130076 -31.600867) (xy 324.10278 -31.552232) (xy 324.082857 -31.500141) (xy 324.070731 -31.445704)
			(xy 324.06666 -31.390082) (xy 322.274006 -31.390082) (xy 322.2908 -31.408825) (xy 322.321573 -31.455338)
			(xy 322.345245 -31.505835) (xy 322.361313 -31.559242) (xy 322.369433 -31.614418) (xy 322.369942 -31.642304)
			(xy 322.369433 -31.67019) (xy 322.361313 -31.725366) (xy 322.345245 -31.778773) (xy 322.321573 -31.82927)
			(xy 322.2908 -31.875783) (xy 322.253583 -31.91732) (xy 322.210715 -31.952995) (xy 322.163109 -31.982049)
			(xy 322.11178 -32.003861) (xy 322.057823 -32.017967) (xy 322.002386 -32.024067) (xy 321.946652 -32.02203)
			(xy 321.891809 -32.0119) (xy 321.839025 -31.993893) (xy 321.789425 -31.968392) (xy 321.744067 -31.935941)
			(xy 321.703918 -31.897232) (xy 321.669832 -31.853089) (xy 321.642536 -31.804454) (xy 321.622613 -31.752363)
			(xy 321.610487 -31.697926) (xy 321.606416 -31.642304) (xy 320.134353 -31.642304) (xy 320.118838 -31.660211)
			(xy 320.07765 -31.695904) (xy 320.031802 -31.725373) (xy 319.982228 -31.748017) (xy 319.929935 -31.763376)
			(xy 319.875989 -31.771138) (xy 319.848738 -31.77159) (xy 319.845944 -31.77159) (xy 319.835981 -31.772074)
			(xy 319.817553 -31.779658) (xy 319.81013 -31.786322) (xy 319.758822 -31.837122) (xy 319.751977 -31.844521)
			(xy 319.744247 -31.863119) (xy 319.743836 -31.87319) (xy 319.743836 -32.707072) (xy 319.744273 -32.717136)
			(xy 319.75201 -32.735718) (xy 319.758822 -32.74314) (xy 319.81013 -32.79394) (xy 319.817543 -32.800615)
			(xy 319.835979 -32.80818) (xy 319.845944 -32.808672) (xy 319.848738 -32.808672) (xy 319.875989 -32.80916)
			(xy 319.929935 -32.816922) (xy 319.982228 -32.832281) (xy 320.031803 -32.854925) (xy 320.077651 -32.884394)
			(xy 320.118839 -32.920088) (xy 320.154528 -32.961279) (xy 320.183993 -33.00713) (xy 320.206632 -33.056707)
			(xy 320.221986 -33.109002) (xy 320.229742 -33.162949) (xy 320.229742 -33.19018) (xy 321.873878 -33.19018)
			(xy 321.877949 -33.134558) (xy 321.890075 -33.080121) (xy 321.909998 -33.02803) (xy 321.937294 -32.979395)
			(xy 321.97138 -32.935252) (xy 322.011529 -32.896543) (xy 322.056887 -32.864092) (xy 322.106487 -32.838591)
			(xy 322.159271 -32.820584) (xy 322.214114 -32.810454) (xy 322.269848 -32.808417) (xy 322.325285 -32.814517)
			(xy 322.379242 -32.828623) (xy 322.430571 -32.850435) (xy 322.478177 -32.879489) (xy 322.521045 -32.915164)
			(xy 322.558262 -32.956701) (xy 322.589035 -33.003214) (xy 322.612707 -33.053711) (xy 322.628775 -33.107118)
			(xy 322.636895 -33.162294) (xy 322.637404 -33.19018) (xy 324.06666 -33.19018) (xy 324.070731 -33.134558)
			(xy 324.082857 -33.080121) (xy 324.10278 -33.02803) (xy 324.130076 -32.979395) (xy 324.164162 -32.935252)
			(xy 324.204311 -32.896543) (xy 324.249669 -32.864092) (xy 324.299269 -32.838591) (xy 324.352053 -32.820584)
			(xy 324.406896 -32.810454) (xy 324.46263 -32.808417) (xy 324.518067 -32.814517) (xy 324.572024 -32.828623)
			(xy 324.623353 -32.850435) (xy 324.670959 -32.879489) (xy 324.713827 -32.915164) (xy 324.751044 -32.956701)
			(xy 324.781817 -33.003214) (xy 324.805489 -33.053711) (xy 324.821557 -33.107118) (xy 324.829677 -33.162294)
			(xy 324.830186 -33.19018) (xy 326.09866 -33.19018) (xy 326.102731 -33.134558) (xy 326.114857 -33.080121)
			(xy 326.13478 -33.02803) (xy 326.162076 -32.979395) (xy 326.196162 -32.935252) (xy 326.236311 -32.896543)
			(xy 326.281669 -32.864092) (xy 326.331269 -32.838591) (xy 326.384053 -32.820584) (xy 326.438896 -32.810454)
			(xy 326.49463 -32.808417) (xy 326.550067 -32.814517) (xy 326.604024 -32.828623) (xy 326.655353 -32.850435)
			(xy 326.702959 -32.879489) (xy 326.745827 -32.915164) (xy 326.783044 -32.956701) (xy 326.813817 -33.003214)
			(xy 326.837489 -33.053711) (xy 326.853557 -33.107118) (xy 326.861677 -33.162294) (xy 326.862186 -33.19018)
			(xy 326.861677 -33.218066) (xy 326.853557 -33.273242) (xy 326.837489 -33.326649) (xy 326.813817 -33.377146)
			(xy 326.783044 -33.423659) (xy 326.745827 -33.465196) (xy 326.702959 -33.500871) (xy 326.655353 -33.529925)
			(xy 326.604024 -33.551737) (xy 326.550067 -33.565843) (xy 326.49463 -33.571943) (xy 326.438896 -33.569906)
			(xy 326.384053 -33.559776) (xy 326.331269 -33.541769) (xy 326.281669 -33.516268) (xy 326.236311 -33.483817)
			(xy 326.196162 -33.445108) (xy 326.162076 -33.400965) (xy 326.13478 -33.35233) (xy 326.114857 -33.300239)
			(xy 326.102731 -33.245802) (xy 326.09866 -33.19018) (xy 324.830186 -33.19018) (xy 324.829677 -33.218066)
			(xy 324.821557 -33.273242) (xy 324.805489 -33.326649) (xy 324.781817 -33.377146) (xy 324.751044 -33.423659)
			(xy 324.713827 -33.465196) (xy 324.670959 -33.500871) (xy 324.623353 -33.529925) (xy 324.572024 -33.551737)
			(xy 324.518067 -33.565843) (xy 324.46263 -33.571943) (xy 324.406896 -33.569906) (xy 324.352053 -33.559776)
			(xy 324.299269 -33.541769) (xy 324.249669 -33.516268) (xy 324.204311 -33.483817) (xy 324.164162 -33.445108)
			(xy 324.130076 -33.400965) (xy 324.10278 -33.35233) (xy 324.082857 -33.300239) (xy 324.070731 -33.245802)
			(xy 324.06666 -33.19018) (xy 322.637404 -33.19018) (xy 322.636895 -33.218066) (xy 322.628775 -33.273242)
			(xy 322.612707 -33.326649) (xy 322.589035 -33.377146) (xy 322.558262 -33.423659) (xy 322.521045 -33.465196)
			(xy 322.478177 -33.500871) (xy 322.430571 -33.529925) (xy 322.379242 -33.551737) (xy 322.325285 -33.565843)
			(xy 322.269848 -33.571943) (xy 322.214114 -33.569906) (xy 322.159271 -33.559776) (xy 322.106487 -33.541769)
			(xy 322.056887 -33.516268) (xy 322.011529 -33.483817) (xy 321.97138 -33.445108) (xy 321.937294 -33.400965)
			(xy 321.909998 -33.35233) (xy 321.890075 -33.300239) (xy 321.877949 -33.245802) (xy 321.873878 -33.19018)
			(xy 320.229742 -33.19018) (xy 320.229742 -33.217451) (xy 320.221986 -33.271398) (xy 320.206632 -33.323693)
			(xy 320.183993 -33.37327) (xy 320.154528 -33.419121) (xy 320.118839 -33.460312) (xy 320.077651 -33.496006)
			(xy 320.031803 -33.525475) (xy 319.982228 -33.548119) (xy 319.929935 -33.563478) (xy 319.875989 -33.57124)
			(xy 319.848738 -33.571688) (xy 319.845944 -33.571688) (xy 319.835981 -33.572172) (xy 319.817553 -33.579756)
			(xy 319.81013 -33.58642) (xy 319.758822 -33.63722) (xy 319.751976 -33.644619) (xy 319.744246 -33.663217)
			(xy 319.743836 -33.673288) (xy 319.743836 -34.506916) (xy 319.744263 -34.516984) (xy 319.751985 -34.535581)
			(xy 319.758822 -34.542984) (xy 319.81013 -34.593784) (xy 319.81754 -34.600465) (xy 319.835977 -34.608039)
			(xy 319.845944 -34.608516) (xy 319.848738 -34.608516) (xy 319.875986 -34.609005) (xy 319.929926 -34.616765)
			(xy 319.982213 -34.632123) (xy 320.031782 -34.654765) (xy 320.077625 -34.68423) (xy 320.118808 -34.719919)
			(xy 320.154493 -34.761106) (xy 320.183954 -34.806951) (xy 320.206591 -34.856523) (xy 320.221943 -34.908811)
			(xy 320.229698 -34.962752) (xy 320.229698 -34.990024) (xy 321.872608 -34.990024) (xy 321.876679 -34.934402)
			(xy 321.888805 -34.879965) (xy 321.908728 -34.827874) (xy 321.936024 -34.779239) (xy 321.97011 -34.735096)
			(xy 322.010259 -34.696387) (xy 322.055617 -34.663936) (xy 322.105217 -34.638435) (xy 322.158001 -34.620428)
			(xy 322.212844 -34.610298) (xy 322.268578 -34.608261) (xy 322.324015 -34.614361) (xy 322.377972 -34.628467)
			(xy 322.429301 -34.650279) (xy 322.476907 -34.679333) (xy 322.519775 -34.715008) (xy 322.556992 -34.756545)
			(xy 322.587765 -34.803058) (xy 322.611437 -34.853555) (xy 322.627505 -34.906962) (xy 322.635625 -34.962138)
			(xy 322.636134 -34.990024) (xy 323.100952 -34.990024) (xy 323.105023 -34.934402) (xy 323.117149 -34.879965)
			(xy 323.137072 -34.827874) (xy 323.164368 -34.779239) (xy 323.198454 -34.735096) (xy 323.238603 -34.696387)
			(xy 323.283961 -34.663936) (xy 323.333561 -34.638435) (xy 323.386345 -34.620428) (xy 323.441188 -34.610298)
			(xy 323.496922 -34.608261) (xy 323.552359 -34.614361) (xy 323.606316 -34.628467) (xy 323.657645 -34.650279)
			(xy 323.705251 -34.679333) (xy 323.748119 -34.715008) (xy 323.785336 -34.756545) (xy 323.816109 -34.803058)
			(xy 323.839781 -34.853555) (xy 323.855849 -34.906962) (xy 323.863969 -34.962138) (xy 323.864478 -34.990024)
			(xy 326.09866 -34.990024) (xy 326.102731 -34.934402) (xy 326.114857 -34.879965) (xy 326.13478 -34.827874)
			(xy 326.162076 -34.779239) (xy 326.196162 -34.735096) (xy 326.236311 -34.696387) (xy 326.281669 -34.663936)
			(xy 326.331269 -34.638435) (xy 326.384053 -34.620428) (xy 326.438896 -34.610298) (xy 326.49463 -34.608261)
			(xy 326.550067 -34.614361) (xy 326.604024 -34.628467) (xy 326.655353 -34.650279) (xy 326.702959 -34.679333)
			(xy 326.745827 -34.715008) (xy 326.783044 -34.756545) (xy 326.813817 -34.803058) (xy 326.837489 -34.853555)
			(xy 326.853557 -34.906962) (xy 326.861677 -34.962138) (xy 326.862186 -34.990024) (xy 326.861677 -35.01791)
			(xy 326.853557 -35.073086) (xy 326.837489 -35.126493) (xy 326.813817 -35.17699) (xy 326.783044 -35.223503)
			(xy 326.745827 -35.26504) (xy 326.702959 -35.300715) (xy 326.655353 -35.329769) (xy 326.604024 -35.351581)
			(xy 326.550067 -35.365687) (xy 326.49463 -35.371787) (xy 326.438896 -35.36975) (xy 326.384053 -35.35962)
			(xy 326.331269 -35.341613) (xy 326.281669 -35.316112) (xy 326.236311 -35.283661) (xy 326.196162 -35.244952)
			(xy 326.162076 -35.200809) (xy 326.13478 -35.152174) (xy 326.114857 -35.100083) (xy 326.102731 -35.045646)
			(xy 326.09866 -34.990024) (xy 323.864478 -34.990024) (xy 323.863969 -35.01791) (xy 323.855849 -35.073086)
			(xy 323.839781 -35.126493) (xy 323.816109 -35.17699) (xy 323.785336 -35.223503) (xy 323.748119 -35.26504)
			(xy 323.705251 -35.300715) (xy 323.657645 -35.329769) (xy 323.606316 -35.351581) (xy 323.552359 -35.365687)
			(xy 323.496922 -35.371787) (xy 323.441188 -35.36975) (xy 323.386345 -35.35962) (xy 323.333561 -35.341613)
			(xy 323.283961 -35.316112) (xy 323.238603 -35.283661) (xy 323.198454 -35.244952) (xy 323.164368 -35.200809)
			(xy 323.137072 -35.152174) (xy 323.117149 -35.100083) (xy 323.105023 -35.045646) (xy 323.100952 -34.990024)
			(xy 322.636134 -34.990024) (xy 322.635625 -35.01791) (xy 322.627505 -35.073086) (xy 322.611437 -35.126493)
			(xy 322.587765 -35.17699) (xy 322.556992 -35.223503) (xy 322.519775 -35.26504) (xy 322.476907 -35.300715)
			(xy 322.429301 -35.329769) (xy 322.377972 -35.351581) (xy 322.324015 -35.365687) (xy 322.268578 -35.371787)
			(xy 322.212844 -35.36975) (xy 322.158001 -35.35962) (xy 322.105217 -35.341613) (xy 322.055617 -35.316112)
			(xy 322.010259 -35.283661) (xy 321.97011 -35.244952) (xy 321.936024 -35.200809) (xy 321.908728 -35.152174)
			(xy 321.888805 -35.100083) (xy 321.876679 -35.045646) (xy 321.872608 -34.990024) (xy 320.229698 -34.990024)
			(xy 320.229698 -35.017248) (xy 320.221943 -35.071189) (xy 320.206591 -35.123477) (xy 320.183954 -35.173049)
			(xy 320.154493 -35.218894) (xy 320.118808 -35.260081) (xy 320.077625 -35.29577) (xy 320.031782 -35.325235)
			(xy 319.982213 -35.347877) (xy 319.929926 -35.363235) (xy 319.875986 -35.370995) (xy 319.848738 -35.371532)
			(xy 319.845944 -35.371532) (xy 319.835982 -35.372017) (xy 319.817558 -35.379606) (xy 319.81013 -35.386264)
			(xy 319.758822 -35.437064) (xy 319.751983 -35.444465) (xy 319.744269 -35.463063) (xy 319.743836 -35.473132)
			(xy 319.743836 -38.193437) (xy 321.298071 -38.193437) (xy 321.298071 -38.106563) (xy 321.306086 -38.020059)
			(xy 321.32205 -37.934663) (xy 321.345824 -37.851105) (xy 321.377207 -37.770097) (xy 321.415931 -37.69233)
			(xy 321.461664 -37.618468) (xy 321.514018 -37.549141) (xy 321.572546 -37.48494) (xy 321.636747 -37.426413)
			(xy 321.706075 -37.37406) (xy 321.779937 -37.328327) (xy 321.857704 -37.289604) (xy 321.938713 -37.258222)
			(xy 322.022271 -37.234448) (xy 322.107667 -37.218485) (xy 322.194171 -37.21047) (xy 322.237608 -37.209984)
			(xy 322.315586 -37.209984) (xy 322.325608 -37.209569) (xy 322.344128 -37.2019) (xy 322.358302 -37.187726)
			(xy 322.365969 -37.169206) (xy 322.366386 -37.159184) (xy 322.366386 -37.151564) (xy 322.362068 -37.137594)
			(xy 322.358004 -37.131244) (xy 322.334085 -37.094009) (xy 322.292384 -37.015944) (xy 322.257999 -36.93439)
			(xy 322.231221 -36.850033) (xy 322.212272 -36.76358) (xy 322.201312 -36.675755) (xy 322.198434 -36.587297)
			(xy 322.203661 -36.498946) (xy 322.216949 -36.411443) (xy 322.238187 -36.325524) (xy 322.267196 -36.241908)
			(xy 322.303734 -36.161296) (xy 322.347495 -36.084366) (xy 322.398109 -36.011762) (xy 322.455155 -35.944093)
			(xy 322.518152 -35.881927) (xy 322.586572 -35.825786) (xy 322.659842 -35.776139) (xy 322.737347 -35.733405)
			(xy 322.818436 -35.69794) (xy 322.90243 -35.670044) (xy 322.988624 -35.649948) (xy 323.076295 -35.637824)
			(xy 323.164708 -35.633771) (xy 323.253121 -35.637824) (xy 323.340792 -35.649948) (xy 323.426986 -35.670044)
			(xy 323.51098 -35.69794) (xy 323.592069 -35.733405) (xy 323.669574 -35.776139) (xy 323.742844 -35.825786)
			(xy 323.811264 -35.881927) (xy 323.874261 -35.944093) (xy 323.931307 -36.011762) (xy 323.981921 -36.084366)
			(xy 324.025682 -36.161296) (xy 324.06222 -36.241908) (xy 324.091229 -36.325524) (xy 324.112467 -36.411443)
			(xy 324.125755 -36.498946) (xy 324.130982 -36.587297) (xy 324.128104 -36.675755) (xy 324.117144 -36.76358)
			(xy 324.098195 -36.850033) (xy 324.071417 -36.93439) (xy 324.037032 -37.015944) (xy 323.995331 -37.094009)
			(xy 323.971412 -37.131244) (xy 323.96303 -37.143944) (xy 323.96303 -37.159184) (xy 323.963433 -37.169208)
			(xy 323.971103 -37.18773) (xy 323.985281 -37.201904) (xy 324.003806 -37.20957) (xy 324.01383 -37.209984)
			(xy 324.091808 -37.209984) (xy 324.135248 -37.21041) (xy 324.221756 -37.218427) (xy 324.307156 -37.234392)
			(xy 324.390719 -37.258168) (xy 324.471731 -37.289553) (xy 324.549502 -37.328279) (xy 324.623368 -37.374015)
			(xy 324.692699 -37.426372) (xy 324.756903 -37.484902) (xy 324.815433 -37.549107) (xy 324.867789 -37.618439)
			(xy 324.913525 -37.692305) (xy 324.95225 -37.770076) (xy 324.983635 -37.851089) (xy 325.00741 -37.934652)
			(xy 325.023374 -38.020052) (xy 325.03139 -38.10656) (xy 325.03139 -38.19344) (xy 325.023374 -38.279948)
			(xy 325.00741 -38.365348) (xy 324.983635 -38.448911) (xy 324.95225 -38.529924) (xy 324.913525 -38.607695)
			(xy 324.867789 -38.681561) (xy 324.815433 -38.750893) (xy 324.756903 -38.815098) (xy 324.692699 -38.873628)
			(xy 324.623368 -38.925985) (xy 324.549502 -38.971721) (xy 324.471731 -39.010447) (xy 324.390719 -39.041832)
			(xy 324.307156 -39.065608) (xy 324.221756 -39.081573) (xy 324.135248 -39.08959) (xy 324.091808 -39.090092)
			(xy 322.237608 -39.090092) (xy 322.194171 -39.08953) (xy 322.107667 -39.081515) (xy 322.022271 -39.065552)
			(xy 321.938713 -39.041778) (xy 321.857704 -39.010396) (xy 321.779937 -38.971673) (xy 321.706075 -38.92594)
			(xy 321.636747 -38.873587) (xy 321.572546 -38.81506) (xy 321.514018 -38.750859) (xy 321.461664 -38.681532)
			(xy 321.415931 -38.60767) (xy 321.377207 -38.529903) (xy 321.345824 -38.448895) (xy 321.32205 -38.365337)
			(xy 321.306086 -38.279941) (xy 321.298071 -38.193437) (xy 319.743836 -38.193437) (xy 319.743836 -42.849038)
			(xy 331.091792 -42.849038) (xy 331.095863 -42.793416) (xy 331.107989 -42.738979) (xy 331.127912 -42.686888)
			(xy 331.155208 -42.638253) (xy 331.189294 -42.59411) (xy 331.229443 -42.555401) (xy 331.274801 -42.52295)
			(xy 331.324401 -42.497449) (xy 331.377185 -42.479442) (xy 331.432028 -42.469312) (xy 331.487762 -42.467275)
			(xy 331.543199 -42.473375) (xy 331.597156 -42.487481) (xy 331.648485 -42.509293) (xy 331.696091 -42.538347)
			(xy 331.738959 -42.574022) (xy 331.776176 -42.615559) (xy 331.806949 -42.662072) (xy 331.830621 -42.712569)
			(xy 331.846689 -42.765976) (xy 331.854809 -42.821152) (xy 331.855318 -42.849038) (xy 331.854809 -42.876924)
			(xy 331.846689 -42.9321) (xy 331.830621 -42.985507) (xy 331.806949 -43.036004) (xy 331.776176 -43.082517)
			(xy 331.738959 -43.124054) (xy 331.696091 -43.159729) (xy 331.648485 -43.188783) (xy 331.597156 -43.210595)
			(xy 331.543199 -43.224701) (xy 331.487762 -43.230801) (xy 331.432028 -43.228764) (xy 331.377185 -43.218634)
			(xy 331.324401 -43.200627) (xy 331.274801 -43.175126) (xy 331.229443 -43.142675) (xy 331.189294 -43.103966)
			(xy 331.155208 -43.059823) (xy 331.127912 -43.011188) (xy 331.107989 -42.959097) (xy 331.095863 -42.90466)
			(xy 331.091792 -42.849038) (xy 319.743836 -42.849038) (xy 319.743836 -43.766228) (xy 330.33765 -43.766228)
			(xy 330.33765 -43.706292) (xy 330.345473 -43.64687) (xy 330.360986 -43.588977) (xy 330.383922 -43.533604)
			(xy 330.413889 -43.481698) (xy 330.450376 -43.434148) (xy 330.492756 -43.391768) (xy 330.540306 -43.355281)
			(xy 330.592212 -43.325314) (xy 330.647585 -43.302378) (xy 330.705478 -43.286865) (xy 330.7649 -43.279042)
			(xy 330.824836 -43.279042) (xy 330.884258 -43.286865) (xy 330.942151 -43.302378) (xy 330.997524 -43.325314)
			(xy 331.04943 -43.355281) (xy 331.09698 -43.391768) (xy 331.13936 -43.434148) (xy 331.175847 -43.481698)
			(xy 331.205814 -43.533604) (xy 331.22875 -43.588977) (xy 331.244263 -43.64687) (xy 331.252086 -43.706292)
			(xy 331.252576 -43.73626) (xy 331.252086 -43.766228) (xy 331.244263 -43.82565) (xy 331.22875 -43.883543)
			(xy 331.205814 -43.938916) (xy 331.175847 -43.990822) (xy 331.13936 -44.038372) (xy 331.09698 -44.080752)
			(xy 331.04943 -44.117239) (xy 330.997524 -44.147206) (xy 330.942151 -44.170142) (xy 330.884258 -44.185655)
			(xy 330.824836 -44.193478) (xy 330.7649 -44.193478) (xy 330.705478 -44.185655) (xy 330.647585 -44.170142)
			(xy 330.592212 -44.147206) (xy 330.540306 -44.117239) (xy 330.492756 -44.080752) (xy 330.450376 -44.038372)
			(xy 330.413889 -43.990822) (xy 330.383922 -43.938916) (xy 330.360986 -43.883543) (xy 330.345473 -43.82565)
			(xy 330.33765 -43.766228) (xy 319.743836 -43.766228) (xy 319.743836 -43.807126) (xy 319.744296 -43.817004)
			(xy 319.751734 -43.835306) (xy 319.758314 -43.842686) (xy 319.758568 -43.84294) (xy 320.236596 -44.320968)
			(xy 320.237104 -44.321476) (xy 320.244489 -44.328048) (xy 320.262788 -44.335477) (xy 320.272664 -44.335954)
		)
		(stroke
			(width 0)
			(type solid)
		)
		(fill yes)
		(layer "B.Cu")
		(net "P12V_SSD11")
	)
	(gr_poly
		(pts
			(xy 446.514728 -44.24807) (xy 446.524908 -44.247629) (xy 446.543672 -44.239727) (xy 446.557876 -44.225141)
			(xy 446.561972 -44.215812) (xy 446.602358 -44.112942) (xy 446.5955 -44.082716) (xy 446.583816 -44.072048)
			(xy 446.561124 -44.050301) (xy 446.521311 -44.001667) (xy 446.488522 -43.948046) (xy 446.463373 -43.890445)
			(xy 446.446337 -43.829946) (xy 446.437734 -43.767686) (xy 446.437258 -43.73626) (xy 446.437748 -43.706292)
			(xy 446.445571 -43.64687) (xy 446.461084 -43.588977) (xy 446.48402 -43.533604) (xy 446.513987 -43.481698)
			(xy 446.550474 -43.434148) (xy 446.592854 -43.391768) (xy 446.640404 -43.355281) (xy 446.69231 -43.325314)
			(xy 446.747683 -43.302378) (xy 446.805576 -43.286865) (xy 446.864998 -43.279042) (xy 446.924934 -43.279042)
			(xy 446.984356 -43.286865) (xy 447.042249 -43.302378) (xy 447.097622 -43.325314) (xy 447.149528 -43.355281)
			(xy 447.197078 -43.391768) (xy 447.239458 -43.434148) (xy 447.275945 -43.481698) (xy 447.305912 -43.533604)
			(xy 447.328848 -43.588977) (xy 447.344361 -43.64687) (xy 447.352184 -43.706292) (xy 447.352674 -43.73626)
			(xy 447.352593 -43.748987) (xy 447.351197 -43.774401) (xy 447.34988 -43.78706) (xy 447.350134 -43.78706)
			(xy 447.345925 -43.819423) (xy 447.329516 -43.882587) (xy 447.3043 -43.942779) (xy 447.270788 -43.998777)
			(xy 447.229659 -44.049447) (xy 447.206116 -44.072048) (xy 447.194686 -44.08297) (xy 447.187574 -44.113196)
			(xy 447.22796 -44.215812) (xy 447.232098 -44.225114) (xy 447.246298 -44.239679) (xy 447.265034 -44.2476)
			(xy 447.275204 -44.24807) (xy 448.177412 -44.24807) (xy 448.187289 -44.247611) (xy 448.205586 -44.240165)
			(xy 448.212972 -44.233592) (xy 448.213226 -44.233338) (xy 448.772534 -43.67403) (xy 448.773042 -43.673522)
			(xy 448.779621 -43.66614) (xy 448.787064 -43.647841) (xy 448.78752 -43.637962) (xy 448.78752 -35.109658)
			(xy 448.768978 -35.083496) (xy 448.753738 -35.078162) (xy 448.727465 -35.06832) (xy 448.6779 -35.042033)
			(xy 448.632718 -35.008773) (xy 448.592891 -34.969258) (xy 448.575684 -34.947098) (xy 448.57035 -34.939986)
			(xy 448.548252 -34.925254) (xy 448.5443 -34.922824) (xy 448.53574 -34.919248) (xy 448.531234 -34.918142)
			(xy 448.501008 -34.911284) (xy 448.482212 -34.914078) (xy 448.47383 -34.91865) (xy 448.455449 -34.928877)
			(xy 448.417162 -34.946306) (xy 448.397376 -34.953448) (xy 448.373176 -34.961492) (xy 448.323442 -34.972787)
			(xy 448.272762 -34.978489) (xy 448.247262 -34.978848) (xy 448.221762 -34.978485) (xy 448.171082 -34.972787)
			(xy 448.12135 -34.961489) (xy 448.097148 -34.953448) (xy 448.077364 -34.946302) (xy 448.039077 -34.928874)
			(xy 448.020694 -34.91865) (xy 448.012312 -34.914078) (xy 447.993516 -34.911284) (xy 447.96329 -34.918142)
			(xy 447.958769 -34.919202) (xy 447.950199 -34.922775) (xy 447.946272 -34.925254) (xy 447.92392 -34.94024)
			(xy 447.91884 -34.947352) (xy 447.900689 -34.970651) (xy 447.858409 -35.011888) (xy 447.810277 -35.046113)
			(xy 447.757444 -35.072508) (xy 447.701172 -35.09044) (xy 447.642808 -35.099482) (xy 447.613278 -35.100006)
			(xy 447.602356 -35.100006) (xy 447.602102 -35.099752) (xy 447.575385 -35.098518) (xy 447.522668 -35.0895)
			(xy 447.471726 -35.073209) (xy 447.423558 -35.049965) (xy 447.379108 -35.020223) (xy 447.339245 -34.984566)
			(xy 447.304752 -34.943692) (xy 447.276304 -34.898403) (xy 447.254458 -34.849585) (xy 447.239642 -34.798195)
			(xy 447.232147 -34.745239) (xy 447.23177 -34.718498) (xy 447.232256 -34.691246) (xy 447.240013 -34.637298)
			(xy 447.255368 -34.585002) (xy 447.278009 -34.535423) (xy 447.307475 -34.489572) (xy 447.343166 -34.44838)
			(xy 447.384356 -34.412687) (xy 447.430206 -34.383218) (xy 447.479783 -34.360575) (xy 447.532078 -34.345217)
			(xy 447.586026 -34.337457) (xy 447.613278 -34.33699) (xy 447.628071 -34.337135) (xy 447.657567 -34.339427)
			(xy 447.672206 -34.341562) (xy 447.683128 -34.34334) (xy 447.704464 -34.337244) (xy 447.780156 -34.272728)
			(xy 447.7893 -34.252662) (xy 447.7893 -33.93694) (xy 447.7893 -33.92551) (xy 447.780156 -33.905444)
			(xy 447.704464 -33.840928) (xy 447.683128 -33.834832) (xy 447.672206 -33.83661) (xy 447.65738 -33.838782)
			(xy 447.6275 -33.841069) (xy 447.612516 -33.841182) (xy 447.612262 -33.841182) (xy 447.58506 -33.840625)
			(xy 447.531226 -33.832749) (xy 447.479057 -33.817304) (xy 447.429612 -33.794603) (xy 447.383894 -33.765108)
			(xy 447.34283 -33.729417) (xy 447.307253 -33.688253) (xy 447.277886 -33.642453) (xy 447.255323 -33.592945)
			(xy 447.240024 -33.540733) (xy 447.232298 -33.486878) (xy 447.23177 -33.459674) (xy 447.232258 -33.432423)
			(xy 447.240017 -33.378477) (xy 447.255374 -33.326184) (xy 447.278016 -33.276609) (xy 447.307483 -33.23076)
			(xy 447.343174 -33.189571) (xy 447.384364 -33.153881) (xy 447.430213 -33.124414) (xy 447.479788 -33.101773)
			(xy 447.532081 -33.086416) (xy 447.586027 -33.078657) (xy 447.613278 -33.078166) (xy 447.613532 -33.078166)
			(xy 447.643039 -33.078719) (xy 447.701349 -33.087806) (xy 447.757566 -33.105758) (xy 447.81035 -33.132148)
			(xy 447.858445 -33.166346) (xy 447.900703 -33.207539) (xy 447.91884 -33.23082) (xy 447.92392 -33.237932)
			(xy 447.946272 -33.252918) (xy 447.950224 -33.255348) (xy 447.958785 -33.258922) (xy 447.96329 -33.26003)
			(xy 447.993516 -33.266888) (xy 448.012312 -33.264094) (xy 448.020694 -33.259522) (xy 448.039076 -33.249296)
			(xy 448.077364 -33.23187) (xy 448.097148 -33.224724) (xy 448.121349 -33.216682) (xy 448.171083 -33.20539)
			(xy 448.221763 -33.199691) (xy 448.247262 -33.199324) (xy 448.272761 -33.199689) (xy 448.323441 -33.205388)
			(xy 448.373173 -33.216688) (xy 448.397376 -33.224724) (xy 448.417159 -33.231871) (xy 448.455446 -33.249299)
			(xy 448.47383 -33.259522) (xy 448.482212 -33.264094) (xy 448.501008 -33.266888) (xy 448.531234 -33.26003)
			(xy 448.535754 -33.258967) (xy 448.544321 -33.255389) (xy 448.548252 -33.252918) (xy 448.57035 -33.238186)
			(xy 448.575684 -33.231074) (xy 448.592887 -33.208911) (xy 448.632716 -33.169399) (xy 448.677902 -33.136147)
			(xy 448.727472 -33.109872) (xy 448.753738 -33.10001) (xy 448.768978 -33.094676) (xy 448.78752 -33.068514)
			(xy 448.78752 -31.509462) (xy 448.768978 -31.4833) (xy 448.753738 -31.477966) (xy 448.727465 -31.468124)
			(xy 448.6779 -31.441837) (xy 448.632718 -31.408578) (xy 448.59289 -31.369063) (xy 448.575684 -31.346902)
			(xy 448.57035 -31.33979) (xy 448.548252 -31.325058) (xy 448.5443 -31.322627) (xy 448.53574 -31.319051)
			(xy 448.531234 -31.317946) (xy 448.501008 -31.311088) (xy 448.482212 -31.313882) (xy 448.47383 -31.318454)
			(xy 448.455449 -31.328681) (xy 448.417161 -31.34611) (xy 448.397376 -31.353252) (xy 448.373176 -31.361296)
			(xy 448.323442 -31.37259) (xy 448.272762 -31.378293) (xy 448.247262 -31.378652) (xy 448.221762 -31.378289)
			(xy 448.171082 -31.372591) (xy 448.121349 -31.361293) (xy 448.097148 -31.353252) (xy 448.077364 -31.346106)
			(xy 448.039077 -31.328678) (xy 448.020694 -31.318454) (xy 448.012312 -31.313882) (xy 447.993516 -31.311088)
			(xy 447.96329 -31.317946) (xy 447.958769 -31.319006) (xy 447.950199 -31.322579) (xy 447.946272 -31.325058)
			(xy 447.92392 -31.340044) (xy 447.91884 -31.347156) (xy 447.900689 -31.370455) (xy 447.858409 -31.411692)
			(xy 447.810277 -31.445916) (xy 447.757443 -31.47231) (xy 447.701172 -31.490243) (xy 447.642808 -31.499284)
			(xy 447.613278 -31.49981) (xy 447.602356 -31.49981) (xy 447.602102 -31.499556) (xy 447.575385 -31.498322)
			(xy 447.522668 -31.489304) (xy 447.471726 -31.473013) (xy 447.423558 -31.449769) (xy 447.379107 -31.420027)
			(xy 447.339244 -31.38437) (xy 447.30475 -31.343496) (xy 447.276302 -31.298207) (xy 447.254455 -31.249389)
			(xy 447.239639 -31.197999) (xy 447.232143 -31.145043) (xy 447.23177 -31.118302) (xy 447.232256 -31.09105)
			(xy 447.240012 -31.037101) (xy 447.255367 -30.984805) (xy 447.278007 -30.935226) (xy 447.307473 -30.889374)
			(xy 447.343164 -30.848181) (xy 447.384354 -30.812488) (xy 447.430205 -30.783019) (xy 447.479782 -30.760375)
			(xy 447.532077 -30.745017) (xy 447.586026 -30.737257) (xy 447.613278 -30.736794) (xy 447.628071 -30.736939)
			(xy 447.657567 -30.739231) (xy 447.672206 -30.741366) (xy 447.683128 -30.743144) (xy 447.704464 -30.737048)
			(xy 447.780156 -30.672532) (xy 447.7893 -30.652466) (xy 447.7893 -30.336744) (xy 447.7893 -30.325314)
			(xy 447.780156 -30.305248) (xy 447.704464 -30.240732) (xy 447.683128 -30.234636) (xy 447.672206 -30.236414)
			(xy 447.65738 -30.238586) (xy 447.6275 -30.240873) (xy 447.612516 -30.240986) (xy 447.612262 -30.240986)
			(xy 447.58506 -30.240429) (xy 447.531226 -30.232553) (xy 447.479057 -30.217108) (xy 447.429611 -30.194407)
			(xy 447.383893 -30.164912) (xy 447.342828 -30.129221) (xy 447.307251 -30.088058) (xy 447.277884 -30.042257)
			(xy 447.255321 -29.992749) (xy 447.240021 -29.940537) (xy 447.232294 -29.886682) (xy 447.23177 -29.859478)
			(xy 447.232257 -29.832227) (xy 447.240016 -29.778281) (xy 447.255373 -29.725987) (xy 447.278015 -29.676411)
			(xy 447.307482 -29.630562) (xy 447.343173 -29.589373) (xy 447.384362 -29.553682) (xy 447.430211 -29.524215)
			(xy 447.479787 -29.501573) (xy 447.532081 -29.486216) (xy 447.586027 -29.478457) (xy 447.613278 -29.47797)
			(xy 447.613532 -29.47797) (xy 447.643039 -29.478523) (xy 447.701349 -29.48761) (xy 447.757565 -29.505562)
			(xy 447.81035 -29.531952) (xy 447.858444 -29.566151) (xy 447.900702 -29.607344) (xy 447.91884 -29.630624)
			(xy 447.92392 -29.637736) (xy 447.946272 -29.652722) (xy 447.950224 -29.655152) (xy 447.958785 -29.658725)
			(xy 447.96329 -29.659834) (xy 447.993516 -29.666692) (xy 448.012312 -29.663898) (xy 448.020694 -29.659326)
			(xy 448.039076 -29.6491) (xy 448.077364 -29.631674) (xy 448.097148 -29.624528) (xy 448.121349 -29.616486)
			(xy 448.171083 -29.605194) (xy 448.221763 -29.599495) (xy 448.247262 -29.599128) (xy 448.272761 -29.599493)
			(xy 448.323441 -29.605193) (xy 448.373173 -29.616492) (xy 448.397376 -29.624528) (xy 448.417159 -29.631675)
			(xy 448.455446 -29.649104) (xy 448.47383 -29.659326) (xy 448.482212 -29.663898) (xy 448.501008 -29.666692)
			(xy 448.531234 -29.659834) (xy 448.535754 -29.658771) (xy 448.544321 -29.655193) (xy 448.548252 -29.652722)
			(xy 448.57035 -29.63799) (xy 448.575684 -29.630878) (xy 448.592887 -29.608715) (xy 448.632715 -29.569202)
			(xy 448.677902 -29.53595) (xy 448.727471 -29.509674) (xy 448.753738 -29.499814) (xy 448.768978 -29.49448)
			(xy 448.78752 -29.468318) (xy 448.78752 -19.837908) (xy 448.787311 -19.831327) (xy 448.783967 -19.818597)
			(xy 448.780916 -19.812762) (xy 448.765676 -19.786346) (xy 448.757548 -19.77771) (xy 448.752214 -19.774154)
			(xy 448.730415 -19.75965) (xy 448.690631 -19.725613) (xy 448.655871 -19.686457) (xy 448.640962 -19.664934)
			(xy 448.640708 -19.66468) (xy 448.640708 -19.664426) (xy 448.634422 -19.656126) (xy 448.616861 -19.644973)
			(xy 448.606672 -19.642836) (xy 448.533266 -19.631152) (xy 448.522901 -19.629971) (xy 448.502696 -19.635077)
			(xy 448.49415 -19.641058) (xy 448.473992 -19.656166) (xy 448.430461 -19.681517) (xy 448.383975 -19.700926)
			(xy 448.335341 -19.714056) (xy 448.285404 -19.720679) (xy 448.260216 -19.721068) (xy 448.252596 -19.721068)
			(xy 448.225703 -19.72007) (xy 448.172583 -19.711445) (xy 448.121203 -19.69544) (xy 448.072582 -19.672372)
			(xy 448.027686 -19.642699) (xy 447.987407 -19.60701) (xy 447.952543 -19.566015) (xy 447.923788 -19.520526)
			(xy 447.901712 -19.471447) (xy 447.886753 -19.419752) (xy 447.879208 -19.366468) (xy 447.878708 -19.33956)
			(xy 447.879197 -19.312311) (xy 447.886958 -19.258369) (xy 447.902317 -19.20608) (xy 447.924961 -19.156509)
			(xy 447.954428 -19.110664) (xy 447.99012 -19.06948) (xy 448.031309 -19.033795) (xy 448.077158 -19.004334)
			(xy 448.126732 -18.981697) (xy 448.179023 -18.966346) (xy 448.232967 -18.958593) (xy 448.260216 -18.958052)
			(xy 448.26428 -18.958052) (xy 448.27952 -18.958306) (xy 448.305682 -18.941288) (xy 448.3481 -18.840196)
			(xy 448.351649 -18.83075) (xy 448.351758 -18.810589) (xy 448.344046 -18.791961) (xy 448.337178 -18.78457)
			(xy 447.967862 -18.415254) (xy 447.96075 -18.407888) (xy 447.941954 -18.400268) (xy 436.229252 -18.400268)
			(xy 436.219185 -18.400699) (xy 436.20059 -18.408422) (xy 436.193184 -18.415254) (xy 435.85892 -18.749518)
			(xy 435.851554 -18.75663) (xy 435.843934 -18.775426) (xy 435.843934 -21.738336) (xy 437.716676 -21.738336)
			(xy 437.717167 -21.709596) (xy 437.725799 -21.652767) (xy 437.742857 -21.597877) (xy 437.767955 -21.546165)
			(xy 437.800527 -21.498804) (xy 437.8198 -21.477478) (xy 437.826404 -21.470366) (xy 437.833516 -21.45284)
			(xy 437.833516 -21.363432) (xy 437.826404 -21.345906) (xy 437.8198 -21.338794) (xy 437.800566 -21.317436)
			(xy 437.768002 -21.270078) (xy 437.74291 -21.218371) (xy 437.725858 -21.163485) (xy 437.717233 -21.106663)
			(xy 437.717229 -21.04919) (xy 437.725846 -20.992366) (xy 437.74289 -20.937478) (xy 437.767975 -20.885767)
			(xy 437.800533 -20.838405) (xy 437.8198 -20.817078) (xy 437.826404 -20.809966) (xy 437.833516 -20.79244)
			(xy 437.833516 -20.703032) (xy 437.826404 -20.685506) (xy 437.8198 -20.678394) (xy 437.800566 -20.657036)
			(xy 437.768002 -20.609678) (xy 437.74291 -20.557971) (xy 437.725858 -20.503085) (xy 437.717233 -20.446263)
			(xy 437.717229 -20.38879) (xy 437.725846 -20.331966) (xy 437.74289 -20.277078) (xy 437.767975 -20.225367)
			(xy 437.800533 -20.178005) (xy 437.8198 -20.156678) (xy 437.826404 -20.149566) (xy 437.833516 -20.13204)
			(xy 437.833516 -20.042632) (xy 437.826404 -20.025106) (xy 437.8198 -20.017994) (xy 437.800566 -19.996636)
			(xy 437.768002 -19.949278) (xy 437.74291 -19.897571) (xy 437.725858 -19.842685) (xy 437.717233 -19.785863)
			(xy 437.717229 -19.72839) (xy 437.725846 -19.671566) (xy 437.74289 -19.616678) (xy 437.767975 -19.564967)
			(xy 437.800533 -19.517605) (xy 437.8198 -19.496278) (xy 437.826404 -19.489166) (xy 437.833516 -19.47164)
			(xy 437.833516 -19.382232) (xy 437.826404 -19.364706) (xy 437.8198 -19.357594) (xy 437.800557 -19.336243)
			(xy 437.767985 -19.288888) (xy 437.742886 -19.237183) (xy 437.725829 -19.182297) (xy 437.7172 -19.125474)
			(xy 437.716676 -19.096736) (xy 437.717162 -19.069485) (xy 437.724918 -19.015537) (xy 437.740273 -18.963242)
			(xy 437.762915 -18.913665) (xy 437.792381 -18.867815) (xy 437.828072 -18.826624) (xy 437.869263 -18.790933)
			(xy 437.915113 -18.761467) (xy 437.96469 -18.738825) (xy 438.016985 -18.72347) (xy 438.070933 -18.715714)
			(xy 438.125435 -18.715714) (xy 438.179383 -18.72347) (xy 438.231678 -18.738825) (xy 438.281255 -18.761467)
			(xy 438.327105 -18.790933) (xy 438.368296 -18.826624) (xy 438.403987 -18.867815) (xy 438.433453 -18.913665)
			(xy 438.456095 -18.963242) (xy 438.47145 -19.015537) (xy 438.479206 -19.069485) (xy 438.479692 -19.096736)
			(xy 438.479192 -19.125476) (xy 438.470564 -19.182304) (xy 438.453509 -19.237195) (xy 438.428412 -19.288907)
			(xy 438.395841 -19.336268) (xy 438.376568 -19.357594) (xy 438.369964 -19.364706) (xy 438.362852 -19.382232)
			(xy 438.362852 -19.47164) (xy 438.369964 -19.489166) (xy 438.376568 -19.496278) (xy 438.395875 -19.517574)
			(xy 438.42844 -19.564941) (xy 438.45353 -19.616658) (xy 438.470577 -19.671554) (xy 438.479197 -19.728385)
			(xy 438.479193 -19.785867) (xy 438.470566 -19.842698) (xy 438.45351 -19.897591) (xy 438.428413 -19.949304)
			(xy 438.395842 -19.996667) (xy 438.376568 -20.017994) (xy 438.369964 -20.025106) (xy 438.362852 -20.042632)
			(xy 438.362852 -20.13204) (xy 438.369964 -20.149566) (xy 438.376568 -20.156678) (xy 438.395875 -20.177974)
			(xy 438.42844 -20.225341) (xy 438.45353 -20.277058) (xy 438.470577 -20.331954) (xy 438.474158 -20.35556)
			(xy 447.878198 -20.35556) (xy 447.882269 -20.299938) (xy 447.894395 -20.245501) (xy 447.914318 -20.19341)
			(xy 447.941614 -20.144775) (xy 447.9757 -20.100632) (xy 448.015849 -20.061923) (xy 448.061207 -20.029472)
			(xy 448.110807 -20.003971) (xy 448.163591 -19.985964) (xy 448.218434 -19.975834) (xy 448.274168 -19.973797)
			(xy 448.329605 -19.979897) (xy 448.383562 -19.994003) (xy 448.434891 -20.015815) (xy 448.482497 -20.044869)
			(xy 448.525365 -20.080544) (xy 448.562582 -20.122081) (xy 448.593355 -20.168594) (xy 448.617027 -20.219091)
			(xy 448.633095 -20.272498) (xy 448.641215 -20.327674) (xy 448.641724 -20.35556) (xy 448.641215 -20.383446)
			(xy 448.633095 -20.438622) (xy 448.617027 -20.492029) (xy 448.593355 -20.542526) (xy 448.562582 -20.589039)
			(xy 448.525365 -20.630576) (xy 448.482497 -20.666251) (xy 448.434891 -20.695305) (xy 448.383562 -20.717117)
			(xy 448.329605 -20.731223) (xy 448.274168 -20.737323) (xy 448.218434 -20.735286) (xy 448.163591 -20.725156)
			(xy 448.110807 -20.707149) (xy 448.061207 -20.681648) (xy 448.015849 -20.649197) (xy 447.9757 -20.610488)
			(xy 447.941614 -20.566345) (xy 447.914318 -20.51771) (xy 447.894395 -20.465619) (xy 447.882269 -20.411182)
			(xy 447.878198 -20.35556) (xy 438.474158 -20.35556) (xy 438.479197 -20.388785) (xy 438.479193 -20.446267)
			(xy 438.470566 -20.503098) (xy 438.45351 -20.557991) (xy 438.428413 -20.609704) (xy 438.395842 -20.657067)
			(xy 438.376568 -20.678394) (xy 438.369964 -20.685506) (xy 438.362852 -20.703032) (xy 438.362852 -20.79244)
			(xy 438.369964 -20.809966) (xy 438.376568 -20.817078) (xy 438.395875 -20.838374) (xy 438.42844 -20.885741)
			(xy 438.45353 -20.937458) (xy 438.470577 -20.992354) (xy 438.479197 -21.049185) (xy 438.479193 -21.106667)
			(xy 438.470566 -21.163498) (xy 438.45351 -21.218391) (xy 438.428413 -21.270104) (xy 438.395842 -21.317467)
			(xy 438.376568 -21.338794) (xy 438.369964 -21.345906) (xy 438.362852 -21.363432) (xy 438.362852 -21.37156)
			(xy 447.878198 -21.37156) (xy 447.882269 -21.315938) (xy 447.894395 -21.261501) (xy 447.914318 -21.20941)
			(xy 447.941614 -21.160775) (xy 447.9757 -21.116632) (xy 448.015849 -21.077923) (xy 448.061207 -21.045472)
			(xy 448.110807 -21.019971) (xy 448.163591 -21.001964) (xy 448.218434 -20.991834) (xy 448.274168 -20.989797)
			(xy 448.329605 -20.995897) (xy 448.383562 -21.010003) (xy 448.434891 -21.031815) (xy 448.482497 -21.060869)
			(xy 448.525365 -21.096544) (xy 448.562582 -21.138081) (xy 448.593355 -21.184594) (xy 448.617027 -21.235091)
			(xy 448.633095 -21.288498) (xy 448.641215 -21.343674) (xy 448.641724 -21.37156) (xy 448.641215 -21.399446)
			(xy 448.633095 -21.454622) (xy 448.617027 -21.508029) (xy 448.593355 -21.558526) (xy 448.562582 -21.605039)
			(xy 448.525365 -21.646576) (xy 448.482497 -21.682251) (xy 448.434891 -21.711305) (xy 448.383562 -21.733117)
			(xy 448.329605 -21.747223) (xy 448.274168 -21.753323) (xy 448.218434 -21.751286) (xy 448.163591 -21.741156)
			(xy 448.110807 -21.723149) (xy 448.061207 -21.697648) (xy 448.015849 -21.665197) (xy 447.9757 -21.626488)
			(xy 447.941614 -21.582345) (xy 447.914318 -21.53371) (xy 447.894395 -21.481619) (xy 447.882269 -21.427182)
			(xy 447.878198 -21.37156) (xy 438.362852 -21.37156) (xy 438.362852 -21.45284) (xy 438.369964 -21.470366)
			(xy 438.376568 -21.477478) (xy 438.395857 -21.498789) (xy 438.42842 -21.546156) (xy 438.453509 -21.597871)
			(xy 438.470556 -21.652766) (xy 438.479174 -21.709596) (xy 438.479692 -21.738336) (xy 438.479206 -21.765587)
			(xy 438.47145 -21.819535) (xy 438.456095 -21.87183) (xy 438.433453 -21.921407) (xy 438.403987 -21.967257)
			(xy 438.368296 -22.008448) (xy 438.327105 -22.044139) (xy 438.281255 -22.073605) (xy 438.231678 -22.096247)
			(xy 438.179383 -22.111602) (xy 438.125435 -22.119358) (xy 438.070933 -22.119358) (xy 438.016985 -22.111602)
			(xy 437.96469 -22.096247) (xy 437.915113 -22.073605) (xy 437.869263 -22.044139) (xy 437.828072 -22.008448)
			(xy 437.792381 -21.967257) (xy 437.762915 -21.921407) (xy 437.740273 -21.87183) (xy 437.724918 -21.819535)
			(xy 437.717162 -21.765587) (xy 437.716676 -21.738336) (xy 435.843934 -21.738336) (xy 435.843934 -22.995152)
			(xy 437.587024 -22.995152) (xy 437.594845 -22.935721) (xy 437.610357 -22.877819) (xy 437.633294 -22.822437)
			(xy 437.663263 -22.770523) (xy 437.699753 -22.722965) (xy 437.742138 -22.680576) (xy 437.789693 -22.644083)
			(xy 437.841605 -22.61411) (xy 437.896985 -22.591168) (xy 437.954885 -22.575652) (xy 438.014316 -22.567826)
			(xy 438.07426 -22.567824) (xy 438.133691 -22.575647) (xy 438.191593 -22.591161) (xy 438.246974 -22.614099)
			(xy 438.298887 -22.64407) (xy 438.346444 -22.680561) (xy 438.388831 -22.722947) (xy 438.425323 -22.770503)
			(xy 438.455296 -22.822415) (xy 438.478236 -22.877796) (xy 438.49375 -22.935697) (xy 438.501575 -22.995128)
			(xy 438.502044 -23.0251) (xy 438.501821 -23.045661) (xy 438.498132 -23.086618) (xy 438.494678 -23.106888)
			(xy 438.492138 -23.120604) (xy 438.501028 -23.145496) (xy 438.587642 -23.22068) (xy 438.61355 -23.226014)
			(xy 438.626758 -23.221696) (xy 438.655963 -23.212616) (xy 438.716323 -23.202787) (xy 438.7469 -23.202138)
			(xy 438.765827 -23.202408) (xy 438.803489 -23.20622) (xy 438.822084 -23.209758) (xy 438.834784 -23.212044)
			(xy 438.858406 -23.205186) (xy 438.936892 -23.128986) (xy 438.944512 -23.105618) (xy 438.94248 -23.092918)
			(xy 438.93942 -23.073888) (xy 438.936109 -23.035483) (xy 438.935876 -23.01621) (xy 438.93635 -22.98624)
			(xy 438.944173 -22.926813) (xy 438.959686 -22.868915) (xy 438.982623 -22.813537) (xy 439.012592 -22.761627)
			(xy 439.04908 -22.714073) (xy 439.091464 -22.671688) (xy 439.139017 -22.635198) (xy 439.190927 -22.605228)
			(xy 439.246304 -22.582289) (xy 439.304201 -22.566775) (xy 439.363629 -22.558951) (xy 439.423569 -22.558951)
			(xy 439.482996 -22.566775) (xy 439.540894 -22.582288) (xy 439.596271 -22.605227) (xy 439.648181 -22.635197)
			(xy 439.695734 -22.671686) (xy 439.738118 -22.71407) (xy 439.774607 -22.761624) (xy 439.804576 -22.813534)
			(xy 439.827514 -22.868912) (xy 439.843026 -22.92681) (xy 439.850849 -22.986237) (xy 439.850848 -23.046177)
			(xy 439.843024 -23.105605) (xy 439.827509 -23.163502) (xy 439.80457 -23.218879) (xy 439.774598 -23.270788)
			(xy 439.738108 -23.318341) (xy 439.695723 -23.360723) (xy 439.648168 -23.397211) (xy 439.596258 -23.42718)
			(xy 439.54088 -23.450116) (xy 439.482982 -23.465628) (xy 439.423554 -23.47345) (xy 439.393584 -23.473918)
			(xy 439.359338 -23.473324) (xy 439.291613 -23.463113) (xy 439.25871 -23.453598) (xy 439.246518 -23.449788)
			(xy 439.222388 -23.45436) (xy 439.136536 -23.522178) (xy 439.12663 -23.544784) (xy 439.127646 -23.557738)
			(xy 439.128408 -23.583646) (xy 439.127922 -23.610897) (xy 439.126618 -23.619964) (xy 442.309232 -23.619964)
			(xy 442.309232 -23.560028) (xy 442.317055 -23.500606) (xy 442.332568 -23.442713) (xy 442.355504 -23.38734)
			(xy 442.385471 -23.335434) (xy 442.421958 -23.287884) (xy 442.464338 -23.245504) (xy 442.511888 -23.209017)
			(xy 442.563794 -23.17905) (xy 442.619167 -23.156114) (xy 442.67706 -23.140601) (xy 442.736482 -23.132778)
			(xy 442.796418 -23.132778) (xy 442.85584 -23.140601) (xy 442.913733 -23.156114) (xy 442.969106 -23.17905)
			(xy 443.021012 -23.209017) (xy 443.068562 -23.245504) (xy 443.110942 -23.287884) (xy 443.147429 -23.335434)
			(xy 443.177396 -23.38734) (xy 443.200332 -23.442713) (xy 443.215845 -23.500606) (xy 443.223668 -23.560028)
			(xy 443.224158 -23.589996) (xy 443.223668 -23.619964) (xy 443.215845 -23.679386) (xy 443.200332 -23.737279)
			(xy 443.177396 -23.792652) (xy 443.147429 -23.844558) (xy 443.119989 -23.880318) (xy 443.54064 -23.880318)
			(xy 443.544711 -23.824696) (xy 443.556837 -23.770259) (xy 443.57676 -23.718168) (xy 443.604056 -23.669533)
			(xy 443.638142 -23.62539) (xy 443.678291 -23.586681) (xy 443.723649 -23.55423) (xy 443.773249 -23.528729)
			(xy 443.826033 -23.510722) (xy 443.880876 -23.500592) (xy 443.93661 -23.498555) (xy 443.992047 -23.504655)
			(xy 444.046004 -23.518761) (xy 444.097333 -23.540573) (xy 444.144939 -23.569627) (xy 444.187807 -23.605302)
			(xy 444.225024 -23.646839) (xy 444.255797 -23.693352) (xy 444.279469 -23.743849) (xy 444.295537 -23.797256)
			(xy 444.303657 -23.852432) (xy 444.304166 -23.880318) (xy 444.55664 -23.880318) (xy 444.560711 -23.824696)
			(xy 444.572837 -23.770259) (xy 444.59276 -23.718168) (xy 444.620056 -23.669533) (xy 444.654142 -23.62539)
			(xy 444.694291 -23.586681) (xy 444.739649 -23.55423) (xy 444.789249 -23.528729) (xy 444.842033 -23.510722)
			(xy 444.896876 -23.500592) (xy 444.95261 -23.498555) (xy 445.008047 -23.504655) (xy 445.062004 -23.518761)
			(xy 445.113333 -23.540573) (xy 445.160939 -23.569627) (xy 445.203807 -23.605302) (xy 445.241024 -23.646839)
			(xy 445.271797 -23.693352) (xy 445.295469 -23.743849) (xy 445.311537 -23.797256) (xy 445.319657 -23.852432)
			(xy 445.320166 -23.880318) (xy 445.57264 -23.880318) (xy 445.576711 -23.824696) (xy 445.588837 -23.770259)
			(xy 445.60876 -23.718168) (xy 445.636056 -23.669533) (xy 445.670142 -23.62539) (xy 445.710291 -23.586681)
			(xy 445.755649 -23.55423) (xy 445.805249 -23.528729) (xy 445.858033 -23.510722) (xy 445.912876 -23.500592)
			(xy 445.96861 -23.498555) (xy 446.024047 -23.504655) (xy 446.078004 -23.518761) (xy 446.129333 -23.540573)
			(xy 446.176939 -23.569627) (xy 446.219807 -23.605302) (xy 446.257024 -23.646839) (xy 446.287797 -23.693352)
			(xy 446.311469 -23.743849) (xy 446.327537 -23.797256) (xy 446.335657 -23.852432) (xy 446.336166 -23.880318)
			(xy 446.590926 -23.880318) (xy 446.594997 -23.824696) (xy 446.607123 -23.770259) (xy 446.627046 -23.718168)
			(xy 446.654342 -23.669533) (xy 446.688428 -23.62539) (xy 446.728577 -23.586681) (xy 446.773935 -23.55423)
			(xy 446.823535 -23.528729) (xy 446.876319 -23.510722) (xy 446.931162 -23.500592) (xy 446.986896 -23.498555)
			(xy 447.042333 -23.504655) (xy 447.09629 -23.518761) (xy 447.147619 -23.540573) (xy 447.195225 -23.569627)
			(xy 447.238093 -23.605302) (xy 447.27531 -23.646839) (xy 447.306083 -23.693352) (xy 447.329755 -23.743849)
			(xy 447.345823 -23.797256) (xy 447.353943 -23.852432) (xy 447.354452 -23.880318) (xy 447.353943 -23.908204)
			(xy 447.345823 -23.96338) (xy 447.329755 -24.016787) (xy 447.306083 -24.067284) (xy 447.27531 -24.113797)
			(xy 447.238093 -24.155334) (xy 447.195225 -24.191009) (xy 447.147619 -24.220063) (xy 447.09629 -24.241875)
			(xy 447.042333 -24.255981) (xy 446.986896 -24.262081) (xy 446.931162 -24.260044) (xy 446.876319 -24.249914)
			(xy 446.823535 -24.231907) (xy 446.773935 -24.206406) (xy 446.728577 -24.173955) (xy 446.688428 -24.135246)
			(xy 446.654342 -24.091103) (xy 446.627046 -24.042468) (xy 446.607123 -23.990377) (xy 446.594997 -23.93594)
			(xy 446.590926 -23.880318) (xy 446.336166 -23.880318) (xy 446.335657 -23.908204) (xy 446.327537 -23.96338)
			(xy 446.311469 -24.016787) (xy 446.287797 -24.067284) (xy 446.257024 -24.113797) (xy 446.219807 -24.155334)
			(xy 446.176939 -24.191009) (xy 446.129333 -24.220063) (xy 446.078004 -24.241875) (xy 446.024047 -24.255981)
			(xy 445.96861 -24.262081) (xy 445.912876 -24.260044) (xy 445.858033 -24.249914) (xy 445.805249 -24.231907)
			(xy 445.755649 -24.206406) (xy 445.710291 -24.173955) (xy 445.670142 -24.135246) (xy 445.636056 -24.091103)
			(xy 445.60876 -24.042468) (xy 445.588837 -23.990377) (xy 445.576711 -23.93594) (xy 445.57264 -23.880318)
			(xy 445.320166 -23.880318) (xy 445.319657 -23.908204) (xy 445.311537 -23.96338) (xy 445.295469 -24.016787)
			(xy 445.271797 -24.067284) (xy 445.241024 -24.113797) (xy 445.203807 -24.155334) (xy 445.160939 -24.191009)
			(xy 445.113333 -24.220063) (xy 445.062004 -24.241875) (xy 445.008047 -24.255981) (xy 444.95261 -24.262081)
			(xy 444.896876 -24.260044) (xy 444.842033 -24.249914) (xy 444.789249 -24.231907) (xy 444.739649 -24.206406)
			(xy 444.694291 -24.173955) (xy 444.654142 -24.135246) (xy 444.620056 -24.091103) (xy 444.59276 -24.042468)
			(xy 444.572837 -23.990377) (xy 444.560711 -23.93594) (xy 444.55664 -23.880318) (xy 444.304166 -23.880318)
			(xy 444.303657 -23.908204) (xy 444.295537 -23.96338) (xy 444.279469 -24.016787) (xy 444.255797 -24.067284)
			(xy 444.225024 -24.113797) (xy 444.187807 -24.155334) (xy 444.144939 -24.191009) (xy 444.097333 -24.220063)
			(xy 444.046004 -24.241875) (xy 443.992047 -24.255981) (xy 443.93661 -24.262081) (xy 443.880876 -24.260044)
			(xy 443.826033 -24.249914) (xy 443.773249 -24.231907) (xy 443.723649 -24.206406) (xy 443.678291 -24.173955)
			(xy 443.638142 -24.135246) (xy 443.604056 -24.091103) (xy 443.57676 -24.042468) (xy 443.556837 -23.990377)
			(xy 443.544711 -23.93594) (xy 443.54064 -23.880318) (xy 443.119989 -23.880318) (xy 443.110942 -23.892108)
			(xy 443.068562 -23.934488) (xy 443.021012 -23.970975) (xy 442.969106 -24.000942) (xy 442.913733 -24.023878)
			(xy 442.85584 -24.039391) (xy 442.796418 -24.047214) (xy 442.736482 -24.047214) (xy 442.67706 -24.039391)
			(xy 442.619167 -24.023878) (xy 442.563794 -24.000942) (xy 442.511888 -23.970975) (xy 442.464338 -23.934488)
			(xy 442.421958 -23.892108) (xy 442.385471 -23.844558) (xy 442.355504 -23.792652) (xy 442.332568 -23.737279)
			(xy 442.317055 -23.679386) (xy 442.309232 -23.619964) (xy 439.126618 -23.619964) (xy 439.120166 -23.664845)
			(xy 439.104811 -23.71714) (xy 439.082169 -23.766717) (xy 439.052703 -23.812567) (xy 439.017012 -23.853758)
			(xy 438.975821 -23.889449) (xy 438.929971 -23.918915) (xy 438.880394 -23.941557) (xy 438.828099 -23.956912)
			(xy 438.774151 -23.964668) (xy 438.719649 -23.964668) (xy 438.665701 -23.956912) (xy 438.613406 -23.941557)
			(xy 438.563829 -23.918915) (xy 438.517979 -23.889449) (xy 438.476788 -23.853758) (xy 438.441097 -23.812567)
			(xy 438.411631 -23.766717) (xy 438.388989 -23.71714) (xy 438.373634 -23.664845) (xy 438.365878 -23.610897)
			(xy 438.365392 -23.583646) (xy 438.36717 -23.548086) (xy 438.36844 -23.53437) (xy 438.357518 -23.51024)
			(xy 438.264554 -23.44293) (xy 438.238138 -23.439882) (xy 438.225692 -23.44547) (xy 438.196939 -23.457298)
			(xy 438.137031 -23.473931) (xy 438.075423 -23.482306) (xy 438.044336 -23.482808) (xy 438.014364 -23.482377)
			(xy 437.954933 -23.474557) (xy 437.89703 -23.459047) (xy 437.841648 -23.436112) (xy 437.789733 -23.406143)
			(xy 437.742174 -23.369655) (xy 437.699784 -23.327271) (xy 437.66329 -23.279717) (xy 437.633315 -23.227806)
			(xy 437.610372 -23.172427) (xy 437.594854 -23.114526) (xy 437.587027 -23.055096) (xy 437.587024 -22.995152)
			(xy 435.843934 -22.995152) (xy 435.843934 -24.189944) (xy 437.598818 -24.189944) (xy 437.602889 -24.134322)
			(xy 437.615015 -24.079885) (xy 437.634938 -24.027794) (xy 437.662234 -23.979159) (xy 437.69632 -23.935016)
			(xy 437.736469 -23.896307) (xy 437.781827 -23.863856) (xy 437.831427 -23.838355) (xy 437.884211 -23.820348)
			(xy 437.939054 -23.810218) (xy 437.994788 -23.808181) (xy 438.050225 -23.814281) (xy 438.104182 -23.828387)
			(xy 438.155511 -23.850199) (xy 438.203117 -23.879253) (xy 438.245985 -23.914928) (xy 438.283202 -23.956465)
			(xy 438.313975 -24.002978) (xy 438.337647 -24.053475) (xy 438.353715 -24.106882) (xy 438.361835 -24.162058)
			(xy 438.362344 -24.189944) (xy 440.1218 -24.189944) (xy 440.125871 -24.134322) (xy 440.137997 -24.079885)
			(xy 440.15792 -24.027794) (xy 440.185216 -23.979159) (xy 440.219302 -23.935016) (xy 440.259451 -23.896307)
			(xy 440.304809 -23.863856) (xy 440.354409 -23.838355) (xy 440.407193 -23.820348) (xy 440.462036 -23.810218)
			(xy 440.51777 -23.808181) (xy 440.573207 -23.814281) (xy 440.627164 -23.828387) (xy 440.678493 -23.850199)
			(xy 440.726099 -23.879253) (xy 440.768967 -23.914928) (xy 440.806184 -23.956465) (xy 440.836957 -24.002978)
			(xy 440.860629 -24.053475) (xy 440.876697 -24.106882) (xy 440.884817 -24.162058) (xy 440.885326 -24.189944)
			(xy 440.884817 -24.21783) (xy 440.876697 -24.273006) (xy 440.860629 -24.326413) (xy 440.836957 -24.37691)
			(xy 440.806184 -24.423423) (xy 440.768967 -24.46496) (xy 440.726099 -24.500635) (xy 440.678493 -24.529689)
			(xy 440.627164 -24.551501) (xy 440.573207 -24.565607) (xy 440.51777 -24.571707) (xy 440.462036 -24.56967)
			(xy 440.407193 -24.55954) (xy 440.354409 -24.541533) (xy 440.304809 -24.516032) (xy 440.259451 -24.483581)
			(xy 440.219302 -24.444872) (xy 440.185216 -24.400729) (xy 440.15792 -24.352094) (xy 440.137997 -24.300003)
			(xy 440.125871 -24.245566) (xy 440.1218 -24.189944) (xy 438.362344 -24.189944) (xy 438.361835 -24.21783)
			(xy 438.353715 -24.273006) (xy 438.337647 -24.326413) (xy 438.313975 -24.37691) (xy 438.283202 -24.423423)
			(xy 438.245985 -24.46496) (xy 438.203117 -24.500635) (xy 438.155511 -24.529689) (xy 438.104182 -24.551501)
			(xy 438.050225 -24.565607) (xy 437.994788 -24.571707) (xy 437.939054 -24.56967) (xy 437.884211 -24.55954)
			(xy 437.831427 -24.541533) (xy 437.781827 -24.516032) (xy 437.736469 -24.483581) (xy 437.69632 -24.444872)
			(xy 437.662234 -24.400729) (xy 437.634938 -24.352094) (xy 437.615015 -24.300003) (xy 437.602889 -24.245566)
			(xy 437.598818 -24.189944) (xy 435.843934 -24.189944) (xy 435.843934 -25.390094) (xy 440.03341 -25.390094)
			(xy 440.0339 -25.360126) (xy 440.041723 -25.300704) (xy 440.057236 -25.242811) (xy 440.080172 -25.187438)
			(xy 440.110139 -25.135532) (xy 440.146626 -25.087982) (xy 440.189006 -25.045602) (xy 440.236556 -25.009115)
			(xy 440.288462 -24.979148) (xy 440.343835 -24.956212) (xy 440.401728 -24.940699) (xy 440.46115 -24.932876)
			(xy 440.521086 -24.932876) (xy 440.580508 -24.940699) (xy 440.638401 -24.956212) (xy 440.693774 -24.979148)
			(xy 440.74568 -25.009115) (xy 440.79323 -25.045602) (xy 440.83561 -25.087982) (xy 440.872097 -25.135532)
			(xy 440.902064 -25.187438) (xy 440.925 -25.242811) (xy 440.940513 -25.300704) (xy 440.948336 -25.360126)
			(xy 440.948826 -25.390094) (xy 440.948383 -25.418878) (xy 440.941165 -25.475992) (xy 440.926842 -25.53175)
			(xy 440.90564 -25.585272) (xy 440.877895 -25.635713) (xy 440.844043 -25.682276) (xy 440.80462 -25.724227)
			(xy 440.78271 -25.7429) (xy 440.774328 -25.749758) (xy 440.764676 -25.769316) (xy 440.761374 -25.867106)
			(xy 440.769502 -25.887172) (xy 440.77763 -25.894792) (xy 440.796025 -25.912874) (xy 440.828264 -25.953139)
			(xy 440.854789 -25.997377) (xy 440.875117 -26.044784) (xy 440.888879 -26.094496) (xy 440.895823 -26.145607)
			(xy 440.896248 -26.171398) (xy 440.895762 -26.198649) (xy 440.888006 -26.252597) (xy 440.872651 -26.304892)
			(xy 440.850009 -26.354469) (xy 440.820543 -26.400319) (xy 440.784852 -26.44151) (xy 440.743661 -26.477201)
			(xy 440.697811 -26.506667) (xy 440.648234 -26.529309) (xy 440.595939 -26.544664) (xy 440.541991 -26.55242)
			(xy 440.487489 -26.55242) (xy 440.433541 -26.544664) (xy 440.381246 -26.529309) (xy 440.331669 -26.506667)
			(xy 440.285819 -26.477201) (xy 440.244628 -26.44151) (xy 440.208937 -26.400319) (xy 440.179471 -26.354469)
			(xy 440.156829 -26.304892) (xy 440.141474 -26.252597) (xy 440.133718 -26.198649) (xy 440.133232 -26.171398)
			(xy 440.133741 -26.142754) (xy 440.142339 -26.086115) (xy 440.159312 -26.031399) (xy 440.184278 -25.979837)
			(xy 440.216675 -25.932589) (xy 440.235848 -25.911302) (xy 440.243214 -25.903174) (xy 440.250072 -25.8826)
			(xy 440.240928 -25.785064) (xy 440.23026 -25.766268) (xy 440.22137 -25.759918) (xy 440.196838 -25.741348)
			(xy 440.15244 -25.698751) (xy 440.114147 -25.650593) (xy 440.082647 -25.597741) (xy 440.058509 -25.541146)
			(xy 440.042166 -25.481829) (xy 440.033915 -25.420858) (xy 440.03341 -25.390094) (xy 435.843934 -25.390094)
			(xy 435.843934 -25.506934) (xy 435.844364 -25.517001) (xy 435.852091 -25.535593) (xy 435.85892 -25.543002)
			(xy 435.910228 -25.593802) (xy 435.917639 -25.600482) (xy 435.936075 -25.608053) (xy 435.946042 -25.608534)
			(xy 435.948836 -25.608534) (xy 435.976083 -25.609023) (xy 436.03002 -25.616782) (xy 436.082305 -25.632139)
			(xy 436.131872 -25.65478) (xy 436.177713 -25.684244) (xy 436.218894 -25.719931) (xy 436.254578 -25.761116)
			(xy 436.284038 -25.806959) (xy 436.306674 -25.856529) (xy 436.322025 -25.908815) (xy 436.32978 -25.962753)
			(xy 436.32978 -25.990042) (xy 437.598818 -25.990042) (xy 437.602889 -25.93442) (xy 437.615015 -25.879983)
			(xy 437.634938 -25.827892) (xy 437.662234 -25.779257) (xy 437.69632 -25.735114) (xy 437.736469 -25.696405)
			(xy 437.781827 -25.663954) (xy 437.831427 -25.638453) (xy 437.884211 -25.620446) (xy 437.939054 -25.610316)
			(xy 437.994788 -25.608279) (xy 438.050225 -25.614379) (xy 438.104182 -25.628485) (xy 438.155511 -25.650297)
			(xy 438.203117 -25.679351) (xy 438.245985 -25.715026) (xy 438.283202 -25.756563) (xy 438.313975 -25.803076)
			(xy 438.337647 -25.853573) (xy 438.353715 -25.90698) (xy 438.361835 -25.962156) (xy 438.362344 -25.990042)
			(xy 438.361835 -26.017928) (xy 438.353715 -26.073104) (xy 438.337647 -26.126511) (xy 438.313975 -26.177008)
			(xy 438.283202 -26.223521) (xy 438.245985 -26.265058) (xy 438.203117 -26.300733) (xy 438.155511 -26.329787)
			(xy 438.104182 -26.351599) (xy 438.050225 -26.365705) (xy 437.994788 -26.371805) (xy 437.939054 -26.369768)
			(xy 437.884211 -26.359638) (xy 437.831427 -26.341631) (xy 437.781827 -26.31613) (xy 437.736469 -26.283679)
			(xy 437.69632 -26.24497) (xy 437.662234 -26.200827) (xy 437.634938 -26.152192) (xy 437.615015 -26.100101)
			(xy 437.602889 -26.045664) (xy 437.598818 -25.990042) (xy 436.32978 -25.990042) (xy 436.32978 -26.017247)
			(xy 436.322025 -26.071185) (xy 436.306674 -26.123471) (xy 436.284038 -26.173041) (xy 436.254578 -26.218884)
			(xy 436.218894 -26.260069) (xy 436.177713 -26.295756) (xy 436.131872 -26.32522) (xy 436.082305 -26.347861)
			(xy 436.03002 -26.363218) (xy 435.976083 -26.370977) (xy 435.948836 -26.37155) (xy 435.946042 -26.37155)
			(xy 435.93608 -26.372036) (xy 435.917658 -26.379627) (xy 435.910228 -26.386282) (xy 435.85892 -26.437082)
			(xy 435.852084 -26.444484) (xy 435.844377 -26.463082) (xy 435.843934 -26.47315) (xy 435.843934 -27.307032)
			(xy 435.844364 -27.317099) (xy 435.85209 -27.335692) (xy 435.85892 -27.3431) (xy 435.910228 -27.3939)
			(xy 435.917639 -27.40058) (xy 435.936075 -27.408152) (xy 435.946042 -27.408632) (xy 435.948836 -27.408632)
			(xy 435.976083 -27.409121) (xy 436.030021 -27.41688) (xy 436.082306 -27.432237) (xy 436.131873 -27.454878)
			(xy 436.177714 -27.484342) (xy 436.218896 -27.52003) (xy 436.25458 -27.561215) (xy 436.284039 -27.607059)
			(xy 436.306675 -27.656628) (xy 436.322027 -27.708914) (xy 436.329782 -27.762853) (xy 436.329782 -27.79014)
			(xy 437.662826 -27.79014) (xy 437.666897 -27.734518) (xy 437.679023 -27.680081) (xy 437.698946 -27.62799)
			(xy 437.726242 -27.579355) (xy 437.760328 -27.535212) (xy 437.800477 -27.496503) (xy 437.845835 -27.464052)
			(xy 437.895435 -27.438551) (xy 437.948219 -27.420544) (xy 438.003062 -27.410414) (xy 438.058796 -27.408377)
			(xy 438.114233 -27.414477) (xy 438.16819 -27.428583) (xy 438.219519 -27.450395) (xy 438.267125 -27.479449)
			(xy 438.309993 -27.515124) (xy 438.34721 -27.556661) (xy 438.377983 -27.603174) (xy 438.401655 -27.653671)
			(xy 438.417723 -27.707078) (xy 438.425843 -27.762254) (xy 438.426352 -27.79014) (xy 440.166758 -27.79014)
			(xy 440.170829 -27.734518) (xy 440.182955 -27.680081) (xy 440.202878 -27.62799) (xy 440.230174 -27.579355)
			(xy 440.26426 -27.535212) (xy 440.304409 -27.496503) (xy 440.349767 -27.464052) (xy 440.399367 -27.438551)
			(xy 440.452151 -27.420544) (xy 440.506994 -27.410414) (xy 440.562728 -27.408377) (xy 440.618165 -27.414477)
			(xy 440.672122 -27.428583) (xy 440.723451 -27.450395) (xy 440.771057 -27.479449) (xy 440.813925 -27.515124)
			(xy 440.851142 -27.556661) (xy 440.881915 -27.603174) (xy 440.905587 -27.653671) (xy 440.921655 -27.707078)
			(xy 440.929775 -27.762254) (xy 440.930284 -27.79014) (xy 440.929787 -27.817347) (xy 442.199818 -27.817347)
			(xy 442.199818 -27.762853) (xy 442.207573 -27.708913) (xy 442.222925 -27.656626) (xy 442.245562 -27.607055)
			(xy 442.275023 -27.561211) (xy 442.310709 -27.520026) (xy 442.351892 -27.484338) (xy 442.397734 -27.454874)
			(xy 442.447303 -27.432234) (xy 442.499589 -27.416878) (xy 442.553529 -27.40912) (xy 442.580776 -27.408632)
			(xy 442.606083 -27.409039) (xy 442.656255 -27.415707) (xy 442.705107 -27.428943) (xy 442.728604 -27.43835)
			(xy 442.736618 -27.441353) (xy 442.753683 -27.442453) (xy 442.77016 -27.437875) (xy 442.777372 -27.43327)
			(xy 442.802772 -27.41549) (xy 442.809656 -27.410213) (xy 442.819731 -27.396111) (xy 442.82453 -27.379457)
			(xy 442.824362 -27.370786) (xy 442.8236 -27.342846) (xy 442.8236 -26.479246) (xy 442.824108 -26.456894)
			(xy 442.824616 -26.444448) (xy 442.814202 -26.421842) (xy 442.729112 -26.355548) (xy 442.704728 -26.350976)
			(xy 442.69279 -26.354786) (xy 442.665453 -26.362626) (xy 442.609211 -26.371045) (xy 442.580776 -26.37155)
			(xy 442.553529 -26.370978) (xy 442.49959 -26.36322) (xy 442.447304 -26.347864) (xy 442.397735 -26.325224)
			(xy 442.351893 -26.295761) (xy 442.31071 -26.260073) (xy 442.275025 -26.218888) (xy 442.245564 -26.173044)
			(xy 442.222927 -26.123474) (xy 442.207575 -26.071187) (xy 442.19982 -26.017247) (xy 442.19982 -25.962753)
			(xy 442.207575 -25.908813) (xy 442.222927 -25.856526) (xy 442.245564 -25.806956) (xy 442.275025 -25.761112)
			(xy 442.31071 -25.719927) (xy 442.351893 -25.684239) (xy 442.397735 -25.654776) (xy 442.447304 -25.632136)
			(xy 442.49959 -25.61678) (xy 442.553529 -25.609022) (xy 442.580776 -25.608534) (xy 442.609727 -25.609099)
			(xy 442.666968 -25.617832) (xy 442.72223 -25.635117) (xy 442.774245 -25.660555) (xy 442.821818 -25.693563)
			(xy 442.863855 -25.733382) (xy 442.899391 -25.779098) (xy 442.927609 -25.829659) (xy 442.928503 -25.832054)
			(xy 444.488316 -25.832054) (xy 444.488799 -25.805451) (xy 444.496174 -25.752759) (xy 444.510801 -25.701604)
			(xy 444.532398 -25.652979) (xy 444.560545 -25.607828) (xy 444.594694 -25.567028) (xy 444.634184 -25.531371)
			(xy 444.655956 -25.516078) (xy 444.667436 -25.507741) (xy 444.685648 -25.486001) (xy 444.69717 -25.460087)
			(xy 444.701113 -25.432002) (xy 444.697171 -25.403917) (xy 444.68565 -25.378003) (xy 444.66744 -25.356262)
			(xy 444.655956 -25.34793) (xy 444.634194 -25.332623) (xy 444.594714 -25.296959) (xy 444.56057 -25.256158)
			(xy 444.532423 -25.21101) (xy 444.510819 -25.162391) (xy 444.496177 -25.111242) (xy 444.488781 -25.058556)
			(xy 444.488316 -25.031954) (xy 444.488802 -25.004703) (xy 444.496558 -24.950755) (xy 444.511913 -24.89846)
			(xy 444.534555 -24.848883) (xy 444.564021 -24.803033) (xy 444.599712 -24.761842) (xy 444.640903 -24.726151)
			(xy 444.686753 -24.696685) (xy 444.73633 -24.674043) (xy 444.788625 -24.658688) (xy 444.842573 -24.650932)
			(xy 444.897075 -24.650932) (xy 444.951023 -24.658688) (xy 445.003318 -24.674043) (xy 445.052895 -24.696685)
			(xy 445.098745 -24.726151) (xy 445.139936 -24.761842) (xy 445.163137 -24.788618) (xy 447.093322 -24.788618)
			(xy 447.093322 -24.728682) (xy 447.101145 -24.66926) (xy 447.116658 -24.611367) (xy 447.139594 -24.555994)
			(xy 447.169561 -24.504088) (xy 447.206048 -24.456538) (xy 447.248428 -24.414158) (xy 447.295978 -24.377671)
			(xy 447.347884 -24.347704) (xy 447.403257 -24.324768) (xy 447.46115 -24.309255) (xy 447.520572 -24.301432)
			(xy 447.580508 -24.301432) (xy 447.63993 -24.309255) (xy 447.697823 -24.324768) (xy 447.753196 -24.347704)
			(xy 447.805102 -24.377671) (xy 447.852652 -24.414158) (xy 447.895032 -24.456538) (xy 447.931519 -24.504088)
			(xy 447.961486 -24.555994) (xy 447.984422 -24.611367) (xy 447.999935 -24.66926) (xy 448.007758 -24.728682)
			(xy 448.008248 -24.75865) (xy 448.007758 -24.788618) (xy 447.999935 -24.84804) (xy 447.984422 -24.905933)
			(xy 447.961486 -24.961306) (xy 447.931519 -25.013212) (xy 447.895032 -25.060762) (xy 447.852652 -25.103142)
			(xy 447.805102 -25.139629) (xy 447.753196 -25.169596) (xy 447.697823 -25.192532) (xy 447.63993 -25.208045)
			(xy 447.580508 -25.215868) (xy 447.520572 -25.215868) (xy 447.46115 -25.208045) (xy 447.403257 -25.192532)
			(xy 447.347884 -25.169596) (xy 447.295978 -25.139629) (xy 447.248428 -25.103142) (xy 447.206048 -25.060762)
			(xy 447.169561 -25.013212) (xy 447.139594 -24.961306) (xy 447.116658 -24.905933) (xy 447.101145 -24.84804)
			(xy 447.093322 -24.788618) (xy 445.163137 -24.788618) (xy 445.175627 -24.803033) (xy 445.205093 -24.848883)
			(xy 445.227735 -24.89846) (xy 445.24309 -24.950755) (xy 445.250846 -25.004703) (xy 445.251332 -25.031954)
			(xy 445.250878 -25.058558) (xy 445.243501 -25.111252) (xy 445.22887 -25.162409) (xy 445.207269 -25.211035)
			(xy 445.179117 -25.256186) (xy 445.144962 -25.296984) (xy 445.105467 -25.332638) (xy 445.083692 -25.34793)
			(xy 445.072209 -25.35626) (xy 445.054006 -25.378005) (xy 445.042491 -25.403919) (xy 445.038551 -25.432002)
			(xy 445.042492 -25.460085) (xy 445.054009 -25.485999) (xy 445.072212 -25.507743) (xy 445.083692 -25.516078)
			(xy 445.105468 -25.531365) (xy 445.144946 -25.567034) (xy 445.179087 -25.607839) (xy 445.207232 -25.65299)
			(xy 445.228833 -25.701613) (xy 445.243473 -25.752763) (xy 445.250868 -25.805452) (xy 445.251332 -25.832054)
			(xy 445.250846 -25.859305) (xy 445.24309 -25.913253) (xy 445.227735 -25.965548) (xy 445.205093 -26.015125)
			(xy 445.175627 -26.060975) (xy 445.139936 -26.102166) (xy 445.098745 -26.137857) (xy 445.052895 -26.167323)
			(xy 445.003318 -26.189965) (xy 444.951023 -26.20532) (xy 444.897075 -26.213076) (xy 444.842573 -26.213076)
			(xy 444.788625 -26.20532) (xy 444.73633 -26.189965) (xy 444.686753 -26.167323) (xy 444.640903 -26.137857)
			(xy 444.599712 -26.102166) (xy 444.564021 -26.060975) (xy 444.534555 -26.015125) (xy 444.511913 -25.965548)
			(xy 444.496558 -25.913253) (xy 444.488802 -25.859305) (xy 444.488316 -25.832054) (xy 442.928503 -25.832054)
			(xy 442.947861 -25.883904) (xy 442.959681 -25.940588) (xy 442.961776 -25.969468) (xy 442.962284 -25.981914)
			(xy 442.974984 -26.00325) (xy 443.066678 -26.060654) (xy 443.091316 -26.062432) (xy 443.102746 -26.057606)
			(xy 443.131101 -26.046131) (xy 443.190101 -26.029978) (xy 443.250723 -26.02181) (xy 443.281308 -26.021284)
			(xy 443.311287 -26.021754) (xy 443.370733 -26.029584) (xy 443.428647 -26.045109) (xy 443.484039 -26.068062)
			(xy 443.535959 -26.098051) (xy 443.583519 -26.134563) (xy 443.625904 -26.176972) (xy 443.66239 -26.224553)
			(xy 443.69235 -26.276489) (xy 443.715273 -26.331894) (xy 443.723027 -26.360882) (xy 445.389506 -26.360882)
			(xy 445.393577 -26.30526) (xy 445.405703 -26.250823) (xy 445.425626 -26.198732) (xy 445.452922 -26.150097)
			(xy 445.487008 -26.105954) (xy 445.527157 -26.067245) (xy 445.572515 -26.034794) (xy 445.622115 -26.009293)
			(xy 445.674899 -25.991286) (xy 445.729742 -25.981156) (xy 445.785476 -25.979119) (xy 445.840913 -25.985219)
			(xy 445.89487 -25.999325) (xy 445.946199 -26.021137) (xy 445.993805 -26.050191) (xy 446.036673 -26.085866)
			(xy 446.07389 -26.127403) (xy 446.104663 -26.173916) (xy 446.128335 -26.224413) (xy 446.144403 -26.27782)
			(xy 446.152523 -26.332996) (xy 446.153032 -26.360882) (xy 446.405506 -26.360882) (xy 446.409577 -26.30526)
			(xy 446.421703 -26.250823) (xy 446.441626 -26.198732) (xy 446.468922 -26.150097) (xy 446.503008 -26.105954)
			(xy 446.543157 -26.067245) (xy 446.588515 -26.034794) (xy 446.638115 -26.009293) (xy 446.690899 -25.991286)
			(xy 446.745742 -25.981156) (xy 446.801476 -25.979119) (xy 446.856913 -25.985219) (xy 446.91087 -25.999325)
			(xy 446.962199 -26.021137) (xy 447.009805 -26.050191) (xy 447.052673 -26.085866) (xy 447.08989 -26.127403)
			(xy 447.120663 -26.173916) (xy 447.144335 -26.224413) (xy 447.160403 -26.27782) (xy 447.168523 -26.332996)
			(xy 447.169032 -26.360882) (xy 447.168523 -26.388768) (xy 447.160403 -26.443944) (xy 447.144335 -26.497351)
			(xy 447.120663 -26.547848) (xy 447.08989 -26.594361) (xy 447.052673 -26.635898) (xy 447.009805 -26.671573)
			(xy 446.962199 -26.700627) (xy 446.91087 -26.722439) (xy 446.856913 -26.736545) (xy 446.801476 -26.742645)
			(xy 446.745742 -26.740608) (xy 446.690899 -26.730478) (xy 446.638115 -26.712471) (xy 446.588515 -26.68697)
			(xy 446.543157 -26.654519) (xy 446.503008 -26.61581) (xy 446.468922 -26.571667) (xy 446.441626 -26.523032)
			(xy 446.421703 -26.470941) (xy 446.409577 -26.416504) (xy 446.405506 -26.360882) (xy 446.153032 -26.360882)
			(xy 446.152523 -26.388768) (xy 446.144403 -26.443944) (xy 446.128335 -26.497351) (xy 446.104663 -26.547848)
			(xy 446.07389 -26.594361) (xy 446.036673 -26.635898) (xy 445.993805 -26.671573) (xy 445.946199 -26.700627)
			(xy 445.89487 -26.722439) (xy 445.840913 -26.736545) (xy 445.785476 -26.742645) (xy 445.729742 -26.740608)
			(xy 445.674899 -26.730478) (xy 445.622115 -26.712471) (xy 445.572515 -26.68697) (xy 445.527157 -26.654519)
			(xy 445.487008 -26.61581) (xy 445.452922 -26.571667) (xy 445.425626 -26.523032) (xy 445.405703 -26.470941)
			(xy 445.393577 -26.416504) (xy 445.389506 -26.360882) (xy 443.723027 -26.360882) (xy 443.730766 -26.389816)
			(xy 443.738562 -26.449266) (xy 443.739016 -26.479246) (xy 443.739016 -26.971244) (xy 447.150996 -26.971244)
			(xy 447.155067 -26.915622) (xy 447.167193 -26.861185) (xy 447.187116 -26.809094) (xy 447.214412 -26.760459)
			(xy 447.248498 -26.716316) (xy 447.288647 -26.677607) (xy 447.334005 -26.645156) (xy 447.383605 -26.619655)
			(xy 447.436389 -26.601648) (xy 447.491232 -26.591518) (xy 447.546966 -26.589481) (xy 447.602403 -26.595581)
			(xy 447.65636 -26.609687) (xy 447.707689 -26.631499) (xy 447.755295 -26.660553) (xy 447.798163 -26.696228)
			(xy 447.83538 -26.737765) (xy 447.866153 -26.784278) (xy 447.889825 -26.834775) (xy 447.905893 -26.888182)
			(xy 447.914013 -26.943358) (xy 447.914522 -26.971244) (xy 447.914013 -26.99913) (xy 447.905893 -27.054306)
			(xy 447.889825 -27.107713) (xy 447.866153 -27.15821) (xy 447.83538 -27.204723) (xy 447.798163 -27.24626)
			(xy 447.755295 -27.281935) (xy 447.707689 -27.310989) (xy 447.65636 -27.332801) (xy 447.602403 -27.346907)
			(xy 447.546966 -27.353007) (xy 447.491232 -27.35097) (xy 447.436389 -27.34084) (xy 447.383605 -27.322833)
			(xy 447.334005 -27.297332) (xy 447.288647 -27.264881) (xy 447.248498 -27.226172) (xy 447.214412 -27.182029)
			(xy 447.187116 -27.133394) (xy 447.167193 -27.081303) (xy 447.155067 -27.026866) (xy 447.150996 -26.971244)
			(xy 443.739016 -26.971244) (xy 443.739016 -27.342846) (xy 443.738616 -27.372823) (xy 443.730787 -27.432263)
			(xy 443.715269 -27.490173) (xy 443.692328 -27.545564) (xy 443.662356 -27.597488) (xy 443.625865 -27.645057)
			(xy 443.583479 -27.687458) (xy 443.535923 -27.723966) (xy 443.484009 -27.753956) (xy 443.428627 -27.776917)
			(xy 443.370722 -27.792455) (xy 443.311285 -27.800305) (xy 443.281308 -27.800808) (xy 443.250172 -27.800267)
			(xy 443.188476 -27.791806) (xy 443.12849 -27.77508) (xy 443.099698 -27.763216) (xy 443.088522 -27.75839)
			(xy 443.0649 -27.75966) (xy 442.973714 -27.810968) (xy 442.960252 -27.830526) (xy 442.958728 -27.842464)
			(xy 442.9545 -27.869492) (xy 442.93932 -27.922048) (xy 442.916792 -27.971899) (xy 442.887377 -28.018023)
			(xy 442.851678 -28.059474) (xy 442.810426 -28.095403) (xy 442.764467 -28.125074) (xy 442.714742 -28.14788)
			(xy 442.662271 -28.163351) (xy 442.608128 -28.171173) (xy 442.580776 -28.171648) (xy 442.553529 -28.17108)
			(xy 442.499589 -28.163322) (xy 442.447303 -28.147966) (xy 442.397734 -28.125326) (xy 442.351892 -28.095862)
			(xy 442.310709 -28.060174) (xy 442.275023 -28.018989) (xy 442.245562 -27.973145) (xy 442.222925 -27.923574)
			(xy 442.207573 -27.871287) (xy 442.199818 -27.817347) (xy 440.929787 -27.817347) (xy 440.929775 -27.818026)
			(xy 440.921655 -27.873202) (xy 440.905587 -27.926609) (xy 440.881915 -27.977106) (xy 440.851142 -28.023619)
			(xy 440.813925 -28.065156) (xy 440.771057 -28.100831) (xy 440.723451 -28.129885) (xy 440.672122 -28.151697)
			(xy 440.618165 -28.165803) (xy 440.562728 -28.171903) (xy 440.506994 -28.169866) (xy 440.452151 -28.159736)
			(xy 440.399367 -28.141729) (xy 440.349767 -28.116228) (xy 440.304409 -28.083777) (xy 440.26426 -28.045068)
			(xy 440.230174 -28.000925) (xy 440.202878 -27.95229) (xy 440.182955 -27.900199) (xy 440.170829 -27.845762)
			(xy 440.166758 -27.79014) (xy 438.426352 -27.79014) (xy 438.425843 -27.818026) (xy 438.417723 -27.873202)
			(xy 438.401655 -27.926609) (xy 438.377983 -27.977106) (xy 438.34721 -28.023619) (xy 438.309993 -28.065156)
			(xy 438.267125 -28.100831) (xy 438.219519 -28.129885) (xy 438.16819 -28.151697) (xy 438.114233 -28.165803)
			(xy 438.058796 -28.171903) (xy 438.003062 -28.169866) (xy 437.948219 -28.159736) (xy 437.895435 -28.141729)
			(xy 437.845835 -28.116228) (xy 437.800477 -28.083777) (xy 437.760328 -28.045068) (xy 437.726242 -28.000925)
			(xy 437.698946 -27.95229) (xy 437.679023 -27.900199) (xy 437.666897 -27.845762) (xy 437.662826 -27.79014)
			(xy 436.329782 -27.79014) (xy 436.329782 -27.817347) (xy 436.322027 -27.871286) (xy 436.306675 -27.923572)
			(xy 436.284039 -27.973141) (xy 436.25458 -28.018985) (xy 436.218896 -28.06017) (xy 436.177714 -28.095858)
			(xy 436.131873 -28.125322) (xy 436.082306 -28.147963) (xy 436.030021 -28.16332) (xy 435.976083 -28.171079)
			(xy 435.948836 -28.171648) (xy 435.946042 -28.171648) (xy 435.93608 -28.172134) (xy 435.917658 -28.179725)
			(xy 435.910228 -28.18638) (xy 435.85892 -28.23718) (xy 435.852084 -28.244582) (xy 435.844376 -28.26318)
			(xy 435.843934 -28.273248) (xy 435.843934 -29.106876) (xy 435.844372 -29.116939) (xy 435.852109 -29.135521)
			(xy 435.85892 -29.142944) (xy 435.910228 -29.193744) (xy 435.917641 -29.200419) (xy 435.936077 -29.207984)
			(xy 435.946042 -29.208476) (xy 435.948836 -29.208476) (xy 435.976087 -29.208964) (xy 436.030033 -29.216725)
			(xy 436.082325 -29.232084) (xy 436.1319 -29.254728) (xy 436.177748 -29.284197) (xy 436.218936 -29.31989)
			(xy 436.254625 -29.361081) (xy 436.284089 -29.406931) (xy 436.306728 -29.456508) (xy 436.322082 -29.508802)
			(xy 436.329838 -29.562749) (xy 436.329838 -29.589984) (xy 437.662826 -29.589984) (xy 437.666897 -29.534362)
			(xy 437.679023 -29.479925) (xy 437.698946 -29.427834) (xy 437.726242 -29.379199) (xy 437.760328 -29.335056)
			(xy 437.800477 -29.296347) (xy 437.845835 -29.263896) (xy 437.895435 -29.238395) (xy 437.948219 -29.220388)
			(xy 438.003062 -29.210258) (xy 438.058796 -29.208221) (xy 438.114233 -29.214321) (xy 438.16819 -29.228427)
			(xy 438.219519 -29.250239) (xy 438.267125 -29.279293) (xy 438.309993 -29.314968) (xy 438.34721 -29.356505)
			(xy 438.377983 -29.403018) (xy 438.401655 -29.453515) (xy 438.417723 -29.506922) (xy 438.425843 -29.562098)
			(xy 438.426352 -29.589984) (xy 440.166758 -29.589984) (xy 440.170829 -29.534362) (xy 440.182955 -29.479925)
			(xy 440.202878 -29.427834) (xy 440.230174 -29.379199) (xy 440.26426 -29.335056) (xy 440.304409 -29.296347)
			(xy 440.349767 -29.263896) (xy 440.399367 -29.238395) (xy 440.452151 -29.220388) (xy 440.506994 -29.210258)
			(xy 440.562728 -29.208221) (xy 440.618165 -29.214321) (xy 440.672122 -29.228427) (xy 440.723451 -29.250239)
			(xy 440.771057 -29.279293) (xy 440.813925 -29.314968) (xy 440.851142 -29.356505) (xy 440.881915 -29.403018)
			(xy 440.905587 -29.453515) (xy 440.921655 -29.506922) (xy 440.929775 -29.562098) (xy 440.930284 -29.589984)
			(xy 442.198758 -29.589984) (xy 442.202829 -29.534362) (xy 442.214955 -29.479925) (xy 442.234878 -29.427834)
			(xy 442.262174 -29.379199) (xy 442.29626 -29.335056) (xy 442.336409 -29.296347) (xy 442.381767 -29.263896)
			(xy 442.431367 -29.238395) (xy 442.484151 -29.220388) (xy 442.538994 -29.210258) (xy 442.594728 -29.208221)
			(xy 442.650165 -29.214321) (xy 442.704122 -29.228427) (xy 442.755451 -29.250239) (xy 442.803057 -29.279293)
			(xy 442.845925 -29.314968) (xy 442.867595 -29.339153) (xy 444.590132 -29.339153) (xy 444.590132 -29.284647)
			(xy 444.597888 -29.230695) (xy 444.613244 -29.178397) (xy 444.635886 -29.128815) (xy 444.665353 -29.082961)
			(xy 444.701045 -29.041766) (xy 444.742237 -29.006071) (xy 444.788089 -28.9766) (xy 444.837668 -28.953954)
			(xy 444.889966 -28.938595) (xy 444.943917 -28.930834) (xy 444.97117 -28.930346) (xy 444.985963 -28.930483)
			(xy 445.015461 -28.932771) (xy 445.030098 -28.934918) (xy 445.04102 -28.936696) (xy 445.062356 -28.9306)
			(xy 445.129666 -28.873196) (xy 445.137645 -28.865615) (xy 445.146721 -28.845586) (xy 445.147192 -28.834588)
			(xy 445.147192 -28.530296) (xy 445.146691 -28.519306) (xy 445.137613 -28.499294) (xy 445.129666 -28.491688)
			(xy 445.062356 -28.434284) (xy 445.04102 -28.428188) (xy 445.030098 -28.429966) (xy 445.015459 -28.432102)
			(xy 444.985963 -28.434393) (xy 444.97117 -28.434538) (xy 444.943922 -28.43399) (xy 444.889982 -28.42623)
			(xy 444.837695 -28.410874) (xy 444.788126 -28.388233) (xy 444.742283 -28.358768) (xy 444.701099 -28.323079)
			(xy 444.665414 -28.281893) (xy 444.635953 -28.236048) (xy 444.613316 -28.186477) (xy 444.597963 -28.134189)
			(xy 444.590208 -28.080248) (xy 444.590208 -28.025752) (xy 444.597963 -27.971812) (xy 444.613316 -27.919523)
			(xy 444.635953 -27.869952) (xy 444.665414 -27.824107) (xy 444.701099 -27.782921) (xy 444.742283 -27.747232)
			(xy 444.788126 -27.717767) (xy 444.837695 -27.695126) (xy 444.889982 -27.67977) (xy 444.943922 -27.67201)
			(xy 444.97117 -27.671522) (xy 444.997096 -27.671968) (xy 445.048473 -27.678971) (xy 445.098429 -27.692865)
			(xy 445.146043 -27.713394) (xy 445.19044 -27.740181) (xy 445.230801 -27.772732) (xy 445.266384 -27.810448)
			(xy 445.281812 -27.831288) (xy 445.287538 -27.838631) (xy 445.303051 -27.84891) (xy 445.312038 -27.851354)
			(xy 445.342264 -27.858212) (xy 445.351539 -27.859971) (xy 445.370204 -27.857223) (xy 445.378586 -27.852878)
			(xy 445.404565 -27.83859) (xy 445.459416 -27.816077) (xy 445.516718 -27.800849) (xy 445.575509 -27.793161)
			(xy 445.605154 -27.79268) (xy 445.634796 -27.793186) (xy 445.693578 -27.800905) (xy 445.750877 -27.816129)
			(xy 445.805737 -27.838605) (xy 445.831722 -27.852878) (xy 445.840126 -27.857146) (xy 445.858763 -27.859866)
			(xy 445.868044 -27.858212) (xy 445.89827 -27.851354) (xy 445.90727 -27.848947) (xy 445.922772 -27.83864)
			(xy 445.928496 -27.831288) (xy 445.943898 -27.810425) (xy 445.979472 -27.77269) (xy 446.019831 -27.740125)
			(xy 446.064232 -27.713331) (xy 446.111855 -27.692803) (xy 446.161821 -27.678919) (xy 446.213208 -27.671935)
			(xy 446.239138 -27.671522) (xy 446.26639 -27.67195) (xy 446.320337 -27.679712) (xy 446.372632 -27.695072)
			(xy 446.422208 -27.717717) (xy 446.468057 -27.747186) (xy 446.509246 -27.782881) (xy 446.544936 -27.824073)
			(xy 446.574402 -27.869925) (xy 446.597042 -27.919504) (xy 446.612396 -27.9718) (xy 446.620152 -28.025748)
			(xy 446.620152 -28.080252) (xy 446.612396 -28.1342) (xy 446.597042 -28.186496) (xy 446.574402 -28.236075)
			(xy 446.544936 -28.281927) (xy 446.509246 -28.323119) (xy 446.468057 -28.358814) (xy 446.422208 -28.388283)
			(xy 446.372632 -28.410928) (xy 446.320337 -28.426288) (xy 446.26639 -28.43405) (xy 446.239138 -28.434538)
			(xy 446.224345 -28.434401) (xy 446.194847 -28.432113) (xy 446.18021 -28.429966) (xy 446.169288 -28.428188)
			(xy 446.147952 -28.434284) (xy 446.080642 -28.491688) (xy 446.072672 -28.499277) (xy 446.063591 -28.5193)
			(xy 446.063116 -28.530296) (xy 446.063116 -28.834588) (xy 446.063623 -28.845577) (xy 446.072697 -28.865589)
			(xy 446.080642 -28.873196) (xy 446.147952 -28.9306) (xy 446.169288 -28.936696) (xy 446.18021 -28.934918)
			(xy 446.194848 -28.932781) (xy 446.224345 -28.93049) (xy 446.239138 -28.930346) (xy 446.266384 -28.930927)
			(xy 446.320321 -28.938687) (xy 446.372605 -28.954043) (xy 446.422171 -28.976684) (xy 446.468011 -29.006148)
			(xy 446.509192 -29.041835) (xy 446.544875 -29.083019) (xy 446.574334 -29.128862) (xy 446.59697 -29.178431)
			(xy 446.612321 -29.230716) (xy 446.620076 -29.284654) (xy 446.620076 -29.339146) (xy 446.612321 -29.393084)
			(xy 446.59697 -29.445369) (xy 446.574334 -29.494938) (xy 446.544875 -29.540781) (xy 446.509192 -29.581965)
			(xy 446.468012 -29.617652) (xy 446.422171 -29.647116) (xy 446.372605 -29.669757) (xy 446.320321 -29.685113)
			(xy 446.266384 -29.692873) (xy 446.239138 -29.693362) (xy 446.213212 -29.692917) (xy 446.161835 -29.685915)
			(xy 446.111879 -29.672021) (xy 446.064264 -29.651492) (xy 446.019867 -29.624705) (xy 445.979506 -29.592153)
			(xy 445.943924 -29.554437) (xy 445.928496 -29.533596) (xy 445.922751 -29.52627) (xy 445.907252 -29.51598)
			(xy 445.89827 -29.51353) (xy 445.868044 -29.506672) (xy 445.858768 -29.50492) (xy 445.840104 -29.507663)
			(xy 445.831722 -29.512006) (xy 445.80574 -29.52629) (xy 445.75089 -29.548804) (xy 445.693589 -29.564033)
			(xy 445.634799 -29.571722) (xy 445.605154 -29.572204) (xy 445.575512 -29.571697) (xy 445.51673 -29.563979)
			(xy 445.459431 -29.548755) (xy 445.404571 -29.526279) (xy 445.378586 -29.512006) (xy 445.370181 -29.507742)
			(xy 445.351544 -29.50502) (xy 445.342264 -29.506672) (xy 445.312038 -29.51353) (xy 445.303041 -29.515946)
			(xy 445.287538 -29.526247) (xy 445.281812 -29.533596) (xy 445.2664 -29.554452) (xy 445.230829 -29.592188)
			(xy 445.190471 -29.624754) (xy 445.146072 -29.651549) (xy 445.09845 -29.672078) (xy 445.048485 -29.685964)
			(xy 444.9971 -29.692948) (xy 444.97117 -29.693362) (xy 444.943917 -29.692966) (xy 444.889966 -29.685205)
			(xy 444.837668 -29.669846) (xy 444.788089 -29.6472) (xy 444.742237 -29.617729) (xy 444.701045 -29.582034)
			(xy 444.665353 -29.540839) (xy 444.635886 -29.494985) (xy 444.613244 -29.445403) (xy 444.597888 -29.393105)
			(xy 444.590132 -29.339153) (xy 442.867595 -29.339153) (xy 442.883142 -29.356505) (xy 442.913915 -29.403018)
			(xy 442.937587 -29.453515) (xy 442.953655 -29.506922) (xy 442.961775 -29.562098) (xy 442.962284 -29.589984)
			(xy 442.961775 -29.61787) (xy 442.953655 -29.673046) (xy 442.937587 -29.726453) (xy 442.913915 -29.77695)
			(xy 442.883142 -29.823463) (xy 442.845925 -29.865) (xy 442.803057 -29.900675) (xy 442.755451 -29.929729)
			(xy 442.704122 -29.951541) (xy 442.650165 -29.965647) (xy 442.594728 -29.971747) (xy 442.538994 -29.96971)
			(xy 442.484151 -29.95958) (xy 442.431367 -29.941573) (xy 442.381767 -29.916072) (xy 442.336409 -29.883621)
			(xy 442.29626 -29.844912) (xy 442.262174 -29.800769) (xy 442.234878 -29.752134) (xy 442.214955 -29.700043)
			(xy 442.202829 -29.645606) (xy 442.198758 -29.589984) (xy 440.930284 -29.589984) (xy 440.929775 -29.61787)
			(xy 440.921655 -29.673046) (xy 440.905587 -29.726453) (xy 440.881915 -29.77695) (xy 440.851142 -29.823463)
			(xy 440.813925 -29.865) (xy 440.771057 -29.900675) (xy 440.723451 -29.929729) (xy 440.672122 -29.951541)
			(xy 440.618165 -29.965647) (xy 440.562728 -29.971747) (xy 440.506994 -29.96971) (xy 440.452151 -29.95958)
			(xy 440.399367 -29.941573) (xy 440.349767 -29.916072) (xy 440.304409 -29.883621) (xy 440.26426 -29.844912)
			(xy 440.230174 -29.800769) (xy 440.202878 -29.752134) (xy 440.182955 -29.700043) (xy 440.170829 -29.645606)
			(xy 440.166758 -29.589984) (xy 438.426352 -29.589984) (xy 438.425843 -29.61787) (xy 438.417723 -29.673046)
			(xy 438.401655 -29.726453) (xy 438.377983 -29.77695) (xy 438.34721 -29.823463) (xy 438.309993 -29.865)
			(xy 438.267125 -29.900675) (xy 438.219519 -29.929729) (xy 438.16819 -29.951541) (xy 438.114233 -29.965647)
			(xy 438.058796 -29.971747) (xy 438.003062 -29.96971) (xy 437.948219 -29.95958) (xy 437.895435 -29.941573)
			(xy 437.845835 -29.916072) (xy 437.800477 -29.883621) (xy 437.760328 -29.844912) (xy 437.726242 -29.800769)
			(xy 437.698946 -29.752134) (xy 437.679023 -29.700043) (xy 437.666897 -29.645606) (xy 437.662826 -29.589984)
			(xy 436.329838 -29.589984) (xy 436.329838 -29.617251) (xy 436.322082 -29.671198) (xy 436.306728 -29.723492)
			(xy 436.284089 -29.773069) (xy 436.254625 -29.818919) (xy 436.218936 -29.86011) (xy 436.177748 -29.895803)
			(xy 436.1319 -29.925272) (xy 436.082325 -29.947916) (xy 436.030033 -29.963275) (xy 435.976087 -29.971036)
			(xy 435.948836 -29.971492) (xy 435.946042 -29.971492) (xy 435.936079 -29.971977) (xy 435.917652 -29.979561)
			(xy 435.910228 -29.986224) (xy 435.85892 -30.037024) (xy 435.852075 -30.044423) (xy 435.844346 -30.063021)
			(xy 435.843934 -30.073092) (xy 435.843934 -30.906974) (xy 435.844371 -30.917037) (xy 435.852108 -30.935619)
			(xy 435.85892 -30.943042) (xy 435.910228 -30.993842) (xy 435.917641 -31.000517) (xy 435.936077 -31.008083)
			(xy 435.946042 -31.008574) (xy 435.948836 -31.008574) (xy 435.976087 -31.009062) (xy 436.030033 -31.016823)
			(xy 436.082326 -31.032182) (xy 436.131901 -31.054827) (xy 436.177749 -31.084295) (xy 436.218937 -31.119988)
			(xy 436.254626 -31.16118) (xy 436.284091 -31.20703) (xy 436.30673 -31.256608) (xy 436.322084 -31.308902)
			(xy 436.32984 -31.362849) (xy 436.32984 -31.417351) (xy 436.322084 -31.471298) (xy 436.30673 -31.523592)
			(xy 436.284091 -31.57317) (xy 436.254626 -31.61902) (xy 436.234453 -31.642304) (xy 437.706514 -31.642304)
			(xy 437.710585 -31.586682) (xy 437.722711 -31.532245) (xy 437.742634 -31.480154) (xy 437.76993 -31.431519)
			(xy 437.804016 -31.387376) (xy 437.844165 -31.348667) (xy 437.889523 -31.316216) (xy 437.939123 -31.290715)
			(xy 437.991907 -31.272708) (xy 438.04675 -31.262578) (xy 438.102484 -31.260541) (xy 438.157921 -31.266641)
			(xy 438.211878 -31.280747) (xy 438.263207 -31.302559) (xy 438.310813 -31.331613) (xy 438.353681 -31.367288)
			(xy 438.374104 -31.390082) (xy 440.166758 -31.390082) (xy 440.170829 -31.33446) (xy 440.182955 -31.280023)
			(xy 440.202878 -31.227932) (xy 440.230174 -31.179297) (xy 440.26426 -31.135154) (xy 440.304409 -31.096445)
			(xy 440.349767 -31.063994) (xy 440.399367 -31.038493) (xy 440.452151 -31.020486) (xy 440.506994 -31.010356)
			(xy 440.562728 -31.008319) (xy 440.618165 -31.014419) (xy 440.672122 -31.028525) (xy 440.723451 -31.050337)
			(xy 440.771057 -31.079391) (xy 440.813925 -31.115066) (xy 440.851142 -31.156603) (xy 440.881915 -31.203116)
			(xy 440.905587 -31.253613) (xy 440.921655 -31.30702) (xy 440.929775 -31.362196) (xy 440.930284 -31.390082)
			(xy 442.198758 -31.390082) (xy 442.202829 -31.33446) (xy 442.214955 -31.280023) (xy 442.234878 -31.227932)
			(xy 442.262174 -31.179297) (xy 442.29626 -31.135154) (xy 442.336409 -31.096445) (xy 442.381767 -31.063994)
			(xy 442.431367 -31.038493) (xy 442.484151 -31.020486) (xy 442.538994 -31.010356) (xy 442.594728 -31.008319)
			(xy 442.650165 -31.014419) (xy 442.704122 -31.028525) (xy 442.755451 -31.050337) (xy 442.803057 -31.079391)
			(xy 442.845925 -31.115066) (xy 442.883142 -31.156603) (xy 442.913915 -31.203116) (xy 442.937587 -31.253613)
			(xy 442.953655 -31.30702) (xy 442.961775 -31.362196) (xy 442.962284 -31.390082) (xy 442.961775 -31.417968)
			(xy 442.953655 -31.473144) (xy 442.937587 -31.526551) (xy 442.913915 -31.577048) (xy 442.883142 -31.623561)
			(xy 442.845925 -31.665098) (xy 442.827716 -31.680252) (xy 444.59015 -31.680252) (xy 444.59015 -31.625748)
			(xy 444.597906 -31.571799) (xy 444.613261 -31.519503) (xy 444.635901 -31.469924) (xy 444.665367 -31.424072)
			(xy 444.701058 -31.382879) (xy 444.742248 -31.347185) (xy 444.788098 -31.317716) (xy 444.837675 -31.295071)
			(xy 444.88997 -31.279712) (xy 444.943918 -31.271952) (xy 444.97117 -31.271464) (xy 444.997097 -31.271893)
			(xy 445.048475 -31.278896) (xy 445.098432 -31.292792) (xy 445.146047 -31.313324) (xy 445.190444 -31.340113)
			(xy 445.230804 -31.372668) (xy 445.266385 -31.410388) (xy 445.281812 -31.43123) (xy 445.287549 -31.438563)
			(xy 445.303054 -31.448849) (xy 445.312038 -31.451296) (xy 445.342264 -31.458154) (xy 445.35154 -31.459908)
			(xy 445.370204 -31.457162) (xy 445.378586 -31.45282) (xy 445.404582 -31.438584) (xy 445.459449 -31.416167)
			(xy 445.516746 -31.401005) (xy 445.575519 -31.393351) (xy 445.605154 -31.392876) (xy 445.634791 -31.393336)
			(xy 445.693574 -31.400956) (xy 445.750877 -31.416115) (xy 445.805739 -31.438556) (xy 445.831722 -31.45282)
			(xy 445.840127 -31.457086) (xy 445.858764 -31.459809) (xy 445.868044 -31.458154) (xy 445.89827 -31.451296)
			(xy 445.907265 -31.448875) (xy 445.922769 -31.438577) (xy 445.928496 -31.43123) (xy 445.943881 -31.410354)
			(xy 445.979459 -31.372622) (xy 446.019823 -31.34006) (xy 446.064227 -31.313269) (xy 446.111852 -31.292742)
			(xy 446.161819 -31.27886) (xy 446.213207 -31.271877) (xy 446.239138 -31.271464) (xy 446.266385 -31.272009)
			(xy 446.320325 -31.279769) (xy 446.372611 -31.295126) (xy 446.42218 -31.317768) (xy 446.468022 -31.347233)
			(xy 446.509205 -31.382922) (xy 446.54489 -31.424108) (xy 446.57435 -31.469953) (xy 446.596987 -31.519524)
			(xy 446.612339 -31.571812) (xy 446.620094 -31.625753) (xy 446.620094 -31.680247) (xy 446.612339 -31.734188)
			(xy 446.596987 -31.786476) (xy 446.57435 -31.836047) (xy 446.54489 -31.881892) (xy 446.509205 -31.923078)
			(xy 446.468022 -31.958767) (xy 446.42218 -31.988232) (xy 446.372611 -32.010874) (xy 446.320325 -32.026231)
			(xy 446.266385 -32.033991) (xy 446.239138 -32.03448) (xy 446.224345 -32.034342) (xy 446.194847 -32.032055)
			(xy 446.18021 -32.029908) (xy 446.169288 -32.02813) (xy 446.147952 -32.034226) (xy 446.080642 -32.09163)
			(xy 446.072698 -32.099242) (xy 446.063603 -32.119248) (xy 446.063116 -32.130238) (xy 446.063116 -32.43453)
			(xy 446.0636 -32.445522) (xy 446.07269 -32.465534) (xy 446.080642 -32.473138) (xy 446.147952 -32.530542)
			(xy 446.169288 -32.536638) (xy 446.18021 -32.53486) (xy 446.194848 -32.532723) (xy 446.224345 -32.530432)
			(xy 446.239138 -32.530288) (xy 446.266387 -32.530784) (xy 446.32033 -32.538545) (xy 446.37262 -32.553903)
			(xy 446.422192 -32.576547) (xy 446.468037 -32.606014) (xy 446.509222 -32.641705) (xy 446.544909 -32.682893)
			(xy 446.574372 -32.728742) (xy 446.59701 -32.778316) (xy 446.612363 -32.830607) (xy 446.620118 -32.884551)
			(xy 446.620118 -32.939049) (xy 446.612363 -32.992993) (xy 446.59701 -33.045284) (xy 446.574372 -33.094858)
			(xy 446.544909 -33.140707) (xy 446.509222 -33.181895) (xy 446.468037 -33.217586) (xy 446.422192 -33.247053)
			(xy 446.37262 -33.269697) (xy 446.32033 -33.285055) (xy 446.266387 -33.292816) (xy 446.239138 -33.293304)
			(xy 446.213213 -33.292841) (xy 446.161837 -33.28584) (xy 446.111882 -33.271948) (xy 446.064268 -33.251421)
			(xy 446.019871 -33.224637) (xy 445.979509 -33.192089) (xy 445.943925 -33.154377) (xy 445.928496 -33.133538)
			(xy 445.922762 -33.126201) (xy 445.907255 -33.115919) (xy 445.89827 -33.113472) (xy 445.868044 -33.106614)
			(xy 445.858768 -33.104857) (xy 445.840104 -33.107603) (xy 445.831722 -33.111948) (xy 445.805723 -33.126178)
			(xy 445.750858 -33.148597) (xy 445.693561 -33.163761) (xy 445.634788 -33.171417) (xy 445.605154 -33.171892)
			(xy 445.575516 -33.171433) (xy 445.516734 -33.163813) (xy 445.459431 -33.148654) (xy 445.404569 -33.126213)
			(xy 445.378586 -33.111948) (xy 445.37018 -33.107685) (xy 445.351544 -33.104962) (xy 445.342264 -33.106614)
			(xy 445.312038 -33.113472) (xy 445.303048 -33.115906) (xy 445.287542 -33.126196) (xy 445.281812 -33.133538)
			(xy 445.266412 -33.154403) (xy 445.230838 -33.192137) (xy 445.190477 -33.224701) (xy 445.146076 -33.251494)
			(xy 445.098453 -33.272022) (xy 445.048487 -33.285906) (xy 444.9971 -33.29289) (xy 444.97117 -33.293304)
			(xy 444.94392 -33.292824) (xy 444.889975 -33.285064) (xy 444.837683 -33.269706) (xy 444.788109 -33.247063)
			(xy 444.742262 -33.217596) (xy 444.701075 -33.181904) (xy 444.665386 -33.140714) (xy 444.635922 -33.094864)
			(xy 444.613283 -33.045289) (xy 444.59793 -32.992996) (xy 444.590174 -32.93905) (xy 444.590174 -32.88455)
			(xy 444.59793 -32.830604) (xy 444.613283 -32.778311) (xy 444.635922 -32.728736) (xy 444.665386 -32.682886)
			(xy 444.701075 -32.641696) (xy 444.742262 -32.606004) (xy 444.788109 -32.576537) (xy 444.837683 -32.553894)
			(xy 444.889975 -32.538536) (xy 444.94392 -32.530776) (xy 444.97117 -32.530288) (xy 444.985963 -32.530425)
			(xy 445.015461 -32.532713) (xy 445.030098 -32.53486) (xy 445.04102 -32.536638) (xy 445.062356 -32.530542)
			(xy 445.129666 -32.473138) (xy 445.137626 -32.46554) (xy 445.146712 -32.445524) (xy 445.147192 -32.43453)
			(xy 445.147192 -32.130238) (xy 445.146724 -32.119245) (xy 445.137623 -32.099233) (xy 445.129666 -32.09163)
			(xy 445.062356 -32.034226) (xy 445.04102 -32.02813) (xy 445.030098 -32.029908) (xy 445.015459 -32.032044)
			(xy 444.985963 -32.034335) (xy 444.97117 -32.03448) (xy 444.943918 -32.034048) (xy 444.88997 -32.026288)
			(xy 444.837675 -32.010929) (xy 444.788098 -31.988284) (xy 444.742248 -31.958815) (xy 444.701058 -31.923121)
			(xy 444.665367 -31.881928) (xy 444.635901 -31.836076) (xy 444.613261 -31.786497) (xy 444.597906 -31.734201)
			(xy 444.59015 -31.680252) (xy 442.827716 -31.680252) (xy 442.803057 -31.700773) (xy 442.755451 -31.729827)
			(xy 442.704122 -31.751639) (xy 442.650165 -31.765745) (xy 442.594728 -31.771845) (xy 442.538994 -31.769808)
			(xy 442.484151 -31.759678) (xy 442.431367 -31.741671) (xy 442.381767 -31.71617) (xy 442.336409 -31.683719)
			(xy 442.29626 -31.64501) (xy 442.262174 -31.600867) (xy 442.234878 -31.552232) (xy 442.214955 -31.500141)
			(xy 442.202829 -31.445704) (xy 442.198758 -31.390082) (xy 440.930284 -31.390082) (xy 440.929775 -31.417968)
			(xy 440.921655 -31.473144) (xy 440.905587 -31.526551) (xy 440.881915 -31.577048) (xy 440.851142 -31.623561)
			(xy 440.813925 -31.665098) (xy 440.771057 -31.700773) (xy 440.723451 -31.729827) (xy 440.672122 -31.751639)
			(xy 440.618165 -31.765745) (xy 440.562728 -31.771845) (xy 440.506994 -31.769808) (xy 440.452151 -31.759678)
			(xy 440.399367 -31.741671) (xy 440.349767 -31.71617) (xy 440.304409 -31.683719) (xy 440.26426 -31.64501)
			(xy 440.230174 -31.600867) (xy 440.202878 -31.552232) (xy 440.182955 -31.500141) (xy 440.170829 -31.445704)
			(xy 440.166758 -31.390082) (xy 438.374104 -31.390082) (xy 438.390898 -31.408825) (xy 438.421671 -31.455338)
			(xy 438.445343 -31.505835) (xy 438.461411 -31.559242) (xy 438.469531 -31.614418) (xy 438.47004 -31.642304)
			(xy 438.469531 -31.67019) (xy 438.461411 -31.725366) (xy 438.445343 -31.778773) (xy 438.421671 -31.82927)
			(xy 438.390898 -31.875783) (xy 438.353681 -31.91732) (xy 438.310813 -31.952995) (xy 438.263207 -31.982049)
			(xy 438.211878 -32.003861) (xy 438.157921 -32.017967) (xy 438.102484 -32.024067) (xy 438.04675 -32.02203)
			(xy 437.991907 -32.0119) (xy 437.939123 -31.993893) (xy 437.889523 -31.968392) (xy 437.844165 -31.935941)
			(xy 437.804016 -31.897232) (xy 437.76993 -31.853089) (xy 437.742634 -31.804454) (xy 437.722711 -31.752363)
			(xy 437.710585 -31.697926) (xy 437.706514 -31.642304) (xy 436.234453 -31.642304) (xy 436.218937 -31.660212)
			(xy 436.177749 -31.695905) (xy 436.131901 -31.725373) (xy 436.082326 -31.748018) (xy 436.030033 -31.763377)
			(xy 435.976087 -31.771138) (xy 435.948836 -31.77159) (xy 435.946042 -31.77159) (xy 435.936079 -31.772075)
			(xy 435.917652 -31.779659) (xy 435.910228 -31.786322) (xy 435.85892 -31.837122) (xy 435.852075 -31.844521)
			(xy 435.844345 -31.863119) (xy 435.843934 -31.87319) (xy 435.843934 -32.707072) (xy 435.844371 -32.717136)
			(xy 435.852108 -32.735718) (xy 435.85892 -32.74314) (xy 435.910228 -32.79394) (xy 435.917641 -32.800615)
			(xy 435.936077 -32.808181) (xy 435.946042 -32.808672) (xy 435.948836 -32.808672) (xy 435.976087 -32.80916)
			(xy 436.030034 -32.816921) (xy 436.082327 -32.83228) (xy 436.131902 -32.854925) (xy 436.17775 -32.884394)
			(xy 436.218938 -32.920087) (xy 436.254628 -32.961278) (xy 436.284092 -33.00713) (xy 436.306732 -33.056707)
			(xy 436.322086 -33.109002) (xy 436.329842 -33.162949) (xy 436.329842 -33.19018) (xy 437.973976 -33.19018)
			(xy 437.978047 -33.134558) (xy 437.990173 -33.080121) (xy 438.010096 -33.02803) (xy 438.037392 -32.979395)
			(xy 438.071478 -32.935252) (xy 438.111627 -32.896543) (xy 438.156985 -32.864092) (xy 438.206585 -32.838591)
			(xy 438.259369 -32.820584) (xy 438.314212 -32.810454) (xy 438.369946 -32.808417) (xy 438.425383 -32.814517)
			(xy 438.47934 -32.828623) (xy 438.530669 -32.850435) (xy 438.578275 -32.879489) (xy 438.621143 -32.915164)
			(xy 438.65836 -32.956701) (xy 438.689133 -33.003214) (xy 438.712805 -33.053711) (xy 438.728873 -33.107118)
			(xy 438.736993 -33.162294) (xy 438.737502 -33.19018) (xy 440.166758 -33.19018) (xy 440.170829 -33.134558)
			(xy 440.182955 -33.080121) (xy 440.202878 -33.02803) (xy 440.230174 -32.979395) (xy 440.26426 -32.935252)
			(xy 440.304409 -32.896543) (xy 440.349767 -32.864092) (xy 440.399367 -32.838591) (xy 440.452151 -32.820584)
			(xy 440.506994 -32.810454) (xy 440.562728 -32.808417) (xy 440.618165 -32.814517) (xy 440.672122 -32.828623)
			(xy 440.723451 -32.850435) (xy 440.771057 -32.879489) (xy 440.813925 -32.915164) (xy 440.851142 -32.956701)
			(xy 440.881915 -33.003214) (xy 440.905587 -33.053711) (xy 440.921655 -33.107118) (xy 440.929775 -33.162294)
			(xy 440.930284 -33.19018) (xy 442.198758 -33.19018) (xy 442.202829 -33.134558) (xy 442.214955 -33.080121)
			(xy 442.234878 -33.02803) (xy 442.262174 -32.979395) (xy 442.29626 -32.935252) (xy 442.336409 -32.896543)
			(xy 442.381767 -32.864092) (xy 442.431367 -32.838591) (xy 442.484151 -32.820584) (xy 442.538994 -32.810454)
			(xy 442.594728 -32.808417) (xy 442.650165 -32.814517) (xy 442.704122 -32.828623) (xy 442.755451 -32.850435)
			(xy 442.803057 -32.879489) (xy 442.845925 -32.915164) (xy 442.883142 -32.956701) (xy 442.913915 -33.003214)
			(xy 442.937587 -33.053711) (xy 442.953655 -33.107118) (xy 442.961775 -33.162294) (xy 442.962284 -33.19018)
			(xy 442.961775 -33.218066) (xy 442.953655 -33.273242) (xy 442.937587 -33.326649) (xy 442.913915 -33.377146)
			(xy 442.883142 -33.423659) (xy 442.845925 -33.465196) (xy 442.803057 -33.500871) (xy 442.755451 -33.529925)
			(xy 442.704122 -33.551737) (xy 442.650165 -33.565843) (xy 442.594728 -33.571943) (xy 442.538994 -33.569906)
			(xy 442.484151 -33.559776) (xy 442.431367 -33.541769) (xy 442.381767 -33.516268) (xy 442.336409 -33.483817)
			(xy 442.29626 -33.445108) (xy 442.262174 -33.400965) (xy 442.234878 -33.35233) (xy 442.214955 -33.300239)
			(xy 442.202829 -33.245802) (xy 442.198758 -33.19018) (xy 440.930284 -33.19018) (xy 440.929775 -33.218066)
			(xy 440.921655 -33.273242) (xy 440.905587 -33.326649) (xy 440.881915 -33.377146) (xy 440.851142 -33.423659)
			(xy 440.813925 -33.465196) (xy 440.771057 -33.500871) (xy 440.723451 -33.529925) (xy 440.672122 -33.551737)
			(xy 440.618165 -33.565843) (xy 440.562728 -33.571943) (xy 440.506994 -33.569906) (xy 440.452151 -33.559776)
			(xy 440.399367 -33.541769) (xy 440.349767 -33.516268) (xy 440.304409 -33.483817) (xy 440.26426 -33.445108)
			(xy 440.230174 -33.400965) (xy 440.202878 -33.35233) (xy 440.182955 -33.300239) (xy 440.170829 -33.245802)
			(xy 440.166758 -33.19018) (xy 438.737502 -33.19018) (xy 438.736993 -33.218066) (xy 438.728873 -33.273242)
			(xy 438.712805 -33.326649) (xy 438.689133 -33.377146) (xy 438.65836 -33.423659) (xy 438.621143 -33.465196)
			(xy 438.578275 -33.500871) (xy 438.530669 -33.529925) (xy 438.47934 -33.551737) (xy 438.425383 -33.565843)
			(xy 438.369946 -33.571943) (xy 438.314212 -33.569906) (xy 438.259369 -33.559776) (xy 438.206585 -33.541769)
			(xy 438.156985 -33.516268) (xy 438.111627 -33.483817) (xy 438.071478 -33.445108) (xy 438.037392 -33.400965)
			(xy 438.010096 -33.35233) (xy 437.990173 -33.300239) (xy 437.978047 -33.245802) (xy 437.973976 -33.19018)
			(xy 436.329842 -33.19018) (xy 436.329842 -33.217451) (xy 436.322086 -33.271398) (xy 436.306732 -33.323693)
			(xy 436.284092 -33.37327) (xy 436.254628 -33.419122) (xy 436.218938 -33.460313) (xy 436.17775 -33.496006)
			(xy 436.131902 -33.525475) (xy 436.082327 -33.54812) (xy 436.030034 -33.563479) (xy 435.976087 -33.57124)
			(xy 435.948836 -33.571688) (xy 435.946042 -33.571688) (xy 435.936079 -33.572173) (xy 435.917651 -33.579757)
			(xy 435.910228 -33.58642) (xy 435.85892 -33.63722) (xy 435.852075 -33.644619) (xy 435.844344 -33.663217)
			(xy 435.843934 -33.673288) (xy 435.843934 -34.506916) (xy 435.844361 -34.516984) (xy 435.852083 -34.535581)
			(xy 435.85892 -34.542984) (xy 435.910228 -34.593784) (xy 435.917638 -34.600465) (xy 435.936075 -34.60804)
			(xy 435.946042 -34.608516) (xy 435.948836 -34.608516) (xy 435.976084 -34.609005) (xy 436.030024 -34.616765)
			(xy 436.082311 -34.632122) (xy 436.131881 -34.654764) (xy 436.177724 -34.684229) (xy 436.218907 -34.719918)
			(xy 436.254592 -34.761105) (xy 436.284053 -34.806951) (xy 436.30669 -34.856522) (xy 436.322043 -34.908811)
			(xy 436.329798 -34.962752) (xy 436.329798 -34.990024) (xy 437.972706 -34.990024) (xy 437.976777 -34.934402)
			(xy 437.988903 -34.879965) (xy 438.008826 -34.827874) (xy 438.036122 -34.779239) (xy 438.070208 -34.735096)
			(xy 438.110357 -34.696387) (xy 438.155715 -34.663936) (xy 438.205315 -34.638435) (xy 438.258099 -34.620428)
			(xy 438.312942 -34.610298) (xy 438.368676 -34.608261) (xy 438.424113 -34.614361) (xy 438.47807 -34.628467)
			(xy 438.529399 -34.650279) (xy 438.577005 -34.679333) (xy 438.619873 -34.715008) (xy 438.65709 -34.756545)
			(xy 438.687863 -34.803058) (xy 438.711535 -34.853555) (xy 438.727603 -34.906962) (xy 438.735723 -34.962138)
			(xy 438.736232 -34.990024) (xy 439.20232 -34.990024) (xy 439.206391 -34.934402) (xy 439.218517 -34.879965)
			(xy 439.23844 -34.827874) (xy 439.265736 -34.779239) (xy 439.299822 -34.735096) (xy 439.339971 -34.696387)
			(xy 439.385329 -34.663936) (xy 439.434929 -34.638435) (xy 439.487713 -34.620428) (xy 439.542556 -34.610298)
			(xy 439.59829 -34.608261) (xy 439.653727 -34.614361) (xy 439.707684 -34.628467) (xy 439.759013 -34.650279)
			(xy 439.806619 -34.679333) (xy 439.849487 -34.715008) (xy 439.886704 -34.756545) (xy 439.917477 -34.803058)
			(xy 439.941149 -34.853555) (xy 439.957217 -34.906962) (xy 439.965337 -34.962138) (xy 439.965846 -34.990024)
			(xy 442.198758 -34.990024) (xy 442.202829 -34.934402) (xy 442.214955 -34.879965) (xy 442.234878 -34.827874)
			(xy 442.262174 -34.779239) (xy 442.29626 -34.735096) (xy 442.336409 -34.696387) (xy 442.381767 -34.663936)
			(xy 442.431367 -34.638435) (xy 442.484151 -34.620428) (xy 442.538994 -34.610298) (xy 442.594728 -34.608261)
			(xy 442.650165 -34.614361) (xy 442.704122 -34.628467) (xy 442.755451 -34.650279) (xy 442.803057 -34.679333)
			(xy 442.845925 -34.715008) (xy 442.883142 -34.756545) (xy 442.913915 -34.803058) (xy 442.937587 -34.853555)
			(xy 442.953655 -34.906962) (xy 442.961775 -34.962138) (xy 442.962284 -34.990024) (xy 442.961775 -35.01791)
			(xy 442.953655 -35.073086) (xy 442.937587 -35.126493) (xy 442.913915 -35.17699) (xy 442.883142 -35.223503)
			(xy 442.845925 -35.26504) (xy 442.803057 -35.300715) (xy 442.755451 -35.329769) (xy 442.704122 -35.351581)
			(xy 442.650165 -35.365687) (xy 442.594728 -35.371787) (xy 442.538994 -35.36975) (xy 442.484151 -35.35962)
			(xy 442.431367 -35.341613) (xy 442.381767 -35.316112) (xy 442.336409 -35.283661) (xy 442.29626 -35.244952)
			(xy 442.262174 -35.200809) (xy 442.234878 -35.152174) (xy 442.214955 -35.100083) (xy 442.202829 -35.045646)
			(xy 442.198758 -34.990024) (xy 439.965846 -34.990024) (xy 439.965337 -35.01791) (xy 439.957217 -35.073086)
			(xy 439.941149 -35.126493) (xy 439.917477 -35.17699) (xy 439.886704 -35.223503) (xy 439.849487 -35.26504)
			(xy 439.806619 -35.300715) (xy 439.759013 -35.329769) (xy 439.707684 -35.351581) (xy 439.653727 -35.365687)
			(xy 439.59829 -35.371787) (xy 439.542556 -35.36975) (xy 439.487713 -35.35962) (xy 439.434929 -35.341613)
			(xy 439.385329 -35.316112) (xy 439.339971 -35.283661) (xy 439.299822 -35.244952) (xy 439.265736 -35.200809)
			(xy 439.23844 -35.152174) (xy 439.218517 -35.100083) (xy 439.206391 -35.045646) (xy 439.20232 -34.990024)
			(xy 438.736232 -34.990024) (xy 438.735723 -35.01791) (xy 438.727603 -35.073086) (xy 438.711535 -35.126493)
			(xy 438.687863 -35.17699) (xy 438.65709 -35.223503) (xy 438.619873 -35.26504) (xy 438.577005 -35.300715)
			(xy 438.529399 -35.329769) (xy 438.47807 -35.351581) (xy 438.424113 -35.365687) (xy 438.368676 -35.371787)
			(xy 438.312942 -35.36975) (xy 438.258099 -35.35962) (xy 438.205315 -35.341613) (xy 438.155715 -35.316112)
			(xy 438.110357 -35.283661) (xy 438.070208 -35.244952) (xy 438.036122 -35.200809) (xy 438.008826 -35.152174)
			(xy 437.988903 -35.100083) (xy 437.976777 -35.045646) (xy 437.972706 -34.990024) (xy 436.329798 -34.990024)
			(xy 436.329798 -35.017248) (xy 436.322043 -35.071189) (xy 436.30669 -35.123478) (xy 436.284053 -35.173049)
			(xy 436.254592 -35.218895) (xy 436.218907 -35.260082) (xy 436.177724 -35.295771) (xy 436.131881 -35.325236)
			(xy 436.082311 -35.347878) (xy 436.030024 -35.363235) (xy 435.976084 -35.370995) (xy 435.948836 -35.371532)
			(xy 435.946042 -35.371532) (xy 435.93608 -35.372017) (xy 435.917656 -35.379606) (xy 435.910228 -35.386264)
			(xy 435.85892 -35.437064) (xy 435.852082 -35.444465) (xy 435.844367 -35.463063) (xy 435.843934 -35.473132)
			(xy 435.843934 -38.193437) (xy 437.398171 -38.193437) (xy 437.398171 -38.106563) (xy 437.406186 -38.020059)
			(xy 437.42215 -37.934664) (xy 437.445924 -37.851106) (xy 437.477307 -37.770098) (xy 437.51603 -37.692331)
			(xy 437.561764 -37.618469) (xy 437.614118 -37.549141) (xy 437.672645 -37.484941) (xy 437.736846 -37.426414)
			(xy 437.806174 -37.374061) (xy 437.880036 -37.328327) (xy 437.957803 -37.289604) (xy 438.038811 -37.258222)
			(xy 438.122369 -37.234448) (xy 438.207765 -37.218486) (xy 438.294269 -37.21047) (xy 438.337706 -37.209984)
			(xy 438.415684 -37.209984) (xy 438.425706 -37.209567) (xy 438.444226 -37.201899) (xy 438.458399 -37.187726)
			(xy 438.466067 -37.169206) (xy 438.466484 -37.159184) (xy 438.466484 -37.151564) (xy 438.462166 -37.137594)
			(xy 438.458102 -37.131244) (xy 438.434666 -37.094789) (xy 438.393671 -37.018427) (xy 438.359683 -36.938699)
			(xy 438.332975 -36.856246) (xy 438.313763 -36.771731) (xy 438.302201 -36.685835) (xy 438.298381 -36.599249)
			(xy 438.302335 -36.512668) (xy 438.314031 -36.426791) (xy 438.333375 -36.342306) (xy 438.360211 -36.259895)
			(xy 438.394323 -36.180219) (xy 438.435437 -36.103921) (xy 438.483221 -36.031613) (xy 438.537293 -35.963878)
			(xy 438.597216 -35.90126) (xy 438.662509 -35.844263) (xy 438.732646 -35.793346) (xy 438.807064 -35.748918)
			(xy 438.885163 -35.711336) (xy 438.966315 -35.680903) (xy 439.049867 -35.657865) (xy 439.135148 -35.642405)
			(xy 439.221471 -35.634648) (xy 439.264806 -35.634168) (xy 439.26506 -35.634168) (xy 439.308392 -35.634599)
			(xy 439.394707 -35.642376) (xy 439.479978 -35.657855) (xy 439.56352 -35.68091) (xy 439.64466 -35.711355)
			(xy 439.722747 -35.748947) (xy 439.797153 -35.793383) (xy 439.867278 -35.844306) (xy 439.932561 -35.901306)
			(xy 439.992474 -35.963924) (xy 440.046538 -36.031658) (xy 440.094317 -36.103962) (xy 440.135426 -36.180256)
			(xy 440.169536 -36.259926) (xy 440.196372 -36.342331) (xy 440.215718 -36.426808) (xy 440.227419 -36.512679)
			(xy 440.23138 -36.599253) (xy 440.22757 -36.685834) (xy 440.21602 -36.771725) (xy 440.196822 -36.856236)
			(xy 440.170131 -36.938688) (xy 440.136161 -37.018418) (xy 440.095185 -37.094783) (xy 440.071764 -37.131244)
			(xy 440.063382 -37.143944) (xy 440.063382 -37.159184) (xy 440.063901 -37.169188) (xy 440.071552 -37.187676)
			(xy 440.085695 -37.201829) (xy 440.104178 -37.209493) (xy 440.114182 -37.209984) (xy 440.191906 -37.209984)
			(xy 440.235346 -37.21041) (xy 440.321854 -37.218427) (xy 440.407254 -37.234391) (xy 440.490817 -37.258167)
			(xy 440.57183 -37.289552) (xy 440.649601 -37.328278) (xy 440.723467 -37.374014) (xy 440.792798 -37.426371)
			(xy 440.857003 -37.484902) (xy 440.915533 -37.549107) (xy 440.967889 -37.618438) (xy 441.013625 -37.692304)
			(xy 441.05235 -37.770076) (xy 441.083735 -37.851088) (xy 441.10751 -37.934651) (xy 441.123474 -38.020051)
			(xy 441.13149 -38.10656) (xy 441.13149 -38.19344) (xy 441.123474 -38.279949) (xy 441.10751 -38.365349)
			(xy 441.083735 -38.448912) (xy 441.05235 -38.529924) (xy 441.013625 -38.607696) (xy 440.967889 -38.681562)
			(xy 440.915533 -38.750893) (xy 440.857003 -38.815098) (xy 440.792798 -38.873629) (xy 440.723467 -38.925986)
			(xy 440.649601 -38.971722) (xy 440.57183 -39.010448) (xy 440.490817 -39.041833) (xy 440.407254 -39.065609)
			(xy 440.321854 -39.081573) (xy 440.235346 -39.08959) (xy 440.191906 -39.090092) (xy 438.337706 -39.090092)
			(xy 438.294269 -39.08953) (xy 438.207765 -39.081514) (xy 438.122369 -39.065552) (xy 438.038811 -39.041778)
			(xy 437.957803 -39.010396) (xy 437.880036 -38.971673) (xy 437.806174 -38.925939) (xy 437.736846 -38.873586)
			(xy 437.672645 -38.815059) (xy 437.614118 -38.750859) (xy 437.561764 -38.681531) (xy 437.51603 -38.607669)
			(xy 437.477307 -38.529902) (xy 437.445924 -38.448894) (xy 437.42215 -38.365336) (xy 437.406186 -38.279941)
			(xy 437.398171 -38.193437) (xy 435.843934 -38.193437) (xy 435.843934 -42.849038) (xy 447.19189 -42.849038)
			(xy 447.195961 -42.793416) (xy 447.208087 -42.738979) (xy 447.22801 -42.686888) (xy 447.255306 -42.638253)
			(xy 447.289392 -42.59411) (xy 447.329541 -42.555401) (xy 447.374899 -42.52295) (xy 447.424499 -42.497449)
			(xy 447.477283 -42.479442) (xy 447.532126 -42.469312) (xy 447.58786 -42.467275) (xy 447.643297 -42.473375)
			(xy 447.697254 -42.487481) (xy 447.748583 -42.509293) (xy 447.796189 -42.538347) (xy 447.839057 -42.574022)
			(xy 447.876274 -42.615559) (xy 447.907047 -42.662072) (xy 447.930719 -42.712569) (xy 447.946787 -42.765976)
			(xy 447.954907 -42.821152) (xy 447.955416 -42.849038) (xy 447.954907 -42.876924) (xy 447.946787 -42.9321)
			(xy 447.930719 -42.985507) (xy 447.907047 -43.036004) (xy 447.876274 -43.082517) (xy 447.839057 -43.124054)
			(xy 447.796189 -43.159729) (xy 447.748583 -43.188783) (xy 447.697254 -43.210595) (xy 447.643297 -43.224701)
			(xy 447.58786 -43.230801) (xy 447.532126 -43.228764) (xy 447.477283 -43.218634) (xy 447.424499 -43.200627)
			(xy 447.374899 -43.175126) (xy 447.329541 -43.142675) (xy 447.289392 -43.103966) (xy 447.255306 -43.059823)
			(xy 447.22801 -43.011188) (xy 447.208087 -42.959097) (xy 447.195961 -42.90466) (xy 447.19189 -42.849038)
			(xy 435.843934 -42.849038) (xy 435.843934 -43.719242) (xy 435.844397 -43.729119) (xy 435.851839 -43.747417)
			(xy 435.858412 -43.754802) (xy 435.858666 -43.755056) (xy 436.336694 -44.233084) (xy 436.337202 -44.233592)
			(xy 436.344587 -44.240163) (xy 436.362886 -44.24759) (xy 436.372762 -44.24807)
		)
		(stroke
			(width 0)
			(type solid)
		)
		(fill yes)
		(layer "B.Cu")
		(net "P12V_SSD15")
	)
	(gr_poly
		(pts
			(xy 214.314786 -44.24807) (xy 214.32496 -44.247619) (xy 214.343705 -44.239704) (xy 214.357891 -44.225118)
			(xy 214.36203 -44.215812) (xy 214.402416 -44.112942) (xy 214.395558 -44.082716) (xy 214.383874 -44.072048)
			(xy 214.361184 -44.0503) (xy 214.321374 -44.001665) (xy 214.288588 -43.948043) (xy 214.263442 -43.890443)
			(xy 214.246408 -43.829944) (xy 214.237806 -43.767685) (xy 214.237316 -43.73626) (xy 214.237806 -43.706292)
			(xy 214.245629 -43.64687) (xy 214.261142 -43.588977) (xy 214.284078 -43.533604) (xy 214.314045 -43.481698)
			(xy 214.350532 -43.434148) (xy 214.392912 -43.391768) (xy 214.440462 -43.355281) (xy 214.492368 -43.325314)
			(xy 214.547741 -43.302378) (xy 214.605634 -43.286865) (xy 214.665056 -43.279042) (xy 214.724992 -43.279042)
			(xy 214.784414 -43.286865) (xy 214.842307 -43.302378) (xy 214.89768 -43.325314) (xy 214.949586 -43.355281)
			(xy 214.997136 -43.391768) (xy 215.039516 -43.434148) (xy 215.076003 -43.481698) (xy 215.10597 -43.533604)
			(xy 215.128906 -43.588977) (xy 215.144419 -43.64687) (xy 215.152242 -43.706292) (xy 215.152732 -43.73626)
			(xy 215.152216 -43.767685) (xy 215.143626 -43.829946) (xy 215.126602 -43.890447) (xy 215.101464 -43.948052)
			(xy 215.068684 -44.001677) (xy 215.028878 -44.050315) (xy 215.006174 -44.072048) (xy 214.99449 -44.082716)
			(xy 214.987632 -44.112942) (xy 215.028018 -44.215812) (xy 215.032154 -44.225118) (xy 215.046352 -44.239695)
			(xy 215.065089 -44.247632) (xy 215.075262 -44.24807) (xy 215.97747 -44.24807) (xy 215.987342 -44.2476)
			(xy 216.005625 -44.24014) (xy 216.01303 -44.233592) (xy 216.013284 -44.233338) (xy 216.572592 -43.67403)
			(xy 216.5731 -43.673522) (xy 216.579684 -43.666142) (xy 216.587134 -43.647842) (xy 216.587578 -43.637962)
			(xy 216.587578 -35.109658) (xy 216.569036 -35.083496) (xy 216.553796 -35.078162) (xy 216.527524 -35.068318)
			(xy 216.477964 -35.042026) (xy 216.432786 -35.008764) (xy 216.392963 -34.969247) (xy 216.375742 -34.947098)
			(xy 216.370408 -34.939986) (xy 216.34831 -34.925254) (xy 216.34436 -34.922819) (xy 216.335802 -34.919234)
			(xy 216.331292 -34.918142) (xy 216.301066 -34.911284) (xy 216.28227 -34.914078) (xy 216.273888 -34.91865)
			(xy 216.255506 -34.928876) (xy 216.217218 -34.946302) (xy 216.197434 -34.953448) (xy 216.173233 -34.96149)
			(xy 216.123499 -34.97278) (xy 216.072819 -34.978478) (xy 216.04732 -34.978848) (xy 216.02182 -34.978488)
			(xy 215.971138 -34.972796) (xy 215.921403 -34.961504) (xy 215.897206 -34.953448) (xy 215.877421 -34.946304)
			(xy 215.839132 -34.92888) (xy 215.820752 -34.91865) (xy 215.81237 -34.914078) (xy 215.793574 -34.911284)
			(xy 215.763348 -34.918142) (xy 215.758828 -34.919206) (xy 215.750262 -34.922785) (xy 215.74633 -34.925254)
			(xy 215.723978 -34.94024) (xy 215.718898 -34.947352) (xy 215.700748 -34.970654) (xy 215.65847 -35.011898)
			(xy 215.610339 -35.04613) (xy 215.557506 -35.072532) (xy 215.501234 -35.090473) (xy 215.442868 -35.099524)
			(xy 215.413336 -35.100006) (xy 215.402414 -35.100006) (xy 215.40216 -35.099752) (xy 215.375445 -35.098515)
			(xy 215.322732 -35.089492) (xy 215.271796 -35.073198) (xy 215.223633 -35.049952) (xy 215.179187 -35.020208)
			(xy 215.13933 -34.984551) (xy 215.104841 -34.943679) (xy 215.076396 -34.898391) (xy 215.054553 -34.849576)
			(xy 215.03974 -34.798189) (xy 215.032246 -34.745238) (xy 215.031828 -34.718498) (xy 215.032291 -34.691246)
			(xy 215.040049 -34.637297) (xy 215.055405 -34.585002) (xy 215.078049 -34.535424) (xy 215.107517 -34.489574)
			(xy 215.143211 -34.448384) (xy 215.184404 -34.412694) (xy 215.230258 -34.38323) (xy 215.279837 -34.360592)
			(xy 215.332135 -34.345241) (xy 215.386084 -34.337489) (xy 215.413336 -34.33699) (xy 215.428129 -34.337133)
			(xy 215.457626 -34.339422) (xy 215.472264 -34.341562) (xy 215.483186 -34.34334) (xy 215.504522 -34.337244)
			(xy 215.571578 -34.280094) (xy 215.579727 -34.27251) (xy 215.589106 -34.25235) (xy 215.589612 -34.241232)
			(xy 215.589612 -33.93694) (xy 215.589047 -33.925833) (xy 215.579694 -33.905682) (xy 215.571578 -33.898078)
			(xy 215.504522 -33.840928) (xy 215.483186 -33.834832) (xy 215.472264 -33.83661) (xy 215.457438 -33.838784)
			(xy 215.427558 -33.841076) (xy 215.412574 -33.841182) (xy 215.41232 -33.841182) (xy 215.385115 -33.840629)
			(xy 215.331275 -33.832759) (xy 215.279099 -33.817319) (xy 215.229647 -33.794622) (xy 215.183921 -33.765129)
			(xy 215.14285 -33.729437) (xy 215.107267 -33.688272) (xy 215.077895 -33.642469) (xy 215.055328 -33.592957)
			(xy 215.040026 -33.540741) (xy 215.032298 -33.48688) (xy 215.031828 -33.459674) (xy 215.032293 -33.432423)
			(xy 215.040053 -33.378477) (xy 215.055412 -33.326184) (xy 215.078056 -33.27661) (xy 215.107526 -33.230763)
			(xy 215.14322 -33.189576) (xy 215.184412 -33.153889) (xy 215.230264 -33.124427) (xy 215.279843 -33.10179)
			(xy 215.332138 -33.08644) (xy 215.386085 -33.078689) (xy 215.413336 -33.078166) (xy 215.41359 -33.078166)
			(xy 215.443095 -33.078723) (xy 215.5014 -33.087818) (xy 215.557611 -33.105776) (xy 215.610388 -33.132171)
			(xy 215.658476 -33.166372) (xy 215.700727 -33.207567) (xy 215.718898 -33.23082) (xy 215.723978 -33.237932)
			(xy 215.74633 -33.252918) (xy 215.750281 -33.255351) (xy 215.75884 -33.258931) (xy 215.763348 -33.26003)
			(xy 215.793574 -33.266888) (xy 215.81237 -33.264094) (xy 215.820752 -33.259522) (xy 215.839133 -33.249295)
			(xy 215.87742 -33.231865) (xy 215.897206 -33.224724) (xy 215.921406 -33.216679) (xy 215.97114 -33.205384)
			(xy 216.02182 -33.199679) (xy 216.04732 -33.199324) (xy 216.07282 -33.199686) (xy 216.123501 -33.205382)
			(xy 216.173234 -33.216677) (xy 216.197434 -33.224724) (xy 216.217218 -33.231869) (xy 216.255507 -33.249295)
			(xy 216.273888 -33.259522) (xy 216.28227 -33.264094) (xy 216.301066 -33.266888) (xy 216.331292 -33.26003)
			(xy 216.335814 -33.258971) (xy 216.344385 -33.255399) (xy 216.34831 -33.252918) (xy 216.370408 -33.238186)
			(xy 216.375742 -33.231074) (xy 216.392944 -33.20891) (xy 216.43277 -33.169393) (xy 216.477955 -33.136136)
			(xy 216.527524 -33.109856) (xy 216.553796 -33.10001) (xy 216.569036 -33.094676) (xy 216.587578 -33.068514)
			(xy 216.587578 -31.509462) (xy 216.569036 -31.4833) (xy 216.553796 -31.477966) (xy 216.527524 -31.468122)
			(xy 216.477964 -31.441831) (xy 216.432785 -31.408568) (xy 216.392962 -31.369052) (xy 216.375742 -31.346902)
			(xy 216.370408 -31.33979) (xy 216.34831 -31.325058) (xy 216.34436 -31.322623) (xy 216.335802 -31.319037)
			(xy 216.331292 -31.317946) (xy 216.301066 -31.311088) (xy 216.28227 -31.313882) (xy 216.273888 -31.318454)
			(xy 216.255506 -31.32868) (xy 216.217218 -31.346105) (xy 216.197434 -31.353252) (xy 216.173233 -31.361294)
			(xy 216.123499 -31.372584) (xy 216.072819 -31.378282) (xy 216.04732 -31.378652) (xy 216.02182 -31.378292)
			(xy 215.971138 -31.3726) (xy 215.921403 -31.361308) (xy 215.897206 -31.353252) (xy 215.877421 -31.346108)
			(xy 215.839132 -31.328685) (xy 215.820752 -31.318454) (xy 215.81237 -31.313882) (xy 215.793574 -31.311088)
			(xy 215.763348 -31.317946) (xy 215.758828 -31.31901) (xy 215.750262 -31.322589) (xy 215.74633 -31.325058)
			(xy 215.723978 -31.340044) (xy 215.718898 -31.347156) (xy 215.700748 -31.370458) (xy 215.65847 -31.411701)
			(xy 215.610339 -31.445933) (xy 215.557505 -31.472335) (xy 215.501233 -31.490276) (xy 215.442868 -31.499326)
			(xy 215.413336 -31.49981) (xy 215.402414 -31.49981) (xy 215.40216 -31.499556) (xy 215.375445 -31.498319)
			(xy 215.322732 -31.489296) (xy 215.271795 -31.473002) (xy 215.223632 -31.449756) (xy 215.179186 -31.420013)
			(xy 215.139328 -31.384356) (xy 215.104839 -31.343483) (xy 215.076394 -31.298196) (xy 215.054551 -31.24938)
			(xy 215.039737 -31.197993) (xy 215.032242 -31.145042) (xy 215.031828 -31.118302) (xy 215.032291 -31.09105)
			(xy 215.040048 -31.037101) (xy 215.055404 -30.984805) (xy 215.078047 -30.935227) (xy 215.107516 -30.889376)
			(xy 215.14321 -30.848186) (xy 215.184403 -30.812495) (xy 215.230257 -30.783031) (xy 215.279837 -30.760392)
			(xy 215.332134 -30.745041) (xy 215.386084 -30.737289) (xy 215.413336 -30.736794) (xy 215.428129 -30.736937)
			(xy 215.457626 -30.739226) (xy 215.472264 -30.741366) (xy 215.483186 -30.743144) (xy 215.504522 -30.737048)
			(xy 215.571578 -30.679898) (xy 215.579727 -30.672314) (xy 215.589108 -30.652154) (xy 215.589612 -30.641036)
			(xy 215.589612 -30.336744) (xy 215.589048 -30.325636) (xy 215.579696 -30.305484) (xy 215.571578 -30.297882)
			(xy 215.504522 -30.240732) (xy 215.483186 -30.234636) (xy 215.472264 -30.236414) (xy 215.457438 -30.238588)
			(xy 215.427558 -30.24088) (xy 215.412574 -30.240986) (xy 215.41232 -30.240986) (xy 215.385115 -30.240433)
			(xy 215.331275 -30.232563) (xy 215.279099 -30.217123) (xy 215.229646 -30.194426) (xy 215.18392 -30.164933)
			(xy 215.142849 -30.129242) (xy 215.107266 -30.088077) (xy 215.077893 -30.042274) (xy 215.055326 -29.992761)
			(xy 215.040023 -29.940545) (xy 215.032294 -29.886684) (xy 215.031828 -29.859478) (xy 215.032293 -29.832227)
			(xy 215.040053 -29.77828) (xy 215.055411 -29.725987) (xy 215.078055 -29.676412) (xy 215.107524 -29.630564)
			(xy 215.143218 -29.589377) (xy 215.184411 -29.553689) (xy 215.230263 -29.524227) (xy 215.279842 -29.501591)
			(xy 215.332137 -29.48624) (xy 215.386085 -29.478489) (xy 215.413336 -29.47797) (xy 215.41359 -29.47797)
			(xy 215.443095 -29.478527) (xy 215.5014 -29.487622) (xy 215.55761 -29.50558) (xy 215.610388 -29.531975)
			(xy 215.658475 -29.566177) (xy 215.700726 -29.607372) (xy 215.718898 -29.630624) (xy 215.723978 -29.637736)
			(xy 215.74633 -29.652722) (xy 215.750281 -29.655155) (xy 215.75884 -29.658735) (xy 215.763348 -29.659834)
			(xy 215.793574 -29.666692) (xy 215.81237 -29.663898) (xy 215.820752 -29.659326) (xy 215.839133 -29.649099)
			(xy 215.87742 -29.631669) (xy 215.897206 -29.624528) (xy 215.921406 -29.616483) (xy 215.97114 -29.605187)
			(xy 216.02182 -29.599483) (xy 216.04732 -29.599128) (xy 216.07282 -29.59949) (xy 216.123501 -29.605186)
			(xy 216.173234 -29.616481) (xy 216.197434 -29.624528) (xy 216.217218 -29.631673) (xy 216.255507 -29.649099)
			(xy 216.273888 -29.659326) (xy 216.28227 -29.663898) (xy 216.301066 -29.666692) (xy 216.331292 -29.659834)
			(xy 216.335814 -29.658775) (xy 216.344385 -29.655203) (xy 216.34831 -29.652722) (xy 216.370408 -29.63799)
			(xy 216.375742 -29.630878) (xy 216.392944 -29.608713) (xy 216.43277 -29.569197) (xy 216.477955 -29.535939)
			(xy 216.527523 -29.509659) (xy 216.553796 -29.499814) (xy 216.569036 -29.49448) (xy 216.587578 -29.468318)
			(xy 216.587578 -19.837908) (xy 216.587369 -19.831327) (xy 216.584029 -19.818595) (xy 216.580974 -19.812762)
			(xy 216.565734 -19.786346) (xy 216.557606 -19.77771) (xy 216.552272 -19.774154) (xy 216.530471 -19.759653)
			(xy 216.490682 -19.725619) (xy 216.455917 -19.686466) (xy 216.44102 -19.664934) (xy 216.440766 -19.66468)
			(xy 216.440766 -19.664426) (xy 216.434477 -19.656131) (xy 216.416914 -19.644993) (xy 216.40673 -19.642836)
			(xy 216.333324 -19.631152) (xy 216.322961 -19.629979) (xy 216.302767 -19.635099) (xy 216.294208 -19.641058)
			(xy 216.27405 -19.656164) (xy 216.230517 -19.68151) (xy 216.184031 -19.700913) (xy 216.135398 -19.714038)
			(xy 216.085461 -19.720656) (xy 216.060274 -19.721068) (xy 216.052654 -19.721068) (xy 216.025758 -19.720074)
			(xy 215.972632 -19.711455) (xy 215.921245 -19.695455) (xy 215.872617 -19.67239) (xy 215.827714 -19.642719)
			(xy 215.787428 -19.60703) (xy 215.752558 -19.566033) (xy 215.723798 -19.520541) (xy 215.701717 -19.471459)
			(xy 215.686756 -19.419759) (xy 215.67921 -19.36647) (xy 215.678766 -19.33956) (xy 215.679254 -19.31231)
			(xy 215.687015 -19.258365) (xy 215.702374 -19.206074) (xy 215.725017 -19.1565) (xy 215.754484 -19.110653)
			(xy 215.790175 -19.069465) (xy 215.831364 -19.033775) (xy 215.877212 -19.00431) (xy 215.926787 -18.981669)
			(xy 215.979079 -18.966313) (xy 216.033024 -18.958553) (xy 216.060274 -18.958052) (xy 216.064338 -18.958052)
			(xy 216.079578 -18.958306) (xy 216.10574 -18.941288) (xy 216.148158 -18.840196) (xy 216.151709 -18.830751)
			(xy 216.151818 -18.81059) (xy 216.144101 -18.791964) (xy 216.137236 -18.78457) (xy 215.76792 -18.415254)
			(xy 215.760808 -18.407888) (xy 215.742012 -18.400268) (xy 204.02931 -18.400268) (xy 204.019238 -18.400688)
			(xy 204.000628 -18.408397) (xy 203.993242 -18.415254) (xy 203.658978 -18.749518) (xy 203.651612 -18.75663)
			(xy 203.643992 -18.775426) (xy 203.643992 -21.738336) (xy 205.516734 -21.738336) (xy 205.517236 -21.709597)
			(xy 205.525867 -21.652769) (xy 205.542923 -21.597879) (xy 205.568019 -21.546167) (xy 205.600586 -21.498805)
			(xy 205.619858 -21.477478) (xy 205.626462 -21.470366) (xy 205.633574 -21.45284) (xy 205.633574 -21.363432)
			(xy 205.626462 -21.345906) (xy 205.619858 -21.338794) (xy 205.600621 -21.317437) (xy 205.568052 -21.270081)
			(xy 205.542956 -21.218374) (xy 205.525902 -21.163488) (xy 205.517275 -21.106664) (xy 205.517271 -21.049189)
			(xy 205.52589 -20.992364) (xy 205.542937 -20.937475) (xy 205.568026 -20.885765) (xy 205.600588 -20.838404)
			(xy 205.619858 -20.817078) (xy 205.626462 -20.809966) (xy 205.633574 -20.79244) (xy 205.633574 -20.703032)
			(xy 205.626462 -20.685506) (xy 205.619858 -20.678394) (xy 205.600621 -20.657037) (xy 205.568052 -20.609681)
			(xy 205.542956 -20.557974) (xy 205.525902 -20.503088) (xy 205.517275 -20.446264) (xy 205.517271 -20.388789)
			(xy 205.52589 -20.331964) (xy 205.542937 -20.277075) (xy 205.568026 -20.225365) (xy 205.600588 -20.178004)
			(xy 205.619858 -20.156678) (xy 205.626462 -20.149566) (xy 205.633574 -20.13204) (xy 205.633574 -20.042632)
			(xy 205.626462 -20.025106) (xy 205.619858 -20.017994) (xy 205.600621 -19.996637) (xy 205.568052 -19.949281)
			(xy 205.542956 -19.897574) (xy 205.525902 -19.842688) (xy 205.517275 -19.785864) (xy 205.517271 -19.728389)
			(xy 205.52589 -19.671564) (xy 205.542937 -19.616675) (xy 205.568026 -19.564965) (xy 205.600588 -19.517604)
			(xy 205.619858 -19.496278) (xy 205.626462 -19.489166) (xy 205.633574 -19.47164) (xy 205.633574 -19.382232)
			(xy 205.626462 -19.364706) (xy 205.619858 -19.357594) (xy 205.600608 -19.336249) (xy 205.568038 -19.288892)
			(xy 205.542941 -19.237185) (xy 205.525886 -19.182298) (xy 205.517258 -19.125474) (xy 205.516734 -19.096736)
			(xy 205.51722 -19.069485) (xy 205.524976 -19.015537) (xy 205.540331 -18.963242) (xy 205.562973 -18.913665)
			(xy 205.592439 -18.867815) (xy 205.62813 -18.826624) (xy 205.669321 -18.790933) (xy 205.715171 -18.761467)
			(xy 205.764748 -18.738825) (xy 205.817043 -18.72347) (xy 205.870991 -18.715714) (xy 205.925493 -18.715714)
			(xy 205.979441 -18.72347) (xy 206.031736 -18.738825) (xy 206.081313 -18.761467) (xy 206.127163 -18.790933)
			(xy 206.168354 -18.826624) (xy 206.204045 -18.867815) (xy 206.233511 -18.913665) (xy 206.256153 -18.963242)
			(xy 206.271508 -19.015537) (xy 206.279264 -19.069485) (xy 206.27975 -19.096736) (xy 206.279235 -19.125475)
			(xy 206.270608 -19.182302) (xy 206.253555 -19.237193) (xy 206.228462 -19.288904) (xy 206.195897 -19.336267)
			(xy 206.176626 -19.357594) (xy 206.170022 -19.364706) (xy 206.16291 -19.382232) (xy 206.16291 -19.47164)
			(xy 206.170022 -19.489166) (xy 206.176626 -19.496278) (xy 206.19593 -19.517575) (xy 206.22849 -19.564944)
			(xy 206.253576 -19.616661) (xy 206.270621 -19.671556) (xy 206.279239 -19.728386) (xy 206.279235 -19.785866)
			(xy 206.27061 -19.842696) (xy 206.253557 -19.897588) (xy 206.228464 -19.949302) (xy 206.195897 -19.996666)
			(xy 206.176626 -20.017994) (xy 206.170022 -20.025106) (xy 206.16291 -20.042632) (xy 206.16291 -20.13204)
			(xy 206.170022 -20.149566) (xy 206.176626 -20.156678) (xy 206.19593 -20.177975) (xy 206.22849 -20.225344)
			(xy 206.253576 -20.277061) (xy 206.270621 -20.331956) (xy 206.2742 -20.35556) (xy 215.678256 -20.35556)
			(xy 215.682327 -20.299938) (xy 215.694453 -20.245501) (xy 215.714376 -20.19341) (xy 215.741672 -20.144775)
			(xy 215.775758 -20.100632) (xy 215.815907 -20.061923) (xy 215.861265 -20.029472) (xy 215.910865 -20.003971)
			(xy 215.963649 -19.985964) (xy 216.018492 -19.975834) (xy 216.074226 -19.973797) (xy 216.129663 -19.979897)
			(xy 216.18362 -19.994003) (xy 216.234949 -20.015815) (xy 216.282555 -20.044869) (xy 216.325423 -20.080544)
			(xy 216.36264 -20.122081) (xy 216.393413 -20.168594) (xy 216.417085 -20.219091) (xy 216.433153 -20.272498)
			(xy 216.441273 -20.327674) (xy 216.441782 -20.35556) (xy 216.441273 -20.383446) (xy 216.433153 -20.438622)
			(xy 216.417085 -20.492029) (xy 216.393413 -20.542526) (xy 216.36264 -20.589039) (xy 216.325423 -20.630576)
			(xy 216.282555 -20.666251) (xy 216.234949 -20.695305) (xy 216.18362 -20.717117) (xy 216.129663 -20.731223)
			(xy 216.074226 -20.737323) (xy 216.018492 -20.735286) (xy 215.963649 -20.725156) (xy 215.910865 -20.707149)
			(xy 215.861265 -20.681648) (xy 215.815907 -20.649197) (xy 215.775758 -20.610488) (xy 215.741672 -20.566345)
			(xy 215.714376 -20.51771) (xy 215.694453 -20.465619) (xy 215.682327 -20.411182) (xy 215.678256 -20.35556)
			(xy 206.2742 -20.35556) (xy 206.279239 -20.388786) (xy 206.279235 -20.446266) (xy 206.27061 -20.503096)
			(xy 206.253557 -20.557988) (xy 206.228464 -20.609702) (xy 206.195897 -20.657066) (xy 206.176626 -20.678394)
			(xy 206.170022 -20.685506) (xy 206.16291 -20.703032) (xy 206.16291 -20.79244) (xy 206.170022 -20.809966)
			(xy 206.176626 -20.817078) (xy 206.19593 -20.838375) (xy 206.22849 -20.885744) (xy 206.253576 -20.937461)
			(xy 206.270621 -20.992356) (xy 206.279239 -21.049186) (xy 206.279235 -21.106666) (xy 206.27061 -21.163496)
			(xy 206.253557 -21.218388) (xy 206.228464 -21.270102) (xy 206.195897 -21.317466) (xy 206.176626 -21.338794)
			(xy 206.170022 -21.345906) (xy 206.16291 -21.363432) (xy 206.16291 -21.37156) (xy 215.678256 -21.37156)
			(xy 215.682327 -21.315938) (xy 215.694453 -21.261501) (xy 215.714376 -21.20941) (xy 215.741672 -21.160775)
			(xy 215.775758 -21.116632) (xy 215.815907 -21.077923) (xy 215.861265 -21.045472) (xy 215.910865 -21.019971)
			(xy 215.963649 -21.001964) (xy 216.018492 -20.991834) (xy 216.074226 -20.989797) (xy 216.129663 -20.995897)
			(xy 216.18362 -21.010003) (xy 216.234949 -21.031815) (xy 216.282555 -21.060869) (xy 216.325423 -21.096544)
			(xy 216.36264 -21.138081) (xy 216.393413 -21.184594) (xy 216.417085 -21.235091) (xy 216.433153 -21.288498)
			(xy 216.441273 -21.343674) (xy 216.441782 -21.37156) (xy 216.441273 -21.399446) (xy 216.433153 -21.454622)
			(xy 216.417085 -21.508029) (xy 216.393413 -21.558526) (xy 216.36264 -21.605039) (xy 216.325423 -21.646576)
			(xy 216.282555 -21.682251) (xy 216.234949 -21.711305) (xy 216.18362 -21.733117) (xy 216.129663 -21.747223)
			(xy 216.074226 -21.753323) (xy 216.018492 -21.751286) (xy 215.963649 -21.741156) (xy 215.910865 -21.723149)
			(xy 215.861265 -21.697648) (xy 215.815907 -21.665197) (xy 215.775758 -21.626488) (xy 215.741672 -21.582345)
			(xy 215.714376 -21.53371) (xy 215.694453 -21.481619) (xy 215.682327 -21.427182) (xy 215.678256 -21.37156)
			(xy 206.16291 -21.37156) (xy 206.16291 -21.45284) (xy 206.170022 -21.470366) (xy 206.176626 -21.477478)
			(xy 206.195908 -21.498796) (xy 206.228474 -21.54616) (xy 206.253565 -21.597873) (xy 206.270613 -21.652767)
			(xy 206.279232 -21.709596) (xy 206.27975 -21.738336) (xy 206.279264 -21.765587) (xy 206.271508 -21.819535)
			(xy 206.256153 -21.87183) (xy 206.233511 -21.921407) (xy 206.204045 -21.967257) (xy 206.168354 -22.008448)
			(xy 206.127163 -22.044139) (xy 206.081313 -22.073605) (xy 206.031736 -22.096247) (xy 205.979441 -22.111602)
			(xy 205.925493 -22.119358) (xy 205.870991 -22.119358) (xy 205.817043 -22.111602) (xy 205.764748 -22.096247)
			(xy 205.715171 -22.073605) (xy 205.669321 -22.044139) (xy 205.62813 -22.008448) (xy 205.592439 -21.967257)
			(xy 205.562973 -21.921407) (xy 205.540331 -21.87183) (xy 205.524976 -21.819535) (xy 205.51722 -21.765587)
			(xy 205.516734 -21.738336) (xy 203.643992 -21.738336) (xy 203.643992 -23.055063) (xy 205.387188 -23.055063)
			(xy 205.387188 -22.995129) (xy 205.395012 -22.935707) (xy 205.410524 -22.877815) (xy 205.433461 -22.822443)
			(xy 205.463428 -22.770539) (xy 205.499914 -22.72299) (xy 205.542295 -22.68061) (xy 205.589844 -22.644125)
			(xy 205.641749 -22.614158) (xy 205.697121 -22.591222) (xy 205.755013 -22.575711) (xy 205.814435 -22.567888)
			(xy 205.874369 -22.567888) (xy 205.933791 -22.575711) (xy 205.991683 -22.591224) (xy 206.047055 -22.61416)
			(xy 206.098959 -22.644127) (xy 206.146508 -22.680613) (xy 206.188888 -22.722993) (xy 206.225374 -22.770542)
			(xy 206.255341 -22.822447) (xy 206.278277 -22.877819) (xy 206.293789 -22.935711) (xy 206.301612 -22.995133)
			(xy 206.302102 -23.0251) (xy 206.301878 -23.045661) (xy 206.298189 -23.086618) (xy 206.294736 -23.106888)
			(xy 206.292196 -23.120604) (xy 206.301086 -23.145496) (xy 206.3877 -23.22068) (xy 206.413608 -23.226014)
			(xy 206.426816 -23.221696) (xy 206.456017 -23.212602) (xy 206.51638 -23.202782) (xy 206.546958 -23.202138)
			(xy 206.565885 -23.202399) (xy 206.603547 -23.206217) (xy 206.622142 -23.209758) (xy 206.634842 -23.212044)
			(xy 206.658464 -23.205186) (xy 206.73695 -23.128986) (xy 206.74457 -23.105618) (xy 206.742538 -23.092918)
			(xy 206.739478 -23.073888) (xy 206.736167 -23.035483) (xy 206.735934 -23.01621) (xy 206.736371 -22.986242)
			(xy 206.744193 -22.926819) (xy 206.759704 -22.868925) (xy 206.782639 -22.813551) (xy 206.812605 -22.761644)
			(xy 206.84909 -22.714093) (xy 206.89147 -22.671711) (xy 206.939019 -22.635222) (xy 206.990924 -22.605253)
			(xy 207.046296 -22.582314) (xy 207.104189 -22.566799) (xy 207.163611 -22.558973) (xy 207.223547 -22.558971)
			(xy 207.282971 -22.566791) (xy 207.340865 -22.582301) (xy 207.396239 -22.605234) (xy 207.448147 -22.635199)
			(xy 207.495699 -22.671683) (xy 207.538082 -22.714062) (xy 207.574572 -22.76161) (xy 207.604543 -22.813514)
			(xy 207.627483 -22.868886) (xy 207.642999 -22.926778) (xy 207.650826 -22.986201) (xy 207.65083 -23.046137)
			(xy 207.643011 -23.10556) (xy 207.627503 -23.163455) (xy 207.60457 -23.21883) (xy 207.574607 -23.270738)
			(xy 207.538124 -23.318291) (xy 207.495746 -23.360675) (xy 207.448199 -23.397166) (xy 207.396296 -23.427138)
			(xy 207.340924 -23.450079) (xy 207.283032 -23.465597) (xy 207.22361 -23.473425) (xy 207.193642 -23.473918)
			(xy 207.159397 -23.473312) (xy 207.091671 -23.463109) (xy 207.058768 -23.453598) (xy 207.046576 -23.449788)
			(xy 207.022446 -23.45436) (xy 206.936594 -23.522178) (xy 206.926688 -23.544784) (xy 206.927704 -23.557738)
			(xy 206.928466 -23.583646) (xy 206.92798 -23.610897) (xy 206.926676 -23.619964) (xy 210.10929 -23.619964)
			(xy 210.10929 -23.560028) (xy 210.117113 -23.500606) (xy 210.132626 -23.442713) (xy 210.155562 -23.38734)
			(xy 210.185529 -23.335434) (xy 210.222016 -23.287884) (xy 210.264396 -23.245504) (xy 210.311946 -23.209017)
			(xy 210.363852 -23.17905) (xy 210.419225 -23.156114) (xy 210.477118 -23.140601) (xy 210.53654 -23.132778)
			(xy 210.596476 -23.132778) (xy 210.655898 -23.140601) (xy 210.713791 -23.156114) (xy 210.769164 -23.17905)
			(xy 210.82107 -23.209017) (xy 210.86862 -23.245504) (xy 210.911 -23.287884) (xy 210.947487 -23.335434)
			(xy 210.977454 -23.38734) (xy 211.00039 -23.442713) (xy 211.015903 -23.500606) (xy 211.023726 -23.560028)
			(xy 211.024216 -23.589996) (xy 211.023726 -23.619964) (xy 211.015903 -23.679386) (xy 211.00039 -23.737279)
			(xy 210.977454 -23.792652) (xy 210.947487 -23.844558) (xy 210.920047 -23.880318) (xy 211.340698 -23.880318)
			(xy 211.344769 -23.824696) (xy 211.356895 -23.770259) (xy 211.376818 -23.718168) (xy 211.404114 -23.669533)
			(xy 211.4382 -23.62539) (xy 211.478349 -23.586681) (xy 211.523707 -23.55423) (xy 211.573307 -23.528729)
			(xy 211.626091 -23.510722) (xy 211.680934 -23.500592) (xy 211.736668 -23.498555) (xy 211.792105 -23.504655)
			(xy 211.846062 -23.518761) (xy 211.897391 -23.540573) (xy 211.944997 -23.569627) (xy 211.987865 -23.605302)
			(xy 212.025082 -23.646839) (xy 212.055855 -23.693352) (xy 212.079527 -23.743849) (xy 212.095595 -23.797256)
			(xy 212.103715 -23.852432) (xy 212.104224 -23.880318) (xy 212.356698 -23.880318) (xy 212.360769 -23.824696)
			(xy 212.372895 -23.770259) (xy 212.392818 -23.718168) (xy 212.420114 -23.669533) (xy 212.4542 -23.62539)
			(xy 212.494349 -23.586681) (xy 212.539707 -23.55423) (xy 212.589307 -23.528729) (xy 212.642091 -23.510722)
			(xy 212.696934 -23.500592) (xy 212.752668 -23.498555) (xy 212.808105 -23.504655) (xy 212.862062 -23.518761)
			(xy 212.913391 -23.540573) (xy 212.960997 -23.569627) (xy 213.003865 -23.605302) (xy 213.041082 -23.646839)
			(xy 213.071855 -23.693352) (xy 213.095527 -23.743849) (xy 213.111595 -23.797256) (xy 213.119715 -23.852432)
			(xy 213.120224 -23.880318) (xy 213.372698 -23.880318) (xy 213.376769 -23.824696) (xy 213.388895 -23.770259)
			(xy 213.408818 -23.718168) (xy 213.436114 -23.669533) (xy 213.4702 -23.62539) (xy 213.510349 -23.586681)
			(xy 213.555707 -23.55423) (xy 213.605307 -23.528729) (xy 213.658091 -23.510722) (xy 213.712934 -23.500592)
			(xy 213.768668 -23.498555) (xy 213.824105 -23.504655) (xy 213.878062 -23.518761) (xy 213.929391 -23.540573)
			(xy 213.976997 -23.569627) (xy 214.019865 -23.605302) (xy 214.057082 -23.646839) (xy 214.087855 -23.693352)
			(xy 214.111527 -23.743849) (xy 214.127595 -23.797256) (xy 214.135715 -23.852432) (xy 214.136224 -23.880318)
			(xy 214.390984 -23.880318) (xy 214.395055 -23.824696) (xy 214.407181 -23.770259) (xy 214.427104 -23.718168)
			(xy 214.4544 -23.669533) (xy 214.488486 -23.62539) (xy 214.528635 -23.586681) (xy 214.573993 -23.55423)
			(xy 214.623593 -23.528729) (xy 214.676377 -23.510722) (xy 214.73122 -23.500592) (xy 214.786954 -23.498555)
			(xy 214.842391 -23.504655) (xy 214.896348 -23.518761) (xy 214.947677 -23.540573) (xy 214.995283 -23.569627)
			(xy 215.038151 -23.605302) (xy 215.075368 -23.646839) (xy 215.106141 -23.693352) (xy 215.129813 -23.743849)
			(xy 215.145881 -23.797256) (xy 215.154001 -23.852432) (xy 215.15451 -23.880318) (xy 215.154001 -23.908204)
			(xy 215.145881 -23.96338) (xy 215.129813 -24.016787) (xy 215.106141 -24.067284) (xy 215.075368 -24.113797)
			(xy 215.038151 -24.155334) (xy 214.995283 -24.191009) (xy 214.947677 -24.220063) (xy 214.896348 -24.241875)
			(xy 214.842391 -24.255981) (xy 214.786954 -24.262081) (xy 214.73122 -24.260044) (xy 214.676377 -24.249914)
			(xy 214.623593 -24.231907) (xy 214.573993 -24.206406) (xy 214.528635 -24.173955) (xy 214.488486 -24.135246)
			(xy 214.4544 -24.091103) (xy 214.427104 -24.042468) (xy 214.407181 -23.990377) (xy 214.395055 -23.93594)
			(xy 214.390984 -23.880318) (xy 214.136224 -23.880318) (xy 214.135715 -23.908204) (xy 214.127595 -23.96338)
			(xy 214.111527 -24.016787) (xy 214.087855 -24.067284) (xy 214.057082 -24.113797) (xy 214.019865 -24.155334)
			(xy 213.976997 -24.191009) (xy 213.929391 -24.220063) (xy 213.878062 -24.241875) (xy 213.824105 -24.255981)
			(xy 213.768668 -24.262081) (xy 213.712934 -24.260044) (xy 213.658091 -24.249914) (xy 213.605307 -24.231907)
			(xy 213.555707 -24.206406) (xy 213.510349 -24.173955) (xy 213.4702 -24.135246) (xy 213.436114 -24.091103)
			(xy 213.408818 -24.042468) (xy 213.388895 -23.990377) (xy 213.376769 -23.93594) (xy 213.372698 -23.880318)
			(xy 213.120224 -23.880318) (xy 213.119715 -23.908204) (xy 213.111595 -23.96338) (xy 213.095527 -24.016787)
			(xy 213.071855 -24.067284) (xy 213.041082 -24.113797) (xy 213.003865 -24.155334) (xy 212.960997 -24.191009)
			(xy 212.913391 -24.220063) (xy 212.862062 -24.241875) (xy 212.808105 -24.255981) (xy 212.752668 -24.262081)
			(xy 212.696934 -24.260044) (xy 212.642091 -24.249914) (xy 212.589307 -24.231907) (xy 212.539707 -24.206406)
			(xy 212.494349 -24.173955) (xy 212.4542 -24.135246) (xy 212.420114 -24.091103) (xy 212.392818 -24.042468)
			(xy 212.372895 -23.990377) (xy 212.360769 -23.93594) (xy 212.356698 -23.880318) (xy 212.104224 -23.880318)
			(xy 212.103715 -23.908204) (xy 212.095595 -23.96338) (xy 212.079527 -24.016787) (xy 212.055855 -24.067284)
			(xy 212.025082 -24.113797) (xy 211.987865 -24.155334) (xy 211.944997 -24.191009) (xy 211.897391 -24.220063)
			(xy 211.846062 -24.241875) (xy 211.792105 -24.255981) (xy 211.736668 -24.262081) (xy 211.680934 -24.260044)
			(xy 211.626091 -24.249914) (xy 211.573307 -24.231907) (xy 211.523707 -24.206406) (xy 211.478349 -24.173955)
			(xy 211.4382 -24.135246) (xy 211.404114 -24.091103) (xy 211.376818 -24.042468) (xy 211.356895 -23.990377)
			(xy 211.344769 -23.93594) (xy 211.340698 -23.880318) (xy 210.920047 -23.880318) (xy 210.911 -23.892108)
			(xy 210.86862 -23.934488) (xy 210.82107 -23.970975) (xy 210.769164 -24.000942) (xy 210.713791 -24.023878)
			(xy 210.655898 -24.039391) (xy 210.596476 -24.047214) (xy 210.53654 -24.047214) (xy 210.477118 -24.039391)
			(xy 210.419225 -24.023878) (xy 210.363852 -24.000942) (xy 210.311946 -23.970975) (xy 210.264396 -23.934488)
			(xy 210.222016 -23.892108) (xy 210.185529 -23.844558) (xy 210.155562 -23.792652) (xy 210.132626 -23.737279)
			(xy 210.117113 -23.679386) (xy 210.10929 -23.619964) (xy 206.926676 -23.619964) (xy 206.920224 -23.664845)
			(xy 206.904869 -23.71714) (xy 206.882227 -23.766717) (xy 206.852761 -23.812567) (xy 206.81707 -23.853758)
			(xy 206.775879 -23.889449) (xy 206.730029 -23.918915) (xy 206.680452 -23.941557) (xy 206.628157 -23.956912)
			(xy 206.574209 -23.964668) (xy 206.519707 -23.964668) (xy 206.465759 -23.956912) (xy 206.413464 -23.941557)
			(xy 206.363887 -23.918915) (xy 206.318037 -23.889449) (xy 206.276846 -23.853758) (xy 206.241155 -23.812567)
			(xy 206.211689 -23.766717) (xy 206.189047 -23.71714) (xy 206.173692 -23.664845) (xy 206.165936 -23.610897)
			(xy 206.16545 -23.583646) (xy 206.167228 -23.548086) (xy 206.168498 -23.53437) (xy 206.157576 -23.51024)
			(xy 206.064612 -23.44293) (xy 206.038196 -23.439882) (xy 206.02575 -23.44547) (xy 205.99699 -23.45728)
			(xy 205.937085 -23.473919) (xy 205.87548 -23.482302) (xy 205.844394 -23.482808) (xy 205.814427 -23.482312)
			(xy 205.755005 -23.474488) (xy 205.697113 -23.458975) (xy 205.641742 -23.436038) (xy 205.589837 -23.406071)
			(xy 205.542289 -23.369584) (xy 205.499909 -23.327204) (xy 205.463424 -23.279654) (xy 205.433457 -23.227749)
			(xy 205.410522 -23.172377) (xy 205.39501 -23.114485) (xy 205.387188 -23.055063) (xy 203.643992 -23.055063)
			(xy 203.643992 -24.189944) (xy 205.398876 -24.189944) (xy 205.402947 -24.134322) (xy 205.415073 -24.079885)
			(xy 205.434996 -24.027794) (xy 205.462292 -23.979159) (xy 205.496378 -23.935016) (xy 205.536527 -23.896307)
			(xy 205.581885 -23.863856) (xy 205.631485 -23.838355) (xy 205.684269 -23.820348) (xy 205.739112 -23.810218)
			(xy 205.794846 -23.808181) (xy 205.850283 -23.814281) (xy 205.90424 -23.828387) (xy 205.955569 -23.850199)
			(xy 206.003175 -23.879253) (xy 206.046043 -23.914928) (xy 206.08326 -23.956465) (xy 206.114033 -24.002978)
			(xy 206.137705 -24.053475) (xy 206.153773 -24.106882) (xy 206.161893 -24.162058) (xy 206.162402 -24.189944)
			(xy 207.921858 -24.189944) (xy 207.925929 -24.134322) (xy 207.938055 -24.079885) (xy 207.957978 -24.027794)
			(xy 207.985274 -23.979159) (xy 208.01936 -23.935016) (xy 208.059509 -23.896307) (xy 208.104867 -23.863856)
			(xy 208.154467 -23.838355) (xy 208.207251 -23.820348) (xy 208.262094 -23.810218) (xy 208.317828 -23.808181)
			(xy 208.373265 -23.814281) (xy 208.427222 -23.828387) (xy 208.478551 -23.850199) (xy 208.526157 -23.879253)
			(xy 208.569025 -23.914928) (xy 208.606242 -23.956465) (xy 208.637015 -24.002978) (xy 208.660687 -24.053475)
			(xy 208.676755 -24.106882) (xy 208.684875 -24.162058) (xy 208.685384 -24.189944) (xy 208.684875 -24.21783)
			(xy 208.676755 -24.273006) (xy 208.660687 -24.326413) (xy 208.637015 -24.37691) (xy 208.606242 -24.423423)
			(xy 208.569025 -24.46496) (xy 208.526157 -24.500635) (xy 208.478551 -24.529689) (xy 208.427222 -24.551501)
			(xy 208.373265 -24.565607) (xy 208.317828 -24.571707) (xy 208.262094 -24.56967) (xy 208.207251 -24.55954)
			(xy 208.154467 -24.541533) (xy 208.104867 -24.516032) (xy 208.059509 -24.483581) (xy 208.01936 -24.444872)
			(xy 207.985274 -24.400729) (xy 207.957978 -24.352094) (xy 207.938055 -24.300003) (xy 207.925929 -24.245566)
			(xy 207.921858 -24.189944) (xy 206.162402 -24.189944) (xy 206.161893 -24.21783) (xy 206.153773 -24.273006)
			(xy 206.137705 -24.326413) (xy 206.114033 -24.37691) (xy 206.08326 -24.423423) (xy 206.046043 -24.46496)
			(xy 206.003175 -24.500635) (xy 205.955569 -24.529689) (xy 205.90424 -24.551501) (xy 205.850283 -24.565607)
			(xy 205.794846 -24.571707) (xy 205.739112 -24.56967) (xy 205.684269 -24.55954) (xy 205.631485 -24.541533)
			(xy 205.581885 -24.516032) (xy 205.536527 -24.483581) (xy 205.496378 -24.444872) (xy 205.462292 -24.400729)
			(xy 205.434996 -24.352094) (xy 205.415073 -24.300003) (xy 205.402947 -24.245566) (xy 205.398876 -24.189944)
			(xy 203.643992 -24.189944) (xy 203.643992 -25.390094) (xy 207.833468 -25.390094) (xy 207.833958 -25.360126)
			(xy 207.841781 -25.300704) (xy 207.857294 -25.242811) (xy 207.88023 -25.187438) (xy 207.910197 -25.135532)
			(xy 207.946684 -25.087982) (xy 207.989064 -25.045602) (xy 208.036614 -25.009115) (xy 208.08852 -24.979148)
			(xy 208.143893 -24.956212) (xy 208.201786 -24.940699) (xy 208.261208 -24.932876) (xy 208.321144 -24.932876)
			(xy 208.380566 -24.940699) (xy 208.438459 -24.956212) (xy 208.493832 -24.979148) (xy 208.545738 -25.009115)
			(xy 208.593288 -25.045602) (xy 208.635668 -25.087982) (xy 208.672155 -25.135532) (xy 208.702122 -25.187438)
			(xy 208.725058 -25.242811) (xy 208.740571 -25.300704) (xy 208.748394 -25.360126) (xy 208.748884 -25.390094)
			(xy 208.748456 -25.418879) (xy 208.741237 -25.475994) (xy 208.726913 -25.531753) (xy 208.705709 -25.585275)
			(xy 208.677961 -25.635716) (xy 208.644106 -25.682279) (xy 208.60468 -25.724228) (xy 208.582768 -25.7429)
			(xy 208.574386 -25.749758) (xy 208.564734 -25.769316) (xy 208.561432 -25.867106) (xy 208.56956 -25.887172)
			(xy 208.577688 -25.894792) (xy 208.596094 -25.912863) (xy 208.62833 -25.953132) (xy 208.654852 -25.997373)
			(xy 208.675178 -26.044781) (xy 208.688938 -26.094494) (xy 208.695881 -26.145607) (xy 208.696306 -26.171398)
			(xy 208.69582 -26.198649) (xy 208.688064 -26.252597) (xy 208.672709 -26.304892) (xy 208.650067 -26.354469)
			(xy 208.620601 -26.400319) (xy 208.58491 -26.44151) (xy 208.543719 -26.477201) (xy 208.497869 -26.506667)
			(xy 208.448292 -26.529309) (xy 208.395997 -26.544664) (xy 208.342049 -26.55242) (xy 208.287547 -26.55242)
			(xy 208.233599 -26.544664) (xy 208.181304 -26.529309) (xy 208.131727 -26.506667) (xy 208.085877 -26.477201)
			(xy 208.044686 -26.44151) (xy 208.008995 -26.400319) (xy 207.979529 -26.354469) (xy 207.956887 -26.304892)
			(xy 207.941532 -26.252597) (xy 207.933776 -26.198649) (xy 207.93329 -26.171398) (xy 207.93381 -26.142755)
			(xy 207.942407 -26.086117) (xy 207.959378 -26.031401) (xy 207.984341 -25.979839) (xy 208.016734 -25.93259)
			(xy 208.035906 -25.911302) (xy 208.043272 -25.903174) (xy 208.05013 -25.8826) (xy 208.040986 -25.785064)
			(xy 208.030318 -25.766268) (xy 208.021428 -25.759918) (xy 207.996886 -25.74136) (xy 207.952491 -25.69876)
			(xy 207.9142 -25.650599) (xy 207.882702 -25.597745) (xy 207.858565 -25.541149) (xy 207.842224 -25.48183)
			(xy 207.833973 -25.420858) (xy 207.833468 -25.390094) (xy 203.643992 -25.390094) (xy 203.643992 -25.506934)
			(xy 203.644421 -25.517002) (xy 203.652143 -25.535598) (xy 203.658978 -25.543002) (xy 203.710286 -25.593802)
			(xy 203.717695 -25.600488) (xy 203.736131 -25.608075) (xy 203.7461 -25.608534) (xy 203.748894 -25.608534)
			(xy 203.776144 -25.608997) (xy 203.83009 -25.616752) (xy 203.882383 -25.632106) (xy 203.931958 -25.654746)
			(xy 203.977807 -25.68421) (xy 204.018996 -25.7199) (xy 204.054686 -25.761088) (xy 204.084151 -25.806937)
			(xy 204.106792 -25.856512) (xy 204.122146 -25.908804) (xy 204.129903 -25.96275) (xy 204.129903 -25.990042)
			(xy 205.398876 -25.990042) (xy 205.402947 -25.93442) (xy 205.415073 -25.879983) (xy 205.434996 -25.827892)
			(xy 205.462292 -25.779257) (xy 205.496378 -25.735114) (xy 205.536527 -25.696405) (xy 205.581885 -25.663954)
			(xy 205.631485 -25.638453) (xy 205.684269 -25.620446) (xy 205.739112 -25.610316) (xy 205.794846 -25.608279)
			(xy 205.850283 -25.614379) (xy 205.90424 -25.628485) (xy 205.955569 -25.650297) (xy 206.003175 -25.679351)
			(xy 206.046043 -25.715026) (xy 206.08326 -25.756563) (xy 206.114033 -25.803076) (xy 206.137705 -25.853573)
			(xy 206.153773 -25.90698) (xy 206.161893 -25.962156) (xy 206.162402 -25.990042) (xy 206.161893 -26.017928)
			(xy 206.153773 -26.073104) (xy 206.137705 -26.126511) (xy 206.114033 -26.177008) (xy 206.08326 -26.223521)
			(xy 206.046043 -26.265058) (xy 206.003175 -26.300733) (xy 205.955569 -26.329787) (xy 205.90424 -26.351599)
			(xy 205.850283 -26.365705) (xy 205.794846 -26.371805) (xy 205.739112 -26.369768) (xy 205.684269 -26.359638)
			(xy 205.631485 -26.341631) (xy 205.581885 -26.31613) (xy 205.536527 -26.283679) (xy 205.496378 -26.24497)
			(xy 205.462292 -26.200827) (xy 205.434996 -26.152192) (xy 205.415073 -26.100101) (xy 205.402947 -26.045664)
			(xy 205.398876 -25.990042) (xy 204.129903 -25.990042) (xy 204.129903 -26.01725) (xy 204.122146 -26.071196)
			(xy 204.106792 -26.123488) (xy 204.084151 -26.173063) (xy 204.054686 -26.218912) (xy 204.018996 -26.2601)
			(xy 203.977807 -26.29579) (xy 203.931958 -26.325254) (xy 203.882383 -26.347894) (xy 203.83009 -26.363248)
			(xy 203.776144 -26.371003) (xy 203.748894 -26.37155) (xy 203.7461 -26.37155) (xy 203.736134 -26.372026)
			(xy 203.717697 -26.379602) (xy 203.710286 -26.386282) (xy 203.658978 -26.437082) (xy 203.652136 -26.444481)
			(xy 203.644419 -26.46308) (xy 203.643992 -26.47315) (xy 203.643992 -27.307032) (xy 203.644421 -27.3171)
			(xy 203.652142 -27.335697) (xy 203.658978 -27.3431) (xy 203.710286 -27.3939) (xy 203.717695 -27.400586)
			(xy 203.736131 -27.408174) (xy 203.7461 -27.408632) (xy 203.748894 -27.408632) (xy 203.776144 -27.409095)
			(xy 203.83009 -27.41685) (xy 203.882383 -27.432204) (xy 203.931959 -27.454844) (xy 203.977808 -27.484309)
			(xy 204.018997 -27.519999) (xy 204.054688 -27.561187) (xy 204.084153 -27.607036) (xy 204.106794 -27.656611)
			(xy 204.122148 -27.708904) (xy 204.129905 -27.76285) (xy 204.129905 -27.79014) (xy 205.462884 -27.79014)
			(xy 205.466955 -27.734518) (xy 205.479081 -27.680081) (xy 205.499004 -27.62799) (xy 205.5263 -27.579355)
			(xy 205.560386 -27.535212) (xy 205.600535 -27.496503) (xy 205.645893 -27.464052) (xy 205.695493 -27.438551)
			(xy 205.748277 -27.420544) (xy 205.80312 -27.410414) (xy 205.858854 -27.408377) (xy 205.914291 -27.414477)
			(xy 205.968248 -27.428583) (xy 206.019577 -27.450395) (xy 206.067183 -27.479449) (xy 206.110051 -27.515124)
			(xy 206.147268 -27.556661) (xy 206.178041 -27.603174) (xy 206.201713 -27.653671) (xy 206.217781 -27.707078)
			(xy 206.225901 -27.762254) (xy 206.22641 -27.79014) (xy 207.966816 -27.79014) (xy 207.970887 -27.734518)
			(xy 207.983013 -27.680081) (xy 208.002936 -27.62799) (xy 208.030232 -27.579355) (xy 208.064318 -27.535212)
			(xy 208.104467 -27.496503) (xy 208.149825 -27.464052) (xy 208.199425 -27.438551) (xy 208.252209 -27.420544)
			(xy 208.307052 -27.410414) (xy 208.362786 -27.408377) (xy 208.418223 -27.414477) (xy 208.47218 -27.428583)
			(xy 208.523509 -27.450395) (xy 208.571115 -27.479449) (xy 208.613983 -27.515124) (xy 208.6512 -27.556661)
			(xy 208.681973 -27.603174) (xy 208.705645 -27.653671) (xy 208.721713 -27.707078) (xy 208.729833 -27.762254)
			(xy 208.730342 -27.79014) (xy 208.729845 -27.817352) (xy 209.999795 -27.817352) (xy 209.999795 -27.762848)
			(xy 210.007552 -27.7089) (xy 210.022909 -27.656605) (xy 210.045551 -27.607028) (xy 210.075019 -27.561178)
			(xy 210.110713 -27.519989) (xy 210.151905 -27.484299) (xy 210.197758 -27.454835) (xy 210.247337 -27.432197)
			(xy 210.299633 -27.416845) (xy 210.353582 -27.409093) (xy 210.380834 -27.408632) (xy 210.406142 -27.40902)
			(xy 210.456314 -27.415696) (xy 210.505166 -27.428939) (xy 210.528662 -27.43835) (xy 210.536661 -27.441398)
			(xy 210.553737 -27.442481) (xy 210.570219 -27.437884) (xy 210.57743 -27.43327) (xy 210.60283 -27.41549)
			(xy 210.609706 -27.410203) (xy 210.619787 -27.396107) (xy 210.624588 -27.379456) (xy 210.62442 -27.370786)
			(xy 210.623404 -27.342846) (xy 210.623404 -26.479246) (xy 210.624166 -26.456894) (xy 210.624674 -26.444448)
			(xy 210.61426 -26.421842) (xy 210.52917 -26.355548) (xy 210.504786 -26.350976) (xy 210.492848 -26.354786)
			(xy 210.465513 -26.362635) (xy 210.409269 -26.371048) (xy 210.380834 -26.37155) (xy 210.353583 -26.371005)
			(xy 210.299634 -26.363253) (xy 210.247338 -26.347902) (xy 210.197759 -26.325263) (xy 210.151906 -26.2958)
			(xy 210.110714 -26.26011) (xy 210.075021 -26.218921) (xy 210.045553 -26.173071) (xy 210.02291 -26.123494)
			(xy 210.007554 -26.071199) (xy 209.999797 -26.017251) (xy 209.999797 -25.962749) (xy 210.007554 -25.908801)
			(xy 210.02291 -25.856506) (xy 210.045553 -25.806929) (xy 210.075021 -25.761079) (xy 210.110714 -25.71989)
			(xy 210.151906 -25.6842) (xy 210.197759 -25.654737) (xy 210.247338 -25.632098) (xy 210.299634 -25.616747)
			(xy 210.353583 -25.608995) (xy 210.380834 -25.608534) (xy 210.409787 -25.609045) (xy 210.467029 -25.617787)
			(xy 210.522293 -25.635079) (xy 210.574308 -25.660524) (xy 210.621881 -25.693539) (xy 210.663917 -25.733364)
			(xy 210.699452 -25.779084) (xy 210.727669 -25.82965) (xy 210.728566 -25.832054) (xy 212.288374 -25.832054)
			(xy 212.288831 -25.80545) (xy 212.296207 -25.752756) (xy 212.310838 -25.701599) (xy 212.332438 -25.652973)
			(xy 212.360589 -25.607822) (xy 212.394744 -25.567023) (xy 212.434239 -25.53137) (xy 212.456014 -25.516078)
			(xy 212.467489 -25.507738) (xy 212.48569 -25.485995) (xy 212.497205 -25.460083) (xy 212.501145 -25.432002)
			(xy 212.497206 -25.403922) (xy 212.485692 -25.378009) (xy 212.467492 -25.356265) (xy 212.456014 -25.34793)
			(xy 212.434243 -25.332636) (xy 212.394765 -25.296969) (xy 212.360623 -25.256165) (xy 212.332478 -25.211015)
			(xy 212.310876 -25.162393) (xy 212.296235 -25.111243) (xy 212.288839 -25.058556) (xy 212.288374 -25.031954)
			(xy 212.28886 -25.004703) (xy 212.296616 -24.950755) (xy 212.311971 -24.89846) (xy 212.334613 -24.848883)
			(xy 212.364079 -24.803033) (xy 212.39977 -24.761842) (xy 212.440961 -24.726151) (xy 212.486811 -24.696685)
			(xy 212.536388 -24.674043) (xy 212.588683 -24.658688) (xy 212.642631 -24.650932) (xy 212.697133 -24.650932)
			(xy 212.751081 -24.658688) (xy 212.803376 -24.674043) (xy 212.852953 -24.696685) (xy 212.898803 -24.726151)
			(xy 212.939994 -24.761842) (xy 212.963195 -24.788618) (xy 214.89338 -24.788618) (xy 214.89338 -24.728682)
			(xy 214.901203 -24.66926) (xy 214.916716 -24.611367) (xy 214.939652 -24.555994) (xy 214.969619 -24.504088)
			(xy 215.006106 -24.456538) (xy 215.048486 -24.414158) (xy 215.096036 -24.377671) (xy 215.147942 -24.347704)
			(xy 215.203315 -24.324768) (xy 215.261208 -24.309255) (xy 215.32063 -24.301432) (xy 215.380566 -24.301432)
			(xy 215.439988 -24.309255) (xy 215.497881 -24.324768) (xy 215.553254 -24.347704) (xy 215.60516 -24.377671)
			(xy 215.65271 -24.414158) (xy 215.69509 -24.456538) (xy 215.731577 -24.504088) (xy 215.761544 -24.555994)
			(xy 215.78448 -24.611367) (xy 215.799993 -24.66926) (xy 215.807816 -24.728682) (xy 215.808306 -24.75865)
			(xy 215.807816 -24.788618) (xy 215.799993 -24.84804) (xy 215.78448 -24.905933) (xy 215.761544 -24.961306)
			(xy 215.731577 -25.013212) (xy 215.69509 -25.060762) (xy 215.65271 -25.103142) (xy 215.60516 -25.139629)
			(xy 215.553254 -25.169596) (xy 215.497881 -25.192532) (xy 215.439988 -25.208045) (xy 215.380566 -25.215868)
			(xy 215.32063 -25.215868) (xy 215.261208 -25.208045) (xy 215.203315 -25.192532) (xy 215.147942 -25.169596)
			(xy 215.096036 -25.139629) (xy 215.048486 -25.103142) (xy 215.006106 -25.060762) (xy 214.969619 -25.013212)
			(xy 214.939652 -24.961306) (xy 214.916716 -24.905933) (xy 214.901203 -24.84804) (xy 214.89338 -24.788618)
			(xy 212.963195 -24.788618) (xy 212.975685 -24.803033) (xy 213.005151 -24.848883) (xy 213.027793 -24.89846)
			(xy 213.043148 -24.950755) (xy 213.050904 -25.004703) (xy 213.05139 -25.031954) (xy 213.050911 -25.058557)
			(xy 213.043535 -25.111249) (xy 213.028906 -25.162404) (xy 213.007309 -25.211029) (xy 212.979162 -25.25618)
			(xy 212.945012 -25.29698) (xy 212.905522 -25.332636) (xy 212.88375 -25.34793) (xy 212.872261 -25.356256)
			(xy 212.854049 -25.377999) (xy 212.842526 -25.403915) (xy 212.838584 -25.432002) (xy 212.842527 -25.460089)
			(xy 212.854051 -25.486005) (xy 212.872265 -25.507747) (xy 212.88375 -25.516078) (xy 212.905517 -25.531378)
			(xy 212.944996 -25.567043) (xy 212.97914 -25.607846) (xy 213.007286 -25.652995) (xy 213.028889 -25.701615)
			(xy 213.04353 -25.752765) (xy 213.050926 -25.805452) (xy 213.05139 -25.832054) (xy 213.050904 -25.859305)
			(xy 213.043148 -25.913253) (xy 213.027793 -25.965548) (xy 213.005151 -26.015125) (xy 212.975685 -26.060975)
			(xy 212.939994 -26.102166) (xy 212.898803 -26.137857) (xy 212.852953 -26.167323) (xy 212.803376 -26.189965)
			(xy 212.751081 -26.20532) (xy 212.697133 -26.213076) (xy 212.642631 -26.213076) (xy 212.588683 -26.20532)
			(xy 212.536388 -26.189965) (xy 212.486811 -26.167323) (xy 212.440961 -26.137857) (xy 212.39977 -26.102166)
			(xy 212.364079 -26.060975) (xy 212.334613 -26.015125) (xy 212.311971 -25.965548) (xy 212.296616 -25.913253)
			(xy 212.28886 -25.859305) (xy 212.288374 -25.832054) (xy 210.728566 -25.832054) (xy 210.74792 -25.883899)
			(xy 210.759739 -25.940586) (xy 210.761834 -25.969468) (xy 210.762342 -25.981914) (xy 210.775042 -26.00325)
			(xy 210.866736 -26.060654) (xy 210.891374 -26.062432) (xy 210.902804 -26.057606) (xy 210.931164 -26.046144)
			(xy 210.990161 -26.029986) (xy 211.050782 -26.021812) (xy 211.081366 -26.021284) (xy 211.111353 -26.021739)
			(xy 211.170814 -26.029564) (xy 211.228744 -26.045083) (xy 211.284153 -26.068032) (xy 211.336093 -26.098018)
			(xy 211.383673 -26.134528) (xy 211.42608 -26.176936) (xy 211.462588 -26.224517) (xy 211.492573 -26.276457)
			(xy 211.515521 -26.331867) (xy 211.523293 -26.360882) (xy 213.189564 -26.360882) (xy 213.193635 -26.30526)
			(xy 213.205761 -26.250823) (xy 213.225684 -26.198732) (xy 213.25298 -26.150097) (xy 213.287066 -26.105954)
			(xy 213.327215 -26.067245) (xy 213.372573 -26.034794) (xy 213.422173 -26.009293) (xy 213.474957 -25.991286)
			(xy 213.5298 -25.981156) (xy 213.585534 -25.979119) (xy 213.640971 -25.985219) (xy 213.694928 -25.999325)
			(xy 213.746257 -26.021137) (xy 213.793863 -26.050191) (xy 213.836731 -26.085866) (xy 213.873948 -26.127403)
			(xy 213.904721 -26.173916) (xy 213.928393 -26.224413) (xy 213.944461 -26.27782) (xy 213.952581 -26.332996)
			(xy 213.95309 -26.360882) (xy 214.205564 -26.360882) (xy 214.209635 -26.30526) (xy 214.221761 -26.250823)
			(xy 214.241684 -26.198732) (xy 214.26898 -26.150097) (xy 214.303066 -26.105954) (xy 214.343215 -26.067245)
			(xy 214.388573 -26.034794) (xy 214.438173 -26.009293) (xy 214.490957 -25.991286) (xy 214.5458 -25.981156)
			(xy 214.601534 -25.979119) (xy 214.656971 -25.985219) (xy 214.710928 -25.999325) (xy 214.762257 -26.021137)
			(xy 214.809863 -26.050191) (xy 214.852731 -26.085866) (xy 214.889948 -26.127403) (xy 214.920721 -26.173916)
			(xy 214.944393 -26.224413) (xy 214.960461 -26.27782) (xy 214.968581 -26.332996) (xy 214.96909 -26.360882)
			(xy 214.968581 -26.388768) (xy 214.960461 -26.443944) (xy 214.944393 -26.497351) (xy 214.920721 -26.547848)
			(xy 214.889948 -26.594361) (xy 214.852731 -26.635898) (xy 214.809863 -26.671573) (xy 214.762257 -26.700627)
			(xy 214.710928 -26.722439) (xy 214.656971 -26.736545) (xy 214.601534 -26.742645) (xy 214.5458 -26.740608)
			(xy 214.490957 -26.730478) (xy 214.438173 -26.712471) (xy 214.388573 -26.68697) (xy 214.343215 -26.654519)
			(xy 214.303066 -26.61581) (xy 214.26898 -26.571667) (xy 214.241684 -26.523032) (xy 214.221761 -26.470941)
			(xy 214.209635 -26.416504) (xy 214.205564 -26.360882) (xy 213.95309 -26.360882) (xy 213.952581 -26.388768)
			(xy 213.944461 -26.443944) (xy 213.928393 -26.497351) (xy 213.904721 -26.547848) (xy 213.873948 -26.594361)
			(xy 213.836731 -26.635898) (xy 213.793863 -26.671573) (xy 213.746257 -26.700627) (xy 213.694928 -26.722439)
			(xy 213.640971 -26.736545) (xy 213.585534 -26.742645) (xy 213.5298 -26.740608) (xy 213.474957 -26.730478)
			(xy 213.422173 -26.712471) (xy 213.372573 -26.68697) (xy 213.327215 -26.654519) (xy 213.287066 -26.61581)
			(xy 213.25298 -26.571667) (xy 213.225684 -26.523032) (xy 213.205761 -26.470941) (xy 213.193635 -26.416504)
			(xy 213.189564 -26.360882) (xy 211.523293 -26.360882) (xy 211.531039 -26.389798) (xy 211.538862 -26.449259)
			(xy 211.539328 -26.479246) (xy 211.539328 -26.971244) (xy 214.951054 -26.971244) (xy 214.955125 -26.915622)
			(xy 214.967251 -26.861185) (xy 214.987174 -26.809094) (xy 215.01447 -26.760459) (xy 215.048556 -26.716316)
			(xy 215.088705 -26.677607) (xy 215.134063 -26.645156) (xy 215.183663 -26.619655) (xy 215.236447 -26.601648)
			(xy 215.29129 -26.591518) (xy 215.347024 -26.589481) (xy 215.402461 -26.595581) (xy 215.456418 -26.609687)
			(xy 215.507747 -26.631499) (xy 215.555353 -26.660553) (xy 215.598221 -26.696228) (xy 215.635438 -26.737765)
			(xy 215.666211 -26.784278) (xy 215.689883 -26.834775) (xy 215.705951 -26.888182) (xy 215.714071 -26.943358)
			(xy 215.71458 -26.971244) (xy 215.714071 -26.99913) (xy 215.705951 -27.054306) (xy 215.689883 -27.107713)
			(xy 215.666211 -27.15821) (xy 215.635438 -27.204723) (xy 215.598221 -27.24626) (xy 215.555353 -27.281935)
			(xy 215.507747 -27.310989) (xy 215.456418 -27.332801) (xy 215.402461 -27.346907) (xy 215.347024 -27.353007)
			(xy 215.29129 -27.35097) (xy 215.236447 -27.34084) (xy 215.183663 -27.322833) (xy 215.134063 -27.297332)
			(xy 215.088705 -27.264881) (xy 215.048556 -27.226172) (xy 215.01447 -27.182029) (xy 214.987174 -27.133394)
			(xy 214.967251 -27.081303) (xy 214.955125 -27.026866) (xy 214.951054 -26.971244) (xy 211.539328 -26.971244)
			(xy 211.539328 -27.342846) (xy 211.538915 -27.372833) (xy 211.531081 -27.432293) (xy 211.515553 -27.490221)
			(xy 211.492597 -27.545627) (xy 211.462605 -27.597563) (xy 211.426091 -27.64514) (xy 211.38368 -27.687544)
			(xy 211.336097 -27.72405) (xy 211.284155 -27.754032) (xy 211.228745 -27.776979) (xy 211.170814 -27.792496)
			(xy 211.111353 -27.80032) (xy 211.081366 -27.800808) (xy 211.050229 -27.80028) (xy 210.988533 -27.791814)
			(xy 210.928548 -27.775083) (xy 210.899756 -27.763216) (xy 210.88858 -27.75839) (xy 210.864958 -27.75966)
			(xy 210.773772 -27.810968) (xy 210.76031 -27.830526) (xy 210.758786 -27.842464) (xy 210.754598 -27.869499)
			(xy 210.739416 -27.922059) (xy 210.716885 -27.971912) (xy 210.687466 -28.018038) (xy 210.651762 -28.059489)
			(xy 210.610506 -28.095419) (xy 210.564541 -28.125088) (xy 210.514812 -28.147891) (xy 210.462335 -28.163359)
			(xy 210.408188 -28.171176) (xy 210.380834 -28.171648) (xy 210.353582 -28.171107) (xy 210.299633 -28.163355)
			(xy 210.247337 -28.148003) (xy 210.197758 -28.125365) (xy 210.151905 -28.095901) (xy 210.110713 -28.060211)
			(xy 210.075019 -28.019022) (xy 210.045551 -27.973172) (xy 210.022909 -27.923595) (xy 210.007552 -27.8713)
			(xy 209.999795 -27.817352) (xy 208.729845 -27.817352) (xy 208.729833 -27.818026) (xy 208.721713 -27.873202)
			(xy 208.705645 -27.926609) (xy 208.681973 -27.977106) (xy 208.6512 -28.023619) (xy 208.613983 -28.065156)
			(xy 208.571115 -28.100831) (xy 208.523509 -28.129885) (xy 208.47218 -28.151697) (xy 208.418223 -28.165803)
			(xy 208.362786 -28.171903) (xy 208.307052 -28.169866) (xy 208.252209 -28.159736) (xy 208.199425 -28.141729)
			(xy 208.149825 -28.116228) (xy 208.104467 -28.083777) (xy 208.064318 -28.045068) (xy 208.030232 -28.000925)
			(xy 208.002936 -27.95229) (xy 207.983013 -27.900199) (xy 207.970887 -27.845762) (xy 207.966816 -27.79014)
			(xy 206.22641 -27.79014) (xy 206.225901 -27.818026) (xy 206.217781 -27.873202) (xy 206.201713 -27.926609)
			(xy 206.178041 -27.977106) (xy 206.147268 -28.023619) (xy 206.110051 -28.065156) (xy 206.067183 -28.100831)
			(xy 206.019577 -28.129885) (xy 205.968248 -28.151697) (xy 205.914291 -28.165803) (xy 205.858854 -28.171903)
			(xy 205.80312 -28.169866) (xy 205.748277 -28.159736) (xy 205.695493 -28.141729) (xy 205.645893 -28.116228)
			(xy 205.600535 -28.083777) (xy 205.560386 -28.045068) (xy 205.5263 -28.000925) (xy 205.499004 -27.95229)
			(xy 205.479081 -27.900199) (xy 205.466955 -27.845762) (xy 205.462884 -27.79014) (xy 204.129905 -27.79014)
			(xy 204.129905 -27.81735) (xy 204.122148 -27.871296) (xy 204.106794 -27.923589) (xy 204.084153 -27.973164)
			(xy 204.054688 -28.019013) (xy 204.018997 -28.060201) (xy 203.977808 -28.095891) (xy 203.931959 -28.125356)
			(xy 203.882383 -28.147996) (xy 203.83009 -28.16335) (xy 203.776144 -28.171105) (xy 203.748894 -28.171648)
			(xy 203.7461 -28.171648) (xy 203.736134 -28.172124) (xy 203.717696 -28.1797) (xy 203.710286 -28.18638)
			(xy 203.658978 -28.23718) (xy 203.652136 -28.244579) (xy 203.644418 -28.263178) (xy 203.643992 -28.273248)
			(xy 203.643992 -29.106876) (xy 203.644429 -29.11694) (xy 203.652161 -29.135526) (xy 203.658978 -29.142944)
			(xy 203.710286 -29.193744) (xy 203.717697 -29.200426) (xy 203.736132 -29.208006) (xy 203.7461 -29.208476)
			(xy 203.748894 -29.208476) (xy 203.776148 -29.208938) (xy 203.830102 -29.216695) (xy 203.882403 -29.232051)
			(xy 203.931986 -29.254694) (xy 203.977842 -29.284163) (xy 204.019037 -29.319859) (xy 204.054733 -29.361053)
			(xy 204.084203 -29.406909) (xy 204.106847 -29.456491) (xy 204.122204 -29.508792) (xy 204.129961 -29.562746)
			(xy 204.129961 -29.589984) (xy 205.462884 -29.589984) (xy 205.466955 -29.534362) (xy 205.479081 -29.479925)
			(xy 205.499004 -29.427834) (xy 205.5263 -29.379199) (xy 205.560386 -29.335056) (xy 205.600535 -29.296347)
			(xy 205.645893 -29.263896) (xy 205.695493 -29.238395) (xy 205.748277 -29.220388) (xy 205.80312 -29.210258)
			(xy 205.858854 -29.208221) (xy 205.914291 -29.214321) (xy 205.968248 -29.228427) (xy 206.019577 -29.250239)
			(xy 206.067183 -29.279293) (xy 206.110051 -29.314968) (xy 206.147268 -29.356505) (xy 206.178041 -29.403018)
			(xy 206.201713 -29.453515) (xy 206.217781 -29.506922) (xy 206.225901 -29.562098) (xy 206.22641 -29.589984)
			(xy 207.966816 -29.589984) (xy 207.970887 -29.534362) (xy 207.983013 -29.479925) (xy 208.002936 -29.427834)
			(xy 208.030232 -29.379199) (xy 208.064318 -29.335056) (xy 208.104467 -29.296347) (xy 208.149825 -29.263896)
			(xy 208.199425 -29.238395) (xy 208.252209 -29.220388) (xy 208.307052 -29.210258) (xy 208.362786 -29.208221)
			(xy 208.418223 -29.214321) (xy 208.47218 -29.228427) (xy 208.523509 -29.250239) (xy 208.571115 -29.279293)
			(xy 208.613983 -29.314968) (xy 208.6512 -29.356505) (xy 208.681973 -29.403018) (xy 208.705645 -29.453515)
			(xy 208.721713 -29.506922) (xy 208.729833 -29.562098) (xy 208.730342 -29.589984) (xy 209.998816 -29.589984)
			(xy 210.002887 -29.534362) (xy 210.015013 -29.479925) (xy 210.034936 -29.427834) (xy 210.062232 -29.379199)
			(xy 210.096318 -29.335056) (xy 210.136467 -29.296347) (xy 210.181825 -29.263896) (xy 210.231425 -29.238395)
			(xy 210.284209 -29.220388) (xy 210.339052 -29.210258) (xy 210.394786 -29.208221) (xy 210.450223 -29.214321)
			(xy 210.50418 -29.228427) (xy 210.555509 -29.250239) (xy 210.603115 -29.279293) (xy 210.645983 -29.314968)
			(xy 210.667656 -29.339157) (xy 212.390109 -29.339157) (xy 212.390109 -29.284643) (xy 212.397868 -29.230683)
			(xy 212.413227 -29.178376) (xy 212.435874 -29.128788) (xy 212.465348 -29.082928) (xy 212.50105 -29.04173)
			(xy 212.542251 -29.006032) (xy 212.588113 -28.976561) (xy 212.637702 -28.953917) (xy 212.69001 -28.938562)
			(xy 212.743971 -28.930807) (xy 212.771228 -28.930346) (xy 212.786021 -28.930476) (xy 212.815519 -28.932768)
			(xy 212.830156 -28.934918) (xy 212.841078 -28.936696) (xy 212.862414 -28.9306) (xy 212.929724 -28.873196)
			(xy 212.937751 -28.865627) (xy 212.946966 -28.845608) (xy 212.947504 -28.834588) (xy 212.947504 -28.530296)
			(xy 212.946967 -28.519277) (xy 212.937747 -28.49926) (xy 212.929724 -28.491688) (xy 212.862414 -28.434284)
			(xy 212.841078 -28.428188) (xy 212.830156 -28.429966) (xy 212.815518 -28.432106) (xy 212.786021 -28.434395)
			(xy 212.771228 -28.434538) (xy 212.743976 -28.434017) (xy 212.690026 -28.426264) (xy 212.637729 -28.410911)
			(xy 212.588149 -28.388272) (xy 212.542296 -28.358807) (xy 212.501104 -28.323116) (xy 212.46541 -28.281926)
			(xy 212.435941 -28.236075) (xy 212.413299 -28.186497) (xy 212.397942 -28.134201) (xy 212.390185 -28.080252)
			(xy 212.390185 -28.025748) (xy 212.397942 -27.971799) (xy 212.413299 -27.919503) (xy 212.435941 -27.869925)
			(xy 212.46541 -27.824074) (xy 212.501104 -27.782884) (xy 212.542296 -27.747193) (xy 212.588149 -27.717728)
			(xy 212.637729 -27.695089) (xy 212.690026 -27.679736) (xy 212.743976 -27.671983) (xy 212.771228 -27.671522)
			(xy 212.797155 -27.671925) (xy 212.848534 -27.678935) (xy 212.898491 -27.692837) (xy 212.946106 -27.713373)
			(xy 212.990502 -27.740167) (xy 213.030862 -27.772724) (xy 213.066443 -27.810445) (xy 213.08187 -27.831288)
			(xy 213.087611 -27.838618) (xy 213.103113 -27.848903) (xy 213.112096 -27.851354) (xy 213.142322 -27.858212)
			(xy 213.1516 -27.859948) (xy 213.170261 -27.857215) (xy 213.178644 -27.852878) (xy 213.204612 -27.838567)
			(xy 213.259467 -27.81606) (xy 213.316772 -27.800839) (xy 213.375566 -27.793157) (xy 213.405212 -27.79268)
			(xy 213.434854 -27.793204) (xy 213.493635 -27.800917) (xy 213.550933 -27.816136) (xy 213.605795 -27.838607)
			(xy 213.63178 -27.852878) (xy 213.640193 -27.857125) (xy 213.658823 -27.859858) (xy 213.668102 -27.858212)
			(xy 213.698328 -27.851354) (xy 213.707322 -27.848929) (xy 213.722827 -27.838635) (xy 213.728554 -27.831288)
			(xy 213.743982 -27.810444) (xy 213.779551 -27.772709) (xy 213.819906 -27.740143) (xy 213.864303 -27.713346)
			(xy 213.911922 -27.692815) (xy 213.961884 -27.678926) (xy 214.013267 -27.671938) (xy 214.039196 -27.671522)
			(xy 214.066451 -27.671925) (xy 214.120407 -27.679682) (xy 214.172709 -27.695039) (xy 214.222294 -27.717683)
			(xy 214.268151 -27.747153) (xy 214.309348 -27.782849) (xy 214.345045 -27.824046) (xy 214.374515 -27.869903)
			(xy 214.39716 -27.919487) (xy 214.412517 -27.971789) (xy 214.420275 -28.025745) (xy 214.420275 -28.080255)
			(xy 214.412517 -28.134211) (xy 214.39716 -28.186513) (xy 214.374515 -28.236097) (xy 214.345045 -28.281954)
			(xy 214.309348 -28.323151) (xy 214.268151 -28.358847) (xy 214.222294 -28.388317) (xy 214.172709 -28.410961)
			(xy 214.120407 -28.426318) (xy 214.066451 -28.434075) (xy 214.039196 -28.434538) (xy 214.024403 -28.434406)
			(xy 213.994905 -28.432115) (xy 213.980268 -28.429966) (xy 213.969346 -28.428188) (xy 213.94801 -28.434284)
			(xy 213.8807 -28.491688) (xy 213.872684 -28.499267) (xy 213.863462 -28.519279) (xy 213.86292 -28.530296)
			(xy 213.86292 -28.834588) (xy 213.863458 -28.845607) (xy 213.872677 -28.865624) (xy 213.8807 -28.873196)
			(xy 213.94801 -28.9306) (xy 213.969346 -28.936696) (xy 213.980268 -28.934918) (xy 213.994906 -28.932775)
			(xy 214.024403 -28.930488) (xy 214.039196 -28.930346) (xy 214.066446 -28.930901) (xy 214.120391 -28.938657)
			(xy 214.172683 -28.95401) (xy 214.222257 -28.97665) (xy 214.268105 -29.006114) (xy 214.309294 -29.041804)
			(xy 214.344983 -29.082991) (xy 214.374448 -29.128839) (xy 214.397088 -29.178414) (xy 214.412443 -29.230705)
			(xy 214.420199 -29.28465) (xy 214.420199 -29.33915) (xy 214.412443 -29.393095) (xy 214.397088 -29.445386)
			(xy 214.374448 -29.494961) (xy 214.344983 -29.540809) (xy 214.309294 -29.581996) (xy 214.268105 -29.617686)
			(xy 214.222257 -29.64715) (xy 214.172683 -29.66979) (xy 214.120391 -29.685143) (xy 214.066446 -29.692899)
			(xy 214.039196 -29.693362) (xy 214.013269 -29.692948) (xy 213.96189 -29.685941) (xy 213.911934 -29.672042)
			(xy 213.864319 -29.651507) (xy 213.819922 -29.624715) (xy 213.779562 -29.592159) (xy 213.743981 -29.554439)
			(xy 213.728554 -29.533596) (xy 213.722788 -29.526288) (xy 213.707305 -29.515988) (xy 213.698328 -29.51353)
			(xy 213.668102 -29.506672) (xy 213.658822 -29.504951) (xy 213.640163 -29.507674) (xy 213.63178 -29.512006)
			(xy 213.605807 -29.526306) (xy 213.550954 -29.548816) (xy 213.49365 -29.564041) (xy 213.434858 -29.571725)
			(xy 213.405212 -29.572204) (xy 213.375569 -29.571715) (xy 213.316787 -29.563992) (xy 213.259488 -29.548763)
			(xy 213.204628 -29.526282) (xy 213.178644 -29.512006) (xy 213.170227 -29.50777) (xy 213.1516 -29.505031)
			(xy 213.142322 -29.506672) (xy 213.112096 -29.51353) (xy 213.103093 -29.515929) (xy 213.087593 -29.526242)
			(xy 213.08187 -29.533596) (xy 213.066423 -29.554425) (xy 213.030858 -29.592161) (xy 212.990506 -29.624729)
			(xy 212.946113 -29.651528) (xy 212.898497 -29.672062) (xy 212.848537 -29.685953) (xy 212.797156 -29.692944)
			(xy 212.771228 -29.693362) (xy 212.743971 -29.692993) (xy 212.69001 -29.685238) (xy 212.637702 -29.669883)
			(xy 212.588113 -29.647239) (xy 212.542251 -29.617768) (xy 212.50105 -29.58207) (xy 212.465348 -29.540872)
			(xy 212.435874 -29.495012) (xy 212.413227 -29.445424) (xy 212.397868 -29.393117) (xy 212.390109 -29.339157)
			(xy 210.667656 -29.339157) (xy 210.6832 -29.356505) (xy 210.713973 -29.403018) (xy 210.737645 -29.453515)
			(xy 210.753713 -29.506922) (xy 210.761833 -29.562098) (xy 210.762342 -29.589984) (xy 210.761833 -29.61787)
			(xy 210.753713 -29.673046) (xy 210.737645 -29.726453) (xy 210.713973 -29.77695) (xy 210.6832 -29.823463)
			(xy 210.645983 -29.865) (xy 210.603115 -29.900675) (xy 210.555509 -29.929729) (xy 210.50418 -29.951541)
			(xy 210.450223 -29.965647) (xy 210.394786 -29.971747) (xy 210.339052 -29.96971) (xy 210.284209 -29.95958)
			(xy 210.231425 -29.941573) (xy 210.181825 -29.916072) (xy 210.136467 -29.883621) (xy 210.096318 -29.844912)
			(xy 210.062232 -29.800769) (xy 210.034936 -29.752134) (xy 210.015013 -29.700043) (xy 210.002887 -29.645606)
			(xy 209.998816 -29.589984) (xy 208.730342 -29.589984) (xy 208.729833 -29.61787) (xy 208.721713 -29.673046)
			(xy 208.705645 -29.726453) (xy 208.681973 -29.77695) (xy 208.6512 -29.823463) (xy 208.613983 -29.865)
			(xy 208.571115 -29.900675) (xy 208.523509 -29.929729) (xy 208.47218 -29.951541) (xy 208.418223 -29.965647)
			(xy 208.362786 -29.971747) (xy 208.307052 -29.96971) (xy 208.252209 -29.95958) (xy 208.199425 -29.941573)
			(xy 208.149825 -29.916072) (xy 208.104467 -29.883621) (xy 208.064318 -29.844912) (xy 208.030232 -29.800769)
			(xy 208.002936 -29.752134) (xy 207.983013 -29.700043) (xy 207.970887 -29.645606) (xy 207.966816 -29.589984)
			(xy 206.22641 -29.589984) (xy 206.225901 -29.61787) (xy 206.217781 -29.673046) (xy 206.201713 -29.726453)
			(xy 206.178041 -29.77695) (xy 206.147268 -29.823463) (xy 206.110051 -29.865) (xy 206.067183 -29.900675)
			(xy 206.019577 -29.929729) (xy 205.968248 -29.951541) (xy 205.914291 -29.965647) (xy 205.858854 -29.971747)
			(xy 205.80312 -29.96971) (xy 205.748277 -29.95958) (xy 205.695493 -29.941573) (xy 205.645893 -29.916072)
			(xy 205.600535 -29.883621) (xy 205.560386 -29.844912) (xy 205.5263 -29.800769) (xy 205.499004 -29.752134)
			(xy 205.479081 -29.700043) (xy 205.466955 -29.645606) (xy 205.462884 -29.589984) (xy 204.129961 -29.589984)
			(xy 204.129961 -29.617254) (xy 204.122204 -29.671208) (xy 204.106847 -29.723509) (xy 204.084203 -29.773091)
			(xy 204.054733 -29.818947) (xy 204.019037 -29.860141) (xy 203.977842 -29.895837) (xy 203.931986 -29.925306)
			(xy 203.882403 -29.947949) (xy 203.830102 -29.963305) (xy 203.776148 -29.971062) (xy 203.748894 -29.971492)
			(xy 203.7461 -29.971492) (xy 203.736132 -29.971966) (xy 203.71769 -29.979536) (xy 203.710286 -29.986224)
			(xy 203.658978 -30.037024) (xy 203.652127 -30.04442) (xy 203.644389 -30.063019) (xy 203.643992 -30.073092)
			(xy 203.643992 -30.906974) (xy 203.644428 -30.917038) (xy 203.652161 -30.935624) (xy 203.658978 -30.943042)
			(xy 203.710286 -30.993842) (xy 203.717697 -31.000524) (xy 203.736132 -31.008105) (xy 203.7461 -31.008574)
			(xy 203.748894 -31.008574) (xy 203.776148 -31.009036) (xy 203.830103 -31.016793) (xy 203.882404 -31.032149)
			(xy 203.931987 -31.054793) (xy 203.977843 -31.084262) (xy 204.019038 -31.119957) (xy 204.054735 -31.161152)
			(xy 204.084204 -31.207008) (xy 204.106849 -31.256591) (xy 204.122206 -31.308892) (xy 204.129963 -31.362846)
			(xy 204.129963 -31.417354) (xy 204.122206 -31.471309) (xy 204.106849 -31.523609) (xy 204.084204 -31.573192)
			(xy 204.054735 -31.619048) (xy 204.034583 -31.642304) (xy 205.506572 -31.642304) (xy 205.510643 -31.586682)
			(xy 205.522769 -31.532245) (xy 205.542692 -31.480154) (xy 205.569988 -31.431519) (xy 205.604074 -31.387376)
			(xy 205.644223 -31.348667) (xy 205.689581 -31.316216) (xy 205.739181 -31.290715) (xy 205.791965 -31.272708)
			(xy 205.846808 -31.262578) (xy 205.902542 -31.260541) (xy 205.957979 -31.266641) (xy 206.011936 -31.280747)
			(xy 206.063265 -31.302559) (xy 206.110871 -31.331613) (xy 206.153739 -31.367288) (xy 206.174162 -31.390082)
			(xy 207.966816 -31.390082) (xy 207.970887 -31.33446) (xy 207.983013 -31.280023) (xy 208.002936 -31.227932)
			(xy 208.030232 -31.179297) (xy 208.064318 -31.135154) (xy 208.104467 -31.096445) (xy 208.149825 -31.063994)
			(xy 208.199425 -31.038493) (xy 208.252209 -31.020486) (xy 208.307052 -31.010356) (xy 208.362786 -31.008319)
			(xy 208.418223 -31.014419) (xy 208.47218 -31.028525) (xy 208.523509 -31.050337) (xy 208.571115 -31.079391)
			(xy 208.613983 -31.115066) (xy 208.6512 -31.156603) (xy 208.681973 -31.203116) (xy 208.705645 -31.253613)
			(xy 208.721713 -31.30702) (xy 208.729833 -31.362196) (xy 208.730342 -31.390082) (xy 209.998816 -31.390082)
			(xy 210.002887 -31.33446) (xy 210.015013 -31.280023) (xy 210.034936 -31.227932) (xy 210.062232 -31.179297)
			(xy 210.096318 -31.135154) (xy 210.136467 -31.096445) (xy 210.181825 -31.063994) (xy 210.231425 -31.038493)
			(xy 210.284209 -31.020486) (xy 210.339052 -31.010356) (xy 210.394786 -31.008319) (xy 210.450223 -31.014419)
			(xy 210.50418 -31.028525) (xy 210.555509 -31.050337) (xy 210.603115 -31.079391) (xy 210.645983 -31.115066)
			(xy 210.6832 -31.156603) (xy 210.713973 -31.203116) (xy 210.737645 -31.253613) (xy 210.753713 -31.30702)
			(xy 210.761833 -31.362196) (xy 210.762342 -31.390082) (xy 210.761833 -31.417968) (xy 210.753713 -31.473144)
			(xy 210.737645 -31.526551) (xy 210.713973 -31.577048) (xy 210.6832 -31.623561) (xy 210.645983 -31.665098)
			(xy 210.627769 -31.680256) (xy 212.390127 -31.680256) (xy 212.390127 -31.625744) (xy 212.397885 -31.571786)
			(xy 212.413244 -31.519482) (xy 212.43589 -31.469897) (xy 212.465363 -31.424039) (xy 212.501062 -31.382842)
			(xy 212.542261 -31.347146) (xy 212.588121 -31.317677) (xy 212.637709 -31.295034) (xy 212.690014 -31.279679)
			(xy 212.743972 -31.271925) (xy 212.771228 -31.271464) (xy 212.797156 -31.271849) (xy 212.848536 -31.27886)
			(xy 212.898494 -31.292764) (xy 212.94611 -31.313303) (xy 212.990506 -31.340099) (xy 213.030865 -31.37266)
			(xy 213.066444 -31.410385) (xy 213.08187 -31.43123) (xy 213.087622 -31.43855) (xy 213.103116 -31.448843)
			(xy 213.112096 -31.451296) (xy 213.142322 -31.458154) (xy 213.1516 -31.459885) (xy 213.170261 -31.457155)
			(xy 213.178644 -31.45282) (xy 213.204628 -31.438561) (xy 213.259499 -31.41615) (xy 213.3168 -31.400994)
			(xy 213.375576 -31.393347) (xy 213.405212 -31.392876) (xy 213.43485 -31.393311) (xy 213.493634 -31.400939)
			(xy 213.550937 -31.416104) (xy 213.605798 -31.438552) (xy 213.63178 -31.45282) (xy 213.640194 -31.457065)
			(xy 213.658823 -31.4598) (xy 213.668102 -31.458154) (xy 213.698328 -31.451296) (xy 213.707317 -31.448858)
			(xy 213.722824 -31.438572) (xy 213.728554 -31.43123) (xy 213.743965 -31.410374) (xy 213.779539 -31.372641)
			(xy 213.819898 -31.340078) (xy 213.864297 -31.313284) (xy 213.911918 -31.292754) (xy 213.961882 -31.278868)
			(xy 214.013267 -31.27188) (xy 214.039196 -31.271464) (xy 214.066447 -31.271983) (xy 214.120394 -31.279739)
			(xy 214.172689 -31.295093) (xy 214.222266 -31.317734) (xy 214.268116 -31.3472) (xy 214.309306 -31.382891)
			(xy 214.344998 -31.424081) (xy 214.374464 -31.469931) (xy 214.397105 -31.519507) (xy 214.41246 -31.571802)
			(xy 214.420217 -31.625749) (xy 214.420217 -31.680251) (xy 214.41246 -31.734198) (xy 214.397105 -31.786493)
			(xy 214.374464 -31.836069) (xy 214.344998 -31.881919) (xy 214.309306 -31.923109) (xy 214.268116 -31.9588)
			(xy 214.222266 -31.988266) (xy 214.172689 -32.010907) (xy 214.120394 -32.026261) (xy 214.066447 -32.034017)
			(xy 214.039196 -32.03448) (xy 214.024403 -32.034347) (xy 213.994905 -32.032057) (xy 213.980268 -32.029908)
			(xy 213.969346 -32.02813) (xy 213.94801 -32.034226) (xy 213.8807 -32.09163) (xy 213.872665 -32.099192)
			(xy 213.863453 -32.119217) (xy 213.86292 -32.130238) (xy 213.86292 -32.43453) (xy 213.863435 -32.445552)
			(xy 213.87267 -32.465569) (xy 213.8807 -32.473138) (xy 213.94801 -32.530542) (xy 213.969346 -32.536638)
			(xy 213.980268 -32.53486) (xy 213.994905 -32.532716) (xy 214.024403 -32.53043) (xy 214.039196 -32.530288)
			(xy 214.066449 -32.530759) (xy 214.1204 -32.538515) (xy 214.172697 -32.553871) (xy 214.222277 -32.576513)
			(xy 214.268131 -32.605981) (xy 214.309323 -32.641674) (xy 214.345017 -32.682866) (xy 214.374485 -32.728719)
			(xy 214.397128 -32.778299) (xy 214.412484 -32.830597) (xy 214.420241 -32.884547) (xy 214.420241 -32.939053)
			(xy 214.412484 -32.993003) (xy 214.397128 -33.045301) (xy 214.374485 -33.094881) (xy 214.345017 -33.140734)
			(xy 214.309323 -33.181926) (xy 214.268131 -33.217619) (xy 214.222277 -33.247087) (xy 214.172697 -33.269729)
			(xy 214.1204 -33.285085) (xy 214.066449 -33.292841) (xy 214.039196 -33.293304) (xy 214.01327 -33.292873)
			(xy 213.961893 -33.285866) (xy 213.911937 -33.271969) (xy 213.864323 -33.251437) (xy 213.819926 -33.224648)
			(xy 213.779565 -33.192095) (xy 213.743982 -33.154379) (xy 213.728554 -33.133538) (xy 213.7228 -33.12622)
			(xy 213.707307 -33.115927) (xy 213.698328 -33.113472) (xy 213.668102 -33.106614) (xy 213.658823 -33.104888)
			(xy 213.640163 -33.107613) (xy 213.63178 -33.111948) (xy 213.60579 -33.126194) (xy 213.550921 -33.14861)
			(xy 213.493622 -33.163769) (xy 213.434847 -33.171419) (xy 213.405212 -33.171892) (xy 213.375574 -33.171451)
			(xy 213.316791 -33.163825) (xy 213.259487 -33.148662) (xy 213.204626 -33.126215) (xy 213.178644 -33.111948)
			(xy 213.170226 -33.107714) (xy 213.1516 -33.104972) (xy 213.142322 -33.106614) (xy 213.112096 -33.113472)
			(xy 213.1031 -33.115889) (xy 213.087598 -33.126191) (xy 213.08187 -33.133538) (xy 213.066435 -33.154376)
			(xy 213.030866 -33.19211) (xy 212.990512 -33.224676) (xy 212.946117 -33.251473) (xy 212.898499 -33.272006)
			(xy 212.848538 -33.285895) (xy 212.797156 -33.292886) (xy 212.771228 -33.293304) (xy 212.743974 -33.292851)
			(xy 212.690019 -33.285097) (xy 212.637717 -33.269743) (xy 212.588133 -33.247102) (xy 212.542276 -33.217634)
			(xy 212.50108 -33.18194) (xy 212.465383 -33.140746) (xy 212.435912 -33.094891) (xy 212.413267 -33.045309)
			(xy 212.397909 -32.993008) (xy 212.390151 -32.939054) (xy 212.390151 -32.884546) (xy 212.397909 -32.830592)
			(xy 212.413267 -32.778291) (xy 212.435912 -32.728709) (xy 212.465383 -32.682854) (xy 212.50108 -32.64166)
			(xy 212.542276 -32.605966) (xy 212.588133 -32.576498) (xy 212.637717 -32.553857) (xy 212.690019 -32.538503)
			(xy 212.743974 -32.530749) (xy 212.771228 -32.530288) (xy 212.786021 -32.530418) (xy 212.815519 -32.532711)
			(xy 212.830156 -32.53486) (xy 212.841078 -32.536638) (xy 212.862414 -32.530542) (xy 212.929724 -32.473138)
			(xy 212.937732 -32.465552) (xy 212.946958 -32.445546) (xy 212.947504 -32.43453) (xy 212.947504 -32.130238)
			(xy 212.946944 -32.119222) (xy 212.93774 -32.099205) (xy 212.929724 -32.09163) (xy 212.862414 -32.034226)
			(xy 212.841078 -32.02813) (xy 212.830156 -32.029908) (xy 212.815518 -32.032049) (xy 212.786021 -32.034337)
			(xy 212.771228 -32.03448) (xy 212.743972 -32.034075) (xy 212.690014 -32.026321) (xy 212.637709 -32.010966)
			(xy 212.588121 -31.988323) (xy 212.542261 -31.958854) (xy 212.501062 -31.923158) (xy 212.465363 -31.881961)
			(xy 212.43589 -31.836103) (xy 212.413244 -31.786518) (xy 212.397885 -31.734214) (xy 212.390127 -31.680256)
			(xy 210.627769 -31.680256) (xy 210.603115 -31.700773) (xy 210.555509 -31.729827) (xy 210.50418 -31.751639)
			(xy 210.450223 -31.765745) (xy 210.394786 -31.771845) (xy 210.339052 -31.769808) (xy 210.284209 -31.759678)
			(xy 210.231425 -31.741671) (xy 210.181825 -31.71617) (xy 210.136467 -31.683719) (xy 210.096318 -31.64501)
			(xy 210.062232 -31.600867) (xy 210.034936 -31.552232) (xy 210.015013 -31.500141) (xy 210.002887 -31.445704)
			(xy 209.998816 -31.390082) (xy 208.730342 -31.390082) (xy 208.729833 -31.417968) (xy 208.721713 -31.473144)
			(xy 208.705645 -31.526551) (xy 208.681973 -31.577048) (xy 208.6512 -31.623561) (xy 208.613983 -31.665098)
			(xy 208.571115 -31.700773) (xy 208.523509 -31.729827) (xy 208.47218 -31.751639) (xy 208.418223 -31.765745)
			(xy 208.362786 -31.771845) (xy 208.307052 -31.769808) (xy 208.252209 -31.759678) (xy 208.199425 -31.741671)
			(xy 208.149825 -31.71617) (xy 208.104467 -31.683719) (xy 208.064318 -31.64501) (xy 208.030232 -31.600867)
			(xy 208.002936 -31.552232) (xy 207.983013 -31.500141) (xy 207.970887 -31.445704) (xy 207.966816 -31.390082)
			(xy 206.174162 -31.390082) (xy 206.190956 -31.408825) (xy 206.221729 -31.455338) (xy 206.245401 -31.505835)
			(xy 206.261469 -31.559242) (xy 206.269589 -31.614418) (xy 206.270098 -31.642304) (xy 206.269589 -31.67019)
			(xy 206.261469 -31.725366) (xy 206.245401 -31.778773) (xy 206.221729 -31.82927) (xy 206.190956 -31.875783)
			(xy 206.153739 -31.91732) (xy 206.110871 -31.952995) (xy 206.063265 -31.982049) (xy 206.011936 -32.003861)
			(xy 205.957979 -32.017967) (xy 205.902542 -32.024067) (xy 205.846808 -32.02203) (xy 205.791965 -32.0119)
			(xy 205.739181 -31.993893) (xy 205.689581 -31.968392) (xy 205.644223 -31.935941) (xy 205.604074 -31.897232)
			(xy 205.569988 -31.853089) (xy 205.542692 -31.804454) (xy 205.522769 -31.752363) (xy 205.510643 -31.697926)
			(xy 205.506572 -31.642304) (xy 204.034583 -31.642304) (xy 204.019038 -31.660243) (xy 203.977843 -31.695938)
			(xy 203.931987 -31.725407) (xy 203.882404 -31.748051) (xy 203.830103 -31.763407) (xy 203.776148 -31.771164)
			(xy 203.748894 -31.77159) (xy 203.7461 -31.77159) (xy 203.736132 -31.772064) (xy 203.71769 -31.779634)
			(xy 203.710286 -31.786322) (xy 203.658978 -31.837122) (xy 203.652127 -31.844518) (xy 203.644388 -31.863117)
			(xy 203.643992 -31.87319) (xy 203.643992 -32.707072) (xy 203.644428 -32.717137) (xy 203.65216 -32.735723)
			(xy 203.658978 -32.74314) (xy 203.710286 -32.79394) (xy 203.717697 -32.800622) (xy 203.736132 -32.808203)
			(xy 203.7461 -32.808672) (xy 203.748894 -32.808672) (xy 203.776149 -32.809134) (xy 203.830103 -32.816891)
			(xy 203.882404 -32.832248) (xy 203.931988 -32.854891) (xy 203.977844 -32.88436) (xy 204.01904 -32.920056)
			(xy 204.054736 -32.961251) (xy 204.084206 -33.007107) (xy 204.10685 -33.05669) (xy 204.122208 -33.108991)
			(xy 204.129965 -33.162945) (xy 204.129965 -33.19018) (xy 205.774034 -33.19018) (xy 205.778105 -33.134558)
			(xy 205.790231 -33.080121) (xy 205.810154 -33.02803) (xy 205.83745 -32.979395) (xy 205.871536 -32.935252)
			(xy 205.911685 -32.896543) (xy 205.957043 -32.864092) (xy 206.006643 -32.838591) (xy 206.059427 -32.820584)
			(xy 206.11427 -32.810454) (xy 206.170004 -32.808417) (xy 206.225441 -32.814517) (xy 206.279398 -32.828623)
			(xy 206.330727 -32.850435) (xy 206.378333 -32.879489) (xy 206.421201 -32.915164) (xy 206.458418 -32.956701)
			(xy 206.489191 -33.003214) (xy 206.512863 -33.053711) (xy 206.528931 -33.107118) (xy 206.537051 -33.162294)
			(xy 206.53756 -33.19018) (xy 207.966816 -33.19018) (xy 207.970887 -33.134558) (xy 207.983013 -33.080121)
			(xy 208.002936 -33.02803) (xy 208.030232 -32.979395) (xy 208.064318 -32.935252) (xy 208.104467 -32.896543)
			(xy 208.149825 -32.864092) (xy 208.199425 -32.838591) (xy 208.252209 -32.820584) (xy 208.307052 -32.810454)
			(xy 208.362786 -32.808417) (xy 208.418223 -32.814517) (xy 208.47218 -32.828623) (xy 208.523509 -32.850435)
			(xy 208.571115 -32.879489) (xy 208.613983 -32.915164) (xy 208.6512 -32.956701) (xy 208.681973 -33.003214)
			(xy 208.705645 -33.053711) (xy 208.721713 -33.107118) (xy 208.729833 -33.162294) (xy 208.730342 -33.19018)
			(xy 209.998816 -33.19018) (xy 210.002887 -33.134558) (xy 210.015013 -33.080121) (xy 210.034936 -33.02803)
			(xy 210.062232 -32.979395) (xy 210.096318 -32.935252) (xy 210.136467 -32.896543) (xy 210.181825 -32.864092)
			(xy 210.231425 -32.838591) (xy 210.284209 -32.820584) (xy 210.339052 -32.810454) (xy 210.394786 -32.808417)
			(xy 210.450223 -32.814517) (xy 210.50418 -32.828623) (xy 210.555509 -32.850435) (xy 210.603115 -32.879489)
			(xy 210.645983 -32.915164) (xy 210.6832 -32.956701) (xy 210.713973 -33.003214) (xy 210.737645 -33.053711)
			(xy 210.753713 -33.107118) (xy 210.761833 -33.162294) (xy 210.762342 -33.19018) (xy 210.761833 -33.218066)
			(xy 210.753713 -33.273242) (xy 210.737645 -33.326649) (xy 210.713973 -33.377146) (xy 210.6832 -33.423659)
			(xy 210.645983 -33.465196) (xy 210.603115 -33.500871) (xy 210.555509 -33.529925) (xy 210.50418 -33.551737)
			(xy 210.450223 -33.565843) (xy 210.394786 -33.571943) (xy 210.339052 -33.569906) (xy 210.284209 -33.559776)
			(xy 210.231425 -33.541769) (xy 210.181825 -33.516268) (xy 210.136467 -33.483817) (xy 210.096318 -33.445108)
			(xy 210.062232 -33.400965) (xy 210.034936 -33.35233) (xy 210.015013 -33.300239) (xy 210.002887 -33.245802)
			(xy 209.998816 -33.19018) (xy 208.730342 -33.19018) (xy 208.729833 -33.218066) (xy 208.721713 -33.273242)
			(xy 208.705645 -33.326649) (xy 208.681973 -33.377146) (xy 208.6512 -33.423659) (xy 208.613983 -33.465196)
			(xy 208.571115 -33.500871) (xy 208.523509 -33.529925) (xy 208.47218 -33.551737) (xy 208.418223 -33.565843)
			(xy 208.362786 -33.571943) (xy 208.307052 -33.569906) (xy 208.252209 -33.559776) (xy 208.199425 -33.541769)
			(xy 208.149825 -33.516268) (xy 208.104467 -33.483817) (xy 208.064318 -33.445108) (xy 208.030232 -33.400965)
			(xy 208.002936 -33.35233) (xy 207.983013 -33.300239) (xy 207.970887 -33.245802) (xy 207.966816 -33.19018)
			(xy 206.53756 -33.19018) (xy 206.537051 -33.218066) (xy 206.528931 -33.273242) (xy 206.512863 -33.326649)
			(xy 206.489191 -33.377146) (xy 206.458418 -33.423659) (xy 206.421201 -33.465196) (xy 206.378333 -33.500871)
			(xy 206.330727 -33.529925) (xy 206.279398 -33.551737) (xy 206.225441 -33.565843) (xy 206.170004 -33.571943)
			(xy 206.11427 -33.569906) (xy 206.059427 -33.559776) (xy 206.006643 -33.541769) (xy 205.957043 -33.516268)
			(xy 205.911685 -33.483817) (xy 205.871536 -33.445108) (xy 205.83745 -33.400965) (xy 205.810154 -33.35233)
			(xy 205.790231 -33.300239) (xy 205.778105 -33.245802) (xy 205.774034 -33.19018) (xy 204.129965 -33.19018)
			(xy 204.129965 -33.217455) (xy 204.122208 -33.271409) (xy 204.10685 -33.32371) (xy 204.084206 -33.373293)
			(xy 204.054736 -33.419149) (xy 204.01904 -33.460344) (xy 203.977844 -33.49604) (xy 203.931988 -33.525509)
			(xy 203.882404 -33.548152) (xy 203.830103 -33.563509) (xy 203.776149 -33.571266) (xy 203.748894 -33.571688)
			(xy 203.7461 -33.571688) (xy 203.736132 -33.572162) (xy 203.71769 -33.579732) (xy 203.710286 -33.58642)
			(xy 203.658978 -33.63722) (xy 203.652126 -33.644616) (xy 203.644387 -33.663215) (xy 203.643992 -33.673288)
			(xy 203.643992 -34.506916) (xy 203.644418 -34.516985) (xy 203.652135 -34.535586) (xy 203.658978 -34.542984)
			(xy 203.710286 -34.593784) (xy 203.717694 -34.600472) (xy 203.73613 -34.608062) (xy 203.7461 -34.608516)
			(xy 203.748894 -34.608516) (xy 203.776145 -34.608979) (xy 203.830094 -34.616735) (xy 203.882389 -34.632089)
			(xy 203.931967 -34.65473) (xy 203.977818 -34.684196) (xy 204.019008 -34.719887) (xy 204.0547 -34.761078)
			(xy 204.084167 -34.806928) (xy 204.106809 -34.856506) (xy 204.122164 -34.908801) (xy 204.129921 -34.962749)
			(xy 204.129921 -34.990024) (xy 205.772764 -34.990024) (xy 205.776835 -34.934402) (xy 205.788961 -34.879965)
			(xy 205.808884 -34.827874) (xy 205.83618 -34.779239) (xy 205.870266 -34.735096) (xy 205.910415 -34.696387)
			(xy 205.955773 -34.663936) (xy 206.005373 -34.638435) (xy 206.058157 -34.620428) (xy 206.113 -34.610298)
			(xy 206.168734 -34.608261) (xy 206.224171 -34.614361) (xy 206.278128 -34.628467) (xy 206.329457 -34.650279)
			(xy 206.377063 -34.679333) (xy 206.419931 -34.715008) (xy 206.457148 -34.756545) (xy 206.487921 -34.803058)
			(xy 206.511593 -34.853555) (xy 206.527661 -34.906962) (xy 206.535781 -34.962138) (xy 206.53629 -34.990024)
			(xy 207.04378 -34.990024) (xy 207.047851 -34.934402) (xy 207.059977 -34.879965) (xy 207.0799 -34.827874)
			(xy 207.107196 -34.779239) (xy 207.141282 -34.735096) (xy 207.181431 -34.696387) (xy 207.226789 -34.663936)
			(xy 207.276389 -34.638435) (xy 207.329173 -34.620428) (xy 207.384016 -34.610298) (xy 207.43975 -34.608261)
			(xy 207.495187 -34.614361) (xy 207.549144 -34.628467) (xy 207.600473 -34.650279) (xy 207.648079 -34.679333)
			(xy 207.690947 -34.715008) (xy 207.728164 -34.756545) (xy 207.758937 -34.803058) (xy 207.782609 -34.853555)
			(xy 207.798677 -34.906962) (xy 207.806797 -34.962138) (xy 207.807306 -34.990024) (xy 209.998816 -34.990024)
			(xy 210.002887 -34.934402) (xy 210.015013 -34.879965) (xy 210.034936 -34.827874) (xy 210.062232 -34.779239)
			(xy 210.096318 -34.735096) (xy 210.136467 -34.696387) (xy 210.181825 -34.663936) (xy 210.231425 -34.638435)
			(xy 210.284209 -34.620428) (xy 210.339052 -34.610298) (xy 210.394786 -34.608261) (xy 210.450223 -34.614361)
			(xy 210.50418 -34.628467) (xy 210.555509 -34.650279) (xy 210.603115 -34.679333) (xy 210.645983 -34.715008)
			(xy 210.6832 -34.756545) (xy 210.713973 -34.803058) (xy 210.737645 -34.853555) (xy 210.753713 -34.906962)
			(xy 210.761833 -34.962138) (xy 210.762342 -34.990024) (xy 210.761833 -35.01791) (xy 210.753713 -35.073086)
			(xy 210.737645 -35.126493) (xy 210.713973 -35.17699) (xy 210.6832 -35.223503) (xy 210.645983 -35.26504)
			(xy 210.603115 -35.300715) (xy 210.555509 -35.329769) (xy 210.50418 -35.351581) (xy 210.450223 -35.365687)
			(xy 210.394786 -35.371787) (xy 210.339052 -35.36975) (xy 210.284209 -35.35962) (xy 210.231425 -35.341613)
			(xy 210.181825 -35.316112) (xy 210.136467 -35.283661) (xy 210.096318 -35.244952) (xy 210.062232 -35.200809)
			(xy 210.034936 -35.152174) (xy 210.015013 -35.100083) (xy 210.002887 -35.045646) (xy 209.998816 -34.990024)
			(xy 207.807306 -34.990024) (xy 207.806797 -35.01791) (xy 207.798677 -35.073086) (xy 207.782609 -35.126493)
			(xy 207.758937 -35.17699) (xy 207.728164 -35.223503) (xy 207.690947 -35.26504) (xy 207.648079 -35.300715)
			(xy 207.600473 -35.329769) (xy 207.549144 -35.351581) (xy 207.495187 -35.365687) (xy 207.43975 -35.371787)
			(xy 207.384016 -35.36975) (xy 207.329173 -35.35962) (xy 207.276389 -35.341613) (xy 207.226789 -35.316112)
			(xy 207.181431 -35.283661) (xy 207.141282 -35.244952) (xy 207.107196 -35.200809) (xy 207.0799 -35.152174)
			(xy 207.059977 -35.100083) (xy 207.047851 -35.045646) (xy 207.04378 -34.990024) (xy 206.53629 -34.990024)
			(xy 206.535781 -35.01791) (xy 206.527661 -35.073086) (xy 206.511593 -35.126493) (xy 206.487921 -35.17699)
			(xy 206.457148 -35.223503) (xy 206.419931 -35.26504) (xy 206.377063 -35.300715) (xy 206.329457 -35.329769)
			(xy 206.278128 -35.351581) (xy 206.224171 -35.365687) (xy 206.168734 -35.371787) (xy 206.113 -35.36975)
			(xy 206.058157 -35.35962) (xy 206.005373 -35.341613) (xy 205.955773 -35.316112) (xy 205.910415 -35.283661)
			(xy 205.870266 -35.244952) (xy 205.83618 -35.200809) (xy 205.808884 -35.152174) (xy 205.788961 -35.100083)
			(xy 205.776835 -35.045646) (xy 205.772764 -34.990024) (xy 204.129921 -34.990024) (xy 204.129921 -35.017251)
			(xy 204.122164 -35.071199) (xy 204.106809 -35.123494) (xy 204.084167 -35.173072) (xy 204.0547 -35.218922)
			(xy 204.019008 -35.260113) (xy 203.977818 -35.295804) (xy 203.931967 -35.32527) (xy 203.882389 -35.347911)
			(xy 203.830094 -35.363265) (xy 203.776145 -35.371021) (xy 203.748894 -35.371532) (xy 203.7461 -35.371532)
			(xy 203.736133 -35.372007) (xy 203.717694 -35.379581) (xy 203.710286 -35.386264) (xy 203.658978 -35.437064)
			(xy 203.652133 -35.444462) (xy 203.64441 -35.463061) (xy 203.643992 -35.473132) (xy 203.643992 -38.193435)
			(xy 205.198286 -38.193435) (xy 205.198286 -38.106565) (xy 205.206301 -38.020065) (xy 205.222263 -37.934673)
			(xy 205.246035 -37.851118) (xy 205.277416 -37.770114) (xy 205.316137 -37.69235) (xy 205.361867 -37.61849)
			(xy 205.414217 -37.549165) (xy 205.472741 -37.484966) (xy 205.536938 -37.42644) (xy 205.606261 -37.374088)
			(xy 205.680118 -37.328354) (xy 205.757881 -37.289631) (xy 205.838884 -37.258247) (xy 205.922438 -37.234471)
			(xy 206.007829 -37.218506) (xy 206.094329 -37.210487) (xy 206.137764 -37.209984) (xy 206.215742 -37.209984)
			(xy 206.225754 -37.209546) (xy 206.24425 -37.20187) (xy 206.258402 -37.187701) (xy 206.266057 -37.169197)
			(xy 206.266542 -37.159184) (xy 206.266542 -37.151564) (xy 206.262224 -37.137594) (xy 206.25816 -37.131244)
			(xy 206.234755 -37.094771) (xy 206.193763 -37.01841) (xy 206.159777 -36.938683) (xy 206.133072 -36.856232)
			(xy 206.113861 -36.77172) (xy 206.1023 -36.685827) (xy 206.098481 -36.599243) (xy 206.102436 -36.512666)
			(xy 206.114131 -36.42679) (xy 206.133474 -36.342309) (xy 206.160309 -36.2599) (xy 206.194419 -36.180227)
			(xy 206.235531 -36.10393) (xy 206.283314 -36.031624) (xy 206.337382 -35.96389) (xy 206.397303 -35.901273)
			(xy 206.462592 -35.844276) (xy 206.532726 -35.793359) (xy 206.60714 -35.74893) (xy 206.685235 -35.711348)
			(xy 206.766384 -35.680913) (xy 206.849933 -35.657872) (xy 206.93521 -35.64241) (xy 207.02153 -35.63465)
			(xy 207.064864 -35.634168) (xy 207.065118 -35.634168) (xy 207.10845 -35.634632) (xy 207.194765 -35.642406)
			(xy 207.280036 -35.657881) (xy 207.363578 -35.680933) (xy 207.444719 -35.711376) (xy 207.522807 -35.748966)
			(xy 207.597213 -35.793399) (xy 207.66734 -35.84432) (xy 207.732623 -35.901318) (xy 207.792537 -35.963935)
			(xy 207.846602 -36.031667) (xy 207.894381 -36.103971) (xy 207.935491 -36.180264) (xy 207.969601 -36.259933)
			(xy 207.996437 -36.342337) (xy 208.015783 -36.426815) (xy 208.027484 -36.512685) (xy 208.031445 -36.599259)
			(xy 208.027635 -36.685839) (xy 208.016084 -36.77173) (xy 207.996885 -36.85624) (xy 207.970192 -36.938691)
			(xy 207.936221 -37.01842) (xy 207.895244 -37.094784) (xy 207.871822 -37.131244) (xy 207.86344 -37.143944)
			(xy 207.86344 -37.159184) (xy 207.863833 -37.169209) (xy 207.871506 -37.187734) (xy 207.885687 -37.201908)
			(xy 207.904215 -37.209571) (xy 207.91424 -37.209984) (xy 207.991964 -37.209984) (xy 208.035406 -37.210393)
			(xy 208.121919 -37.218406) (xy 208.207323 -37.234368) (xy 208.29089 -37.258142) (xy 208.371908 -37.289526)
			(xy 208.449683 -37.328251) (xy 208.523554 -37.373987) (xy 208.59289 -37.426345) (xy 208.657098 -37.484876)
			(xy 208.715632 -37.549083) (xy 208.767992 -37.618416) (xy 208.813731 -37.692285) (xy 208.852459 -37.77006)
			(xy 208.883846 -37.851075) (xy 208.907623 -37.934642) (xy 208.923589 -38.020046) (xy 208.931605 -38.106558)
			(xy 208.931605 -38.193442) (xy 208.923589 -38.279954) (xy 208.907623 -38.365358) (xy 208.883846 -38.448924)
			(xy 208.852459 -38.52994) (xy 208.813731 -38.607715) (xy 208.767992 -38.681584) (xy 208.715632 -38.750917)
			(xy 208.657098 -38.815124) (xy 208.59289 -38.873655) (xy 208.523554 -38.926013) (xy 208.449683 -38.971749)
			(xy 208.371908 -39.010474) (xy 208.29089 -39.041858) (xy 208.207323 -39.065632) (xy 208.121919 -39.081594)
			(xy 208.035406 -39.089607) (xy 207.991964 -39.090092) (xy 206.137764 -39.090092) (xy 206.094329 -39.089513)
			(xy 206.007829 -39.081494) (xy 205.922438 -39.065529) (xy 205.838884 -39.041753) (xy 205.757881 -39.010369)
			(xy 205.680118 -38.971646) (xy 205.606261 -38.925912) (xy 205.536938 -38.87356) (xy 205.472741 -38.815034)
			(xy 205.414217 -38.750835) (xy 205.361867 -38.68151) (xy 205.316137 -38.60765) (xy 205.277416 -38.529886)
			(xy 205.246035 -38.448882) (xy 205.222263 -38.365327) (xy 205.206301 -38.279935) (xy 205.198286 -38.193435)
			(xy 203.643992 -38.193435) (xy 203.643992 -42.849038) (xy 214.991948 -42.849038) (xy 214.996019 -42.793416)
			(xy 215.008145 -42.738979) (xy 215.028068 -42.686888) (xy 215.055364 -42.638253) (xy 215.08945 -42.59411)
			(xy 215.129599 -42.555401) (xy 215.174957 -42.52295) (xy 215.224557 -42.497449) (xy 215.277341 -42.479442)
			(xy 215.332184 -42.469312) (xy 215.387918 -42.467275) (xy 215.443355 -42.473375) (xy 215.497312 -42.487481)
			(xy 215.548641 -42.509293) (xy 215.596247 -42.538347) (xy 215.639115 -42.574022) (xy 215.676332 -42.615559)
			(xy 215.707105 -42.662072) (xy 215.730777 -42.712569) (xy 215.746845 -42.765976) (xy 215.754965 -42.821152)
			(xy 215.755474 -42.849038) (xy 215.754965 -42.876924) (xy 215.746845 -42.9321) (xy 215.730777 -42.985507)
			(xy 215.707105 -43.036004) (xy 215.676332 -43.082517) (xy 215.639115 -43.124054) (xy 215.596247 -43.159729)
			(xy 215.548641 -43.188783) (xy 215.497312 -43.210595) (xy 215.443355 -43.224701) (xy 215.387918 -43.230801)
			(xy 215.332184 -43.228764) (xy 215.277341 -43.218634) (xy 215.224557 -43.200627) (xy 215.174957 -43.175126)
			(xy 215.129599 -43.142675) (xy 215.08945 -43.103966) (xy 215.055364 -43.059823) (xy 215.028068 -43.011188)
			(xy 215.008145 -42.959097) (xy 214.996019 -42.90466) (xy 214.991948 -42.849038) (xy 203.643992 -42.849038)
			(xy 203.643992 -43.719242) (xy 203.644456 -43.729117) (xy 203.651905 -43.74741) (xy 203.65847 -43.754802)
			(xy 203.658724 -43.755056) (xy 204.136752 -44.233084) (xy 204.13726 -44.233592) (xy 204.144643 -44.240169)
			(xy 204.162942 -44.247611) (xy 204.17282 -44.24807)
		)
		(stroke
			(width 0)
			(type solid)
		)
		(fill yes)
		(layer "B.Cu")
		(net "P12V_SSD7")
	)
	(gr_poly
		(pts
			(xy 20.214844 -44.24807) (xy 20.225023 -44.247626) (xy 20.243781 -44.239721) (xy 20.25798 -44.225135)
			(xy 20.262088 -44.215812) (xy 20.302474 -44.112942) (xy 20.295616 -44.082716) (xy 20.283932 -44.072048)
			(xy 20.261243 -44.050299) (xy 20.221437 -44.001663) (xy 20.188654 -43.948041) (xy 20.16351 -43.89044)
			(xy 20.146478 -43.829943) (xy 20.137876 -43.767685) (xy 20.137374 -43.73626) (xy 20.137864 -43.706292)
			(xy 20.145687 -43.64687) (xy 20.1612 -43.588977) (xy 20.184136 -43.533604) (xy 20.214103 -43.481698)
			(xy 20.25059 -43.434148) (xy 20.29297 -43.391768) (xy 20.34052 -43.355281) (xy 20.392426 -43.325314)
			(xy 20.447799 -43.302378) (xy 20.505692 -43.286865) (xy 20.565114 -43.279042) (xy 20.62505 -43.279042)
			(xy 20.684472 -43.286865) (xy 20.742365 -43.302378) (xy 20.797738 -43.325314) (xy 20.849644 -43.355281)
			(xy 20.897194 -43.391768) (xy 20.939574 -43.434148) (xy 20.976061 -43.481698) (xy 21.006028 -43.533604)
			(xy 21.028964 -43.588977) (xy 21.044477 -43.64687) (xy 21.0523 -43.706292) (xy 21.05279 -43.73626)
			(xy 21.052273 -43.767685) (xy 21.043683 -43.829945) (xy 21.026658 -43.890445) (xy 21.001518 -43.948048)
			(xy 20.968736 -44.001671) (xy 20.928928 -44.050307) (xy 20.906232 -44.072048) (xy 20.894548 -44.082716)
			(xy 20.88769 -44.112942) (xy 20.928076 -44.215812) (xy 20.932215 -44.225112) (xy 20.946415 -44.239673)
			(xy 20.965151 -44.247589) (xy 20.97532 -44.24807) (xy 21.877528 -44.24807) (xy 21.887595 -44.247641)
			(xy 21.90619 -44.239916) (xy 21.913596 -44.233084) (xy 22.47265 -43.67403) (xy 22.479491 -43.66663)
			(xy 22.487208 -43.648031) (xy 22.487636 -43.637962) (xy 22.487636 -37.589206) (xy 22.487171 -37.579859)
			(xy 22.480404 -37.562427) (xy 22.467866 -37.548553) (xy 22.459696 -37.543994) (xy 22.365716 -37.496496)
			(xy 22.337268 -37.499036) (xy 22.325584 -37.507672) (xy 22.300789 -37.525307) (xy 22.246774 -37.553309)
			(xy 22.188999 -37.572382) (xy 22.128929 -37.582041) (xy 22.098508 -37.582602) (xy 22.071255 -37.582139)
			(xy 22.017304 -37.574383) (xy 21.965006 -37.559028) (xy 21.915426 -37.536387) (xy 21.869573 -37.506919)
			(xy 21.82838 -37.471226) (xy 21.792686 -37.430034) (xy 21.763217 -37.384181) (xy 21.740575 -37.334601)
			(xy 21.725218 -37.282304) (xy 21.717461 -37.228353) (xy 21.717461 -37.173847) (xy 21.725218 -37.119896)
			(xy 21.740575 -37.067599) (xy 21.763217 -37.018019) (xy 21.792686 -36.972166) (xy 21.82838 -36.930974)
			(xy 21.869573 -36.895281) (xy 21.915426 -36.865813) (xy 21.965006 -36.843172) (xy 22.017304 -36.827817)
			(xy 22.071255 -36.820061) (xy 22.098508 -36.819586) (xy 22.128927 -36.820178) (xy 22.188995 -36.829833)
			(xy 22.246771 -36.848895) (xy 22.30079 -36.876882) (xy 22.325584 -36.894516) (xy 22.337268 -36.903152)
			(xy 22.365716 -36.905692) (xy 22.459696 -36.858194) (xy 22.467858 -36.853618) (xy 22.480421 -36.839772)
			(xy 22.48715 -36.82233) (xy 22.487636 -36.812982) (xy 22.487636 -35.109658) (xy 22.469094 -35.083496)
			(xy 22.453854 -35.078162) (xy 22.426592 -35.06791) (xy 22.37529 -35.040338) (xy 22.328764 -35.005305)
			(xy 22.288088 -34.963621) (xy 22.27072 -34.94024) (xy 22.264992 -34.932894) (xy 22.249489 -34.922594)
			(xy 22.240494 -34.920174) (xy 22.210268 -34.913316) (xy 22.20099 -34.911676) (xy 22.182366 -34.914421)
			(xy 22.173946 -34.91865) (xy 22.147961 -34.932924) (xy 22.093101 -34.955401) (xy 22.035803 -34.970628)
			(xy 21.977021 -34.978349) (xy 21.947378 -34.978848) (xy 21.917732 -34.978368) (xy 21.85894 -34.970684)
			(xy 21.801636 -34.955459) (xy 21.746783 -34.93295) (xy 21.72081 -34.91865) (xy 21.712429 -34.914299)
			(xy 21.693761 -34.911541) (xy 21.684488 -34.913316) (xy 21.654262 -34.920174) (xy 21.645284 -34.922631)
			(xy 21.629794 -34.932925) (xy 21.624036 -34.94024) (xy 21.608608 -34.96108) (xy 21.573024 -34.998796)
			(xy 21.532663 -35.031347) (xy 21.488266 -35.058134) (xy 21.440652 -35.078665) (xy 21.390697 -35.092561)
			(xy 21.33932 -35.099566) (xy 21.313394 -35.100006) (xy 21.286143 -35.09952) (xy 21.232196 -35.091763)
			(xy 21.179903 -35.076407) (xy 21.130326 -35.053766) (xy 21.084477 -35.024299) (xy 21.043288 -34.988608)
			(xy 21.007597 -34.947418) (xy 20.978131 -34.901568) (xy 20.955491 -34.851992) (xy 20.940136 -34.799698)
			(xy 20.93238 -34.745751) (xy 20.93238 -34.691249) (xy 20.940136 -34.637302) (xy 20.955491 -34.585008)
			(xy 20.978131 -34.535432) (xy 21.007597 -34.489582) (xy 21.043288 -34.448392) (xy 21.084477 -34.412701)
			(xy 21.130326 -34.383234) (xy 21.179903 -34.360593) (xy 21.232196 -34.345237) (xy 21.286143 -34.33748)
			(xy 21.313394 -34.33699) (xy 21.328187 -34.337132) (xy 21.357685 -34.339417) (xy 21.372322 -34.341562)
			(xy 21.383244 -34.34334) (xy 21.40458 -34.337244) (xy 21.47189 -34.27984) (xy 21.479838 -34.272234)
			(xy 21.488923 -34.252222) (xy 21.489416 -34.241232) (xy 21.489416 -33.93694) (xy 21.488928 -33.925951)
			(xy 21.479825 -33.905953) (xy 21.47189 -33.898332) (xy 21.40458 -33.840928) (xy 21.383244 -33.834832)
			(xy 21.372322 -33.83661) (xy 21.357685 -33.838758) (xy 21.328187 -33.841048) (xy 21.313394 -33.841182)
			(xy 21.286145 -33.840695) (xy 21.232202 -33.832939) (xy 21.179911 -33.817584) (xy 21.130338 -33.794944)
			(xy 21.084492 -33.76548) (xy 21.043305 -33.729791) (xy 21.007617 -33.688604) (xy 20.978153 -33.642757)
			(xy 20.955514 -33.593183) (xy 20.94016 -33.540893) (xy 20.932404 -33.486949) (xy 20.932404 -33.432451)
			(xy 20.94016 -33.378507) (xy 20.955514 -33.326217) (xy 20.978153 -33.276643) (xy 21.007617 -33.230796)
			(xy 21.043305 -33.189609) (xy 21.084492 -33.15392) (xy 21.130338 -33.124456) (xy 21.179911 -33.101816)
			(xy 21.232202 -33.086461) (xy 21.286145 -33.078705) (xy 21.313394 -33.078166) (xy 21.339323 -33.078581)
			(xy 21.390709 -33.085568) (xy 21.440674 -33.099454) (xy 21.488296 -33.119983) (xy 21.532696 -33.146776)
			(xy 21.573056 -33.179339) (xy 21.608631 -33.217071) (xy 21.624036 -33.237932) (xy 21.629765 -33.245275)
			(xy 21.645271 -33.255564) (xy 21.654262 -33.257998) (xy 21.684488 -33.264856) (xy 21.693767 -33.266505)
			(xy 21.712398 -33.263772) (xy 21.72081 -33.259522) (xy 21.746796 -33.245252) (xy 21.801657 -33.222783)
			(xy 21.858956 -33.207564) (xy 21.917736 -33.199851) (xy 21.947378 -33.199324) (xy 21.977024 -33.199801)
			(xy 22.035818 -33.207482) (xy 22.093123 -33.222704) (xy 22.147978 -33.245211) (xy 22.173946 -33.259522)
			(xy 22.182329 -33.263858) (xy 22.20099 -33.266592) (xy 22.210268 -33.264856) (xy 22.240494 -33.257998)
			(xy 22.249475 -33.255546) (xy 22.264972 -33.245256) (xy 22.27072 -33.237932) (xy 22.288086 -33.214548)
			(xy 22.32874 -33.172839) (xy 22.37527 -33.137806) (xy 22.426591 -33.110264) (xy 22.453854 -33.10001)
			(xy 22.469094 -33.094676) (xy 22.487636 -33.068514) (xy 22.487636 -31.509462) (xy 22.469094 -31.4833)
			(xy 22.453854 -31.477966) (xy 22.426592 -31.467715) (xy 22.37529 -31.440142) (xy 22.328763 -31.405109)
			(xy 22.288087 -31.363425) (xy 22.27072 -31.340044) (xy 22.264992 -31.332697) (xy 22.24949 -31.322397)
			(xy 22.240494 -31.319978) (xy 22.210268 -31.31312) (xy 22.20099 -31.31148) (xy 22.182366 -31.314225)
			(xy 22.173946 -31.318454) (xy 22.147961 -31.332728) (xy 22.093101 -31.355205) (xy 22.035802 -31.370431)
			(xy 21.977021 -31.378152) (xy 21.947378 -31.378652) (xy 21.917732 -31.378172) (xy 21.85894 -31.370488)
			(xy 21.801636 -31.355263) (xy 21.746783 -31.332755) (xy 21.72081 -31.318454) (xy 21.712429 -31.314103)
			(xy 21.693761 -31.311345) (xy 21.684488 -31.31312) (xy 21.654262 -31.319978) (xy 21.645284 -31.322435)
			(xy 21.629795 -31.33273) (xy 21.624036 -31.340044) (xy 21.608607 -31.360884) (xy 21.573024 -31.398599)
			(xy 21.532662 -31.43115) (xy 21.488266 -31.457937) (xy 21.440652 -31.478468) (xy 21.390697 -31.492363)
			(xy 21.33932 -31.499369) (xy 21.313394 -31.49981) (xy 21.286143 -31.499324) (xy 21.232196 -31.491567)
			(xy 21.179901 -31.476211) (xy 21.130324 -31.453569) (xy 21.084475 -31.424103) (xy 21.043285 -31.388411)
			(xy 21.007594 -31.347221) (xy 20.978128 -31.30137) (xy 20.955487 -31.251793) (xy 20.940132 -31.199499)
			(xy 20.932376 -31.145551) (xy 20.932376 -31.091049) (xy 20.940132 -31.037101) (xy 20.955487 -30.984807)
			(xy 20.978128 -30.93523) (xy 21.007594 -30.889379) (xy 21.043285 -30.848189) (xy 21.084475 -30.812497)
			(xy 21.130324 -30.783031) (xy 21.179901 -30.760389) (xy 21.232196 -30.745033) (xy 21.286143 -30.737276)
			(xy 21.313394 -30.736794) (xy 21.328187 -30.736936) (xy 21.357685 -30.739221) (xy 21.372322 -30.741366)
			(xy 21.383244 -30.743144) (xy 21.40458 -30.737048) (xy 21.47189 -30.679644) (xy 21.479839 -30.672038)
			(xy 21.488925 -30.652027) (xy 21.489416 -30.641036) (xy 21.489416 -30.336744) (xy 21.488929 -30.325755)
			(xy 21.479826 -30.305756) (xy 21.47189 -30.298136) (xy 21.40458 -30.240732) (xy 21.383244 -30.234636)
			(xy 21.372322 -30.236414) (xy 21.357685 -30.238562) (xy 21.328187 -30.240852) (xy 21.313394 -30.240986)
			(xy 21.286145 -30.240499) (xy 21.232201 -30.232743) (xy 21.17991 -30.217388) (xy 21.130336 -30.194748)
			(xy 21.084489 -30.165283) (xy 21.043302 -30.129594) (xy 21.007613 -30.088406) (xy 20.978149 -30.042558)
			(xy 20.95551 -29.992985) (xy 20.940156 -29.940693) (xy 20.9324 -29.886749) (xy 20.9324 -29.832251)
			(xy 20.940156 -29.778307) (xy 20.95551 -29.726015) (xy 20.978149 -29.676442) (xy 21.007613 -29.630594)
			(xy 21.043302 -29.589406) (xy 21.084489 -29.553717) (xy 21.130336 -29.524252) (xy 21.17991 -29.501612)
			(xy 21.232201 -29.486257) (xy 21.286145 -29.478501) (xy 21.313394 -29.47797) (xy 21.339323 -29.478385)
			(xy 21.390709 -29.485372) (xy 21.440673 -29.499258) (xy 21.488295 -29.519787) (xy 21.532695 -29.54658)
			(xy 21.573055 -29.579144) (xy 21.608629 -29.616876) (xy 21.624036 -29.637736) (xy 21.629766 -29.645079)
			(xy 21.645272 -29.655366) (xy 21.654262 -29.657802) (xy 21.684488 -29.66466) (xy 21.693767 -29.666309)
			(xy 21.712399 -29.663576) (xy 21.72081 -29.659326) (xy 21.746796 -29.645056) (xy 21.801657 -29.622586)
			(xy 21.858955 -29.607368) (xy 21.917736 -29.599654) (xy 21.947378 -29.599128) (xy 21.977024 -29.599605)
			(xy 22.035818 -29.607286) (xy 22.093123 -29.622508) (xy 22.147978 -29.645015) (xy 22.173946 -29.659326)
			(xy 22.182329 -29.663662) (xy 22.20099 -29.666395) (xy 22.210268 -29.66466) (xy 22.240494 -29.657802)
			(xy 22.249476 -29.655351) (xy 22.264973 -29.645061) (xy 22.27072 -29.637736) (xy 22.288086 -29.614351)
			(xy 22.32874 -29.572643) (xy 22.37527 -29.537609) (xy 22.42659 -29.510067) (xy 22.453854 -29.499814)
			(xy 22.469094 -29.49448) (xy 22.487636 -29.468318) (xy 22.487636 -26.798016) (xy 22.487134 -26.787834)
			(xy 22.479149 -26.769097) (xy 22.472142 -26.761694) (xy 22.412452 -26.703528) (xy 22.393656 -26.696162)
			(xy 22.383242 -26.696416) (xy 22.37232 -26.69667) (xy 22.345069 -26.696208) (xy 22.291121 -26.688454)
			(xy 22.238826 -26.673101) (xy 22.189248 -26.650462) (xy 22.143397 -26.620998) (xy 22.102206 -26.585308)
			(xy 22.066514 -26.544119) (xy 22.037047 -26.498269) (xy 22.014406 -26.448693) (xy 21.99905 -26.396398)
			(xy 21.991293 -26.342451) (xy 21.991293 -26.287949) (xy 21.99905 -26.234002) (xy 22.014406 -26.181707)
			(xy 22.037047 -26.132131) (xy 22.066514 -26.086281) (xy 22.102206 -26.045092) (xy 22.143397 -26.009402)
			(xy 22.189248 -25.979938) (xy 22.238826 -25.957299) (xy 22.291121 -25.941946) (xy 22.345069 -25.934192)
			(xy 22.37232 -25.933654) (xy 22.383242 -25.933908) (xy 22.393656 -25.934162) (xy 22.412452 -25.926796)
			(xy 22.472142 -25.86863) (xy 22.479154 -25.86123) (xy 22.487137 -25.842491) (xy 22.487636 -25.832308)
			(xy 22.487636 -24.296624) (xy 22.487197 -24.286561) (xy 22.479456 -24.267983) (xy 22.47265 -24.260556)
			(xy 15.68577 -17.473676) (xy 15.677248 -17.466103) (xy 15.655754 -17.458599) (xy 15.644368 -17.459198)
			(xy 15.554198 -17.46885) (xy 15.53464 -17.481042) (xy 15.528544 -17.490694) (xy 15.504634 -17.527134)
			(xy 15.451203 -17.596001) (xy 15.391783 -17.659772) (xy 15.32686 -17.717931) (xy 15.25696 -17.770002)
			(xy 15.182652 -17.815563) (xy 15.104541 -17.854244) (xy 15.023263 -17.885728) (xy 14.939478 -17.909761)
			(xy 14.853869 -17.926146) (xy 14.767131 -17.934751) (xy 14.679971 -17.935505) (xy 14.593097 -17.928402)
			(xy 14.507217 -17.9135) (xy 14.423029 -17.890921) (xy 14.341218 -17.860847) (xy 14.26245 -17.823524)
			(xy 14.187365 -17.779255) (xy 14.116575 -17.728401) (xy 14.050655 -17.671374) (xy 13.990141 -17.60864)
			(xy 13.935527 -17.540708) (xy 13.887255 -17.468132) (xy 13.84572 -17.391501) (xy 13.811259 -17.311439)
			(xy 13.784152 -17.228598) (xy 13.76462 -17.143651) (xy 13.752821 -17.05729) (xy 13.748853 -16.970217)
			(xy 13.752746 -16.883141) (xy 13.76447 -16.796769) (xy 13.783929 -16.711806) (xy 13.810964 -16.628941)
			(xy 13.845356 -16.54885) (xy 13.865606 -16.510254) (xy 13.871956 -16.498316) (xy 13.871448 -16.471646)
			(xy 13.819886 -16.385032) (xy 13.815081 -16.377667) (xy 13.801523 -16.366486) (xy 13.784985 -16.360546)
			(xy 13.776198 -16.36014) (xy 12.037822 -16.36014) (xy 11.994383 -16.359653) (xy 11.907876 -16.351638)
			(xy 11.822478 -16.335674) (xy 11.738917 -16.311899) (xy 11.657907 -16.280516) (xy 11.580137 -16.241791)
			(xy 11.506272 -16.196056) (xy 11.436943 -16.143701) (xy 11.372739 -16.085172) (xy 11.31421 -16.020969)
			(xy 11.261855 -15.951639) (xy 11.21612 -15.877775) (xy 11.177395 -15.800005) (xy 11.146012 -15.718995)
			(xy 11.122236 -15.635434) (xy 11.106273 -15.550035) (xy 11.098257 -15.463529) (xy 11.098257 -15.376651)
			(xy 11.106273 -15.290145) (xy 11.122236 -15.204746) (xy 11.146012 -15.121185) (xy 11.177395 -15.040175)
			(xy 11.21612 -14.962405) (xy 11.261855 -14.888541) (xy 11.31421 -14.819211) (xy 11.372739 -14.755008)
			(xy 11.436943 -14.696479) (xy 11.506272 -14.644124) (xy 11.580137 -14.598389) (xy 11.657907 -14.559664)
			(xy 11.738917 -14.528281) (xy 11.822478 -14.504506) (xy 11.907876 -14.488542) (xy 11.994383 -14.480527)
			(xy 12.037822 -14.480032) (xy 12.569444 -14.480032) (xy 12.579486 -14.479601) (xy 12.598031 -14.471887)
			(xy 12.612205 -14.457656) (xy 12.616434 -14.448536) (xy 12.622276 -14.434058) (xy 12.616434 -14.40434)
			(xy 12.346686 -14.134592) (xy 12.339275 -14.127911) (xy 12.320839 -14.120335) (xy 12.310872 -14.11986)
			(xy 8.96493 -14.11986) (xy 8.896626 -14.11934) (xy 8.760266 -14.111105) (xy 8.624648 -14.094688)
			(xy 8.490262 -14.070148) (xy 8.357594 -14.037573) (xy 8.227125 -13.997082) (xy 8.099326 -13.948821)
			(xy 7.974659 -13.892964) (xy 7.913878 -13.861796) (xy 7.90829 -13.858748) (xy 7.896606 -13.855954)
			(xy 6.79196 -13.855954) (xy 6.781954 -13.856448) (xy 6.763468 -13.864113) (xy 6.749317 -13.878263)
			(xy 6.74165 -13.896748) (xy 6.74116 -13.906754) (xy 6.74116 -18.535904) (xy 6.741692 -18.547342)
			(xy 6.751621 -18.567953) (xy 6.76021 -18.575528) (xy 6.830822 -18.632424) (xy 6.853174 -18.637504)
			(xy 6.86435 -18.635218) (xy 6.920512 -18.623328) (xy 7.03383 -18.604868) (xy 7.147976 -18.592527)
			(xy 7.26262 -18.586341) (xy 7.320026 -18.585942) (xy 7.384498 -18.586419) (xy 7.513206 -18.594204)
			(xy 7.641209 -18.609747) (xy 7.76804 -18.632989) (xy 7.893236 -18.663847) (xy 8.016341 -18.702208)
			(xy 8.136905 -18.747931) (xy 8.254488 -18.800851) (xy 8.368662 -18.860774) (xy 8.479009 -18.927481)
			(xy 8.585127 -19.000729) (xy 8.686629 -19.080251) (xy 8.783145 -19.165756) (xy 8.874322 -19.256932)
			(xy 8.959827 -19.353447) (xy 9.039349 -19.454949) (xy 9.112597 -19.561067) (xy 9.179304 -19.671415)
			(xy 9.239227 -19.785588) (xy 9.292147 -19.903171) (xy 9.337871 -20.023735) (xy 9.376232 -20.14684)
			(xy 9.40709 -20.272036) (xy 9.430333 -20.398867) (xy 9.445875 -20.52687) (xy 9.453661 -20.655578)
			(xy 9.454134 -20.72005) (xy 9.453663 -20.783943) (xy 9.446012 -20.911501) (xy 9.430743 -21.038372)
			(xy 9.407909 -21.164101) (xy 9.377592 -21.28824) (xy 9.339901 -21.410341) (xy 9.294972 -21.529969)
			(xy 9.242964 -21.646693) (xy 9.195367 -21.738336) (xy 11.416792 -21.738336) (xy 11.417279 -21.709596)
			(xy 11.425911 -21.652767) (xy 11.44297 -21.597876) (xy 11.468069 -21.546165) (xy 11.500642 -21.498804)
			(xy 11.519916 -21.477478) (xy 11.52652 -21.470366) (xy 11.533632 -21.45284) (xy 11.533632 -21.363432)
			(xy 11.52652 -21.345906) (xy 11.519916 -21.338794) (xy 11.500642 -21.31747) (xy 11.468077 -21.270107)
			(xy 11.442986 -21.218395) (xy 11.425937 -21.163504) (xy 11.417315 -21.106676) (xy 11.417315 -21.049198)
			(xy 11.425938 -20.992371) (xy 11.442988 -20.93748) (xy 11.46808 -20.885768) (xy 11.500645 -20.838405)
			(xy 11.519916 -20.817078) (xy 11.52652 -20.809966) (xy 11.533632 -20.79244) (xy 11.533632 -20.703032)
			(xy 11.52652 -20.685506) (xy 11.519916 -20.678394) (xy 11.500642 -20.65707) (xy 11.468077 -20.609707)
			(xy 11.442986 -20.557995) (xy 11.425937 -20.503104) (xy 11.417315 -20.446276) (xy 11.417315 -20.388798)
			(xy 11.425938 -20.331971) (xy 11.442988 -20.27708) (xy 11.46808 -20.225368) (xy 11.500645 -20.178005)
			(xy 11.519916 -20.156678) (xy 11.52652 -20.149566) (xy 11.533632 -20.13204) (xy 11.533632 -20.042632)
			(xy 11.52652 -20.025106) (xy 11.519916 -20.017994) (xy 11.500642 -19.99667) (xy 11.468077 -19.949307)
			(xy 11.442986 -19.897595) (xy 11.425937 -19.842704) (xy 11.417315 -19.785876) (xy 11.417315 -19.728398)
			(xy 11.425938 -19.671571) (xy 11.442988 -19.61668) (xy 11.46808 -19.564968) (xy 11.500645 -19.517605)
			(xy 11.519916 -19.496278) (xy 11.52652 -19.489166) (xy 11.533632 -19.47164) (xy 11.533632 -19.382232)
			(xy 11.52652 -19.364706) (xy 11.519916 -19.357594) (xy 11.500659 -19.336255) (xy 11.468091 -19.288896)
			(xy 11.442997 -19.237187) (xy 11.425943 -19.182299) (xy 11.417316 -19.125474) (xy 11.416792 -19.096736)
			(xy 11.417278 -19.069485) (xy 11.425034 -19.015537) (xy 11.440389 -18.963242) (xy 11.463031 -18.913665)
			(xy 11.492497 -18.867815) (xy 11.528188 -18.826624) (xy 11.569379 -18.790933) (xy 11.615229 -18.761467)
			(xy 11.664806 -18.738825) (xy 11.717101 -18.72347) (xy 11.771049 -18.715714) (xy 11.825551 -18.715714)
			(xy 11.879499 -18.72347) (xy 11.931794 -18.738825) (xy 11.981371 -18.761467) (xy 12.027221 -18.790933)
			(xy 12.068412 -18.826624) (xy 12.104103 -18.867815) (xy 12.133569 -18.913665) (xy 12.156211 -18.963242)
			(xy 12.171566 -19.015537) (xy 12.179322 -19.069485) (xy 12.179808 -19.096736) (xy 12.179304 -19.125476)
			(xy 12.170676 -19.182304) (xy 12.153621 -19.237195) (xy 12.128526 -19.288906) (xy 12.095957 -19.336268)
			(xy 12.076684 -19.357594) (xy 12.07008 -19.364706) (xy 12.062968 -19.382232) (xy 12.062968 -19.47164)
			(xy 12.07008 -19.489166) (xy 12.076684 -19.496278) (xy 12.09595 -19.517608) (xy 12.128515 -19.56497)
			(xy 12.153606 -19.616682) (xy 12.170656 -19.671572) (xy 12.179279 -19.728399) (xy 12.17928 -19.785876)
			(xy 12.170658 -19.842702) (xy 12.153609 -19.897593) (xy 12.128518 -19.949304) (xy 12.095954 -19.996667)
			(xy 12.076684 -20.017994) (xy 12.07008 -20.025106) (xy 12.062968 -20.042632) (xy 12.062968 -20.13204)
			(xy 12.07008 -20.149566) (xy 12.076684 -20.156678) (xy 12.09595 -20.178008) (xy 12.128515 -20.22537)
			(xy 12.153606 -20.277082) (xy 12.170656 -20.331972) (xy 12.179279 -20.388799) (xy 12.17928 -20.446276)
			(xy 12.170658 -20.503102) (xy 12.153609 -20.557993) (xy 12.128518 -20.609704) (xy 12.095954 -20.657067)
			(xy 12.076684 -20.678394) (xy 12.07008 -20.685506) (xy 12.062968 -20.703032) (xy 12.062968 -20.79244)
			(xy 12.07008 -20.809966) (xy 12.076684 -20.817078) (xy 12.09595 -20.838408) (xy 12.128515 -20.88577)
			(xy 12.153606 -20.937482) (xy 12.170656 -20.992372) (xy 12.179279 -21.049199) (xy 12.17928 -21.106676)
			(xy 12.170658 -21.163502) (xy 12.153609 -21.218393) (xy 12.128518 -21.270104) (xy 12.095954 -21.317467)
			(xy 12.076684 -21.338794) (xy 12.07008 -21.345906) (xy 12.062968 -21.363432) (xy 12.062968 -21.45284)
			(xy 12.07008 -21.470366) (xy 12.076684 -21.477478) (xy 12.095975 -21.498787) (xy 12.128538 -21.546154)
			(xy 12.153626 -21.597871) (xy 12.170672 -21.652765) (xy 12.17929 -21.709596) (xy 12.179808 -21.738336)
			(xy 12.179322 -21.765587) (xy 12.171566 -21.819535) (xy 12.156211 -21.87183) (xy 12.133569 -21.921407)
			(xy 12.104103 -21.967257) (xy 12.068412 -22.008448) (xy 12.027221 -22.044139) (xy 11.981371 -22.073605)
			(xy 11.931794 -22.096247) (xy 11.879499 -22.111602) (xy 11.825551 -22.119358) (xy 11.771049 -22.119358)
			(xy 11.717101 -22.111602) (xy 11.664806 -22.096247) (xy 11.615229 -22.073605) (xy 11.569379 -22.044139)
			(xy 11.528188 -22.008448) (xy 11.492497 -21.967257) (xy 11.463031 -21.921407) (xy 11.440389 -21.87183)
			(xy 11.425034 -21.819535) (xy 11.417278 -21.765587) (xy 11.416792 -21.738336) (xy 9.195367 -21.738336)
			(xy 9.184065 -21.760096) (xy 9.118485 -21.869772) (xy 9.04646 -21.975326) (xy 8.968248 -22.076382)
			(xy 8.884128 -22.172576) (xy 8.794404 -22.263564) (xy 8.699395 -22.349021) (xy 8.599443 -22.428638)
			(xy 8.494906 -22.502132) (xy 8.386158 -22.569239) (xy 8.273589 -22.629718) (xy 8.157603 -22.683353)
			(xy 8.098282 -22.707092) (xy 8.086344 -22.711918) (xy 8.069834 -22.731222) (xy 8.049768 -22.827234)
			(xy 8.047823 -22.839761) (xy 8.055007 -22.864038) (xy 8.063484 -22.873462) (xy 8.210043 -23.020021)
			(xy 11.223709 -23.020021) (xy 11.223709 -22.960083) (xy 11.231532 -22.900657) (xy 11.247045 -22.842761)
			(xy 11.269982 -22.787385) (xy 11.299951 -22.735477) (xy 11.336439 -22.687925) (xy 11.378822 -22.645542)
			(xy 11.426374 -22.609053) (xy 11.478282 -22.579084) (xy 11.533657 -22.556146) (xy 11.591553 -22.540633)
			(xy 11.650979 -22.532809) (xy 11.710917 -22.532809) (xy 11.770343 -22.540632) (xy 11.828239 -22.556145)
			(xy 11.883615 -22.579082) (xy 11.935523 -22.609051) (xy 11.983075 -22.645539) (xy 12.025458 -22.687922)
			(xy 12.061947 -22.735474) (xy 12.091916 -22.787382) (xy 12.114854 -22.842757) (xy 12.130367 -22.900653)
			(xy 12.138191 -22.960079) (xy 12.13866 -22.990048) (xy 12.138406 -23.004018) (xy 12.138152 -23.01494)
			(xy 12.138683 -23.01621) (xy 12.711682 -23.01621) (xy 12.715753 -22.960588) (xy 12.727879 -22.906151)
			(xy 12.747802 -22.85406) (xy 12.775098 -22.805425) (xy 12.809184 -22.761282) (xy 12.849333 -22.722573)
			(xy 12.894691 -22.690122) (xy 12.944291 -22.664621) (xy 12.997075 -22.646614) (xy 13.051918 -22.636484)
			(xy 13.107652 -22.634447) (xy 13.163089 -22.640547) (xy 13.217046 -22.654653) (xy 13.268375 -22.676465)
			(xy 13.315981 -22.705519) (xy 13.358849 -22.741194) (xy 13.396066 -22.782731) (xy 13.426839 -22.829244)
			(xy 13.450511 -22.879741) (xy 13.466579 -22.933148) (xy 13.474699 -22.988324) (xy 13.475208 -23.01621)
			(xy 13.474699 -23.044096) (xy 13.466579 -23.099272) (xy 13.450511 -23.152679) (xy 13.426839 -23.203176)
			(xy 13.396066 -23.249689) (xy 13.358849 -23.291226) (xy 13.315981 -23.326901) (xy 13.268375 -23.355955)
			(xy 13.217046 -23.377767) (xy 13.163089 -23.391873) (xy 13.107652 -23.397973) (xy 13.051918 -23.395936)
			(xy 12.997075 -23.385806) (xy 12.944291 -23.367799) (xy 12.894691 -23.342298) (xy 12.849333 -23.309847)
			(xy 12.809184 -23.271138) (xy 12.775098 -23.226995) (xy 12.747802 -23.17836) (xy 12.727879 -23.126269)
			(xy 12.715753 -23.071832) (xy 12.711682 -23.01621) (xy 12.138683 -23.01621) (xy 12.146534 -23.035006)
			(xy 12.217908 -23.102062) (xy 12.238482 -23.109174) (xy 12.249404 -23.108158) (xy 12.284456 -23.106634)
			(xy 12.311709 -23.107093) (xy 12.365661 -23.11485) (xy 12.417959 -23.130205) (xy 12.46754 -23.152848)
			(xy 12.513394 -23.182316) (xy 12.554588 -23.21801) (xy 12.590282 -23.259203) (xy 12.61975 -23.305056)
			(xy 12.642393 -23.354637) (xy 12.65775 -23.406935) (xy 12.665507 -23.460887) (xy 12.665507 -23.515393)
			(xy 12.65775 -23.569345) (xy 12.642886 -23.619964) (xy 16.009348 -23.619964) (xy 16.009348 -23.560028)
			(xy 16.017171 -23.500606) (xy 16.032684 -23.442713) (xy 16.05562 -23.38734) (xy 16.085587 -23.335434)
			(xy 16.122074 -23.287884) (xy 16.164454 -23.245504) (xy 16.212004 -23.209017) (xy 16.26391 -23.17905)
			(xy 16.319283 -23.156114) (xy 16.377176 -23.140601) (xy 16.436598 -23.132778) (xy 16.496534 -23.132778)
			(xy 16.555956 -23.140601) (xy 16.613849 -23.156114) (xy 16.669222 -23.17905) (xy 16.721128 -23.209017)
			(xy 16.768678 -23.245504) (xy 16.811058 -23.287884) (xy 16.847545 -23.335434) (xy 16.877512 -23.38734)
			(xy 16.900448 -23.442713) (xy 16.915961 -23.500606) (xy 16.923784 -23.560028) (xy 16.924274 -23.589996)
			(xy 16.923784 -23.619964) (xy 16.915961 -23.679386) (xy 16.900448 -23.737279) (xy 16.877512 -23.792652)
			(xy 16.847545 -23.844558) (xy 16.820105 -23.880318) (xy 17.240756 -23.880318) (xy 17.244827 -23.824696)
			(xy 17.256953 -23.770259) (xy 17.276876 -23.718168) (xy 17.304172 -23.669533) (xy 17.338258 -23.62539)
			(xy 17.378407 -23.586681) (xy 17.423765 -23.55423) (xy 17.473365 -23.528729) (xy 17.526149 -23.510722)
			(xy 17.580992 -23.500592) (xy 17.636726 -23.498555) (xy 17.692163 -23.504655) (xy 17.74612 -23.518761)
			(xy 17.797449 -23.540573) (xy 17.845055 -23.569627) (xy 17.887923 -23.605302) (xy 17.92514 -23.646839)
			(xy 17.955913 -23.693352) (xy 17.979585 -23.743849) (xy 17.995653 -23.797256) (xy 18.003773 -23.852432)
			(xy 18.004282 -23.880318) (xy 18.256756 -23.880318) (xy 18.260827 -23.824696) (xy 18.272953 -23.770259)
			(xy 18.292876 -23.718168) (xy 18.320172 -23.669533) (xy 18.354258 -23.62539) (xy 18.394407 -23.586681)
			(xy 18.439765 -23.55423) (xy 18.489365 -23.528729) (xy 18.542149 -23.510722) (xy 18.596992 -23.500592)
			(xy 18.652726 -23.498555) (xy 18.708163 -23.504655) (xy 18.76212 -23.518761) (xy 18.813449 -23.540573)
			(xy 18.861055 -23.569627) (xy 18.903923 -23.605302) (xy 18.94114 -23.646839) (xy 18.971913 -23.693352)
			(xy 18.995585 -23.743849) (xy 19.011653 -23.797256) (xy 19.019773 -23.852432) (xy 19.020282 -23.880318)
			(xy 19.019773 -23.908204) (xy 19.011653 -23.96338) (xy 18.995585 -24.016787) (xy 18.971913 -24.067284)
			(xy 18.94114 -24.113797) (xy 18.903923 -24.155334) (xy 18.861055 -24.191009) (xy 18.813449 -24.220063)
			(xy 18.76212 -24.241875) (xy 18.708163 -24.255981) (xy 18.652726 -24.262081) (xy 18.596992 -24.260044)
			(xy 18.542149 -24.249914) (xy 18.489365 -24.231907) (xy 18.439765 -24.206406) (xy 18.394407 -24.173955)
			(xy 18.354258 -24.135246) (xy 18.320172 -24.091103) (xy 18.292876 -24.042468) (xy 18.272953 -23.990377)
			(xy 18.260827 -23.93594) (xy 18.256756 -23.880318) (xy 18.004282 -23.880318) (xy 18.003773 -23.908204)
			(xy 17.995653 -23.96338) (xy 17.979585 -24.016787) (xy 17.955913 -24.067284) (xy 17.92514 -24.113797)
			(xy 17.887923 -24.155334) (xy 17.845055 -24.191009) (xy 17.797449 -24.220063) (xy 17.74612 -24.241875)
			(xy 17.692163 -24.255981) (xy 17.636726 -24.262081) (xy 17.580992 -24.260044) (xy 17.526149 -24.249914)
			(xy 17.473365 -24.231907) (xy 17.423765 -24.206406) (xy 17.378407 -24.173955) (xy 17.338258 -24.135246)
			(xy 17.304172 -24.091103) (xy 17.276876 -24.042468) (xy 17.256953 -23.990377) (xy 17.244827 -23.93594)
			(xy 17.240756 -23.880318) (xy 16.820105 -23.880318) (xy 16.811058 -23.892108) (xy 16.768678 -23.934488)
			(xy 16.721128 -23.970975) (xy 16.669222 -24.000942) (xy 16.613849 -24.023878) (xy 16.555956 -24.039391)
			(xy 16.496534 -24.047214) (xy 16.436598 -24.047214) (xy 16.377176 -24.039391) (xy 16.319283 -24.023878)
			(xy 16.26391 -24.000942) (xy 16.212004 -23.970975) (xy 16.164454 -23.934488) (xy 16.122074 -23.892108)
			(xy 16.085587 -23.844558) (xy 16.05562 -23.792652) (xy 16.032684 -23.737279) (xy 16.017171 -23.679386)
			(xy 16.009348 -23.619964) (xy 12.642886 -23.619964) (xy 12.642393 -23.621643) (xy 12.61975 -23.671224)
			(xy 12.590282 -23.717077) (xy 12.554588 -23.75827) (xy 12.513394 -23.793964) (xy 12.46754 -23.823432)
			(xy 12.417959 -23.846075) (xy 12.365661 -23.86143) (xy 12.311709 -23.869187) (xy 12.284456 -23.86965)
			(xy 12.256357 -23.869137) (xy 12.200763 -23.860913) (xy 12.146978 -23.844622) (xy 12.096166 -23.820614)
			(xy 12.049426 -23.789411) (xy 12.007771 -23.751687) (xy 11.972102 -23.70826) (xy 11.943192 -23.660068)
			(xy 11.921665 -23.608156) (xy 11.907989 -23.553648) (xy 11.904726 -23.525734) (xy 11.90371 -23.514812)
			(xy 11.892788 -23.496016) (xy 11.81354 -23.438612) (xy 11.792204 -23.434294) (xy 11.781282 -23.43658)
			(xy 11.756527 -23.441796) (xy 11.706247 -23.447401) (xy 11.680952 -23.447756) (xy 11.650983 -23.447291)
			(xy 11.591557 -23.439468) (xy 11.533661 -23.423955) (xy 11.478285 -23.401018) (xy 11.426377 -23.371049)
			(xy 11.378825 -23.334561) (xy 11.336442 -23.292178) (xy 11.299953 -23.244626) (xy 11.269984 -23.192718)
			(xy 11.247046 -23.137343) (xy 11.231533 -23.079447) (xy 11.223709 -23.020021) (xy 8.210043 -23.020021)
			(xy 9.379966 -24.189944) (xy 13.821916 -24.189944) (xy 13.825987 -24.134322) (xy 13.838113 -24.079885)
			(xy 13.858036 -24.027794) (xy 13.885332 -23.979159) (xy 13.919418 -23.935016) (xy 13.959567 -23.896307)
			(xy 14.004925 -23.863856) (xy 14.054525 -23.838355) (xy 14.107309 -23.820348) (xy 14.162152 -23.810218)
			(xy 14.217886 -23.808181) (xy 14.273323 -23.814281) (xy 14.32728 -23.828387) (xy 14.378609 -23.850199)
			(xy 14.426215 -23.879253) (xy 14.469083 -23.914928) (xy 14.5063 -23.956465) (xy 14.537073 -24.002978)
			(xy 14.560745 -24.053475) (xy 14.576813 -24.106882) (xy 14.584933 -24.162058) (xy 14.585442 -24.189944)
			(xy 14.584933 -24.21783) (xy 14.576813 -24.273006) (xy 14.560745 -24.326413) (xy 14.548157 -24.353266)
			(xy 19.380198 -24.353266) (xy 19.384269 -24.297644) (xy 19.396395 -24.243207) (xy 19.416318 -24.191116)
			(xy 19.443614 -24.142481) (xy 19.4777 -24.098338) (xy 19.517849 -24.059629) (xy 19.563207 -24.027178)
			(xy 19.612807 -24.001677) (xy 19.665591 -23.98367) (xy 19.720434 -23.97354) (xy 19.776168 -23.971503)
			(xy 19.831605 -23.977603) (xy 19.885562 -23.991709) (xy 19.936891 -24.013521) (xy 19.984497 -24.042575)
			(xy 20.027365 -24.07825) (xy 20.064582 -24.119787) (xy 20.095355 -24.1663) (xy 20.119027 -24.216797)
			(xy 20.135095 -24.270204) (xy 20.143215 -24.32538) (xy 20.143724 -24.353266) (xy 20.143215 -24.381152)
			(xy 20.135095 -24.436328) (xy 20.119027 -24.489735) (xy 20.095355 -24.540232) (xy 20.064582 -24.586745)
			(xy 20.027365 -24.628282) (xy 19.984497 -24.663957) (xy 19.936891 -24.693011) (xy 19.885562 -24.714823)
			(xy 19.831605 -24.728929) (xy 19.776168 -24.735029) (xy 19.720434 -24.732992) (xy 19.665591 -24.722862)
			(xy 19.612807 -24.704855) (xy 19.563207 -24.679354) (xy 19.517849 -24.646903) (xy 19.4777 -24.608194)
			(xy 19.443614 -24.564051) (xy 19.416318 -24.515416) (xy 19.396395 -24.463325) (xy 19.384269 -24.408888)
			(xy 19.380198 -24.353266) (xy 14.548157 -24.353266) (xy 14.537073 -24.37691) (xy 14.5063 -24.423423)
			(xy 14.469083 -24.46496) (xy 14.426215 -24.500635) (xy 14.378609 -24.529689) (xy 14.32728 -24.551501)
			(xy 14.273323 -24.565607) (xy 14.217886 -24.571707) (xy 14.162152 -24.56967) (xy 14.107309 -24.55954)
			(xy 14.054525 -24.541533) (xy 14.004925 -24.516032) (xy 13.959567 -24.483581) (xy 13.919418 -24.444872)
			(xy 13.885332 -24.400729) (xy 13.858036 -24.352094) (xy 13.838113 -24.300003) (xy 13.825987 -24.245566)
			(xy 13.821916 -24.189944) (xy 9.379966 -24.189944) (xy 9.529064 -24.339042) (xy 9.535908 -24.346441)
			(xy 9.543632 -24.36504) (xy 9.54405 -24.37511) (xy 9.54405 -25.390094) (xy 13.733526 -25.390094)
			(xy 13.734016 -25.360126) (xy 13.741839 -25.300704) (xy 13.757352 -25.242811) (xy 13.780288 -25.187438)
			(xy 13.810255 -25.135532) (xy 13.846742 -25.087982) (xy 13.889122 -25.045602) (xy 13.936672 -25.009115)
			(xy 13.988578 -24.979148) (xy 14.043951 -24.956212) (xy 14.101844 -24.940699) (xy 14.161266 -24.932876)
			(xy 14.221202 -24.932876) (xy 14.280624 -24.940699) (xy 14.338517 -24.956212) (xy 14.39389 -24.979148)
			(xy 14.445796 -25.009115) (xy 14.493346 -25.045602) (xy 14.535726 -25.087982) (xy 14.572213 -25.135532)
			(xy 14.60218 -25.187438) (xy 14.625116 -25.242811) (xy 14.640629 -25.300704) (xy 14.648452 -25.360126)
			(xy 14.648942 -25.390094) (xy 14.648493 -25.418878) (xy 14.641275 -25.475991) (xy 14.626953 -25.531749)
			(xy 14.605752 -25.58527) (xy 14.578008 -25.635711) (xy 14.544157 -25.682275) (xy 14.504735 -25.724227)
			(xy 14.482826 -25.7429) (xy 14.474444 -25.749758) (xy 14.464792 -25.769316) (xy 14.46149 -25.867106)
			(xy 14.469618 -25.887172) (xy 14.477746 -25.894792) (xy 14.496144 -25.912871) (xy 14.528382 -25.953137)
			(xy 14.554907 -25.997376) (xy 14.575234 -26.044783) (xy 14.588995 -26.094495) (xy 14.595939 -26.145607)
			(xy 14.596364 -26.171398) (xy 14.595878 -26.198649) (xy 14.588122 -26.252597) (xy 14.572767 -26.304892)
			(xy 14.550125 -26.354469) (xy 14.520659 -26.400319) (xy 14.484968 -26.44151) (xy 14.443777 -26.477201)
			(xy 14.397927 -26.506667) (xy 14.34835 -26.529309) (xy 14.296055 -26.544664) (xy 14.242107 -26.55242)
			(xy 14.187605 -26.55242) (xy 14.133657 -26.544664) (xy 14.081362 -26.529309) (xy 14.031785 -26.506667)
			(xy 13.985935 -26.477201) (xy 13.944744 -26.44151) (xy 13.909053 -26.400319) (xy 13.879587 -26.354469)
			(xy 13.856945 -26.304892) (xy 13.84159 -26.252597) (xy 13.833834 -26.198649) (xy 13.833348 -26.171398)
			(xy 13.833852 -26.142754) (xy 13.842451 -26.086114) (xy 13.859425 -26.031398) (xy 13.884392 -25.979836)
			(xy 13.91679 -25.932588) (xy 13.935964 -25.911302) (xy 13.94333 -25.903174) (xy 13.950188 -25.8826)
			(xy 13.941044 -25.785064) (xy 13.930376 -25.766268) (xy 13.921486 -25.759918) (xy 13.896957 -25.741343)
			(xy 13.852559 -25.698748) (xy 13.814264 -25.650591) (xy 13.782764 -25.597739) (xy 13.758625 -25.541145)
			(xy 13.742283 -25.481828) (xy 13.734031 -25.420857) (xy 13.733526 -25.390094) (xy 9.54405 -25.390094)
			(xy 9.54405 -25.506934) (xy 9.544481 -25.517) (xy 9.552209 -25.535591) (xy 9.559036 -25.543002) (xy 9.617456 -25.600914)
			(xy 9.635998 -25.608534) (xy 9.646412 -25.608534) (xy 9.648952 -25.608534) (xy 9.676203 -25.60902)
			(xy 9.73015 -25.616777) (xy 9.782444 -25.632132) (xy 9.832021 -25.654773) (xy 9.877871 -25.684239)
			(xy 9.919061 -25.719931) (xy 9.954752 -25.76112) (xy 9.984218 -25.806971) (xy 10.006859 -25.856547)
			(xy 10.022214 -25.908842) (xy 10.02997 -25.962789) (xy 10.02997 -25.990042) (xy 11.298934 -25.990042)
			(xy 11.303005 -25.93442) (xy 11.315131 -25.879983) (xy 11.335054 -25.827892) (xy 11.36235 -25.779257)
			(xy 11.396436 -25.735114) (xy 11.436585 -25.696405) (xy 11.481943 -25.663954) (xy 11.531543 -25.638453)
			(xy 11.584327 -25.620446) (xy 11.63917 -25.610316) (xy 11.694904 -25.608279) (xy 11.750341 -25.614379)
			(xy 11.804298 -25.628485) (xy 11.855627 -25.650297) (xy 11.903233 -25.679351) (xy 11.946101 -25.715026)
			(xy 11.983318 -25.756563) (xy 12.014091 -25.803076) (xy 12.037763 -25.853573) (xy 12.053831 -25.90698)
			(xy 12.061951 -25.962156) (xy 12.06246 -25.990042) (xy 12.061951 -26.017928) (xy 12.053831 -26.073104)
			(xy 12.037763 -26.126511) (xy 12.014091 -26.177008) (xy 11.983318 -26.223521) (xy 11.946101 -26.265058)
			(xy 11.903233 -26.300733) (xy 11.855627 -26.329787) (xy 11.804298 -26.351599) (xy 11.750341 -26.365705)
			(xy 11.694904 -26.371805) (xy 11.63917 -26.369768) (xy 11.584327 -26.359638) (xy 11.531543 -26.341631)
			(xy 11.481943 -26.31613) (xy 11.436585 -26.283679) (xy 11.396436 -26.24497) (xy 11.36235 -26.200827)
			(xy 11.335054 -26.152192) (xy 11.315131 -26.100101) (xy 11.303005 -26.045664) (xy 11.298934 -25.990042)
			(xy 10.02997 -25.990042) (xy 10.02997 -26.017291) (xy 10.022214 -26.071238) (xy 10.006859 -26.123533)
			(xy 9.984218 -26.173109) (xy 9.954752 -26.21896) (xy 9.919061 -26.260149) (xy 9.877871 -26.295841)
			(xy 9.832021 -26.325307) (xy 9.782444 -26.347948) (xy 9.73015 -26.363303) (xy 9.676203 -26.37106)
			(xy 9.648952 -26.37155) (xy 9.635998 -26.37155) (xy 9.617456 -26.37917) (xy 9.559036 -26.437082)
			(xy 9.552198 -26.444483) (xy 9.544488 -26.463082) (xy 9.54405 -26.47315) (xy 9.54405 -27.307032)
			(xy 9.54448 -27.317098) (xy 9.552209 -27.33569) (xy 9.559036 -27.3431) (xy 9.617456 -27.401012) (xy 9.635998 -27.408632)
			(xy 9.646412 -27.408632) (xy 9.648952 -27.408632) (xy 9.676203 -27.409118) (xy 9.730151 -27.416875)
			(xy 9.782445 -27.43223) (xy 9.832022 -27.454871) (xy 9.877872 -27.484338) (xy 9.919062 -27.520029)
			(xy 9.954754 -27.561219) (xy 9.98422 -27.60707) (xy 10.006861 -27.656647) (xy 10.022216 -27.708941)
			(xy 10.029972 -27.762889) (xy 10.029972 -27.79014) (xy 11.362942 -27.79014) (xy 11.367013 -27.734518)
			(xy 11.379139 -27.680081) (xy 11.399062 -27.62799) (xy 11.426358 -27.579355) (xy 11.460444 -27.535212)
			(xy 11.500593 -27.496503) (xy 11.545951 -27.464052) (xy 11.595551 -27.438551) (xy 11.648335 -27.420544)
			(xy 11.703178 -27.410414) (xy 11.758912 -27.408377) (xy 11.814349 -27.414477) (xy 11.868306 -27.428583)
			(xy 11.919635 -27.450395) (xy 11.967241 -27.479449) (xy 12.010109 -27.515124) (xy 12.047326 -27.556661)
			(xy 12.078099 -27.603174) (xy 12.101771 -27.653671) (xy 12.117839 -27.707078) (xy 12.125959 -27.762254)
			(xy 12.126468 -27.79014) (xy 13.866874 -27.79014) (xy 13.870945 -27.734518) (xy 13.883071 -27.680081)
			(xy 13.902994 -27.62799) (xy 13.93029 -27.579355) (xy 13.964376 -27.535212) (xy 14.004525 -27.496503)
			(xy 14.049883 -27.464052) (xy 14.099483 -27.438551) (xy 14.152267 -27.420544) (xy 14.20711 -27.410414)
			(xy 14.262844 -27.408377) (xy 14.318281 -27.414477) (xy 14.372238 -27.428583) (xy 14.423567 -27.450395)
			(xy 14.471173 -27.479449) (xy 14.514041 -27.515124) (xy 14.551258 -27.556661) (xy 14.582031 -27.603174)
			(xy 14.605703 -27.653671) (xy 14.621771 -27.707078) (xy 14.629891 -27.762254) (xy 14.6304 -27.79014)
			(xy 14.629903 -27.817393) (xy 15.899845 -27.817393) (xy 15.899845 -27.762887) (xy 15.907602 -27.708936)
			(xy 15.922958 -27.656638) (xy 15.945601 -27.607058) (xy 15.975069 -27.561204) (xy 16.010763 -27.520012)
			(xy 16.051956 -27.484318) (xy 16.097809 -27.45485) (xy 16.14739 -27.432208) (xy 16.199688 -27.416852)
			(xy 16.253639 -27.409095) (xy 16.280892 -27.408632) (xy 16.306199 -27.409033) (xy 16.356371 -27.415704)
			(xy 16.405223 -27.428942) (xy 16.42872 -27.43835) (xy 16.43673 -27.441365) (xy 16.453798 -27.442461)
			(xy 16.470276 -27.437877) (xy 16.477488 -27.43327) (xy 16.502888 -27.41549) (xy 16.509775 -27.410217)
			(xy 16.519849 -27.396113) (xy 16.524647 -27.379457) (xy 16.524478 -27.370786) (xy 16.523716 -27.342846)
			(xy 16.523716 -26.479246) (xy 16.524224 -26.456894) (xy 16.524732 -26.444448) (xy 16.514318 -26.421842)
			(xy 16.429228 -26.355548) (xy 16.404844 -26.350976) (xy 16.392906 -26.354786) (xy 16.365568 -26.362622)
			(xy 16.309327 -26.371044) (xy 16.280892 -26.37155) (xy 16.253639 -26.371083) (xy 16.199688 -26.363326)
			(xy 16.147391 -26.34797) (xy 16.09781 -26.325328) (xy 16.051957 -26.29586) (xy 16.010765 -26.260167)
			(xy 15.975071 -26.218974) (xy 15.945603 -26.173121) (xy 15.92296 -26.123541) (xy 15.907604 -26.071244)
			(xy 15.899847 -26.017293) (xy 15.899847 -25.962787) (xy 15.907604 -25.908836) (xy 15.92296 -25.856539)
			(xy 15.945603 -25.806959) (xy 15.975071 -25.761106) (xy 16.010765 -25.719913) (xy 16.051957 -25.68422)
			(xy 16.09781 -25.654752) (xy 16.147391 -25.63211) (xy 16.199688 -25.616754) (xy 16.253639 -25.608997)
			(xy 16.280892 -25.608534) (xy 16.309844 -25.609084) (xy 16.367085 -25.617819) (xy 16.422348 -25.635106)
			(xy 16.474363 -25.660546) (xy 16.521936 -25.693556) (xy 16.563973 -25.733377) (xy 16.599508 -25.779094)
			(xy 16.627726 -25.829656) (xy 16.628621 -25.832054) (xy 18.188432 -25.832054) (xy 18.188908 -25.805451)
			(xy 18.196283 -25.752758) (xy 18.210911 -25.701603) (xy 18.232509 -25.652977) (xy 18.260657 -25.607826)
			(xy 18.294808 -25.567027) (xy 18.334299 -25.531371) (xy 18.356072 -25.516078) (xy 18.367551 -25.50774)
			(xy 18.385759 -25.485999) (xy 18.39728 -25.460086) (xy 18.401222 -25.432002) (xy 18.397281 -25.403919)
			(xy 18.385762 -25.378005) (xy 18.367554 -25.356263) (xy 18.356072 -25.34793) (xy 18.334314 -25.332618)
			(xy 18.294833 -25.296956) (xy 18.260688 -25.256156) (xy 18.23254 -25.211009) (xy 18.210936 -25.16239)
			(xy 18.196293 -25.111242) (xy 18.188897 -25.058555) (xy 18.188432 -25.031954) (xy 18.188918 -25.004703)
			(xy 18.196674 -24.950755) (xy 18.212029 -24.89846) (xy 18.234671 -24.848883) (xy 18.264137 -24.803033)
			(xy 18.299828 -24.761842) (xy 18.341019 -24.726151) (xy 18.386869 -24.696685) (xy 18.436446 -24.674043)
			(xy 18.488741 -24.658688) (xy 18.542689 -24.650932) (xy 18.597191 -24.650932) (xy 18.651139 -24.658688)
			(xy 18.703434 -24.674043) (xy 18.753011 -24.696685) (xy 18.798861 -24.726151) (xy 18.840052 -24.761842)
			(xy 18.875743 -24.803033) (xy 18.905209 -24.848883) (xy 18.927851 -24.89846) (xy 18.943206 -24.950755)
			(xy 18.950962 -25.004703) (xy 18.951448 -25.031954) (xy 18.950987 -25.058558) (xy 18.94361 -25.111251)
			(xy 18.92898 -25.162408) (xy 18.90738 -25.211033) (xy 18.87923 -25.256184) (xy 18.845076 -25.296983)
			(xy 18.805582 -25.332638) (xy 18.783808 -25.34793) (xy 18.772323 -25.356259) (xy 18.754118 -25.378003)
			(xy 18.742601 -25.403918) (xy 18.73866 -25.432002) (xy 18.742602 -25.460086) (xy 18.754121 -25.486001)
			(xy 18.772327 -25.507744) (xy 18.783808 -25.516078) (xy 18.805565 -25.531391) (xy 18.845047 -25.567053)
			(xy 18.879193 -25.607852) (xy 18.907341 -25.652999) (xy 18.928946 -25.701618) (xy 18.943588 -25.752766)
			(xy 18.950984 -25.805453) (xy 18.951448 -25.832054) (xy 18.950962 -25.859305) (xy 18.943206 -25.913253)
			(xy 18.927851 -25.965548) (xy 18.905209 -26.015125) (xy 18.875743 -26.060975) (xy 18.840052 -26.102166)
			(xy 18.798861 -26.137857) (xy 18.753011 -26.167323) (xy 18.703434 -26.189965) (xy 18.651139 -26.20532)
			(xy 18.597191 -26.213076) (xy 18.542689 -26.213076) (xy 18.488741 -26.20532) (xy 18.436446 -26.189965)
			(xy 18.386869 -26.167323) (xy 18.341019 -26.137857) (xy 18.299828 -26.102166) (xy 18.264137 -26.060975)
			(xy 18.234671 -26.015125) (xy 18.212029 -25.965548) (xy 18.196674 -25.913253) (xy 18.188918 -25.859305)
			(xy 18.188432 -25.832054) (xy 16.628621 -25.832054) (xy 16.647977 -25.883903) (xy 16.659797 -25.940587)
			(xy 16.661892 -25.969468) (xy 16.6624 -25.981914) (xy 16.6751 -26.00325) (xy 16.766794 -26.060654)
			(xy 16.791432 -26.062432) (xy 16.802862 -26.057606) (xy 16.831216 -26.046126) (xy 16.890216 -26.029975)
			(xy 16.950839 -26.021809) (xy 16.981424 -26.021284) (xy 17.011404 -26.021739) (xy 17.07085 -26.029571)
			(xy 17.128764 -26.045097) (xy 17.184156 -26.068053) (xy 17.236076 -26.098044) (xy 17.283636 -26.134557)
			(xy 17.326021 -26.176967) (xy 17.362507 -26.224549) (xy 17.392467 -26.276487) (xy 17.415389 -26.331892)
			(xy 17.423143 -26.360882) (xy 19.089622 -26.360882) (xy 19.093693 -26.30526) (xy 19.105819 -26.250823)
			(xy 19.125742 -26.198732) (xy 19.153038 -26.150097) (xy 19.187124 -26.105954) (xy 19.227273 -26.067245)
			(xy 19.272631 -26.034794) (xy 19.322231 -26.009293) (xy 19.375015 -25.991286) (xy 19.429858 -25.981156)
			(xy 19.485592 -25.979119) (xy 19.541029 -25.985219) (xy 19.594986 -25.999325) (xy 19.646315 -26.021137)
			(xy 19.693921 -26.050191) (xy 19.736789 -26.085866) (xy 19.774006 -26.127403) (xy 19.804779 -26.173916)
			(xy 19.828451 -26.224413) (xy 19.844519 -26.27782) (xy 19.852639 -26.332996) (xy 19.853148 -26.360882)
			(xy 20.105622 -26.360882) (xy 20.109693 -26.30526) (xy 20.121819 -26.250823) (xy 20.141742 -26.198732)
			(xy 20.169038 -26.150097) (xy 20.203124 -26.105954) (xy 20.243273 -26.067245) (xy 20.288631 -26.034794)
			(xy 20.338231 -26.009293) (xy 20.391015 -25.991286) (xy 20.445858 -25.981156) (xy 20.501592 -25.979119)
			(xy 20.557029 -25.985219) (xy 20.610986 -25.999325) (xy 20.662315 -26.021137) (xy 20.709921 -26.050191)
			(xy 20.752789 -26.085866) (xy 20.790006 -26.127403) (xy 20.820779 -26.173916) (xy 20.844451 -26.224413)
			(xy 20.860519 -26.27782) (xy 20.868639 -26.332996) (xy 20.869148 -26.360882) (xy 20.868639 -26.388768)
			(xy 20.860519 -26.443944) (xy 20.844451 -26.497351) (xy 20.820779 -26.547848) (xy 20.790006 -26.594361)
			(xy 20.752789 -26.635898) (xy 20.709921 -26.671573) (xy 20.662315 -26.700627) (xy 20.610986 -26.722439)
			(xy 20.557029 -26.736545) (xy 20.501592 -26.742645) (xy 20.445858 -26.740608) (xy 20.391015 -26.730478)
			(xy 20.338231 -26.712471) (xy 20.288631 -26.68697) (xy 20.243273 -26.654519) (xy 20.203124 -26.61581)
			(xy 20.169038 -26.571667) (xy 20.141742 -26.523032) (xy 20.121819 -26.470941) (xy 20.109693 -26.416504)
			(xy 20.105622 -26.360882) (xy 19.853148 -26.360882) (xy 19.852639 -26.388768) (xy 19.844519 -26.443944)
			(xy 19.828451 -26.497351) (xy 19.804779 -26.547848) (xy 19.774006 -26.594361) (xy 19.736789 -26.635898)
			(xy 19.693921 -26.671573) (xy 19.646315 -26.700627) (xy 19.594986 -26.722439) (xy 19.541029 -26.736545)
			(xy 19.485592 -26.742645) (xy 19.429858 -26.740608) (xy 19.375015 -26.730478) (xy 19.322231 -26.712471)
			(xy 19.272631 -26.68697) (xy 19.227273 -26.654519) (xy 19.187124 -26.61581) (xy 19.153038 -26.571667)
			(xy 19.125742 -26.523032) (xy 19.105819 -26.470941) (xy 19.093693 -26.416504) (xy 19.089622 -26.360882)
			(xy 17.423143 -26.360882) (xy 17.430882 -26.389815) (xy 17.438678 -26.449266) (xy 17.439132 -26.479246)
			(xy 17.439132 -27.342846) (xy 17.438716 -27.372822) (xy 17.430887 -27.432261) (xy 17.41537 -27.49017)
			(xy 17.39243 -27.54556) (xy 17.362459 -27.597483) (xy 17.32597 -27.645051) (xy 17.283585 -27.687452)
			(xy 17.236031 -27.72396) (xy 17.18412 -27.753951) (xy 17.128739 -27.776913) (xy 17.070836 -27.792452)
			(xy 17.0114 -27.800304) (xy 16.981424 -27.800808) (xy 16.950288 -27.800261) (xy 16.888592 -27.791803)
			(xy 16.828607 -27.775079) (xy 16.799814 -27.763216) (xy 16.788638 -27.75839) (xy 16.765016 -27.75966)
			(xy 16.67383 -27.810968) (xy 16.660368 -27.830526) (xy 16.658844 -27.842464) (xy 16.654696 -27.869507)
			(xy 16.639512 -27.922069) (xy 16.616978 -27.971925) (xy 16.587555 -28.018052) (xy 16.551847 -28.059505)
			(xy 16.510585 -28.095434) (xy 16.464616 -28.125103) (xy 16.414881 -28.147903) (xy 16.3624 -28.163367)
			(xy 16.308248 -28.171179) (xy 16.280892 -28.171648) (xy 16.253639 -28.171185) (xy 16.199688 -28.163428)
			(xy 16.14739 -28.148072) (xy 16.097809 -28.12543) (xy 16.051956 -28.095962) (xy 16.010763 -28.060268)
			(xy 15.975069 -28.019076) (xy 15.945601 -27.973222) (xy 15.922958 -27.923642) (xy 15.907602 -27.871344)
			(xy 15.899845 -27.817393) (xy 14.629903 -27.817393) (xy 14.629891 -27.818026) (xy 14.621771 -27.873202)
			(xy 14.605703 -27.926609) (xy 14.582031 -27.977106) (xy 14.551258 -28.023619) (xy 14.514041 -28.065156)
			(xy 14.471173 -28.100831) (xy 14.423567 -28.129885) (xy 14.372238 -28.151697) (xy 14.318281 -28.165803)
			(xy 14.262844 -28.171903) (xy 14.20711 -28.169866) (xy 14.152267 -28.159736) (xy 14.099483 -28.141729)
			(xy 14.049883 -28.116228) (xy 14.004525 -28.083777) (xy 13.964376 -28.045068) (xy 13.93029 -28.000925)
			(xy 13.902994 -27.95229) (xy 13.883071 -27.900199) (xy 13.870945 -27.845762) (xy 13.866874 -27.79014)
			(xy 12.126468 -27.79014) (xy 12.125959 -27.818026) (xy 12.117839 -27.873202) (xy 12.101771 -27.926609)
			(xy 12.078099 -27.977106) (xy 12.047326 -28.023619) (xy 12.010109 -28.065156) (xy 11.967241 -28.100831)
			(xy 11.919635 -28.129885) (xy 11.868306 -28.151697) (xy 11.814349 -28.165803) (xy 11.758912 -28.171903)
			(xy 11.703178 -28.169866) (xy 11.648335 -28.159736) (xy 11.595551 -28.141729) (xy 11.545951 -28.116228)
			(xy 11.500593 -28.083777) (xy 11.460444 -28.045068) (xy 11.426358 -28.000925) (xy 11.399062 -27.95229)
			(xy 11.379139 -27.900199) (xy 11.367013 -27.845762) (xy 11.362942 -27.79014) (xy 10.029972 -27.79014)
			(xy 10.029972 -27.817391) (xy 10.022216 -27.871339) (xy 10.006861 -27.923633) (xy 9.98422 -27.97321)
			(xy 9.954754 -28.019061) (xy 9.919062 -28.060251) (xy 9.877872 -28.095942) (xy 9.832022 -28.125409)
			(xy 9.782445 -28.14805) (xy 9.730151 -28.163405) (xy 9.676203 -28.171162) (xy 9.648952 -28.171648)
			(xy 9.635998 -28.171648) (xy 9.617456 -28.179268) (xy 9.559036 -28.23718) (xy 9.552198 -28.244581)
			(xy 9.544487 -28.26318) (xy 9.54405 -28.273248) (xy 9.54405 -29.106876) (xy 9.544488 -29.116939)
			(xy 9.552228 -29.135519) (xy 9.559036 -29.142944) (xy 9.617456 -29.200856) (xy 9.635998 -29.208476)
			(xy 9.646412 -29.208476) (xy 9.648952 -29.208476) (xy 9.676203 -29.208962) (xy 9.73015 -29.216719)
			(xy 9.782444 -29.232074) (xy 9.83202 -29.254715) (xy 9.87787 -29.284181) (xy 9.919059 -29.319872)
			(xy 9.95475 -29.361062) (xy 9.984216 -29.406912) (xy 10.006857 -29.456488) (xy 10.022212 -29.508782)
			(xy 10.029968 -29.562729) (xy 10.029968 -29.589984) (xy 11.362942 -29.589984) (xy 11.367013 -29.534362)
			(xy 11.379139 -29.479925) (xy 11.399062 -29.427834) (xy 11.426358 -29.379199) (xy 11.460444 -29.335056)
			(xy 11.500593 -29.296347) (xy 11.545951 -29.263896) (xy 11.595551 -29.238395) (xy 11.648335 -29.220388)
			(xy 11.703178 -29.210258) (xy 11.758912 -29.208221) (xy 11.814349 -29.214321) (xy 11.868306 -29.228427)
			(xy 11.919635 -29.250239) (xy 11.967241 -29.279293) (xy 12.010109 -29.314968) (xy 12.047326 -29.356505)
			(xy 12.078099 -29.403018) (xy 12.101771 -29.453515) (xy 12.117839 -29.506922) (xy 12.125959 -29.562098)
			(xy 12.126468 -29.589984) (xy 13.866874 -29.589984) (xy 13.870945 -29.534362) (xy 13.883071 -29.479925)
			(xy 13.902994 -29.427834) (xy 13.93029 -29.379199) (xy 13.964376 -29.335056) (xy 14.004525 -29.296347)
			(xy 14.049883 -29.263896) (xy 14.099483 -29.238395) (xy 14.152267 -29.220388) (xy 14.20711 -29.210258)
			(xy 14.262844 -29.208221) (xy 14.318281 -29.214321) (xy 14.372238 -29.228427) (xy 14.423567 -29.250239)
			(xy 14.471173 -29.279293) (xy 14.514041 -29.314968) (xy 14.551258 -29.356505) (xy 14.582031 -29.403018)
			(xy 14.605703 -29.453515) (xy 14.621771 -29.506922) (xy 14.629891 -29.562098) (xy 14.6304 -29.589984)
			(xy 15.898874 -29.589984) (xy 15.902945 -29.534362) (xy 15.915071 -29.479925) (xy 15.934994 -29.427834)
			(xy 15.96229 -29.379199) (xy 15.996376 -29.335056) (xy 16.036525 -29.296347) (xy 16.081883 -29.263896)
			(xy 16.131483 -29.238395) (xy 16.184267 -29.220388) (xy 16.23911 -29.210258) (xy 16.294844 -29.208221)
			(xy 16.350281 -29.214321) (xy 16.404238 -29.228427) (xy 16.455567 -29.250239) (xy 16.503173 -29.279293)
			(xy 16.546041 -29.314968) (xy 16.567664 -29.339101) (xy 18.290272 -29.339101) (xy 18.290272 -29.284599)
			(xy 18.298028 -29.230652) (xy 18.313383 -29.178359) (xy 18.336023 -29.128782) (xy 18.365489 -29.082932)
			(xy 18.40118 -29.041743) (xy 18.442369 -29.006051) (xy 18.488219 -28.976585) (xy 18.537795 -28.953944)
			(xy 18.590088 -28.938589) (xy 18.644035 -28.930832) (xy 18.671286 -28.930346) (xy 18.686079 -28.930481)
			(xy 18.715577 -28.93277) (xy 18.730214 -28.934918) (xy 18.741136 -28.936696) (xy 18.762472 -28.9306)
			(xy 18.829782 -28.873196) (xy 18.837763 -28.865617) (xy 18.846837 -28.845586) (xy 18.847308 -28.834588)
			(xy 18.847308 -28.530296) (xy 18.846802 -28.519307) (xy 18.837727 -28.499295) (xy 18.829782 -28.491688)
			(xy 18.762472 -28.434284) (xy 18.741136 -28.428188) (xy 18.730214 -28.429966) (xy 18.715577 -28.432111)
			(xy 18.686079 -28.434396) (xy 18.671286 -28.434538) (xy 18.644038 -28.433991) (xy 18.590096 -28.426233)
			(xy 18.537807 -28.410878) (xy 18.488235 -28.388238) (xy 18.44239 -28.358774) (xy 18.401205 -28.323085)
			(xy 18.365518 -28.281899) (xy 18.336055 -28.236052) (xy 18.313417 -28.18648) (xy 18.298064 -28.134191)
			(xy 18.290308 -28.080248) (xy 18.290308 -28.025752) (xy 18.298064 -27.971809) (xy 18.313417 -27.91952)
			(xy 18.336055 -27.869948) (xy 18.365518 -27.824101) (xy 18.401205 -27.782915) (xy 18.44239 -27.747226)
			(xy 18.488235 -27.717762) (xy 18.537807 -27.695122) (xy 18.590096 -27.679767) (xy 18.644038 -27.672009)
			(xy 18.671286 -27.671522) (xy 18.697212 -27.671956) (xy 18.74859 -27.678961) (xy 18.798546 -27.692857)
			(xy 18.84616 -27.713388) (xy 18.890557 -27.740177) (xy 18.930918 -27.77273) (xy 18.9665 -27.810447)
			(xy 18.981928 -27.831288) (xy 18.987683 -27.838605) (xy 19.003175 -27.848898) (xy 19.012154 -27.851354)
			(xy 19.04238 -27.858212) (xy 19.051654 -27.859979) (xy 19.07032 -27.857226) (xy 19.078702 -27.852878)
			(xy 19.104678 -27.838583) (xy 19.15953 -27.816073) (xy 19.216833 -27.800846) (xy 19.275624 -27.79316)
			(xy 19.30527 -27.79268) (xy 19.334913 -27.793179) (xy 19.393695 -27.8009) (xy 19.450993 -27.816126)
			(xy 19.505853 -27.838604) (xy 19.531838 -27.852878) (xy 19.54026 -27.857104) (xy 19.558882 -27.85985)
			(xy 19.56816 -27.858212) (xy 19.598386 -27.851354) (xy 19.607388 -27.848953) (xy 19.622889 -27.838642)
			(xy 19.628612 -27.831288) (xy 19.644004 -27.810417) (xy 19.679579 -27.772683) (xy 19.719941 -27.740118)
			(xy 19.764344 -27.713325) (xy 19.811968 -27.692798) (xy 19.861936 -27.678916) (xy 19.913324 -27.671934)
			(xy 19.939254 -27.671522) (xy 19.966505 -27.672008) (xy 20.020452 -27.679765) (xy 20.072747 -27.695121)
			(xy 20.122323 -27.717762) (xy 20.168173 -27.747228) (xy 20.209363 -27.78292) (xy 20.245054 -27.82411)
			(xy 20.27452 -27.86996) (xy 20.297161 -27.919537) (xy 20.312516 -27.971832) (xy 20.320272 -28.025779)
			(xy 20.320272 -28.080281) (xy 20.312516 -28.134228) (xy 20.297161 -28.186523) (xy 20.27452 -28.2361)
			(xy 20.245054 -28.28195) (xy 20.209363 -28.32314) (xy 20.168173 -28.358832) (xy 20.122323 -28.388298)
			(xy 20.072747 -28.410939) (xy 20.020452 -28.426295) (xy 19.966505 -28.434052) (xy 19.939254 -28.434538)
			(xy 19.924461 -28.434399) (xy 19.894963 -28.432112) (xy 19.880326 -28.429966) (xy 19.869404 -28.428188)
			(xy 19.848068 -28.434284) (xy 19.780758 -28.491688) (xy 19.77279 -28.499279) (xy 19.763707 -28.5193)
			(xy 19.763232 -28.530296) (xy 19.763232 -28.834588) (xy 19.763734 -28.845578) (xy 19.77281 -28.865591)
			(xy 19.780758 -28.873196) (xy 19.848068 -28.9306) (xy 19.869404 -28.936696) (xy 19.880326 -28.934918)
			(xy 19.894964 -28.93278) (xy 19.924461 -28.93049) (xy 19.939254 -28.930346) (xy 19.966505 -28.930824)
			(xy 20.020453 -28.938581) (xy 20.072748 -28.953937) (xy 20.122325 -28.976578) (xy 20.168176 -29.006045)
			(xy 20.209366 -29.041737) (xy 20.245057 -29.082928) (xy 20.274524 -29.128778) (xy 20.297165 -29.178356)
			(xy 20.31252 -29.230651) (xy 20.320276 -29.284599) (xy 20.320276 -29.339101) (xy 20.31252 -29.393049)
			(xy 20.297165 -29.445344) (xy 20.274524 -29.494922) (xy 20.245057 -29.540772) (xy 20.209366 -29.581963)
			(xy 20.168176 -29.617655) (xy 20.122325 -29.647122) (xy 20.072748 -29.669763) (xy 20.020453 -29.685119)
			(xy 19.966505 -29.692876) (xy 19.939254 -29.693362) (xy 19.913326 -29.692979) (xy 19.861946 -29.685966)
			(xy 19.811989 -29.672062) (xy 19.764374 -29.651522) (xy 19.719978 -29.624725) (xy 19.679618 -29.592165)
			(xy 19.644038 -29.55444) (xy 19.628612 -29.533596) (xy 19.622861 -29.526275) (xy 19.607367 -29.515982)
			(xy 19.598386 -29.51353) (xy 19.56816 -29.506672) (xy 19.558883 -29.504928) (xy 19.54022 -29.507666)
			(xy 19.531838 -29.512006) (xy 19.505873 -29.526323) (xy 19.451017 -29.548828) (xy 19.393711 -29.564048)
			(xy 19.334917 -29.571728) (xy 19.30527 -29.572204) (xy 19.275628 -29.57169) (xy 19.216846 -29.563974)
			(xy 19.159548 -29.548752) (xy 19.104687 -29.526278) (xy 19.078702 -29.512006) (xy 19.070294 -29.50775)
			(xy 19.05166 -29.505023) (xy 19.04238 -29.506672) (xy 19.012154 -29.51353) (xy 19.003159 -29.515953)
			(xy 18.987655 -29.526249) (xy 18.981928 -29.533596) (xy 18.966506 -29.554445) (xy 18.930937 -29.59218)
			(xy 18.890581 -29.624747) (xy 18.846183 -29.651543) (xy 18.798563 -29.672074) (xy 18.7486 -29.685961)
			(xy 18.697215 -29.692947) (xy 18.671286 -29.693362) (xy 18.644035 -29.692868) (xy 18.590088 -29.685111)
			(xy 18.537795 -29.669756) (xy 18.488219 -29.647115) (xy 18.442369 -29.617649) (xy 18.40118 -29.581957)
			(xy 18.365489 -29.540768) (xy 18.336023 -29.494918) (xy 18.313383 -29.445341) (xy 18.298028 -29.393048)
			(xy 18.290272 -29.339101) (xy 16.567664 -29.339101) (xy 16.583258 -29.356505) (xy 16.614031 -29.403018)
			(xy 16.637703 -29.453515) (xy 16.653771 -29.506922) (xy 16.661891 -29.562098) (xy 16.6624 -29.589984)
			(xy 16.661891 -29.61787) (xy 16.653771 -29.673046) (xy 16.637703 -29.726453) (xy 16.614031 -29.77695)
			(xy 16.583258 -29.823463) (xy 16.546041 -29.865) (xy 16.503173 -29.900675) (xy 16.455567 -29.929729)
			(xy 16.404238 -29.951541) (xy 16.350281 -29.965647) (xy 16.294844 -29.971747) (xy 16.23911 -29.96971)
			(xy 16.184267 -29.95958) (xy 16.131483 -29.941573) (xy 16.081883 -29.916072) (xy 16.036525 -29.883621)
			(xy 15.996376 -29.844912) (xy 15.96229 -29.800769) (xy 15.934994 -29.752134) (xy 15.915071 -29.700043)
			(xy 15.902945 -29.645606) (xy 15.898874 -29.589984) (xy 14.6304 -29.589984) (xy 14.629891 -29.61787)
			(xy 14.621771 -29.673046) (xy 14.605703 -29.726453) (xy 14.582031 -29.77695) (xy 14.551258 -29.823463)
			(xy 14.514041 -29.865) (xy 14.471173 -29.900675) (xy 14.423567 -29.929729) (xy 14.372238 -29.951541)
			(xy 14.318281 -29.965647) (xy 14.262844 -29.971747) (xy 14.20711 -29.96971) (xy 14.152267 -29.95958)
			(xy 14.099483 -29.941573) (xy 14.049883 -29.916072) (xy 14.004525 -29.883621) (xy 13.964376 -29.844912)
			(xy 13.93029 -29.800769) (xy 13.902994 -29.752134) (xy 13.883071 -29.700043) (xy 13.870945 -29.645606)
			(xy 13.866874 -29.589984) (xy 12.126468 -29.589984) (xy 12.125959 -29.61787) (xy 12.117839 -29.673046)
			(xy 12.101771 -29.726453) (xy 12.078099 -29.77695) (xy 12.047326 -29.823463) (xy 12.010109 -29.865)
			(xy 11.967241 -29.900675) (xy 11.919635 -29.929729) (xy 11.868306 -29.951541) (xy 11.814349 -29.965647)
			(xy 11.758912 -29.971747) (xy 11.703178 -29.96971) (xy 11.648335 -29.95958) (xy 11.595551 -29.941573)
			(xy 11.545951 -29.916072) (xy 11.500593 -29.883621) (xy 11.460444 -29.844912) (xy 11.426358 -29.800769)
			(xy 11.399062 -29.752134) (xy 11.379139 -29.700043) (xy 11.367013 -29.645606) (xy 11.362942 -29.589984)
			(xy 10.029968 -29.589984) (xy 10.029968 -29.617231) (xy 10.022212 -29.671178) (xy 10.006857 -29.723472)
			(xy 9.984216 -29.773048) (xy 9.95475 -29.818898) (xy 9.919059 -29.860088) (xy 9.87787 -29.895779)
			(xy 9.83202 -29.925245) (xy 9.782444 -29.947886) (xy 9.73015 -29.963241) (xy 9.676203 -29.970998)
			(xy 9.648952 -29.971492) (xy 9.635998 -29.971492) (xy 9.617456 -29.979112) (xy 9.559036 -30.037024)
			(xy 9.552189 -30.044422) (xy 9.544458 -30.063021) (xy 9.54405 -30.073092) (xy 9.54405 -30.901132)
			(xy 12.123926 -30.901132) (xy 12.127997 -30.84551) (xy 12.140123 -30.791073) (xy 12.160046 -30.738982)
			(xy 12.187342 -30.690347) (xy 12.221428 -30.646204) (xy 12.261577 -30.607495) (xy 12.306935 -30.575044)
			(xy 12.356535 -30.549543) (xy 12.409319 -30.531536) (xy 12.464162 -30.521406) (xy 12.519896 -30.519369)
			(xy 12.575333 -30.525469) (xy 12.62929 -30.539575) (xy 12.680619 -30.561387) (xy 12.728225 -30.590441)
			(xy 12.771093 -30.626116) (xy 12.80831 -30.667653) (xy 12.839083 -30.714166) (xy 12.862755 -30.764663)
			(xy 12.878823 -30.81807) (xy 12.886943 -30.873246) (xy 12.887452 -30.901132) (xy 12.886943 -30.929018)
			(xy 12.878823 -30.984194) (xy 12.862755 -31.037601) (xy 12.839083 -31.088098) (xy 12.80831 -31.134611)
			(xy 12.771093 -31.176148) (xy 12.728225 -31.211823) (xy 12.680619 -31.240877) (xy 12.62929 -31.262689)
			(xy 12.575333 -31.276795) (xy 12.519896 -31.282895) (xy 12.464162 -31.280858) (xy 12.409319 -31.270728)
			(xy 12.356535 -31.252721) (xy 12.306935 -31.22722) (xy 12.261577 -31.194769) (xy 12.221428 -31.15606)
			(xy 12.187342 -31.111917) (xy 12.160046 -31.063282) (xy 12.140123 -31.011191) (xy 12.127997 -30.956754)
			(xy 12.123926 -30.901132) (xy 9.54405 -30.901132) (xy 9.54405 -30.906974) (xy 9.544488 -30.917037)
			(xy 9.552227 -30.935617) (xy 9.559036 -30.943042) (xy 9.617456 -31.000954) (xy 9.635998 -31.008574)
			(xy 9.646412 -31.008574) (xy 9.648952 -31.008574) (xy 9.676203 -31.00906) (xy 9.73015 -31.016817)
			(xy 9.782444 -31.032172) (xy 9.832021 -31.054813) (xy 9.877871 -31.084279) (xy 9.919061 -31.119971)
			(xy 9.954752 -31.16116) (xy 9.984218 -31.207011) (xy 10.006859 -31.256587) (xy 10.022214 -31.308882)
			(xy 10.02997 -31.362829) (xy 10.02997 -31.390082) (xy 13.866874 -31.390082) (xy 13.870945 -31.33446)
			(xy 13.883071 -31.280023) (xy 13.902994 -31.227932) (xy 13.93029 -31.179297) (xy 13.964376 -31.135154)
			(xy 14.004525 -31.096445) (xy 14.049883 -31.063994) (xy 14.099483 -31.038493) (xy 14.152267 -31.020486)
			(xy 14.20711 -31.010356) (xy 14.262844 -31.008319) (xy 14.318281 -31.014419) (xy 14.372238 -31.028525)
			(xy 14.423567 -31.050337) (xy 14.471173 -31.079391) (xy 14.514041 -31.115066) (xy 14.551258 -31.156603)
			(xy 14.582031 -31.203116) (xy 14.605703 -31.253613) (xy 14.621771 -31.30702) (xy 14.629891 -31.362196)
			(xy 14.6304 -31.390082) (xy 15.898874 -31.390082) (xy 15.902945 -31.33446) (xy 15.915071 -31.280023)
			(xy 15.934994 -31.227932) (xy 15.96229 -31.179297) (xy 15.996376 -31.135154) (xy 16.036525 -31.096445)
			(xy 16.081883 -31.063994) (xy 16.131483 -31.038493) (xy 16.184267 -31.020486) (xy 16.23911 -31.010356)
			(xy 16.294844 -31.008319) (xy 16.350281 -31.014419) (xy 16.404238 -31.028525) (xy 16.455567 -31.050337)
			(xy 16.503173 -31.079391) (xy 16.546041 -31.115066) (xy 16.583258 -31.156603) (xy 16.614031 -31.203116)
			(xy 16.637703 -31.253613) (xy 16.653771 -31.30702) (xy 16.661891 -31.362196) (xy 16.6624 -31.390082)
			(xy 16.661891 -31.417968) (xy 16.653771 -31.473144) (xy 16.637703 -31.526551) (xy 16.614031 -31.577048)
			(xy 16.583258 -31.623561) (xy 16.546041 -31.665098) (xy 16.52783 -31.680253) (xy 18.29025 -31.680253)
			(xy 18.29025 -31.625747) (xy 18.298007 -31.571797) (xy 18.313362 -31.519499) (xy 18.336004 -31.46992)
			(xy 18.365471 -31.424066) (xy 18.401164 -31.382874) (xy 18.442355 -31.347179) (xy 18.488207 -31.317711)
			(xy 18.537786 -31.295067) (xy 18.590083 -31.27971) (xy 18.644033 -31.271951) (xy 18.671286 -31.271464)
			(xy 18.697213 -31.271881) (xy 18.748592 -31.278886) (xy 18.798549 -31.292784) (xy 18.846164 -31.313318)
			(xy 18.890561 -31.34011) (xy 18.930921 -31.372666) (xy 18.966502 -31.410387) (xy 18.981928 -31.43123)
			(xy 18.987695 -31.438537) (xy 19.003178 -31.448837) (xy 19.012154 -31.451296) (xy 19.04238 -31.458154)
			(xy 19.051655 -31.459916) (xy 19.07032 -31.457165) (xy 19.078702 -31.45282) (xy 19.104695 -31.438578)
			(xy 19.159563 -31.416162) (xy 19.216861 -31.401002) (xy 19.275635 -31.39335) (xy 19.30527 -31.392876)
			(xy 19.334908 -31.393329) (xy 19.39369 -31.400952) (xy 19.450994 -31.416112) (xy 19.505855 -31.438555)
			(xy 19.531838 -31.45282) (xy 19.540261 -31.457044) (xy 19.558883 -31.459793) (xy 19.56816 -31.458154)
			(xy 19.598386 -31.451296) (xy 19.607383 -31.448882) (xy 19.622886 -31.438579) (xy 19.628612 -31.43123)
			(xy 19.643987 -31.410346) (xy 19.679567 -31.372615) (xy 19.719932 -31.340053) (xy 19.764338 -31.313263)
			(xy 19.811965 -31.292738) (xy 19.861934 -31.278857) (xy 19.913323 -31.271876) (xy 19.939254 -31.271464)
			(xy 19.966505 -31.271946) (xy 20.020453 -31.279703) (xy 20.072747 -31.295059) (xy 20.122324 -31.3177)
			(xy 20.168174 -31.347167) (xy 20.209364 -31.382858) (xy 20.245056 -31.424049) (xy 20.274522 -31.469899)
			(xy 20.297163 -31.519476) (xy 20.312518 -31.571771) (xy 20.320274 -31.625719) (xy 20.320274 -31.680221)
			(xy 20.312518 -31.734169) (xy 20.297163 -31.786464) (xy 20.274522 -31.836041) (xy 20.245056 -31.881891)
			(xy 20.209364 -31.923082) (xy 20.168174 -31.958773) (xy 20.122324 -31.98824) (xy 20.072747 -32.010881)
			(xy 20.020453 -32.026237) (xy 19.966505 -32.033994) (xy 19.939254 -32.03448) (xy 19.924461 -32.03434)
			(xy 19.894963 -32.032054) (xy 19.880326 -32.029908) (xy 19.869404 -32.02813) (xy 19.848068 -32.034226)
			(xy 19.780758 -32.09163) (xy 19.772816 -32.099245) (xy 19.763719 -32.119248) (xy 19.763232 -32.130238)
			(xy 19.763232 -32.43453) (xy 19.763711 -32.445522) (xy 19.772803 -32.465535) (xy 19.780758 -32.473138)
			(xy 19.848068 -32.530542) (xy 19.869404 -32.536638) (xy 19.880326 -32.53486) (xy 19.894964 -32.532721)
			(xy 19.924461 -32.530432) (xy 19.939254 -32.530288) (xy 19.966505 -32.530782) (xy 20.020452 -32.538539)
			(xy 20.072745 -32.553894) (xy 20.122321 -32.576535) (xy 20.168171 -32.606001) (xy 20.20936 -32.641693)
			(xy 20.245051 -32.682882) (xy 20.274517 -32.728732) (xy 20.297157 -32.778309) (xy 20.312512 -32.830602)
			(xy 20.320268 -32.884549) (xy 20.320268 -32.939051) (xy 20.312512 -32.992998) (xy 20.297157 -33.045291)
			(xy 20.274517 -33.094868) (xy 20.245051 -33.140718) (xy 20.20936 -33.181907) (xy 20.168171 -33.217599)
			(xy 20.122321 -33.247065) (xy 20.072745 -33.269706) (xy 20.020452 -33.285061) (xy 19.966505 -33.292818)
			(xy 19.939254 -33.293304) (xy 19.913327 -33.292904) (xy 19.861948 -33.285892) (xy 19.811992 -33.271989)
			(xy 19.764378 -33.251452) (xy 19.719982 -33.224658) (xy 19.679621 -33.192101) (xy 19.644039 -33.15438)
			(xy 19.628612 -33.133538) (xy 19.622873 -33.126207) (xy 19.607369 -33.115921) (xy 19.598386 -33.113472)
			(xy 19.56816 -33.106614) (xy 19.558883 -33.104865) (xy 19.54022 -33.107606) (xy 19.531838 -33.111948)
			(xy 19.505856 -33.126211) (xy 19.450984 -33.148622) (xy 19.393683 -33.163776) (xy 19.334906 -33.171422)
			(xy 19.30527 -33.171892) (xy 19.275633 -33.171426) (xy 19.21685 -33.163808) (xy 19.159547 -33.148652)
			(xy 19.104685 -33.126212) (xy 19.078702 -33.111948) (xy 19.070293 -33.107693) (xy 19.05166 -33.104965)
			(xy 19.04238 -33.106614) (xy 19.012154 -33.113472) (xy 19.003166 -33.115913) (xy 18.987659 -33.126197)
			(xy 18.981928 -33.133538) (xy 18.966519 -33.154396) (xy 18.930946 -33.19213) (xy 18.890587 -33.224694)
			(xy 18.846187 -33.251488) (xy 18.798565 -33.272017) (xy 18.748601 -33.285903) (xy 18.697215 -33.292889)
			(xy 18.671286 -33.293304) (xy 18.644035 -33.292825) (xy 18.590088 -33.285067) (xy 18.537795 -33.269711)
			(xy 18.488219 -33.247068) (xy 18.44237 -33.217601) (xy 18.401181 -33.181909) (xy 18.36549 -33.140719)
			(xy 18.336025 -33.094869) (xy 18.313385 -33.045292) (xy 18.29803 -32.992998) (xy 18.290274 -32.939051)
			(xy 18.290274 -32.884549) (xy 18.29803 -32.830602) (xy 18.313385 -32.778308) (xy 18.336025 -32.728731)
			(xy 18.36549 -32.682881) (xy 18.401181 -32.641691) (xy 18.44237 -32.605999) (xy 18.488219 -32.576532)
			(xy 18.537795 -32.553889) (xy 18.590088 -32.538533) (xy 18.644035 -32.530775) (xy 18.671286 -32.530288)
			(xy 18.686079 -32.530423) (xy 18.715577 -32.532712) (xy 18.730214 -32.53486) (xy 18.741136 -32.536638)
			(xy 18.762472 -32.530542) (xy 18.829782 -32.473138) (xy 18.837744 -32.465542) (xy 18.846829 -32.445524)
			(xy 18.847308 -32.43453) (xy 18.847308 -32.130238) (xy 18.846834 -32.119245) (xy 18.837737 -32.099234)
			(xy 18.829782 -32.09163) (xy 18.762472 -32.034226) (xy 18.741136 -32.02813) (xy 18.730214 -32.029908)
			(xy 18.715577 -32.032054) (xy 18.686079 -32.034338) (xy 18.671286 -32.03448) (xy 18.644033 -32.034049)
			(xy 18.590083 -32.02629) (xy 18.537786 -32.010933) (xy 18.488207 -31.988289) (xy 18.442355 -31.958821)
			(xy 18.401164 -31.923126) (xy 18.365471 -31.881934) (xy 18.336004 -31.83608) (xy 18.313362 -31.786501)
			(xy 18.298007 -31.734203) (xy 18.29025 -31.680253) (xy 16.52783 -31.680253) (xy 16.503173 -31.700773)
			(xy 16.455567 -31.729827) (xy 16.404238 -31.751639) (xy 16.350281 -31.765745) (xy 16.294844 -31.771845)
			(xy 16.23911 -31.769808) (xy 16.184267 -31.759678) (xy 16.131483 -31.741671) (xy 16.081883 -31.71617)
			(xy 16.036525 -31.683719) (xy 15.996376 -31.64501) (xy 15.96229 -31.600867) (xy 15.934994 -31.552232)
			(xy 15.915071 -31.500141) (xy 15.902945 -31.445704) (xy 15.898874 -31.390082) (xy 14.6304 -31.390082)
			(xy 14.629891 -31.417968) (xy 14.621771 -31.473144) (xy 14.605703 -31.526551) (xy 14.582031 -31.577048)
			(xy 14.551258 -31.623561) (xy 14.514041 -31.665098) (xy 14.471173 -31.700773) (xy 14.423567 -31.729827)
			(xy 14.372238 -31.751639) (xy 14.318281 -31.765745) (xy 14.262844 -31.771845) (xy 14.20711 -31.769808)
			(xy 14.152267 -31.759678) (xy 14.099483 -31.741671) (xy 14.049883 -31.71617) (xy 14.004525 -31.683719)
			(xy 13.964376 -31.64501) (xy 13.93029 -31.600867) (xy 13.902994 -31.552232) (xy 13.883071 -31.500141)
			(xy 13.870945 -31.445704) (xy 13.866874 -31.390082) (xy 10.02997 -31.390082) (xy 10.02997 -31.417331)
			(xy 10.022214 -31.471278) (xy 10.006859 -31.523573) (xy 9.984218 -31.573149) (xy 9.954752 -31.619)
			(xy 9.919061 -31.660189) (xy 9.877871 -31.695881) (xy 9.832021 -31.725347) (xy 9.782444 -31.747988)
			(xy 9.73015 -31.763343) (xy 9.676203 -31.7711) (xy 9.648952 -31.77159) (xy 9.635998 -31.77159) (xy 9.617456 -31.77921)
			(xy 9.559036 -31.837122) (xy 9.552189 -31.84452) (xy 9.544457 -31.863118) (xy 9.54405 -31.87319)
			(xy 9.54405 -32.707072) (xy 9.544488 -32.717135) (xy 9.552226 -32.735716) (xy 9.559036 -32.74314)
			(xy 9.617456 -32.801052) (xy 9.635998 -32.808672) (xy 9.646412 -32.808672) (xy 9.648952 -32.808672)
			(xy 9.676203 -32.809158) (xy 9.730151 -32.816915) (xy 9.782445 -32.83227) (xy 9.832022 -32.854911)
			(xy 9.877872 -32.884378) (xy 9.919062 -32.920069) (xy 9.954754 -32.961259) (xy 9.98422 -33.00711)
			(xy 10.006861 -33.056687) (xy 10.022216 -33.108981) (xy 10.029972 -33.162929) (xy 10.029972 -33.19018)
			(xy 11.538456 -33.19018) (xy 11.542527 -33.134558) (xy 11.554653 -33.080121) (xy 11.574576 -33.02803)
			(xy 11.601872 -32.979395) (xy 11.635958 -32.935252) (xy 11.676107 -32.896543) (xy 11.721465 -32.864092)
			(xy 11.771065 -32.838591) (xy 11.823849 -32.820584) (xy 11.878692 -32.810454) (xy 11.934426 -32.808417)
			(xy 11.989863 -32.814517) (xy 12.04382 -32.828623) (xy 12.095149 -32.850435) (xy 12.142755 -32.879489)
			(xy 12.185623 -32.915164) (xy 12.22284 -32.956701) (xy 12.253613 -33.003214) (xy 12.277285 -33.053711)
			(xy 12.293353 -33.107118) (xy 12.301473 -33.162294) (xy 12.301982 -33.19018) (xy 13.866874 -33.19018)
			(xy 13.870945 -33.134558) (xy 13.883071 -33.080121) (xy 13.902994 -33.02803) (xy 13.93029 -32.979395)
			(xy 13.964376 -32.935252) (xy 14.004525 -32.896543) (xy 14.049883 -32.864092) (xy 14.099483 -32.838591)
			(xy 14.152267 -32.820584) (xy 14.20711 -32.810454) (xy 14.262844 -32.808417) (xy 14.318281 -32.814517)
			(xy 14.372238 -32.828623) (xy 14.423567 -32.850435) (xy 14.471173 -32.879489) (xy 14.514041 -32.915164)
			(xy 14.551258 -32.956701) (xy 14.582031 -33.003214) (xy 14.605703 -33.053711) (xy 14.621771 -33.107118)
			(xy 14.629891 -33.162294) (xy 14.6304 -33.19018) (xy 15.898874 -33.19018) (xy 15.902945 -33.134558)
			(xy 15.915071 -33.080121) (xy 15.934994 -33.02803) (xy 15.96229 -32.979395) (xy 15.996376 -32.935252)
			(xy 16.036525 -32.896543) (xy 16.081883 -32.864092) (xy 16.131483 -32.838591) (xy 16.184267 -32.820584)
			(xy 16.23911 -32.810454) (xy 16.294844 -32.808417) (xy 16.350281 -32.814517) (xy 16.404238 -32.828623)
			(xy 16.455567 -32.850435) (xy 16.503173 -32.879489) (xy 16.546041 -32.915164) (xy 16.583258 -32.956701)
			(xy 16.614031 -33.003214) (xy 16.637703 -33.053711) (xy 16.653771 -33.107118) (xy 16.661891 -33.162294)
			(xy 16.6624 -33.19018) (xy 16.661891 -33.218066) (xy 16.653771 -33.273242) (xy 16.637703 -33.326649)
			(xy 16.614031 -33.377146) (xy 16.583258 -33.423659) (xy 16.546041 -33.465196) (xy 16.503173 -33.500871)
			(xy 16.455567 -33.529925) (xy 16.404238 -33.551737) (xy 16.350281 -33.565843) (xy 16.294844 -33.571943)
			(xy 16.23911 -33.569906) (xy 16.184267 -33.559776) (xy 16.131483 -33.541769) (xy 16.081883 -33.516268)
			(xy 16.036525 -33.483817) (xy 15.996376 -33.445108) (xy 15.96229 -33.400965) (xy 15.934994 -33.35233)
			(xy 15.915071 -33.300239) (xy 15.902945 -33.245802) (xy 15.898874 -33.19018) (xy 14.6304 -33.19018)
			(xy 14.629891 -33.218066) (xy 14.621771 -33.273242) (xy 14.605703 -33.326649) (xy 14.582031 -33.377146)
			(xy 14.551258 -33.423659) (xy 14.514041 -33.465196) (xy 14.471173 -33.500871) (xy 14.423567 -33.529925)
			(xy 14.372238 -33.551737) (xy 14.318281 -33.565843) (xy 14.262844 -33.571943) (xy 14.20711 -33.569906)
			(xy 14.152267 -33.559776) (xy 14.099483 -33.541769) (xy 14.049883 -33.516268) (xy 14.004525 -33.483817)
			(xy 13.964376 -33.445108) (xy 13.93029 -33.400965) (xy 13.902994 -33.35233) (xy 13.883071 -33.300239)
			(xy 13.870945 -33.245802) (xy 13.866874 -33.19018) (xy 12.301982 -33.19018) (xy 12.301473 -33.218066)
			(xy 12.293353 -33.273242) (xy 12.277285 -33.326649) (xy 12.253613 -33.377146) (xy 12.22284 -33.423659)
			(xy 12.185623 -33.465196) (xy 12.142755 -33.500871) (xy 12.095149 -33.529925) (xy 12.04382 -33.551737)
			(xy 11.989863 -33.565843) (xy 11.934426 -33.571943) (xy 11.878692 -33.569906) (xy 11.823849 -33.559776)
			(xy 11.771065 -33.541769) (xy 11.721465 -33.516268) (xy 11.676107 -33.483817) (xy 11.635958 -33.445108)
			(xy 11.601872 -33.400965) (xy 11.574576 -33.35233) (xy 11.554653 -33.300239) (xy 11.542527 -33.245802)
			(xy 11.538456 -33.19018) (xy 10.029972 -33.19018) (xy 10.029972 -33.217431) (xy 10.022216 -33.271379)
			(xy 10.006861 -33.323673) (xy 9.98422 -33.37325) (xy 9.954754 -33.419101) (xy 9.919062 -33.460291)
			(xy 9.877872 -33.495982) (xy 9.832022 -33.525449) (xy 9.782445 -33.54809) (xy 9.730151 -33.563445)
			(xy 9.676203 -33.571202) (xy 9.648952 -33.571688) (xy 9.635998 -33.571688) (xy 9.617456 -33.579308)
			(xy 9.559036 -33.63722) (xy 9.552189 -33.644618) (xy 9.544456 -33.663216) (xy 9.54405 -33.673288)
			(xy 9.54405 -34.506916) (xy 9.544477 -34.516984) (xy 9.552202 -34.535579) (xy 9.559036 -34.542984)
			(xy 9.617456 -34.600896) (xy 9.635998 -34.608516) (xy 9.646412 -34.608516) (xy 9.648952 -34.608516)
			(xy 9.676203 -34.609002) (xy 9.73015 -34.616759) (xy 9.782444 -34.632114) (xy 9.83202 -34.654755)
			(xy 9.87787 -34.684221) (xy 9.919059 -34.719912) (xy 9.95475 -34.761102) (xy 9.984216 -34.806952)
			(xy 10.006857 -34.856528) (xy 10.022212 -34.908822) (xy 10.029968 -34.962769) (xy 10.029968 -34.990024)
			(xy 11.53871 -34.990024) (xy 11.542781 -34.934402) (xy 11.554907 -34.879965) (xy 11.57483 -34.827874)
			(xy 11.602126 -34.779239) (xy 11.636212 -34.735096) (xy 11.676361 -34.696387) (xy 11.721719 -34.663936)
			(xy 11.771319 -34.638435) (xy 11.824103 -34.620428) (xy 11.878946 -34.610298) (xy 11.93468 -34.608261)
			(xy 11.990117 -34.614361) (xy 12.044074 -34.628467) (xy 12.095403 -34.650279) (xy 12.143009 -34.679333)
			(xy 12.185877 -34.715008) (xy 12.223094 -34.756545) (xy 12.253867 -34.803058) (xy 12.277539 -34.853555)
			(xy 12.293607 -34.906962) (xy 12.301727 -34.962138) (xy 12.302236 -34.990024) (xy 12.93698 -34.990024)
			(xy 12.941051 -34.934402) (xy 12.953177 -34.879965) (xy 12.9731 -34.827874) (xy 13.000396 -34.779239)
			(xy 13.034482 -34.735096) (xy 13.074631 -34.696387) (xy 13.119989 -34.663936) (xy 13.169589 -34.638435)
			(xy 13.222373 -34.620428) (xy 13.277216 -34.610298) (xy 13.33295 -34.608261) (xy 13.388387 -34.614361)
			(xy 13.442344 -34.628467) (xy 13.493673 -34.650279) (xy 13.541279 -34.679333) (xy 13.584147 -34.715008)
			(xy 13.621364 -34.756545) (xy 13.652137 -34.803058) (xy 13.675809 -34.853555) (xy 13.691877 -34.906962)
			(xy 13.699997 -34.962138) (xy 13.700506 -34.990024) (xy 15.898874 -34.990024) (xy 15.902945 -34.934402)
			(xy 15.915071 -34.879965) (xy 15.934994 -34.827874) (xy 15.96229 -34.779239) (xy 15.996376 -34.735096)
			(xy 16.036525 -34.696387) (xy 16.081883 -34.663936) (xy 16.131483 -34.638435) (xy 16.184267 -34.620428)
			(xy 16.23911 -34.610298) (xy 16.294844 -34.608261) (xy 16.350281 -34.614361) (xy 16.404238 -34.628467)
			(xy 16.455567 -34.650279) (xy 16.503173 -34.679333) (xy 16.546041 -34.715008) (xy 16.583258 -34.756545)
			(xy 16.614031 -34.803058) (xy 16.637703 -34.853555) (xy 16.653771 -34.906962) (xy 16.661891 -34.962138)
			(xy 16.6624 -34.990024) (xy 16.661891 -35.01791) (xy 16.653771 -35.073086) (xy 16.637703 -35.126493)
			(xy 16.614031 -35.17699) (xy 16.583258 -35.223503) (xy 16.546041 -35.26504) (xy 16.503173 -35.300715)
			(xy 16.455567 -35.329769) (xy 16.404238 -35.351581) (xy 16.350281 -35.365687) (xy 16.294844 -35.371787)
			(xy 16.23911 -35.36975) (xy 16.184267 -35.35962) (xy 16.131483 -35.341613) (xy 16.081883 -35.316112)
			(xy 16.036525 -35.283661) (xy 15.996376 -35.244952) (xy 15.96229 -35.200809) (xy 15.934994 -35.152174)
			(xy 15.915071 -35.100083) (xy 15.902945 -35.045646) (xy 15.898874 -34.990024) (xy 13.700506 -34.990024)
			(xy 13.699997 -35.01791) (xy 13.691877 -35.073086) (xy 13.675809 -35.126493) (xy 13.652137 -35.17699)
			(xy 13.621364 -35.223503) (xy 13.584147 -35.26504) (xy 13.541279 -35.300715) (xy 13.493673 -35.329769)
			(xy 13.442344 -35.351581) (xy 13.388387 -35.365687) (xy 13.33295 -35.371787) (xy 13.277216 -35.36975)
			(xy 13.222373 -35.35962) (xy 13.169589 -35.341613) (xy 13.119989 -35.316112) (xy 13.074631 -35.283661)
			(xy 13.034482 -35.244952) (xy 13.000396 -35.200809) (xy 12.9731 -35.152174) (xy 12.953177 -35.100083)
			(xy 12.941051 -35.045646) (xy 12.93698 -34.990024) (xy 12.302236 -34.990024) (xy 12.301727 -35.01791)
			(xy 12.293607 -35.073086) (xy 12.277539 -35.126493) (xy 12.253867 -35.17699) (xy 12.223094 -35.223503)
			(xy 12.185877 -35.26504) (xy 12.143009 -35.300715) (xy 12.095403 -35.329769) (xy 12.044074 -35.351581)
			(xy 11.990117 -35.365687) (xy 11.93468 -35.371787) (xy 11.878946 -35.36975) (xy 11.824103 -35.35962)
			(xy 11.771319 -35.341613) (xy 11.721719 -35.316112) (xy 11.676361 -35.283661) (xy 11.636212 -35.244952)
			(xy 11.602126 -35.200809) (xy 11.57483 -35.152174) (xy 11.554907 -35.100083) (xy 11.542781 -35.045646)
			(xy 11.53871 -34.990024) (xy 10.029968 -34.990024) (xy 10.029968 -35.017271) (xy 10.022212 -35.071218)
			(xy 10.006857 -35.123512) (xy 9.984216 -35.173088) (xy 9.95475 -35.218938) (xy 9.919059 -35.260128)
			(xy 9.87787 -35.295819) (xy 9.83202 -35.325285) (xy 9.782444 -35.347926) (xy 9.73015 -35.363281)
			(xy 9.676203 -35.371038) (xy 9.648952 -35.371532) (xy 9.635998 -35.371532) (xy 9.617456 -35.379152)
			(xy 9.559036 -35.437064) (xy 9.552196 -35.444464) (xy 9.544479 -35.463063) (xy 9.54405 -35.473132)
			(xy 9.54405 -38.193479) (xy 11.098251 -38.193479) (xy 11.098251 -38.106601) (xy 11.106267 -38.020094)
			(xy 11.122231 -37.934695) (xy 11.146006 -37.851134) (xy 11.17739 -37.770122) (xy 11.216115 -37.692352)
			(xy 11.26185 -37.618487) (xy 11.314206 -37.549157) (xy 11.372735 -37.484954) (xy 11.436939 -37.426425)
			(xy 11.506269 -37.374069) (xy 11.580134 -37.328334) (xy 11.657904 -37.289609) (xy 11.738915 -37.258225)
			(xy 11.822477 -37.23445) (xy 11.907876 -37.218486) (xy 11.994383 -37.210471) (xy 12.037822 -37.209984)
			(xy 12.1158 -37.209984) (xy 12.125823 -37.20958) (xy 12.144343 -37.201907) (xy 12.158516 -37.18773)
			(xy 12.166183 -37.169207) (xy 12.1666 -37.159184) (xy 12.1666 -37.151564) (xy 12.162282 -37.137594)
			(xy 12.158218 -37.131244) (xy 12.134299 -37.094009) (xy 12.092598 -37.015944) (xy 12.058213 -36.93439)
			(xy 12.031435 -36.850033) (xy 12.012486 -36.76358) (xy 12.001526 -36.675755) (xy 11.998648 -36.587297)
			(xy 12.003875 -36.498946) (xy 12.017163 -36.411443) (xy 12.038401 -36.325524) (xy 12.06741 -36.241908)
			(xy 12.103948 -36.161296) (xy 12.147709 -36.084366) (xy 12.198323 -36.011762) (xy 12.255369 -35.944093)
			(xy 12.318366 -35.881927) (xy 12.386786 -35.825786) (xy 12.460056 -35.776139) (xy 12.537561 -35.733405)
			(xy 12.61865 -35.69794) (xy 12.702644 -35.670044) (xy 12.788838 -35.649948) (xy 12.876509 -35.637824)
			(xy 12.964922 -35.633771) (xy 13.053335 -35.637824) (xy 13.141006 -35.649948) (xy 13.2272 -35.670044)
			(xy 13.311194 -35.69794) (xy 13.392283 -35.733405) (xy 13.469788 -35.776139) (xy 13.543058 -35.825786)
			(xy 13.605154 -35.876738) (xy 18.717258 -35.876738) (xy 18.721329 -35.821116) (xy 18.733455 -35.766679)
			(xy 18.753378 -35.714588) (xy 18.780674 -35.665953) (xy 18.81476 -35.62181) (xy 18.854909 -35.583101)
			(xy 18.900267 -35.55065) (xy 18.949867 -35.525149) (xy 19.002651 -35.507142) (xy 19.057494 -35.497012)
			(xy 19.113228 -35.494975) (xy 19.168665 -35.501075) (xy 19.222622 -35.515181) (xy 19.273951 -35.536993)
			(xy 19.321557 -35.566047) (xy 19.364425 -35.601722) (xy 19.401642 -35.643259) (xy 19.432415 -35.689772)
			(xy 19.456087 -35.740269) (xy 19.472155 -35.793676) (xy 19.480275 -35.848852) (xy 19.480784 -35.876738)
			(xy 19.480275 -35.904624) (xy 19.472155 -35.9598) (xy 19.456087 -36.013207) (xy 19.432415 -36.063704)
			(xy 19.401642 -36.110217) (xy 19.364425 -36.151754) (xy 19.321557 -36.187429) (xy 19.273951 -36.216483)
			(xy 19.222622 -36.238295) (xy 19.168665 -36.252401) (xy 19.113228 -36.258501) (xy 19.057494 -36.256464)
			(xy 19.002651 -36.246334) (xy 18.949867 -36.228327) (xy 18.900267 -36.202826) (xy 18.854909 -36.170375)
			(xy 18.81476 -36.131666) (xy 18.780674 -36.087523) (xy 18.753378 -36.038888) (xy 18.733455 -35.986797)
			(xy 18.721329 -35.93236) (xy 18.717258 -35.876738) (xy 13.605154 -35.876738) (xy 13.611478 -35.881927)
			(xy 13.674475 -35.944093) (xy 13.731521 -36.011762) (xy 13.782135 -36.084366) (xy 13.825896 -36.161296)
			(xy 13.862434 -36.241908) (xy 13.891443 -36.325524) (xy 13.912681 -36.411443) (xy 13.925969 -36.498946)
			(xy 13.928394 -36.539928) (xy 20.538676 -36.539928) (xy 20.538676 -36.479992) (xy 20.546499 -36.42057)
			(xy 20.562012 -36.362677) (xy 20.584948 -36.307304) (xy 20.614915 -36.255398) (xy 20.651402 -36.207848)
			(xy 20.693782 -36.165468) (xy 20.741332 -36.128981) (xy 20.793238 -36.099014) (xy 20.848611 -36.076078)
			(xy 20.906504 -36.060565) (xy 20.965926 -36.052742) (xy 21.025862 -36.052742) (xy 21.085284 -36.060565)
			(xy 21.143177 -36.076078) (xy 21.19855 -36.099014) (xy 21.250456 -36.128981) (xy 21.298006 -36.165468)
			(xy 21.340386 -36.207848) (xy 21.376873 -36.255398) (xy 21.40684 -36.307304) (xy 21.429776 -36.362677)
			(xy 21.445289 -36.42057) (xy 21.453112 -36.479992) (xy 21.453602 -36.50996) (xy 21.453112 -36.539928)
			(xy 21.445289 -36.59935) (xy 21.429776 -36.657243) (xy 21.40684 -36.712616) (xy 21.376873 -36.764522)
			(xy 21.340386 -36.812072) (xy 21.298006 -36.854452) (xy 21.250456 -36.890939) (xy 21.19855 -36.920906)
			(xy 21.143177 -36.943842) (xy 21.085284 -36.959355) (xy 21.025862 -36.967178) (xy 20.965926 -36.967178)
			(xy 20.906504 -36.959355) (xy 20.848611 -36.943842) (xy 20.793238 -36.920906) (xy 20.741332 -36.890939)
			(xy 20.693782 -36.854452) (xy 20.651402 -36.812072) (xy 20.614915 -36.764522) (xy 20.584948 -36.712616)
			(xy 20.562012 -36.657243) (xy 20.546499 -36.59935) (xy 20.538676 -36.539928) (xy 13.928394 -36.539928)
			(xy 13.931196 -36.587297) (xy 13.928318 -36.675755) (xy 13.917358 -36.76358) (xy 13.898409 -36.850033)
			(xy 13.871631 -36.93439) (xy 13.837246 -37.015944) (xy 13.795545 -37.094009) (xy 13.771626 -37.131244)
			(xy 13.763244 -37.143944) (xy 13.763244 -37.159184) (xy 13.763634 -37.16921) (xy 13.771306 -37.187735)
			(xy 13.785489 -37.201909) (xy 13.804018 -37.209572) (xy 13.814044 -37.209984) (xy 13.892022 -37.209984)
			(xy 13.93546 -37.21049) (xy 14.021965 -37.218506) (xy 14.107362 -37.234469) (xy 14.190921 -37.258244)
			(xy 14.271931 -37.289628) (xy 14.349699 -37.328352) (xy 14.423562 -37.374086) (xy 14.492891 -37.426441)
			(xy 14.546333 -37.47516) (xy 17.75917 -37.47516) (xy 17.763241 -37.419538) (xy 17.775367 -37.365101)
			(xy 17.79529 -37.31301) (xy 17.822586 -37.264375) (xy 17.856672 -37.220232) (xy 17.896821 -37.181523)
			(xy 17.942179 -37.149072) (xy 17.991779 -37.123571) (xy 18.044563 -37.105564) (xy 18.099406 -37.095434)
			(xy 18.15514 -37.093397) (xy 18.210577 -37.099497) (xy 18.264534 -37.113603) (xy 18.315863 -37.135415)
			(xy 18.363469 -37.164469) (xy 18.406337 -37.200144) (xy 18.443554 -37.241681) (xy 18.474327 -37.288194)
			(xy 18.497999 -37.338691) (xy 18.514067 -37.392098) (xy 18.522187 -37.447274) (xy 18.522696 -37.47516)
			(xy 18.522187 -37.503046) (xy 18.514067 -37.558222) (xy 18.497999 -37.611629) (xy 18.474327 -37.662126)
			(xy 18.454347 -37.692326) (xy 19.873196 -37.692326) (xy 19.873196 -37.63239) (xy 19.881019 -37.572968)
			(xy 19.896532 -37.515075) (xy 19.919468 -37.459702) (xy 19.949435 -37.407796) (xy 19.985922 -37.360246)
			(xy 20.028302 -37.317866) (xy 20.075852 -37.281379) (xy 20.127758 -37.251412) (xy 20.183131 -37.228476)
			(xy 20.241024 -37.212963) (xy 20.300446 -37.20514) (xy 20.360382 -37.20514) (xy 20.419804 -37.212963)
			(xy 20.477697 -37.228476) (xy 20.53307 -37.251412) (xy 20.584976 -37.281379) (xy 20.632526 -37.317866)
			(xy 20.674906 -37.360246) (xy 20.711393 -37.407796) (xy 20.74136 -37.459702) (xy 20.764296 -37.515075)
			(xy 20.779809 -37.572968) (xy 20.787632 -37.63239) (xy 20.788122 -37.662358) (xy 20.787632 -37.692326)
			(xy 20.779809 -37.751748) (xy 20.764296 -37.809641) (xy 20.74136 -37.865014) (xy 20.711393 -37.91692)
			(xy 20.674906 -37.96447) (xy 20.632526 -38.00685) (xy 20.584976 -38.043337) (xy 20.53307 -38.073304)
			(xy 20.477697 -38.09624) (xy 20.419804 -38.111753) (xy 20.360382 -38.119576) (xy 20.300446 -38.119576)
			(xy 20.241024 -38.111753) (xy 20.183131 -38.09624) (xy 20.127758 -38.073304) (xy 20.075852 -38.043337)
			(xy 20.028302 -38.00685) (xy 19.985922 -37.96447) (xy 19.949435 -37.91692) (xy 19.919468 -37.865014)
			(xy 19.896532 -37.809641) (xy 19.881019 -37.751748) (xy 19.873196 -37.692326) (xy 18.454347 -37.692326)
			(xy 18.443554 -37.708639) (xy 18.406337 -37.750176) (xy 18.363469 -37.785851) (xy 18.315863 -37.814905)
			(xy 18.264534 -37.836717) (xy 18.210577 -37.850823) (xy 18.15514 -37.856923) (xy 18.099406 -37.854886)
			(xy 18.044563 -37.844756) (xy 17.991779 -37.826749) (xy 17.942179 -37.801248) (xy 17.896821 -37.768797)
			(xy 17.856672 -37.730088) (xy 17.822586 -37.685945) (xy 17.79529 -37.63731) (xy 17.775367 -37.585219)
			(xy 17.763241 -37.530782) (xy 17.75917 -37.47516) (xy 14.546333 -37.47516) (xy 14.557093 -37.484969)
			(xy 14.615621 -37.549171) (xy 14.667975 -37.618499) (xy 14.713709 -37.692363) (xy 14.752433 -37.770131)
			(xy 14.783816 -37.85114) (xy 14.807591 -37.9347) (xy 14.823555 -38.020097) (xy 14.83157 -38.106602)
			(xy 14.83157 -38.193478) (xy 14.823555 -38.279983) (xy 14.807591 -38.36538) (xy 14.783816 -38.44894)
			(xy 14.76746 -38.49116) (xy 17.75917 -38.49116) (xy 17.763241 -38.435538) (xy 17.775367 -38.381101)
			(xy 17.79529 -38.32901) (xy 17.822586 -38.280375) (xy 17.856672 -38.236232) (xy 17.896821 -38.197523)
			(xy 17.942179 -38.165072) (xy 17.991779 -38.139571) (xy 18.044563 -38.121564) (xy 18.099406 -38.111434)
			(xy 18.15514 -38.109397) (xy 18.210577 -38.115497) (xy 18.264534 -38.129603) (xy 18.315863 -38.151415)
			(xy 18.363469 -38.180469) (xy 18.406337 -38.216144) (xy 18.443554 -38.257681) (xy 18.474327 -38.304194)
			(xy 18.497999 -38.354691) (xy 18.514067 -38.408098) (xy 18.522187 -38.463274) (xy 18.522696 -38.49116)
			(xy 18.522187 -38.519046) (xy 18.514067 -38.574222) (xy 18.497999 -38.627629) (xy 18.474327 -38.678126)
			(xy 18.459049 -38.701218) (xy 21.437598 -38.701218) (xy 21.441669 -38.645596) (xy 21.453795 -38.591159)
			(xy 21.473718 -38.539068) (xy 21.501014 -38.490433) (xy 21.5351 -38.44629) (xy 21.575249 -38.407581)
			(xy 21.620607 -38.37513) (xy 21.670207 -38.349629) (xy 21.722991 -38.331622) (xy 21.777834 -38.321492)
			(xy 21.833568 -38.319455) (xy 21.889005 -38.325555) (xy 21.942962 -38.339661) (xy 21.994291 -38.361473)
			(xy 22.041897 -38.390527) (xy 22.084765 -38.426202) (xy 22.121982 -38.467739) (xy 22.152755 -38.514252)
			(xy 22.176427 -38.564749) (xy 22.192495 -38.618156) (xy 22.200615 -38.673332) (xy 22.201124 -38.701218)
			(xy 22.200615 -38.729104) (xy 22.192495 -38.78428) (xy 22.176427 -38.837687) (xy 22.152755 -38.888184)
			(xy 22.121982 -38.934697) (xy 22.084765 -38.976234) (xy 22.041897 -39.011909) (xy 21.994291 -39.040963)
			(xy 21.942962 -39.062775) (xy 21.889005 -39.076881) (xy 21.833568 -39.082981) (xy 21.777834 -39.080944)
			(xy 21.722991 -39.070814) (xy 21.670207 -39.052807) (xy 21.620607 -39.027306) (xy 21.575249 -38.994855)
			(xy 21.5351 -38.956146) (xy 21.501014 -38.912003) (xy 21.473718 -38.863368) (xy 21.453795 -38.811277)
			(xy 21.441669 -38.75684) (xy 21.437598 -38.701218) (xy 18.459049 -38.701218) (xy 18.443554 -38.724639)
			(xy 18.406337 -38.766176) (xy 18.363469 -38.801851) (xy 18.315863 -38.830905) (xy 18.264534 -38.852717)
			(xy 18.210577 -38.866823) (xy 18.15514 -38.872923) (xy 18.099406 -38.870886) (xy 18.044563 -38.860756)
			(xy 17.991779 -38.842749) (xy 17.942179 -38.817248) (xy 17.896821 -38.784797) (xy 17.856672 -38.746088)
			(xy 17.822586 -38.701945) (xy 17.79529 -38.65331) (xy 17.775367 -38.601219) (xy 17.763241 -38.546782)
			(xy 17.75917 -38.49116) (xy 14.76746 -38.49116) (xy 14.752433 -38.529949) (xy 14.713709 -38.607717)
			(xy 14.667975 -38.681581) (xy 14.615621 -38.750909) (xy 14.557093 -38.815111) (xy 14.492891 -38.873639)
			(xy 14.423562 -38.925994) (xy 14.349699 -38.971728) (xy 14.271931 -39.010452) (xy 14.190921 -39.041836)
			(xy 14.107362 -39.065611) (xy 14.021965 -39.081574) (xy 13.93546 -39.08959) (xy 13.892022 -39.090092)
			(xy 12.037822 -39.090092) (xy 11.994383 -39.089609) (xy 11.907876 -39.081594) (xy 11.822477 -39.06563)
			(xy 11.738915 -39.041855) (xy 11.657904 -39.010471) (xy 11.580134 -38.971746) (xy 11.506269 -38.926011)
			(xy 11.436939 -38.873655) (xy 11.372735 -38.815126) (xy 11.314206 -38.750923) (xy 11.26185 -38.681593)
			(xy 11.216115 -38.607728) (xy 11.17739 -38.529958) (xy 11.146006 -38.448946) (xy 11.122231 -38.365385)
			(xy 11.106267 -38.279986) (xy 11.098251 -38.193479) (xy 9.54405 -38.193479) (xy 9.54405 -41.469056)
			(xy 11.297918 -41.469056) (xy 11.301989 -41.413434) (xy 11.314115 -41.358997) (xy 11.334038 -41.306906)
			(xy 11.361334 -41.258271) (xy 11.39542 -41.214128) (xy 11.435569 -41.175419) (xy 11.480927 -41.142968)
			(xy 11.530527 -41.117467) (xy 11.583311 -41.09946) (xy 11.638154 -41.08933) (xy 11.693888 -41.087293)
			(xy 11.749325 -41.093393) (xy 11.803282 -41.107499) (xy 11.854611 -41.129311) (xy 11.902217 -41.158365)
			(xy 11.945085 -41.19404) (xy 11.982302 -41.235577) (xy 12.013075 -41.28209) (xy 12.036747 -41.332587)
			(xy 12.052815 -41.385994) (xy 12.060935 -41.44117) (xy 12.061444 -41.469056) (xy 12.060935 -41.496942)
			(xy 12.052815 -41.552118) (xy 12.036747 -41.605525) (xy 12.013075 -41.656022) (xy 11.982302 -41.702535)
			(xy 11.945085 -41.744072) (xy 11.902217 -41.779747) (xy 11.854611 -41.808801) (xy 11.803282 -41.830613)
			(xy 11.749325 -41.844719) (xy 11.693888 -41.850819) (xy 11.638154 -41.848782) (xy 11.583311 -41.838652)
			(xy 11.530527 -41.820645) (xy 11.480927 -41.795144) (xy 11.435569 -41.762693) (xy 11.39542 -41.723984)
			(xy 11.361334 -41.679841) (xy 11.334038 -41.631206) (xy 11.314115 -41.579115) (xy 11.301989 -41.524678)
			(xy 11.297918 -41.469056) (xy 9.54405 -41.469056) (xy 9.54405 -42.849038) (xy 20.892006 -42.849038)
			(xy 20.896077 -42.793416) (xy 20.908203 -42.738979) (xy 20.928126 -42.686888) (xy 20.955422 -42.638253)
			(xy 20.989508 -42.59411) (xy 21.029657 -42.555401) (xy 21.075015 -42.52295) (xy 21.124615 -42.497449)
			(xy 21.177399 -42.479442) (xy 21.232242 -42.469312) (xy 21.287976 -42.467275) (xy 21.343413 -42.473375)
			(xy 21.39737 -42.487481) (xy 21.448699 -42.509293) (xy 21.496305 -42.538347) (xy 21.539173 -42.574022)
			(xy 21.57639 -42.615559) (xy 21.607163 -42.662072) (xy 21.630835 -42.712569) (xy 21.646903 -42.765976)
			(xy 21.655023 -42.821152) (xy 21.655532 -42.849038) (xy 21.655023 -42.876924) (xy 21.646903 -42.9321)
			(xy 21.630835 -42.985507) (xy 21.607163 -43.036004) (xy 21.57639 -43.082517) (xy 21.539173 -43.124054)
			(xy 21.496305 -43.159729) (xy 21.448699 -43.188783) (xy 21.39737 -43.210595) (xy 21.343413 -43.224701)
			(xy 21.287976 -43.230801) (xy 21.232242 -43.228764) (xy 21.177399 -43.218634) (xy 21.124615 -43.200627)
			(xy 21.075015 -43.175126) (xy 21.029657 -43.142675) (xy 20.989508 -43.103966) (xy 20.955422 -43.059823)
			(xy 20.928126 -43.011188) (xy 20.908203 -42.959097) (xy 20.896077 -42.90466) (xy 20.892006 -42.849038)
			(xy 9.54405 -42.849038) (xy 9.54405 -43.719242) (xy 9.544482 -43.729308) (xy 9.552213 -43.747896)
			(xy 9.559036 -43.75531) (xy 10.03681 -44.233084) (xy 10.044208 -44.23993) (xy 10.062806 -44.247664)
			(xy 10.072878 -44.24807)
		)
		(stroke
			(width 0)
			(type solid)
		)
		(fill yes)
		(layer "B.Cu")
		(net "P12V_SSD0")
	)
	(gr_poly
		(pts
			(xy 138.577066 -44.37634) (xy 138.58694 -44.375872) (xy 138.60523 -44.368421) (xy 138.612626 -44.361862)
			(xy 138.61288 -44.361608) (xy 139.172188 -43.8023) (xy 139.172696 -43.801792) (xy 139.179281 -43.794411)
			(xy 139.186741 -43.776113) (xy 139.187174 -43.766232) (xy 139.187174 -36.349686) (xy 139.1666 -36.322762)
			(xy 139.149836 -36.31819) (xy 139.121191 -36.30983) (xy 139.066187 -36.286695) (xy 139.014655 -36.256609)
			(xy 138.967468 -36.220084) (xy 138.925427 -36.177737) (xy 138.889244 -36.130287) (xy 138.859533 -36.078538)
			(xy 138.836797 -36.023368) (xy 138.821421 -35.965711) (xy 138.813667 -35.906546) (xy 138.813666 -35.846874)
			(xy 138.821417 -35.787708) (xy 138.83679 -35.730051) (xy 138.859524 -35.67488) (xy 138.889233 -35.62313)
			(xy 138.925414 -35.575678) (xy 138.967453 -35.53333) (xy 139.014638 -35.496802) (xy 139.066169 -35.466714)
			(xy 139.121172 -35.443577) (xy 139.149836 -35.435286) (xy 139.1666 -35.430714) (xy 139.187174 -35.40379)
			(xy 139.187174 -26.653236) (xy 139.187013 -26.64786) (xy 139.184709 -26.637356) (xy 139.182602 -26.632408)
			(xy 139.17041 -26.604722) (xy 139.16279 -26.597864) (xy 139.14418 -26.579743) (xy 139.111536 -26.53934)
			(xy 139.084666 -26.494887) (xy 139.064067 -26.447203) (xy 139.050117 -26.397169) (xy 139.043076 -26.345705)
			(xy 139.042648 -26.319734) (xy 139.043211 -26.290084) (xy 139.052374 -26.231497) (xy 139.07047 -26.175025)
			(xy 139.083288 -26.148284) (xy 139.088622 -26.137616) (xy 139.08913 -26.114756) (xy 139.050776 -26.031698)
			(xy 139.045378 -26.021595) (xy 139.027704 -26.007071) (xy 139.01674 -26.003758) (xy 139.016486 -26.003758)
			(xy 138.986913 -25.996102) (xy 138.929962 -25.974003) (xy 138.876457 -25.944523) (xy 138.827351 -25.908187)
			(xy 138.783515 -25.865641) (xy 138.745729 -25.81764) (xy 138.714666 -25.765039) (xy 138.690878 -25.708773)
			(xy 138.674786 -25.649842) (xy 138.666679 -25.589294) (xy 138.66622 -25.55875) (xy 138.666756 -25.527479)
			(xy 138.675278 -25.46552) (xy 138.692155 -25.405299) (xy 138.717074 -25.347935) (xy 138.749571 -25.294499)
			(xy 138.789039 -25.245984) (xy 138.834746 -25.203294) (xy 138.885839 -25.167224) (xy 138.941366 -25.138446)
			(xy 139.000295 -25.117495) (xy 139.061527 -25.104763) (xy 139.092686 -25.102058) (xy 139.102338 -25.101296)
			(xy 139.11961 -25.093168) (xy 139.173458 -25.03551) (xy 139.175998 -25.032462) (xy 139.181115 -25.025539)
			(xy 139.18683 -25.009313) (xy 139.187174 -25.000712) (xy 139.187174 -19.808444) (xy 139.186721 -19.798604)
			(xy 139.179296 -19.78038) (xy 139.165531 -19.766316) (xy 139.156694 -19.761962) (xy 139.057634 -19.718528)
			(xy 139.027916 -19.723608) (xy 139.01674 -19.733768) (xy 138.995501 -19.75262) (xy 138.948487 -19.784469)
			(xy 138.897267 -19.808992) (xy 138.842976 -19.825644) (xy 138.786816 -19.834057) (xy 138.758422 -19.834606)
			(xy 138.73165 -19.834155) (xy 138.678631 -19.826667) (xy 138.627182 -19.811835) (xy 138.578313 -19.789952)
			(xy 138.532987 -19.761447) (xy 138.492094 -19.726882) (xy 138.456439 -19.686935) (xy 138.441176 -19.664934)
			(xy 138.43508 -19.656044) (xy 138.417554 -19.644614) (xy 138.33348 -19.631152) (xy 138.32312 -19.629988)
			(xy 138.302936 -19.635121) (xy 138.294364 -19.641058) (xy 138.274207 -19.656167) (xy 138.230676 -19.681519)
			(xy 138.18419 -19.70093) (xy 138.135556 -19.714062) (xy 138.085618 -19.720687) (xy 138.06043 -19.721068)
			(xy 138.05281 -19.721068) (xy 138.025916 -19.720071) (xy 137.972795 -19.711448) (xy 137.921413 -19.695444)
			(xy 137.87279 -19.672376) (xy 137.827893 -19.642704) (xy 137.787612 -19.607015) (xy 137.752747 -19.566019)
			(xy 137.72399 -19.52053) (xy 137.701913 -19.47145) (xy 137.686953 -19.419754) (xy 137.679409 -19.366469)
			(xy 137.678922 -19.33956) (xy 137.679411 -19.312311) (xy 137.687172 -19.25837) (xy 137.702531 -19.206082)
			(xy 137.725175 -19.156511) (xy 137.754643 -19.110668) (xy 137.790335 -19.069485) (xy 137.831524 -19.033801)
			(xy 137.877373 -19.004341) (xy 137.926947 -18.981707) (xy 137.979238 -18.966357) (xy 138.033181 -18.958606)
			(xy 138.06043 -18.958052) (xy 138.087204 -18.9585) (xy 138.140228 -18.965981) (xy 138.191683 -18.980807)
			(xy 138.240558 -19.002685) (xy 138.285892 -19.031185) (xy 138.326793 -19.065747) (xy 138.362457 -19.105691)
			(xy 138.377676 -19.127724) (xy 138.383772 -19.136614) (xy 138.401298 -19.148044) (xy 138.495786 -19.163284)
			(xy 138.516106 -19.158204) (xy 138.524488 -19.1516) (xy 138.547714 -19.134259) (xy 138.598356 -19.106067)
			(xy 138.652684 -19.085871) (xy 138.680952 -19.079464) (xy 138.694668 -19.07667) (xy 138.715242 -19.057874)
			(xy 138.74496 -18.95856) (xy 138.747192 -18.949726) (xy 138.745944 -18.931562) (xy 138.738418 -18.914983)
			(xy 138.73226 -18.908268) (xy 138.626342 -18.80235) (xy 138.616436 -18.798286) (xy 138.592739 -18.788332)
			(xy 138.548032 -18.762973) (xy 138.507134 -18.731839) (xy 138.470788 -18.695497) (xy 138.43965 -18.654603)
			(xy 138.414286 -18.609899) (xy 138.404346 -18.586196) (xy 138.400282 -18.57629) (xy 138.367516 -18.543524)
			(xy 138.360404 -18.536158) (xy 138.341608 -18.528538) (xy 126.628906 -18.528538) (xy 126.618836 -18.528961)
			(xy 126.600234 -18.536678) (xy 126.592838 -18.543524) (xy 126.258574 -18.877788) (xy 126.251208 -18.8849)
			(xy 126.243588 -18.903696) (xy 126.243588 -21.738336) (xy 127.51689 -21.738336) (xy 127.517377 -21.709596)
			(xy 127.526009 -21.652767) (xy 127.543068 -21.597876) (xy 127.568168 -21.546165) (xy 127.60074 -21.498804)
			(xy 127.620014 -21.477478) (xy 127.626618 -21.470366) (xy 127.63373 -21.45284) (xy 127.63373 -21.363432)
			(xy 127.626618 -21.345906) (xy 127.620014 -21.338794) (xy 127.600779 -21.317436) (xy 127.568214 -21.270079)
			(xy 127.543121 -21.218372) (xy 127.526069 -21.163486) (xy 127.517443 -21.106663) (xy 127.517439 -21.049189)
			(xy 127.526057 -20.992365) (xy 127.543102 -20.937477) (xy 127.568187 -20.885767) (xy 127.600746 -20.838405)
			(xy 127.620014 -20.817078) (xy 127.626618 -20.809966) (xy 127.63373 -20.79244) (xy 127.63373 -20.703032)
			(xy 127.626618 -20.685506) (xy 127.620014 -20.678394) (xy 127.600779 -20.657036) (xy 127.568214 -20.609679)
			(xy 127.543121 -20.557972) (xy 127.526069 -20.503086) (xy 127.517443 -20.446263) (xy 127.517439 -20.388789)
			(xy 127.526057 -20.331965) (xy 127.543102 -20.277077) (xy 127.568187 -20.225367) (xy 127.600746 -20.178005)
			(xy 127.620014 -20.156678) (xy 127.626618 -20.149566) (xy 127.63373 -20.13204) (xy 127.63373 -20.042632)
			(xy 127.626618 -20.025106) (xy 127.620014 -20.017994) (xy 127.600779 -19.996636) (xy 127.568214 -19.949279)
			(xy 127.543121 -19.897572) (xy 127.526069 -19.842686) (xy 127.517443 -19.785863) (xy 127.517439 -19.728389)
			(xy 127.526057 -19.671565) (xy 127.543102 -19.616677) (xy 127.568187 -19.564967) (xy 127.600746 -19.517605)
			(xy 127.620014 -19.496278) (xy 127.626618 -19.489166) (xy 127.63373 -19.47164) (xy 127.63373 -19.382232)
			(xy 127.626618 -19.364706) (xy 127.620014 -19.357594) (xy 127.600756 -19.336256) (xy 127.568189 -19.288896)
			(xy 127.543095 -19.237188) (xy 127.526041 -19.182299) (xy 127.517414 -19.125474) (xy 127.51689 -19.096736)
			(xy 127.517376 -19.069485) (xy 127.525132 -19.015537) (xy 127.540487 -18.963242) (xy 127.563129 -18.913665)
			(xy 127.592595 -18.867815) (xy 127.628286 -18.826624) (xy 127.669477 -18.790933) (xy 127.715327 -18.761467)
			(xy 127.764904 -18.738825) (xy 127.817199 -18.72347) (xy 127.871147 -18.715714) (xy 127.925649 -18.715714)
			(xy 127.979597 -18.72347) (xy 128.031892 -18.738825) (xy 128.081469 -18.761467) (xy 128.127319 -18.790933)
			(xy 128.16851 -18.826624) (xy 128.204201 -18.867815) (xy 128.233667 -18.913665) (xy 128.256309 -18.963242)
			(xy 128.271664 -19.015537) (xy 128.27942 -19.069485) (xy 128.279906 -19.096736) (xy 128.279403 -19.125476)
			(xy 128.270775 -19.182304) (xy 128.25372 -19.237195) (xy 128.228624 -19.288906) (xy 128.196055 -19.336268)
			(xy 128.176782 -19.357594) (xy 128.170178 -19.364706) (xy 128.163066 -19.382232) (xy 128.163066 -19.47164)
			(xy 128.170178 -19.489166) (xy 128.176782 -19.496278) (xy 128.196088 -19.517574) (xy 128.228652 -19.564942)
			(xy 128.253741 -19.616659) (xy 128.270788 -19.671554) (xy 128.279407 -19.728386) (xy 128.279403 -19.785867)
			(xy 128.270776 -19.842697) (xy 128.253722 -19.89759) (xy 128.228625 -19.949304) (xy 128.196055 -19.996667)
			(xy 128.176782 -20.017994) (xy 128.170178 -20.025106) (xy 128.163066 -20.042632) (xy 128.163066 -20.13204)
			(xy 128.170178 -20.149566) (xy 128.176782 -20.156678) (xy 128.196088 -20.177974) (xy 128.228652 -20.225342)
			(xy 128.253741 -20.277059) (xy 128.270788 -20.331954) (xy 128.274368 -20.35556) (xy 137.678412 -20.35556)
			(xy 137.682483 -20.299938) (xy 137.694609 -20.245501) (xy 137.714532 -20.19341) (xy 137.741828 -20.144775)
			(xy 137.775914 -20.100632) (xy 137.816063 -20.061923) (xy 137.861421 -20.029472) (xy 137.911021 -20.003971)
			(xy 137.963805 -19.985964) (xy 138.018648 -19.975834) (xy 138.074382 -19.973797) (xy 138.129819 -19.979897)
			(xy 138.183776 -19.994003) (xy 138.235105 -20.015815) (xy 138.282711 -20.044869) (xy 138.325579 -20.080544)
			(xy 138.362796 -20.122081) (xy 138.393569 -20.168594) (xy 138.417241 -20.219091) (xy 138.433309 -20.272498)
			(xy 138.441429 -20.327674) (xy 138.441938 -20.35556) (xy 138.441429 -20.383446) (xy 138.433309 -20.438622)
			(xy 138.417241 -20.492029) (xy 138.393569 -20.542526) (xy 138.362796 -20.589039) (xy 138.325579 -20.630576)
			(xy 138.282711 -20.666251) (xy 138.235105 -20.695305) (xy 138.183776 -20.717117) (xy 138.129819 -20.731223)
			(xy 138.074382 -20.737323) (xy 138.018648 -20.735286) (xy 137.963805 -20.725156) (xy 137.911021 -20.707149)
			(xy 137.861421 -20.681648) (xy 137.816063 -20.649197) (xy 137.775914 -20.610488) (xy 137.741828 -20.566345)
			(xy 137.714532 -20.51771) (xy 137.694609 -20.465619) (xy 137.682483 -20.411182) (xy 137.678412 -20.35556)
			(xy 128.274368 -20.35556) (xy 128.279407 -20.388786) (xy 128.279403 -20.446267) (xy 128.270776 -20.503097)
			(xy 128.253722 -20.55799) (xy 128.228625 -20.609704) (xy 128.196055 -20.657067) (xy 128.176782 -20.678394)
			(xy 128.170178 -20.685506) (xy 128.163066 -20.703032) (xy 128.163066 -20.79244) (xy 128.170178 -20.809966)
			(xy 128.176782 -20.817078) (xy 128.196088 -20.838374) (xy 128.228652 -20.885742) (xy 128.253741 -20.937459)
			(xy 128.270788 -20.992354) (xy 128.279407 -21.049186) (xy 128.279403 -21.106667) (xy 128.270776 -21.163497)
			(xy 128.253722 -21.21839) (xy 128.228625 -21.270104) (xy 128.196055 -21.317467) (xy 128.176782 -21.338794)
			(xy 128.170178 -21.345906) (xy 128.163066 -21.363432) (xy 128.163066 -21.37156) (xy 137.678412 -21.37156)
			(xy 137.682483 -21.315938) (xy 137.694609 -21.261501) (xy 137.714532 -21.20941) (xy 137.741828 -21.160775)
			(xy 137.775914 -21.116632) (xy 137.816063 -21.077923) (xy 137.861421 -21.045472) (xy 137.911021 -21.019971)
			(xy 137.963805 -21.001964) (xy 138.018648 -20.991834) (xy 138.074382 -20.989797) (xy 138.129819 -20.995897)
			(xy 138.183776 -21.010003) (xy 138.235105 -21.031815) (xy 138.282711 -21.060869) (xy 138.325579 -21.096544)
			(xy 138.362796 -21.138081) (xy 138.393569 -21.184594) (xy 138.417241 -21.235091) (xy 138.433309 -21.288498)
			(xy 138.441429 -21.343674) (xy 138.441938 -21.37156) (xy 138.441429 -21.399446) (xy 138.433309 -21.454622)
			(xy 138.417241 -21.508029) (xy 138.393569 -21.558526) (xy 138.362796 -21.605039) (xy 138.325579 -21.646576)
			(xy 138.282711 -21.682251) (xy 138.235105 -21.711305) (xy 138.183776 -21.733117) (xy 138.129819 -21.747223)
			(xy 138.074382 -21.753323) (xy 138.018648 -21.751286) (xy 137.963805 -21.741156) (xy 137.911021 -21.723149)
			(xy 137.861421 -21.697648) (xy 137.816063 -21.665197) (xy 137.775914 -21.626488) (xy 137.741828 -21.582345)
			(xy 137.714532 -21.53371) (xy 137.694609 -21.481619) (xy 137.682483 -21.427182) (xy 137.678412 -21.37156)
			(xy 128.163066 -21.37156) (xy 128.163066 -21.45284) (xy 128.170178 -21.470366) (xy 128.176782 -21.477478)
			(xy 128.196073 -21.498787) (xy 128.228636 -21.546155) (xy 128.253724 -21.597871) (xy 128.27077 -21.652765)
			(xy 128.279388 -21.709596) (xy 128.279906 -21.738336) (xy 128.27942 -21.765587) (xy 128.271664 -21.819535)
			(xy 128.256309 -21.87183) (xy 128.233667 -21.921407) (xy 128.204201 -21.967257) (xy 128.16851 -22.008448)
			(xy 128.127319 -22.044139) (xy 128.081469 -22.073605) (xy 128.031892 -22.096247) (xy 127.979597 -22.111602)
			(xy 127.925649 -22.119358) (xy 127.871147 -22.119358) (xy 127.817199 -22.111602) (xy 127.764904 -22.096247)
			(xy 127.715327 -22.073605) (xy 127.669477 -22.044139) (xy 127.628286 -22.008448) (xy 127.592595 -21.967257)
			(xy 127.563129 -21.921407) (xy 127.540487 -21.87183) (xy 127.525132 -21.819535) (xy 127.517376 -21.765587)
			(xy 127.51689 -21.738336) (xy 126.243588 -21.738336) (xy 126.243588 -23.05503) (xy 127.38743 -23.05503)
			(xy 127.387434 -22.995103) (xy 127.39526 -22.935689) (xy 127.410775 -22.877805) (xy 127.433711 -22.82244)
			(xy 127.463678 -22.770544) (xy 127.500162 -22.723002) (xy 127.54254 -22.680629) (xy 127.590085 -22.64415)
			(xy 127.641985 -22.614189) (xy 127.697352 -22.591258) (xy 127.755238 -22.575751) (xy 127.814653 -22.567931)
			(xy 127.87458 -22.567933) (xy 127.933995 -22.575757) (xy 127.99188 -22.591269) (xy 128.047245 -22.614204)
			(xy 128.099143 -22.644169) (xy 128.146685 -22.680651) (xy 128.18906 -22.723027) (xy 128.22554 -22.770571)
			(xy 128.255504 -22.82247) (xy 128.278436 -22.877836) (xy 128.293946 -22.935722) (xy 128.301768 -22.995136)
			(xy 128.302258 -23.0251) (xy 128.302035 -23.045661) (xy 128.298346 -23.086618) (xy 128.294892 -23.106888)
			(xy 128.292352 -23.120604) (xy 128.301242 -23.145496) (xy 128.387856 -23.22068) (xy 128.413764 -23.226014)
			(xy 128.426972 -23.221696) (xy 128.456176 -23.212612) (xy 128.516537 -23.202786) (xy 128.547114 -23.202138)
			(xy 128.566041 -23.202406) (xy 128.603703 -23.206219) (xy 128.622298 -23.209758) (xy 128.634998 -23.212044)
			(xy 128.65862 -23.205186) (xy 128.737106 -23.128986) (xy 128.744726 -23.105618) (xy 128.742694 -23.092918)
			(xy 128.739634 -23.073888) (xy 128.736323 -23.035483) (xy 128.73609 -23.01621) (xy 128.73655 -22.98624)
			(xy 128.744373 -22.926813) (xy 128.759885 -22.868915) (xy 128.782822 -22.813538) (xy 128.812791 -22.761628)
			(xy 128.849279 -22.714074) (xy 128.891662 -22.67169) (xy 128.939215 -22.6352) (xy 128.991124 -22.605229)
			(xy 129.0465 -22.58229) (xy 129.104397 -22.566776) (xy 129.163824 -22.558952) (xy 129.223764 -22.558951)
			(xy 129.283191 -22.566774) (xy 129.341088 -22.582287) (xy 129.396466 -22.605224) (xy 129.448375 -22.635193)
			(xy 129.495929 -22.671682) (xy 129.538313 -22.714065) (xy 129.574802 -22.761618) (xy 129.604773 -22.813527)
			(xy 129.627711 -22.868904) (xy 129.643225 -22.926801) (xy 129.651049 -22.986228) (xy 129.651049 -23.046168)
			(xy 129.643226 -23.105595) (xy 129.627712 -23.163492) (xy 129.604774 -23.218869) (xy 129.574805 -23.270779)
			(xy 129.538316 -23.318332) (xy 129.495932 -23.360716) (xy 129.448379 -23.397205) (xy 129.396469 -23.427174)
			(xy 129.341092 -23.450112) (xy 129.283195 -23.465626) (xy 129.223768 -23.473449) (xy 129.193798 -23.473918)
			(xy 129.159553 -23.473321) (xy 129.091827 -23.463112) (xy 129.058924 -23.453598) (xy 129.046732 -23.449788)
			(xy 129.022602 -23.45436) (xy 128.93675 -23.522178) (xy 128.926844 -23.544784) (xy 128.92786 -23.557738)
			(xy 128.928622 -23.583646) (xy 128.928136 -23.610897) (xy 128.926832 -23.619964) (xy 132.109446 -23.619964)
			(xy 132.109446 -23.560028) (xy 132.117269 -23.500606) (xy 132.132782 -23.442713) (xy 132.155718 -23.38734)
			(xy 132.185685 -23.335434) (xy 132.222172 -23.287884) (xy 132.264552 -23.245504) (xy 132.312102 -23.209017)
			(xy 132.364008 -23.17905) (xy 132.419381 -23.156114) (xy 132.477274 -23.140601) (xy 132.536696 -23.132778)
			(xy 132.596632 -23.132778) (xy 132.656054 -23.140601) (xy 132.713947 -23.156114) (xy 132.76932 -23.17905)
			(xy 132.821226 -23.209017) (xy 132.868776 -23.245504) (xy 132.911156 -23.287884) (xy 132.947643 -23.335434)
			(xy 132.97761 -23.38734) (xy 133.000546 -23.442713) (xy 133.016059 -23.500606) (xy 133.023882 -23.560028)
			(xy 133.024372 -23.589996) (xy 133.023882 -23.619964) (xy 133.016059 -23.679386) (xy 133.000546 -23.737279)
			(xy 132.97761 -23.792652) (xy 132.947643 -23.844558) (xy 132.920203 -23.880318) (xy 133.340854 -23.880318)
			(xy 133.344925 -23.824696) (xy 133.357051 -23.770259) (xy 133.376974 -23.718168) (xy 133.40427 -23.669533)
			(xy 133.438356 -23.62539) (xy 133.478505 -23.586681) (xy 133.523863 -23.55423) (xy 133.573463 -23.528729)
			(xy 133.626247 -23.510722) (xy 133.68109 -23.500592) (xy 133.736824 -23.498555) (xy 133.792261 -23.504655)
			(xy 133.846218 -23.518761) (xy 133.897547 -23.540573) (xy 133.945153 -23.569627) (xy 133.988021 -23.605302)
			(xy 134.025238 -23.646839) (xy 134.056011 -23.693352) (xy 134.079683 -23.743849) (xy 134.095751 -23.797256)
			(xy 134.103871 -23.852432) (xy 134.10438 -23.880318) (xy 134.356854 -23.880318) (xy 134.360925 -23.824696)
			(xy 134.373051 -23.770259) (xy 134.392974 -23.718168) (xy 134.42027 -23.669533) (xy 134.454356 -23.62539)
			(xy 134.494505 -23.586681) (xy 134.539863 -23.55423) (xy 134.589463 -23.528729) (xy 134.642247 -23.510722)
			(xy 134.69709 -23.500592) (xy 134.752824 -23.498555) (xy 134.808261 -23.504655) (xy 134.862218 -23.518761)
			(xy 134.913547 -23.540573) (xy 134.961153 -23.569627) (xy 135.004021 -23.605302) (xy 135.041238 -23.646839)
			(xy 135.072011 -23.693352) (xy 135.095683 -23.743849) (xy 135.111751 -23.797256) (xy 135.119871 -23.852432)
			(xy 135.12038 -23.880318) (xy 135.372854 -23.880318) (xy 135.376925 -23.824696) (xy 135.389051 -23.770259)
			(xy 135.408974 -23.718168) (xy 135.43627 -23.669533) (xy 135.470356 -23.62539) (xy 135.510505 -23.586681)
			(xy 135.555863 -23.55423) (xy 135.605463 -23.528729) (xy 135.658247 -23.510722) (xy 135.71309 -23.500592)
			(xy 135.768824 -23.498555) (xy 135.824261 -23.504655) (xy 135.878218 -23.518761) (xy 135.929547 -23.540573)
			(xy 135.977153 -23.569627) (xy 136.020021 -23.605302) (xy 136.057238 -23.646839) (xy 136.088011 -23.693352)
			(xy 136.111683 -23.743849) (xy 136.127751 -23.797256) (xy 136.135871 -23.852432) (xy 136.13638 -23.880318)
			(xy 136.39114 -23.880318) (xy 136.395211 -23.824696) (xy 136.407337 -23.770259) (xy 136.42726 -23.718168)
			(xy 136.454556 -23.669533) (xy 136.488642 -23.62539) (xy 136.528791 -23.586681) (xy 136.574149 -23.55423)
			(xy 136.623749 -23.528729) (xy 136.676533 -23.510722) (xy 136.731376 -23.500592) (xy 136.78711 -23.498555)
			(xy 136.842547 -23.504655) (xy 136.896504 -23.518761) (xy 136.947833 -23.540573) (xy 136.995439 -23.569627)
			(xy 137.038307 -23.605302) (xy 137.075524 -23.646839) (xy 137.106297 -23.693352) (xy 137.129969 -23.743849)
			(xy 137.146037 -23.797256) (xy 137.154157 -23.852432) (xy 137.154666 -23.880318) (xy 137.154157 -23.908204)
			(xy 137.146037 -23.96338) (xy 137.129969 -24.016787) (xy 137.106297 -24.067284) (xy 137.075524 -24.113797)
			(xy 137.038307 -24.155334) (xy 136.995439 -24.191009) (xy 136.947833 -24.220063) (xy 136.896504 -24.241875)
			(xy 136.842547 -24.255981) (xy 136.78711 -24.262081) (xy 136.731376 -24.260044) (xy 136.676533 -24.249914)
			(xy 136.623749 -24.231907) (xy 136.574149 -24.206406) (xy 136.528791 -24.173955) (xy 136.488642 -24.135246)
			(xy 136.454556 -24.091103) (xy 136.42726 -24.042468) (xy 136.407337 -23.990377) (xy 136.395211 -23.93594)
			(xy 136.39114 -23.880318) (xy 136.13638 -23.880318) (xy 136.135871 -23.908204) (xy 136.127751 -23.96338)
			(xy 136.111683 -24.016787) (xy 136.088011 -24.067284) (xy 136.057238 -24.113797) (xy 136.020021 -24.155334)
			(xy 135.977153 -24.191009) (xy 135.929547 -24.220063) (xy 135.878218 -24.241875) (xy 135.824261 -24.255981)
			(xy 135.768824 -24.262081) (xy 135.71309 -24.260044) (xy 135.658247 -24.249914) (xy 135.605463 -24.231907)
			(xy 135.555863 -24.206406) (xy 135.510505 -24.173955) (xy 135.470356 -24.135246) (xy 135.43627 -24.091103)
			(xy 135.408974 -24.042468) (xy 135.389051 -23.990377) (xy 135.376925 -23.93594) (xy 135.372854 -23.880318)
			(xy 135.12038 -23.880318) (xy 135.119871 -23.908204) (xy 135.111751 -23.96338) (xy 135.095683 -24.016787)
			(xy 135.072011 -24.067284) (xy 135.041238 -24.113797) (xy 135.004021 -24.155334) (xy 134.961153 -24.191009)
			(xy 134.913547 -24.220063) (xy 134.862218 -24.241875) (xy 134.808261 -24.255981) (xy 134.752824 -24.262081)
			(xy 134.69709 -24.260044) (xy 134.642247 -24.249914) (xy 134.589463 -24.231907) (xy 134.539863 -24.206406)
			(xy 134.494505 -24.173955) (xy 134.454356 -24.135246) (xy 134.42027 -24.091103) (xy 134.392974 -24.042468)
			(xy 134.373051 -23.990377) (xy 134.360925 -23.93594) (xy 134.356854 -23.880318) (xy 134.10438 -23.880318)
			(xy 134.103871 -23.908204) (xy 134.095751 -23.96338) (xy 134.079683 -24.016787) (xy 134.056011 -24.067284)
			(xy 134.025238 -24.113797) (xy 133.988021 -24.155334) (xy 133.945153 -24.191009) (xy 133.897547 -24.220063)
			(xy 133.846218 -24.241875) (xy 133.792261 -24.255981) (xy 133.736824 -24.262081) (xy 133.68109 -24.260044)
			(xy 133.626247 -24.249914) (xy 133.573463 -24.231907) (xy 133.523863 -24.206406) (xy 133.478505 -24.173955)
			(xy 133.438356 -24.135246) (xy 133.40427 -24.091103) (xy 133.376974 -24.042468) (xy 133.357051 -23.990377)
			(xy 133.344925 -23.93594) (xy 133.340854 -23.880318) (xy 132.920203 -23.880318) (xy 132.911156 -23.892108)
			(xy 132.868776 -23.934488) (xy 132.821226 -23.970975) (xy 132.76932 -24.000942) (xy 132.713947 -24.023878)
			(xy 132.656054 -24.039391) (xy 132.596632 -24.047214) (xy 132.536696 -24.047214) (xy 132.477274 -24.039391)
			(xy 132.419381 -24.023878) (xy 132.364008 -24.000942) (xy 132.312102 -23.970975) (xy 132.264552 -23.934488)
			(xy 132.222172 -23.892108) (xy 132.185685 -23.844558) (xy 132.155718 -23.792652) (xy 132.132782 -23.737279)
			(xy 132.117269 -23.679386) (xy 132.109446 -23.619964) (xy 128.926832 -23.619964) (xy 128.92038 -23.664845)
			(xy 128.905025 -23.71714) (xy 128.882383 -23.766717) (xy 128.852917 -23.812567) (xy 128.817226 -23.853758)
			(xy 128.776035 -23.889449) (xy 128.730185 -23.918915) (xy 128.680608 -23.941557) (xy 128.628313 -23.956912)
			(xy 128.574365 -23.964668) (xy 128.519863 -23.964668) (xy 128.465915 -23.956912) (xy 128.41362 -23.941557)
			(xy 128.364043 -23.918915) (xy 128.318193 -23.889449) (xy 128.277002 -23.853758) (xy 128.241311 -23.812567)
			(xy 128.211845 -23.766717) (xy 128.189203 -23.71714) (xy 128.173848 -23.664845) (xy 128.166092 -23.610897)
			(xy 128.165606 -23.583646) (xy 128.167384 -23.548086) (xy 128.168654 -23.53437) (xy 128.157732 -23.51024)
			(xy 128.064768 -23.44293) (xy 128.038352 -23.439882) (xy 128.025906 -23.44547) (xy 127.997151 -23.457294)
			(xy 127.937244 -23.473928) (xy 127.875637 -23.482305) (xy 127.84455 -23.482808) (xy 127.814586 -23.482265)
			(xy 127.755173 -23.474436) (xy 127.697289 -23.45892) (xy 127.641925 -23.435981) (xy 127.59003 -23.406013)
			(xy 127.542489 -23.369527) (xy 127.500118 -23.327148) (xy 127.463641 -23.279601) (xy 127.433682 -23.2277)
			(xy 127.410753 -23.172332) (xy 127.395247 -23.114446) (xy 127.38743 -23.05503) (xy 126.243588 -23.05503)
			(xy 126.243588 -24.189944) (xy 127.399032 -24.189944) (xy 127.403103 -24.134322) (xy 127.415229 -24.079885)
			(xy 127.435152 -24.027794) (xy 127.462448 -23.979159) (xy 127.496534 -23.935016) (xy 127.536683 -23.896307)
			(xy 127.582041 -23.863856) (xy 127.631641 -23.838355) (xy 127.684425 -23.820348) (xy 127.739268 -23.810218)
			(xy 127.795002 -23.808181) (xy 127.850439 -23.814281) (xy 127.904396 -23.828387) (xy 127.955725 -23.850199)
			(xy 128.003331 -23.879253) (xy 128.046199 -23.914928) (xy 128.083416 -23.956465) (xy 128.114189 -24.002978)
			(xy 128.137861 -24.053475) (xy 128.153929 -24.106882) (xy 128.162049 -24.162058) (xy 128.162558 -24.189944)
			(xy 129.922014 -24.189944) (xy 129.926085 -24.134322) (xy 129.938211 -24.079885) (xy 129.958134 -24.027794)
			(xy 129.98543 -23.979159) (xy 130.019516 -23.935016) (xy 130.059665 -23.896307) (xy 130.105023 -23.863856)
			(xy 130.154623 -23.838355) (xy 130.207407 -23.820348) (xy 130.26225 -23.810218) (xy 130.317984 -23.808181)
			(xy 130.373421 -23.814281) (xy 130.427378 -23.828387) (xy 130.478707 -23.850199) (xy 130.526313 -23.879253)
			(xy 130.569181 -23.914928) (xy 130.606398 -23.956465) (xy 130.637171 -24.002978) (xy 130.660843 -24.053475)
			(xy 130.676911 -24.106882) (xy 130.685031 -24.162058) (xy 130.68554 -24.189944) (xy 130.685031 -24.21783)
			(xy 130.676911 -24.273006) (xy 130.660843 -24.326413) (xy 130.637171 -24.37691) (xy 130.606398 -24.423423)
			(xy 130.569181 -24.46496) (xy 130.526313 -24.500635) (xy 130.478707 -24.529689) (xy 130.427378 -24.551501)
			(xy 130.373421 -24.565607) (xy 130.317984 -24.571707) (xy 130.26225 -24.56967) (xy 130.207407 -24.55954)
			(xy 130.154623 -24.541533) (xy 130.105023 -24.516032) (xy 130.059665 -24.483581) (xy 130.019516 -24.444872)
			(xy 129.98543 -24.400729) (xy 129.958134 -24.352094) (xy 129.938211 -24.300003) (xy 129.926085 -24.245566)
			(xy 129.922014 -24.189944) (xy 128.162558 -24.189944) (xy 128.162049 -24.21783) (xy 128.153929 -24.273006)
			(xy 128.137861 -24.326413) (xy 128.114189 -24.37691) (xy 128.083416 -24.423423) (xy 128.046199 -24.46496)
			(xy 128.003331 -24.500635) (xy 127.955725 -24.529689) (xy 127.904396 -24.551501) (xy 127.850439 -24.565607)
			(xy 127.795002 -24.571707) (xy 127.739268 -24.56967) (xy 127.684425 -24.55954) (xy 127.631641 -24.541533)
			(xy 127.582041 -24.516032) (xy 127.536683 -24.483581) (xy 127.496534 -24.444872) (xy 127.462448 -24.400729)
			(xy 127.435152 -24.352094) (xy 127.415229 -24.300003) (xy 127.403103 -24.245566) (xy 127.399032 -24.189944)
			(xy 126.243588 -24.189944) (xy 126.243588 -25.390094) (xy 129.833624 -25.390094) (xy 129.834114 -25.360126)
			(xy 129.841937 -25.300704) (xy 129.85745 -25.242811) (xy 129.880386 -25.187438) (xy 129.910353 -25.135532)
			(xy 129.94684 -25.087982) (xy 129.98922 -25.045602) (xy 130.03677 -25.009115) (xy 130.088676 -24.979148)
			(xy 130.144049 -24.956212) (xy 130.201942 -24.940699) (xy 130.261364 -24.932876) (xy 130.3213 -24.932876)
			(xy 130.380722 -24.940699) (xy 130.438615 -24.956212) (xy 130.493988 -24.979148) (xy 130.545894 -25.009115)
			(xy 130.593444 -25.045602) (xy 130.635824 -25.087982) (xy 130.672311 -25.135532) (xy 130.702278 -25.187438)
			(xy 130.725214 -25.242811) (xy 130.740727 -25.300704) (xy 130.74855 -25.360126) (xy 130.74904 -25.390094)
			(xy 130.748592 -25.418878) (xy 130.741374 -25.475991) (xy 130.727051 -25.531749) (xy 130.705851 -25.585271)
			(xy 130.678106 -25.635711) (xy 130.644255 -25.682275) (xy 130.604833 -25.724227) (xy 130.582924 -25.7429)
			(xy 130.574542 -25.749758) (xy 130.56489 -25.769316) (xy 130.561588 -25.867106) (xy 130.569716 -25.887172)
			(xy 130.577844 -25.894792) (xy 130.596242 -25.912871) (xy 130.62848 -25.953137) (xy 130.655004 -25.997376)
			(xy 130.675332 -26.044783) (xy 130.689093 -26.094495) (xy 130.696037 -26.145607) (xy 130.696462 -26.171398)
			(xy 130.695976 -26.198649) (xy 130.68822 -26.252597) (xy 130.672865 -26.304892) (xy 130.650223 -26.354469)
			(xy 130.620757 -26.400319) (xy 130.585066 -26.44151) (xy 130.543875 -26.477201) (xy 130.498025 -26.506667)
			(xy 130.448448 -26.529309) (xy 130.396153 -26.544664) (xy 130.342205 -26.55242) (xy 130.287703 -26.55242)
			(xy 130.233755 -26.544664) (xy 130.18146 -26.529309) (xy 130.131883 -26.506667) (xy 130.086033 -26.477201)
			(xy 130.044842 -26.44151) (xy 130.009151 -26.400319) (xy 129.979685 -26.354469) (xy 129.957043 -26.304892)
			(xy 129.941688 -26.252597) (xy 129.933932 -26.198649) (xy 129.933446 -26.171398) (xy 129.933951 -26.142754)
			(xy 129.94255 -26.086114) (xy 129.959523 -26.031398) (xy 129.98449 -25.979836) (xy 130.016888 -25.932588)
			(xy 130.036062 -25.911302) (xy 130.043428 -25.903174) (xy 130.050286 -25.8826) (xy 130.041142 -25.785064)
			(xy 130.030474 -25.766268) (xy 130.021584 -25.759918) (xy 129.997055 -25.741344) (xy 129.952656 -25.698748)
			(xy 129.914362 -25.650591) (xy 129.882862 -25.597739) (xy 129.858723 -25.541145) (xy 129.842381 -25.481828)
			(xy 129.834129 -25.420857) (xy 129.833624 -25.390094) (xy 126.243588 -25.390094) (xy 126.243588 -25.990042)
			(xy 127.399032 -25.990042) (xy 127.403103 -25.93442) (xy 127.415229 -25.879983) (xy 127.435152 -25.827892)
			(xy 127.462448 -25.779257) (xy 127.496534 -25.735114) (xy 127.536683 -25.696405) (xy 127.582041 -25.663954)
			(xy 127.631641 -25.638453) (xy 127.684425 -25.620446) (xy 127.739268 -25.610316) (xy 127.795002 -25.608279)
			(xy 127.850439 -25.614379) (xy 127.904396 -25.628485) (xy 127.955725 -25.650297) (xy 128.003331 -25.679351)
			(xy 128.046199 -25.715026) (xy 128.083416 -25.756563) (xy 128.114189 -25.803076) (xy 128.137861 -25.853573)
			(xy 128.153929 -25.90698) (xy 128.162049 -25.962156) (xy 128.162558 -25.990042) (xy 128.162049 -26.017928)
			(xy 128.153929 -26.073104) (xy 128.137861 -26.126511) (xy 128.114189 -26.177008) (xy 128.083416 -26.223521)
			(xy 128.046199 -26.265058) (xy 128.003331 -26.300733) (xy 127.955725 -26.329787) (xy 127.904396 -26.351599)
			(xy 127.850439 -26.365705) (xy 127.795002 -26.371805) (xy 127.739268 -26.369768) (xy 127.684425 -26.359638)
			(xy 127.631641 -26.341631) (xy 127.582041 -26.31613) (xy 127.536683 -26.283679) (xy 127.496534 -26.24497)
			(xy 127.462448 -26.200827) (xy 127.435152 -26.152192) (xy 127.415229 -26.100101) (xy 127.403103 -26.045664)
			(xy 127.399032 -25.990042) (xy 126.243588 -25.990042) (xy 126.243588 -27.79014) (xy 127.46304 -27.79014)
			(xy 127.467111 -27.734518) (xy 127.479237 -27.680081) (xy 127.49916 -27.62799) (xy 127.526456 -27.579355)
			(xy 127.560542 -27.535212) (xy 127.600691 -27.496503) (xy 127.646049 -27.464052) (xy 127.695649 -27.438551)
			(xy 127.748433 -27.420544) (xy 127.803276 -27.410414) (xy 127.85901 -27.408377) (xy 127.914447 -27.414477)
			(xy 127.968404 -27.428583) (xy 128.019733 -27.450395) (xy 128.067339 -27.479449) (xy 128.110207 -27.515124)
			(xy 128.147424 -27.556661) (xy 128.178197 -27.603174) (xy 128.201869 -27.653671) (xy 128.217937 -27.707078)
			(xy 128.226057 -27.762254) (xy 128.226566 -27.79014) (xy 129.966972 -27.79014) (xy 129.971043 -27.734518)
			(xy 129.983169 -27.680081) (xy 130.003092 -27.62799) (xy 130.030388 -27.579355) (xy 130.064474 -27.535212)
			(xy 130.104623 -27.496503) (xy 130.149981 -27.464052) (xy 130.199581 -27.438551) (xy 130.252365 -27.420544)
			(xy 130.307208 -27.410414) (xy 130.362942 -27.408377) (xy 130.418379 -27.414477) (xy 130.472336 -27.428583)
			(xy 130.523665 -27.450395) (xy 130.571271 -27.479449) (xy 130.614139 -27.515124) (xy 130.651356 -27.556661)
			(xy 130.682129 -27.603174) (xy 130.705801 -27.653671) (xy 130.721869 -27.707078) (xy 130.729989 -27.762254)
			(xy 130.730498 -27.79014) (xy 130.730001 -27.817348) (xy 132.000018 -27.817348) (xy 132.000018 -27.762852)
			(xy 132.007774 -27.708911) (xy 132.023127 -27.656623) (xy 132.045765 -27.607051) (xy 132.075227 -27.561206)
			(xy 132.110913 -27.520021) (xy 132.152098 -27.484333) (xy 132.197942 -27.454869) (xy 132.247513 -27.43223)
			(xy 132.299801 -27.416876) (xy 132.353742 -27.409119) (xy 132.38099 -27.408632) (xy 132.406297 -27.409034)
			(xy 132.456469 -27.415704) (xy 132.505321 -27.428942) (xy 132.528818 -27.43835) (xy 132.536828 -27.441363)
			(xy 132.553896 -27.44246) (xy 132.570374 -27.437877) (xy 132.577586 -27.43327) (xy 132.602986 -27.41549)
			(xy 132.609873 -27.410216) (xy 132.619947 -27.396112) (xy 132.624745 -27.379457) (xy 132.624576 -27.370786)
			(xy 132.62356 -27.342846) (xy 132.62356 -26.479246) (xy 132.624322 -26.456894) (xy 132.62483 -26.444448)
			(xy 132.614416 -26.421842) (xy 132.529326 -26.355548) (xy 132.504942 -26.350976) (xy 132.493004 -26.354786)
			(xy 132.465666 -26.362623) (xy 132.409425 -26.371044) (xy 132.38099 -26.37155) (xy 132.353742 -26.370979)
			(xy 132.299802 -26.363222) (xy 132.247514 -26.347868) (xy 132.197943 -26.325229) (xy 132.152099 -26.295766)
			(xy 132.110915 -26.260078) (xy 132.075228 -26.218893) (xy 132.045766 -26.173048) (xy 132.023128 -26.123477)
			(xy 132.007776 -26.071189) (xy 132.00002 -26.017248) (xy 132.00002 -25.962752) (xy 132.007776 -25.908811)
			(xy 132.023128 -25.856523) (xy 132.045766 -25.806952) (xy 132.075228 -25.761107) (xy 132.110915 -25.719922)
			(xy 132.152099 -25.684234) (xy 132.197943 -25.654771) (xy 132.247514 -25.632132) (xy 132.299802 -25.616778)
			(xy 132.353742 -25.609021) (xy 132.38099 -25.608534) (xy 132.409942 -25.609086) (xy 132.467183 -25.617821)
			(xy 132.522445 -25.635107) (xy 132.574461 -25.660547) (xy 132.622033 -25.693557) (xy 132.664071 -25.733378)
			(xy 132.699606 -25.779094) (xy 132.727824 -25.829657) (xy 132.728719 -25.832054) (xy 134.28853 -25.832054)
			(xy 134.289007 -25.805451) (xy 134.296382 -25.752758) (xy 134.31101 -25.701603) (xy 134.332608 -25.652977)
			(xy 134.360755 -25.607827) (xy 134.394906 -25.567027) (xy 134.434397 -25.531371) (xy 134.45617 -25.516078)
			(xy 134.467649 -25.50774) (xy 134.485858 -25.485999) (xy 134.497378 -25.460086) (xy 134.501321 -25.432002)
			(xy 134.49738 -25.403918) (xy 134.48586 -25.378004) (xy 134.467652 -25.356263) (xy 134.45617 -25.34793)
			(xy 134.434412 -25.332619) (xy 134.394931 -25.296956) (xy 134.360786 -25.256156) (xy 134.332638 -25.211009)
			(xy 134.311034 -25.16239) (xy 134.296391 -25.111242) (xy 134.288995 -25.058555) (xy 134.28853 -25.031954)
			(xy 134.289016 -25.004703) (xy 134.296772 -24.950755) (xy 134.312127 -24.89846) (xy 134.334769 -24.848883)
			(xy 134.364235 -24.803033) (xy 134.399926 -24.761842) (xy 134.441117 -24.726151) (xy 134.486967 -24.696685)
			(xy 134.536544 -24.674043) (xy 134.588839 -24.658688) (xy 134.642787 -24.650932) (xy 134.697289 -24.650932)
			(xy 134.751237 -24.658688) (xy 134.803532 -24.674043) (xy 134.853109 -24.696685) (xy 134.898959 -24.726151)
			(xy 134.94015 -24.761842) (xy 134.963351 -24.788618) (xy 136.893536 -24.788618) (xy 136.893536 -24.728682)
			(xy 136.901359 -24.66926) (xy 136.916872 -24.611367) (xy 136.939808 -24.555994) (xy 136.969775 -24.504088)
			(xy 137.006262 -24.456538) (xy 137.048642 -24.414158) (xy 137.096192 -24.377671) (xy 137.148098 -24.347704)
			(xy 137.203471 -24.324768) (xy 137.261364 -24.309255) (xy 137.320786 -24.301432) (xy 137.380722 -24.301432)
			(xy 137.440144 -24.309255) (xy 137.498037 -24.324768) (xy 137.55341 -24.347704) (xy 137.605316 -24.377671)
			(xy 137.652866 -24.414158) (xy 137.695246 -24.456538) (xy 137.731733 -24.504088) (xy 137.7617 -24.555994)
			(xy 137.784636 -24.611367) (xy 137.800149 -24.66926) (xy 137.807972 -24.728682) (xy 137.808462 -24.75865)
			(xy 137.807972 -24.788618) (xy 137.800149 -24.84804) (xy 137.784636 -24.905933) (xy 137.7617 -24.961306)
			(xy 137.731733 -25.013212) (xy 137.695246 -25.060762) (xy 137.652866 -25.103142) (xy 137.605316 -25.139629)
			(xy 137.55341 -25.169596) (xy 137.498037 -25.192532) (xy 137.440144 -25.208045) (xy 137.380722 -25.215868)
			(xy 137.320786 -25.215868) (xy 137.261364 -25.208045) (xy 137.203471 -25.192532) (xy 137.148098 -25.169596)
			(xy 137.096192 -25.139629) (xy 137.048642 -25.103142) (xy 137.006262 -25.060762) (xy 136.969775 -25.013212)
			(xy 136.939808 -24.961306) (xy 136.916872 -24.905933) (xy 136.901359 -24.84804) (xy 136.893536 -24.788618)
			(xy 134.963351 -24.788618) (xy 134.975841 -24.803033) (xy 135.005307 -24.848883) (xy 135.027949 -24.89846)
			(xy 135.043304 -24.950755) (xy 135.05106 -25.004703) (xy 135.051546 -25.031954) (xy 135.051086 -25.058558)
			(xy 135.043709 -25.111251) (xy 135.029079 -25.162408) (xy 135.007479 -25.211034) (xy 134.979328 -25.256184)
			(xy 134.945174 -25.296983) (xy 134.90568 -25.332638) (xy 134.883906 -25.34793) (xy 134.872421 -25.356259)
			(xy 134.854217 -25.378003) (xy 134.842699 -25.403918) (xy 134.838759 -25.432002) (xy 134.842701 -25.460086)
			(xy 134.854219 -25.486) (xy 134.872425 -25.507744) (xy 134.883906 -25.516078) (xy 134.905663 -25.531392)
			(xy 134.945145 -25.567053) (xy 134.979291 -25.607852) (xy 135.007439 -25.652999) (xy 135.029043 -25.701618)
			(xy 135.043686 -25.752766) (xy 135.051082 -25.805453) (xy 135.051546 -25.832054) (xy 135.05106 -25.859305)
			(xy 135.043304 -25.913253) (xy 135.027949 -25.965548) (xy 135.005307 -26.015125) (xy 134.975841 -26.060975)
			(xy 134.94015 -26.102166) (xy 134.898959 -26.137857) (xy 134.853109 -26.167323) (xy 134.803532 -26.189965)
			(xy 134.751237 -26.20532) (xy 134.697289 -26.213076) (xy 134.642787 -26.213076) (xy 134.588839 -26.20532)
			(xy 134.536544 -26.189965) (xy 134.486967 -26.167323) (xy 134.441117 -26.137857) (xy 134.399926 -26.102166)
			(xy 134.364235 -26.060975) (xy 134.334769 -26.015125) (xy 134.312127 -25.965548) (xy 134.296772 -25.913253)
			(xy 134.289016 -25.859305) (xy 134.28853 -25.832054) (xy 132.728719 -25.832054) (xy 132.748075 -25.883903)
			(xy 132.759895 -25.940587) (xy 132.76199 -25.969468) (xy 132.762498 -25.981914) (xy 132.775198 -26.00325)
			(xy 132.866892 -26.060654) (xy 132.89153 -26.062432) (xy 132.90296 -26.057606) (xy 132.931314 -26.046127)
			(xy 132.990314 -26.029975) (xy 133.050937 -26.021809) (xy 133.081522 -26.021284) (xy 133.11151 -26.021687)
			(xy 133.170973 -26.029518) (xy 133.228904 -26.045045) (xy 133.284314 -26.068) (xy 133.336253 -26.097991)
			(xy 133.383833 -26.134506) (xy 133.426239 -26.176919) (xy 133.462746 -26.224504) (xy 133.49273 -26.276447)
			(xy 133.515677 -26.33186) (xy 133.523451 -26.360882) (xy 135.18972 -26.360882) (xy 135.193791 -26.30526)
			(xy 135.205917 -26.250823) (xy 135.22584 -26.198732) (xy 135.253136 -26.150097) (xy 135.287222 -26.105954)
			(xy 135.327371 -26.067245) (xy 135.372729 -26.034794) (xy 135.422329 -26.009293) (xy 135.475113 -25.991286)
			(xy 135.529956 -25.981156) (xy 135.58569 -25.979119) (xy 135.641127 -25.985219) (xy 135.695084 -25.999325)
			(xy 135.746413 -26.021137) (xy 135.794019 -26.050191) (xy 135.836887 -26.085866) (xy 135.874104 -26.127403)
			(xy 135.904877 -26.173916) (xy 135.928549 -26.224413) (xy 135.944617 -26.27782) (xy 135.952737 -26.332996)
			(xy 135.953246 -26.360882) (xy 136.20572 -26.360882) (xy 136.209791 -26.30526) (xy 136.221917 -26.250823)
			(xy 136.24184 -26.198732) (xy 136.269136 -26.150097) (xy 136.303222 -26.105954) (xy 136.343371 -26.067245)
			(xy 136.388729 -26.034794) (xy 136.438329 -26.009293) (xy 136.491113 -25.991286) (xy 136.545956 -25.981156)
			(xy 136.60169 -25.979119) (xy 136.657127 -25.985219) (xy 136.711084 -25.999325) (xy 136.762413 -26.021137)
			(xy 136.810019 -26.050191) (xy 136.852887 -26.085866) (xy 136.890104 -26.127403) (xy 136.920877 -26.173916)
			(xy 136.944549 -26.224413) (xy 136.960617 -26.27782) (xy 136.968737 -26.332996) (xy 136.969246 -26.360882)
			(xy 136.968737 -26.388768) (xy 136.960617 -26.443944) (xy 136.944549 -26.497351) (xy 136.920877 -26.547848)
			(xy 136.890104 -26.594361) (xy 136.852887 -26.635898) (xy 136.810019 -26.671573) (xy 136.762413 -26.700627)
			(xy 136.711084 -26.722439) (xy 136.657127 -26.736545) (xy 136.60169 -26.742645) (xy 136.545956 -26.740608)
			(xy 136.491113 -26.730478) (xy 136.438329 -26.712471) (xy 136.388729 -26.68697) (xy 136.343371 -26.654519)
			(xy 136.303222 -26.61581) (xy 136.269136 -26.571667) (xy 136.24184 -26.523032) (xy 136.221917 -26.470941)
			(xy 136.209791 -26.416504) (xy 136.20572 -26.360882) (xy 135.953246 -26.360882) (xy 135.952737 -26.388768)
			(xy 135.944617 -26.443944) (xy 135.928549 -26.497351) (xy 135.904877 -26.547848) (xy 135.874104 -26.594361)
			(xy 135.836887 -26.635898) (xy 135.794019 -26.671573) (xy 135.746413 -26.700627) (xy 135.695084 -26.722439)
			(xy 135.641127 -26.736545) (xy 135.58569 -26.742645) (xy 135.529956 -26.740608) (xy 135.475113 -26.730478)
			(xy 135.422329 -26.712471) (xy 135.372729 -26.68697) (xy 135.327371 -26.654519) (xy 135.287222 -26.61581)
			(xy 135.253136 -26.571667) (xy 135.22584 -26.523032) (xy 135.205917 -26.470941) (xy 135.193791 -26.416504)
			(xy 135.18972 -26.360882) (xy 133.523451 -26.360882) (xy 133.531195 -26.389794) (xy 133.539018 -26.449258)
			(xy 133.539484 -26.479246) (xy 133.539484 -26.971244) (xy 136.95121 -26.971244) (xy 136.955281 -26.915622)
			(xy 136.967407 -26.861185) (xy 136.98733 -26.809094) (xy 137.014626 -26.760459) (xy 137.048712 -26.716316)
			(xy 137.088861 -26.677607) (xy 137.134219 -26.645156) (xy 137.183819 -26.619655) (xy 137.236603 -26.601648)
			(xy 137.291446 -26.591518) (xy 137.34718 -26.589481) (xy 137.402617 -26.595581) (xy 137.456574 -26.609687)
			(xy 137.507903 -26.631499) (xy 137.555509 -26.660553) (xy 137.598377 -26.696228) (xy 137.635594 -26.737765)
			(xy 137.666367 -26.784278) (xy 137.690039 -26.834775) (xy 137.706107 -26.888182) (xy 137.714227 -26.943358)
			(xy 137.714736 -26.971244) (xy 137.714227 -26.99913) (xy 137.706107 -27.054306) (xy 137.690039 -27.107713)
			(xy 137.666367 -27.15821) (xy 137.635594 -27.204723) (xy 137.598377 -27.24626) (xy 137.555509 -27.281935)
			(xy 137.507903 -27.310989) (xy 137.456574 -27.332801) (xy 137.402617 -27.346907) (xy 137.34718 -27.353007)
			(xy 137.291446 -27.35097) (xy 137.236603 -27.34084) (xy 137.183819 -27.322833) (xy 137.134219 -27.297332)
			(xy 137.088861 -27.264881) (xy 137.048712 -27.226172) (xy 137.014626 -27.182029) (xy 136.98733 -27.133394)
			(xy 136.967407 -27.081303) (xy 136.955281 -27.026866) (xy 136.95121 -26.971244) (xy 133.539484 -26.971244)
			(xy 133.539484 -27.342846) (xy 133.539015 -27.37283) (xy 133.531182 -27.432286) (xy 133.515657 -27.49021)
			(xy 133.492704 -27.545613) (xy 133.462717 -27.597546) (xy 133.426208 -27.645121) (xy 133.383803 -27.687524)
			(xy 133.336226 -27.72403) (xy 133.284291 -27.754015) (xy 133.228887 -27.776964) (xy 133.170962 -27.792487)
			(xy 133.111506 -27.800317) (xy 133.081522 -27.800808) (xy 133.050386 -27.800262) (xy 132.98869 -27.791803)
			(xy 132.928705 -27.775079) (xy 132.899912 -27.763216) (xy 132.888736 -27.75839) (xy 132.865114 -27.75966)
			(xy 132.773928 -27.810968) (xy 132.760466 -27.830526) (xy 132.758942 -27.842464) (xy 132.754796 -27.869507)
			(xy 132.739612 -27.92207) (xy 132.717077 -27.971926) (xy 132.687654 -28.018053) (xy 132.651946 -28.059506)
			(xy 132.610684 -28.095435) (xy 132.564714 -28.125103) (xy 132.514979 -28.147903) (xy 132.462498 -28.163367)
			(xy 132.408346 -28.171179) (xy 132.38099 -28.171648) (xy 132.353742 -28.171081) (xy 132.299801 -28.163324)
			(xy 132.247513 -28.14797) (xy 132.197942 -28.125331) (xy 132.152098 -28.095867) (xy 132.110913 -28.060179)
			(xy 132.075227 -28.018994) (xy 132.045765 -27.973149) (xy 132.023127 -27.923577) (xy 132.007774 -27.871289)
			(xy 132.000018 -27.817348) (xy 130.730001 -27.817348) (xy 130.729989 -27.818026) (xy 130.721869 -27.873202)
			(xy 130.705801 -27.926609) (xy 130.682129 -27.977106) (xy 130.651356 -28.023619) (xy 130.614139 -28.065156)
			(xy 130.571271 -28.100831) (xy 130.523665 -28.129885) (xy 130.472336 -28.151697) (xy 130.418379 -28.165803)
			(xy 130.362942 -28.171903) (xy 130.307208 -28.169866) (xy 130.252365 -28.159736) (xy 130.199581 -28.141729)
			(xy 130.149981 -28.116228) (xy 130.104623 -28.083777) (xy 130.064474 -28.045068) (xy 130.030388 -28.000925)
			(xy 130.003092 -27.95229) (xy 129.983169 -27.900199) (xy 129.971043 -27.845762) (xy 129.966972 -27.79014)
			(xy 128.226566 -27.79014) (xy 128.226057 -27.818026) (xy 128.217937 -27.873202) (xy 128.201869 -27.926609)
			(xy 128.178197 -27.977106) (xy 128.147424 -28.023619) (xy 128.110207 -28.065156) (xy 128.067339 -28.100831)
			(xy 128.019733 -28.129885) (xy 127.968404 -28.151697) (xy 127.914447 -28.165803) (xy 127.85901 -28.171903)
			(xy 127.803276 -28.169866) (xy 127.748433 -28.159736) (xy 127.695649 -28.141729) (xy 127.646049 -28.116228)
			(xy 127.600691 -28.083777) (xy 127.560542 -28.045068) (xy 127.526456 -28.000925) (xy 127.49916 -27.95229)
			(xy 127.479237 -27.900199) (xy 127.467111 -27.845762) (xy 127.46304 -27.79014) (xy 126.243588 -27.79014)
			(xy 126.243588 -29.589984) (xy 127.46304 -29.589984) (xy 127.467111 -29.534362) (xy 127.479237 -29.479925)
			(xy 127.49916 -29.427834) (xy 127.526456 -29.379199) (xy 127.560542 -29.335056) (xy 127.600691 -29.296347)
			(xy 127.646049 -29.263896) (xy 127.695649 -29.238395) (xy 127.748433 -29.220388) (xy 127.803276 -29.210258)
			(xy 127.85901 -29.208221) (xy 127.914447 -29.214321) (xy 127.968404 -29.228427) (xy 128.019733 -29.250239)
			(xy 128.067339 -29.279293) (xy 128.110207 -29.314968) (xy 128.147424 -29.356505) (xy 128.178197 -29.403018)
			(xy 128.201869 -29.453515) (xy 128.217937 -29.506922) (xy 128.226057 -29.562098) (xy 128.226566 -29.589984)
			(xy 129.966972 -29.589984) (xy 129.971043 -29.534362) (xy 129.983169 -29.479925) (xy 130.003092 -29.427834)
			(xy 130.030388 -29.379199) (xy 130.064474 -29.335056) (xy 130.104623 -29.296347) (xy 130.149981 -29.263896)
			(xy 130.199581 -29.238395) (xy 130.252365 -29.220388) (xy 130.307208 -29.210258) (xy 130.362942 -29.208221)
			(xy 130.418379 -29.214321) (xy 130.472336 -29.228427) (xy 130.523665 -29.250239) (xy 130.571271 -29.279293)
			(xy 130.614139 -29.314968) (xy 130.651356 -29.356505) (xy 130.682129 -29.403018) (xy 130.705801 -29.453515)
			(xy 130.721869 -29.506922) (xy 130.729989 -29.562098) (xy 130.730498 -29.589984) (xy 131.998972 -29.589984)
			(xy 132.003043 -29.534362) (xy 132.015169 -29.479925) (xy 132.035092 -29.427834) (xy 132.062388 -29.379199)
			(xy 132.096474 -29.335056) (xy 132.136623 -29.296347) (xy 132.181981 -29.263896) (xy 132.231581 -29.238395)
			(xy 132.284365 -29.220388) (xy 132.339208 -29.210258) (xy 132.394942 -29.208221) (xy 132.450379 -29.214321)
			(xy 132.504336 -29.228427) (xy 132.555665 -29.250239) (xy 132.603271 -29.279293) (xy 132.646139 -29.314968)
			(xy 132.66781 -29.339154) (xy 134.390332 -29.339154) (xy 134.390332 -29.284646) (xy 134.398089 -29.230693)
			(xy 134.413445 -29.178394) (xy 134.436088 -29.128811) (xy 134.465556 -29.082956) (xy 134.50125 -29.041762)
			(xy 134.542443 -29.006066) (xy 134.588297 -28.976595) (xy 134.637879 -28.953951) (xy 134.690178 -28.938592)
			(xy 134.74413 -28.930833) (xy 134.771384 -28.930346) (xy 134.786177 -28.930481) (xy 134.815675 -28.93277)
			(xy 134.830312 -28.934918) (xy 134.841234 -28.936696) (xy 134.86257 -28.9306) (xy 134.92988 -28.873196)
			(xy 134.937915 -28.865636) (xy 134.947124 -28.845609) (xy 134.94766 -28.834588) (xy 134.94766 -28.530296)
			(xy 134.947137 -28.519275) (xy 134.937908 -28.499258) (xy 134.92988 -28.491688) (xy 134.86257 -28.434284)
			(xy 134.841234 -28.428188) (xy 134.830312 -28.429966) (xy 134.815673 -28.4321) (xy 134.786177 -28.434393)
			(xy 134.771384 -28.434538) (xy 134.744136 -28.433991) (xy 134.690194 -28.426233) (xy 134.637905 -28.410878)
			(xy 134.588334 -28.388237) (xy 134.542489 -28.358773) (xy 134.501304 -28.323084) (xy 134.465617 -28.281898)
			(xy 134.436155 -28.236052) (xy 134.413517 -28.18648) (xy 134.398164 -28.13419) (xy 134.390408 -28.080248)
			(xy 134.390408 -28.025752) (xy 134.398164 -27.97181) (xy 134.413517 -27.91952) (xy 134.436155 -27.869948)
			(xy 134.465617 -27.824102) (xy 134.501304 -27.782916) (xy 134.542489 -27.747227) (xy 134.588334 -27.717763)
			(xy 134.637905 -27.695122) (xy 134.690194 -27.679767) (xy 134.744136 -27.672009) (xy 134.771384 -27.671522)
			(xy 134.79731 -27.671958) (xy 134.848688 -27.678962) (xy 134.898644 -27.692858) (xy 134.946258 -27.713389)
			(xy 134.990655 -27.740177) (xy 135.031016 -27.77273) (xy 135.066598 -27.810447) (xy 135.082026 -27.831288)
			(xy 135.087782 -27.838605) (xy 135.103274 -27.848898) (xy 135.112252 -27.851354) (xy 135.142478 -27.858212)
			(xy 135.151752 -27.859978) (xy 135.170418 -27.857226) (xy 135.1788 -27.852878) (xy 135.204777 -27.838584)
			(xy 135.259628 -27.816073) (xy 135.316931 -27.800847) (xy 135.375722 -27.79316) (xy 135.405368 -27.79268)
			(xy 135.435011 -27.79318) (xy 135.493793 -27.8009) (xy 135.551091 -27.816126) (xy 135.605951 -27.838604)
			(xy 135.631936 -27.852878) (xy 135.640358 -27.857103) (xy 135.65898 -27.85985) (xy 135.668258 -27.858212)
			(xy 135.698484 -27.851354) (xy 135.707486 -27.848952) (xy 135.722987 -27.838641) (xy 135.72871 -27.831288)
			(xy 135.744104 -27.810418) (xy 135.779678 -27.772683) (xy 135.82004 -27.740119) (xy 135.864442 -27.713326)
			(xy 135.912067 -27.692799) (xy 135.962034 -27.678916) (xy 136.013422 -27.671934) (xy 136.039352 -27.671522)
			(xy 136.066609 -27.671922) (xy 136.12057 -27.679674) (xy 136.172877 -27.695027) (xy 136.222468 -27.717668)
			(xy 136.26833 -27.747137) (xy 136.309532 -27.782834) (xy 136.345234 -27.824031) (xy 136.374709 -27.86989)
			(xy 136.397356 -27.919477) (xy 136.412716 -27.971783) (xy 136.420475 -28.025743) (xy 136.420475 -28.080257)
			(xy 136.412716 -28.134217) (xy 136.397356 -28.186522) (xy 136.374709 -28.23611) (xy 136.345234 -28.281969)
			(xy 136.309532 -28.323166) (xy 136.26833 -28.358863) (xy 136.222468 -28.388332) (xy 136.172877 -28.410973)
			(xy 136.12057 -28.426326) (xy 136.066609 -28.434078) (xy 136.039352 -28.434538) (xy 136.024559 -28.434399)
			(xy 135.995061 -28.432113) (xy 135.980424 -28.429966) (xy 135.969502 -28.428188) (xy 135.948166 -28.434284)
			(xy 135.880856 -28.491688) (xy 135.872833 -28.49926) (xy 135.863616 -28.519277) (xy 135.863076 -28.530296)
			(xy 135.863076 -28.834588) (xy 135.863628 -28.845605) (xy 135.872838 -28.865621) (xy 135.880856 -28.873196)
			(xy 135.948166 -28.9306) (xy 135.969502 -28.936696) (xy 135.980424 -28.934918) (xy 135.995062 -28.93278)
			(xy 136.024559 -28.93049) (xy 136.039352 -28.930346) (xy 136.066604 -28.930898) (xy 136.120553 -28.938648)
			(xy 136.172851 -28.953998) (xy 136.222431 -28.976635) (xy 136.268285 -29.006099) (xy 136.309478 -29.041788)
			(xy 136.345173 -29.082977) (xy 136.374641 -29.128827) (xy 136.397285 -29.178404) (xy 136.412641 -29.2307)
			(xy 136.420399 -29.284648) (xy 136.420399 -29.339152) (xy 136.412641 -29.3931) (xy 136.397285 -29.445396)
			(xy 136.374641 -29.494973) (xy 136.345173 -29.540823) (xy 136.309478 -29.582012) (xy 136.268285 -29.617701)
			(xy 136.222431 -29.647165) (xy 136.172851 -29.669802) (xy 136.120553 -29.685152) (xy 136.066604 -29.692902)
			(xy 136.039352 -29.693362) (xy 136.013426 -29.692906) (xy 135.96205 -29.685906) (xy 135.912094 -29.672014)
			(xy 135.864479 -29.651487) (xy 135.820082 -29.624701) (xy 135.779721 -29.592151) (xy 135.744138 -29.554436)
			(xy 135.72871 -29.533596) (xy 135.72296 -29.526274) (xy 135.707465 -29.515982) (xy 135.698484 -29.51353)
			(xy 135.668258 -29.506672) (xy 135.658981 -29.504927) (xy 135.640318 -29.507666) (xy 135.631936 -29.512006)
			(xy 135.605972 -29.526323) (xy 135.551115 -29.548829) (xy 135.493809 -29.564049) (xy 135.435015 -29.571728)
			(xy 135.405368 -29.572204) (xy 135.375726 -29.571691) (xy 135.316944 -29.563975) (xy 135.259646 -29.548753)
			(xy 135.204785 -29.526278) (xy 135.1788 -29.512006) (xy 135.170392 -29.507749) (xy 135.151758 -29.505023)
			(xy 135.142478 -29.506672) (xy 135.112252 -29.51353) (xy 135.103257 -29.515952) (xy 135.087753 -29.526249)
			(xy 135.082026 -29.533596) (xy 135.066606 -29.554446) (xy 135.031036 -29.592181) (xy 134.99068 -29.624748)
			(xy 134.946282 -29.651544) (xy 134.898661 -29.672074) (xy 134.848698 -29.685961) (xy 134.797313 -29.692947)
			(xy 134.771384 -29.693362) (xy 134.74413 -29.692967) (xy 134.690178 -29.685208) (xy 134.637879 -29.669849)
			(xy 134.588297 -29.647205) (xy 134.542443 -29.617734) (xy 134.50125 -29.582038) (xy 134.465556 -29.540844)
			(xy 134.436088 -29.494989) (xy 134.413445 -29.445406) (xy 134.398089 -29.393107) (xy 134.390332 -29.339154)
			(xy 132.66781 -29.339154) (xy 132.683356 -29.356505) (xy 132.714129 -29.403018) (xy 132.737801 -29.453515)
			(xy 132.753869 -29.506922) (xy 132.761989 -29.562098) (xy 132.762498 -29.589984) (xy 132.761989 -29.61787)
			(xy 132.753869 -29.673046) (xy 132.737801 -29.726453) (xy 132.714129 -29.77695) (xy 132.683356 -29.823463)
			(xy 132.646139 -29.865) (xy 132.620001 -29.886752) (xy 137.032456 -29.886752) (xy 137.032456 -29.832248)
			(xy 137.040213 -29.778297) (xy 137.055568 -29.726) (xy 137.07821 -29.676421) (xy 137.107677 -29.630568)
			(xy 137.14337 -29.589376) (xy 137.184562 -29.553682) (xy 137.230414 -29.524214) (xy 137.279993 -29.501571)
			(xy 137.33229 -29.486214) (xy 137.38624 -29.478456) (xy 137.413492 -29.47797) (xy 137.439418 -29.478421)
			(xy 137.490793 -29.485426) (xy 137.540748 -29.49932) (xy 137.588362 -29.519849) (xy 137.632758 -29.546635)
			(xy 137.67312 -29.579184) (xy 137.708705 -29.616897) (xy 137.724134 -29.637736) (xy 137.729897 -29.645046)
			(xy 137.745383 -29.655344) (xy 137.75436 -29.657802) (xy 137.784586 -29.66466) (xy 137.79386 -29.666425)
			(xy 137.812526 -29.663672) (xy 137.820908 -29.659326) (xy 137.846885 -29.645033) (xy 137.901737 -29.622521)
			(xy 137.959039 -29.607294) (xy 138.01783 -29.599608) (xy 138.047476 -29.599128) (xy 138.077119 -29.599631)
			(xy 138.1359 -29.607352) (xy 138.193198 -29.622577) (xy 138.248059 -29.645053) (xy 138.274044 -29.659326)
			(xy 138.282465 -29.663553) (xy 138.301088 -29.6663) (xy 138.310366 -29.66466) (xy 138.340592 -29.657802)
			(xy 138.349589 -29.655388) (xy 138.365091 -29.645085) (xy 138.370818 -29.637736) (xy 138.386253 -29.616898)
			(xy 138.421822 -29.579165) (xy 138.462177 -29.5466) (xy 138.506572 -29.519804) (xy 138.55419 -29.499271)
			(xy 138.60415 -29.48538) (xy 138.655532 -29.478388) (xy 138.68146 -29.47797) (xy 138.708713 -29.478475)
			(xy 138.762665 -29.486226) (xy 138.814965 -29.501578) (xy 138.864547 -29.524217) (xy 138.910403 -29.553682)
			(xy 138.951598 -29.589374) (xy 138.987294 -29.630565) (xy 139.016764 -29.676418) (xy 139.039408 -29.725998)
			(xy 139.054765 -29.778296) (xy 139.062523 -29.832247) (xy 139.062523 -29.886753) (xy 139.054765 -29.940704)
			(xy 139.039408 -29.993002) (xy 139.016764 -30.042582) (xy 138.987294 -30.088435) (xy 138.951598 -30.129626)
			(xy 138.910403 -30.165318) (xy 138.864547 -30.194783) (xy 138.814965 -30.217422) (xy 138.762665 -30.232774)
			(xy 138.708713 -30.240525) (xy 138.68146 -30.240986) (xy 138.666667 -30.240846) (xy 138.637169 -30.23856)
			(xy 138.622532 -30.236414) (xy 138.61161 -30.234636) (xy 138.590274 -30.240732) (xy 138.522964 -30.298136)
			(xy 138.514921 -30.30569) (xy 138.505715 -30.325721) (xy 138.505184 -30.336744) (xy 138.505184 -30.641036)
			(xy 138.505707 -30.652057) (xy 138.514938 -30.672072) (xy 138.522964 -30.679644) (xy 138.590274 -30.737048)
			(xy 138.61161 -30.743144) (xy 138.622532 -30.741366) (xy 138.63717 -30.739226) (xy 138.666667 -30.736938)
			(xy 138.68146 -30.736794) (xy 138.708715 -30.737251) (xy 138.76267 -30.745003) (xy 138.814973 -30.760356)
			(xy 138.864559 -30.782996) (xy 138.910417 -30.812463) (xy 138.951615 -30.848157) (xy 138.987313 -30.889351)
			(xy 139.016785 -30.935206) (xy 139.03943 -30.984789) (xy 139.054788 -31.03709) (xy 139.062547 -31.091045)
			(xy 139.062547 -31.145555) (xy 139.054788 -31.19951) (xy 139.03943 -31.251811) (xy 139.016785 -31.301394)
			(xy 138.987313 -31.347249) (xy 138.951615 -31.388443) (xy 138.910417 -31.424137) (xy 138.864559 -31.453604)
			(xy 138.814973 -31.476244) (xy 138.76267 -31.491597) (xy 138.708715 -31.499349) (xy 138.68146 -31.49981)
			(xy 138.655533 -31.499403) (xy 138.604155 -31.492392) (xy 138.554199 -31.47849) (xy 138.506585 -31.457954)
			(xy 138.462189 -31.431161) (xy 138.421828 -31.398606) (xy 138.386246 -31.360886) (xy 138.370818 -31.340044)
			(xy 138.365075 -31.332715) (xy 138.349575 -31.322428) (xy 138.340592 -31.319978) (xy 138.310366 -31.31312)
			(xy 138.301089 -31.311374) (xy 138.282426 -31.314112) (xy 138.274044 -31.318454) (xy 138.24808 -31.332772)
			(xy 138.193224 -31.355277) (xy 138.135917 -31.370496) (xy 138.077123 -31.378175) (xy 138.047476 -31.378652)
			(xy 138.017834 -31.378129) (xy 137.959053 -31.370415) (xy 137.901755 -31.355196) (xy 137.846894 -31.332724)
			(xy 137.820908 -31.318454) (xy 137.812497 -31.314202) (xy 137.793865 -31.311471) (xy 137.784586 -31.31312)
			(xy 137.75436 -31.319978) (xy 137.745372 -31.322419) (xy 137.729865 -31.332703) (xy 137.724134 -31.340044)
			(xy 137.708723 -31.3609) (xy 137.67315 -31.398634) (xy 137.632791 -31.431198) (xy 137.588392 -31.457992)
			(xy 137.540771 -31.478522) (xy 137.490806 -31.492408) (xy 137.439421 -31.499395) (xy 137.413492 -31.49981)
			(xy 137.386241 -31.49932) (xy 137.332295 -31.491562) (xy 137.280001 -31.476207) (xy 137.230425 -31.453565)
			(xy 137.184576 -31.424099) (xy 137.143387 -31.388407) (xy 137.107696 -31.347218) (xy 137.078231 -31.301368)
			(xy 137.055591 -31.251791) (xy 137.040236 -31.199497) (xy 137.03248 -31.145551) (xy 137.03248 -31.091049)
			(xy 137.040236 -31.037103) (xy 137.055591 -30.984809) (xy 137.078231 -30.935232) (xy 137.107696 -30.889382)
			(xy 137.143387 -30.848193) (xy 137.184576 -30.812501) (xy 137.230425 -30.783035) (xy 137.280001 -30.760393)
			(xy 137.332295 -30.745038) (xy 137.386241 -30.73728) (xy 137.413492 -30.736794) (xy 137.428285 -30.736929)
			(xy 137.457783 -30.739218) (xy 137.47242 -30.741366) (xy 137.483342 -30.743144) (xy 137.504678 -30.737048)
			(xy 137.571988 -30.679644) (xy 137.579988 -30.672051) (xy 137.58922 -30.65205) (xy 137.589768 -30.641036)
			(xy 137.589768 -30.336744) (xy 137.589216 -30.325727) (xy 137.580007 -30.305709) (xy 137.571988 -30.298136)
			(xy 137.504678 -30.240732) (xy 137.483342 -30.234636) (xy 137.47242 -30.236414) (xy 137.457783 -30.238559)
			(xy 137.428285 -30.240844) (xy 137.413492 -30.240986) (xy 137.38624 -30.240544) (xy 137.33229 -30.232786)
			(xy 137.279993 -30.217429) (xy 137.230414 -30.194786) (xy 137.184562 -30.165318) (xy 137.14337 -30.129624)
			(xy 137.107677 -30.088432) (xy 137.07821 -30.042579) (xy 137.055568 -29.993) (xy 137.040213 -29.940703)
			(xy 137.032456 -29.886752) (xy 132.620001 -29.886752) (xy 132.603271 -29.900675) (xy 132.555665 -29.929729)
			(xy 132.504336 -29.951541) (xy 132.450379 -29.965647) (xy 132.394942 -29.971747) (xy 132.339208 -29.96971)
			(xy 132.284365 -29.95958) (xy 132.231581 -29.941573) (xy 132.181981 -29.916072) (xy 132.136623 -29.883621)
			(xy 132.096474 -29.844912) (xy 132.062388 -29.800769) (xy 132.035092 -29.752134) (xy 132.015169 -29.700043)
			(xy 132.003043 -29.645606) (xy 131.998972 -29.589984) (xy 130.730498 -29.589984) (xy 130.729989 -29.61787)
			(xy 130.721869 -29.673046) (xy 130.705801 -29.726453) (xy 130.682129 -29.77695) (xy 130.651356 -29.823463)
			(xy 130.614139 -29.865) (xy 130.571271 -29.900675) (xy 130.523665 -29.929729) (xy 130.472336 -29.951541)
			(xy 130.418379 -29.965647) (xy 130.362942 -29.971747) (xy 130.307208 -29.96971) (xy 130.252365 -29.95958)
			(xy 130.199581 -29.941573) (xy 130.149981 -29.916072) (xy 130.104623 -29.883621) (xy 130.064474 -29.844912)
			(xy 130.030388 -29.800769) (xy 130.003092 -29.752134) (xy 129.983169 -29.700043) (xy 129.971043 -29.645606)
			(xy 129.966972 -29.589984) (xy 128.226566 -29.589984) (xy 128.226057 -29.61787) (xy 128.217937 -29.673046)
			(xy 128.201869 -29.726453) (xy 128.178197 -29.77695) (xy 128.147424 -29.823463) (xy 128.110207 -29.865)
			(xy 128.067339 -29.900675) (xy 128.019733 -29.929729) (xy 127.968404 -29.951541) (xy 127.914447 -29.965647)
			(xy 127.85901 -29.971747) (xy 127.803276 -29.96971) (xy 127.748433 -29.95958) (xy 127.695649 -29.941573)
			(xy 127.646049 -29.916072) (xy 127.600691 -29.883621) (xy 127.560542 -29.844912) (xy 127.526456 -29.800769)
			(xy 127.49916 -29.752134) (xy 127.479237 -29.700043) (xy 127.467111 -29.645606) (xy 127.46304 -29.589984)
			(xy 126.243588 -29.589984) (xy 126.243588 -30.899608) (xy 128.307844 -30.899608) (xy 128.311915 -30.843986)
			(xy 128.324041 -30.789549) (xy 128.343964 -30.737458) (xy 128.37126 -30.688823) (xy 128.405346 -30.64468)
			(xy 128.445495 -30.605971) (xy 128.490853 -30.57352) (xy 128.540453 -30.548019) (xy 128.593237 -30.530012)
			(xy 128.64808 -30.519882) (xy 128.703814 -30.517845) (xy 128.759251 -30.523945) (xy 128.813208 -30.538051)
			(xy 128.864537 -30.559863) (xy 128.912143 -30.588917) (xy 128.955011 -30.624592) (xy 128.992228 -30.666129)
			(xy 129.023001 -30.712642) (xy 129.046673 -30.763139) (xy 129.062741 -30.816546) (xy 129.070861 -30.871722)
			(xy 129.07137 -30.899608) (xy 129.070861 -30.927494) (xy 129.062741 -30.98267) (xy 129.046673 -31.036077)
			(xy 129.023001 -31.086574) (xy 128.992228 -31.133087) (xy 128.955011 -31.174624) (xy 128.912143 -31.210299)
			(xy 128.864537 -31.239353) (xy 128.813208 -31.261165) (xy 128.759251 -31.275271) (xy 128.703814 -31.281371)
			(xy 128.64808 -31.279334) (xy 128.593237 -31.269204) (xy 128.540453 -31.251197) (xy 128.490853 -31.225696)
			(xy 128.445495 -31.193245) (xy 128.405346 -31.154536) (xy 128.37126 -31.110393) (xy 128.343964 -31.061758)
			(xy 128.324041 -31.009667) (xy 128.311915 -30.95523) (xy 128.307844 -30.899608) (xy 126.243588 -30.899608)
			(xy 126.243588 -31.390082) (xy 129.966972 -31.390082) (xy 129.971043 -31.33446) (xy 129.983169 -31.280023)
			(xy 130.003092 -31.227932) (xy 130.030388 -31.179297) (xy 130.064474 -31.135154) (xy 130.104623 -31.096445)
			(xy 130.149981 -31.063994) (xy 130.199581 -31.038493) (xy 130.252365 -31.020486) (xy 130.307208 -31.010356)
			(xy 130.362942 -31.008319) (xy 130.418379 -31.014419) (xy 130.472336 -31.028525) (xy 130.523665 -31.050337)
			(xy 130.571271 -31.079391) (xy 130.614139 -31.115066) (xy 130.651356 -31.156603) (xy 130.682129 -31.203116)
			(xy 130.705801 -31.253613) (xy 130.721869 -31.30702) (xy 130.729989 -31.362196) (xy 130.730498 -31.390082)
			(xy 131.998972 -31.390082) (xy 132.003043 -31.33446) (xy 132.015169 -31.280023) (xy 132.035092 -31.227932)
			(xy 132.062388 -31.179297) (xy 132.096474 -31.135154) (xy 132.136623 -31.096445) (xy 132.181981 -31.063994)
			(xy 132.231581 -31.038493) (xy 132.284365 -31.020486) (xy 132.339208 -31.010356) (xy 132.394942 -31.008319)
			(xy 132.450379 -31.014419) (xy 132.504336 -31.028525) (xy 132.555665 -31.050337) (xy 132.603271 -31.079391)
			(xy 132.646139 -31.115066) (xy 132.683356 -31.156603) (xy 132.714129 -31.203116) (xy 132.737801 -31.253613)
			(xy 132.753869 -31.30702) (xy 132.761989 -31.362196) (xy 132.762498 -31.390082) (xy 132.761989 -31.417968)
			(xy 132.753869 -31.473144) (xy 132.737801 -31.526551) (xy 132.714129 -31.577048) (xy 132.683356 -31.623561)
			(xy 132.646139 -31.665098) (xy 132.627928 -31.680253) (xy 134.39035 -31.680253) (xy 134.39035 -31.625747)
			(xy 134.398106 -31.571797) (xy 134.413462 -31.5195) (xy 134.436104 -31.46992) (xy 134.465571 -31.424067)
			(xy 134.501263 -31.382874) (xy 134.542454 -31.34718) (xy 134.588306 -31.317711) (xy 134.637885 -31.295068)
			(xy 134.690182 -31.27971) (xy 134.744132 -31.271951) (xy 134.771384 -31.271464) (xy 134.797311 -31.271882)
			(xy 134.84869 -31.278887) (xy 134.898647 -31.292785) (xy 134.946262 -31.313318) (xy 134.990659 -31.34011)
			(xy 135.031019 -31.372666) (xy 135.0666 -31.410387) (xy 135.082026 -31.43123) (xy 135.087793 -31.438536)
			(xy 135.103276 -31.448837) (xy 135.112252 -31.451296) (xy 135.142478 -31.458154) (xy 135.151753 -31.459915)
			(xy 135.170418 -31.457165) (xy 135.1788 -31.45282) (xy 135.204793 -31.438578) (xy 135.259661 -31.416163)
			(xy 135.316959 -31.401002) (xy 135.375733 -31.39335) (xy 135.405368 -31.392876) (xy 135.435006 -31.39333)
			(xy 135.493788 -31.400952) (xy 135.551092 -31.416112) (xy 135.605953 -31.438555) (xy 135.631936 -31.45282)
			(xy 135.640359 -31.457043) (xy 135.658981 -31.459792) (xy 135.668258 -31.458154) (xy 135.698484 -31.451296)
			(xy 135.707481 -31.448881) (xy 135.722983 -31.438578) (xy 135.72871 -31.43123) (xy 135.744087 -31.410347)
			(xy 135.779666 -31.372616) (xy 135.820031 -31.340054) (xy 135.864437 -31.313264) (xy 135.912063 -31.292739)
			(xy 135.962032 -31.278857) (xy 136.013421 -31.271876) (xy 136.039352 -31.271464) (xy 136.066605 -31.27198)
			(xy 136.120557 -31.279731) (xy 136.172857 -31.295082) (xy 136.22244 -31.31772) (xy 136.268295 -31.347184)
			(xy 136.309491 -31.382875) (xy 136.345187 -31.424066) (xy 136.374657 -31.469918) (xy 136.397302 -31.519498)
			(xy 136.412659 -31.571796) (xy 136.420417 -31.625747) (xy 136.420417 -31.680253) (xy 136.412659 -31.734204)
			(xy 136.397302 -31.786502) (xy 136.374657 -31.836082) (xy 136.345187 -31.881934) (xy 136.309491 -31.923125)
			(xy 136.268295 -31.958816) (xy 136.22244 -31.98828) (xy 136.172857 -32.010918) (xy 136.120557 -32.026269)
			(xy 136.066605 -32.03402) (xy 136.039352 -32.03448) (xy 136.024559 -32.034341) (xy 135.995061 -32.032054)
			(xy 135.980424 -32.029908) (xy 135.969502 -32.02813) (xy 135.948166 -32.034226) (xy 135.880856 -32.09163)
			(xy 135.872815 -32.099185) (xy 135.863608 -32.119215) (xy 135.863076 -32.130238) (xy 135.863076 -32.43453)
			(xy 135.863605 -32.44555) (xy 135.872832 -32.465566) (xy 135.880856 -32.473138) (xy 135.948166 -32.530542)
			(xy 135.969502 -32.536638) (xy 135.980424 -32.53486) (xy 135.995062 -32.532721) (xy 136.024559 -32.530432)
			(xy 136.039352 -32.530288) (xy 136.066607 -32.530756) (xy 136.120562 -32.538507) (xy 136.172865 -32.553859)
			(xy 136.222451 -32.576499) (xy 136.26831 -32.605965) (xy 136.309508 -32.641658) (xy 136.345206 -32.682852)
			(xy 136.374678 -32.728707) (xy 136.397324 -32.77829) (xy 136.412682 -32.830591) (xy 136.420441 -32.884545)
			(xy 136.420441 -32.939055) (xy 136.412682 -32.993009) (xy 136.397324 -33.04531) (xy 136.374678 -33.094893)
			(xy 136.345206 -33.140748) (xy 136.309508 -33.181942) (xy 136.26831 -33.217635) (xy 136.222451 -33.247101)
			(xy 136.172865 -33.269741) (xy 136.120562 -33.285093) (xy 136.066607 -33.292844) (xy 136.039352 -33.293304)
			(xy 136.013427 -33.292831) (xy 135.962052 -33.285832) (xy 135.912097 -33.271942) (xy 135.864483 -33.251416)
			(xy 135.820086 -33.224634) (xy 135.779724 -33.192087) (xy 135.744139 -33.154376) (xy 135.72871 -33.133538)
			(xy 135.722971 -33.126206) (xy 135.707468 -33.115921) (xy 135.698484 -33.113472) (xy 135.668258 -33.106614)
			(xy 135.658982 -33.104864) (xy 135.640318 -33.107605) (xy 135.631936 -33.111948) (xy 135.605954 -33.126211)
			(xy 135.551083 -33.148622) (xy 135.493781 -33.163777) (xy 135.435004 -33.171422) (xy 135.405368 -33.171892)
			(xy 135.375731 -33.171427) (xy 135.316948 -33.163808) (xy 135.259645 -33.148652) (xy 135.204783 -33.126212)
			(xy 135.1788 -33.111948) (xy 135.170391 -33.107692) (xy 135.151758 -33.104964) (xy 135.142478 -33.106614)
			(xy 135.112252 -33.113472) (xy 135.103263 -33.115912) (xy 135.087757 -33.126197) (xy 135.082026 -33.133538)
			(xy 135.066618 -33.154397) (xy 135.031045 -33.19213) (xy 134.990686 -33.224695) (xy 134.946286 -33.251489)
			(xy 134.898664 -33.272018) (xy 134.848699 -33.285904) (xy 134.797314 -33.292889) (xy 134.771384 -33.293304)
			(xy 134.744133 -33.292825) (xy 134.690187 -33.285067) (xy 134.637893 -33.26971) (xy 134.588318 -33.247068)
			(xy 134.542469 -33.217601) (xy 134.50128 -33.181909) (xy 134.46559 -33.140719) (xy 134.436125 -33.094868)
			(xy 134.413484 -33.045292) (xy 134.39813 -32.992998) (xy 134.390374 -32.939051) (xy 134.390374 -32.884549)
			(xy 134.39813 -32.830602) (xy 134.413484 -32.778308) (xy 134.436125 -32.728732) (xy 134.46559 -32.682881)
			(xy 134.50128 -32.641691) (xy 134.542469 -32.605999) (xy 134.588318 -32.576532) (xy 134.637893 -32.55389)
			(xy 134.690187 -32.538533) (xy 134.744133 -32.530775) (xy 134.771384 -32.530288) (xy 134.786177 -32.530424)
			(xy 134.815675 -32.532712) (xy 134.830312 -32.53486) (xy 134.841234 -32.536638) (xy 134.86257 -32.530542)
			(xy 134.92988 -32.473138) (xy 134.937896 -32.465561) (xy 134.947116 -32.445547) (xy 134.94766 -32.43453)
			(xy 134.94766 -32.130238) (xy 134.947114 -32.11922) (xy 134.937901 -32.099202) (xy 134.92988 -32.09163)
			(xy 134.86257 -32.034226) (xy 134.841234 -32.02813) (xy 134.830312 -32.029908) (xy 134.815673 -32.032042)
			(xy 134.786177 -32.034335) (xy 134.771384 -32.03448) (xy 134.744131 -32.034049) (xy 134.690182 -32.02629)
			(xy 134.637885 -32.010932) (xy 134.588306 -31.988289) (xy 134.542454 -31.95882) (xy 134.501263 -31.923126)
			(xy 134.465571 -31.881933) (xy 134.436104 -31.83608) (xy 134.413462 -31.7865) (xy 134.398106 -31.734203)
			(xy 134.39035 -31.680253) (xy 132.627928 -31.680253) (xy 132.603271 -31.700773) (xy 132.555665 -31.729827)
			(xy 132.504336 -31.751639) (xy 132.450379 -31.765745) (xy 132.394942 -31.771845) (xy 132.339208 -31.769808)
			(xy 132.284365 -31.759678) (xy 132.231581 -31.741671) (xy 132.181981 -31.71617) (xy 132.136623 -31.683719)
			(xy 132.096474 -31.64501) (xy 132.062388 -31.600867) (xy 132.035092 -31.552232) (xy 132.015169 -31.500141)
			(xy 132.003043 -31.445704) (xy 131.998972 -31.390082) (xy 130.730498 -31.390082) (xy 130.729989 -31.417968)
			(xy 130.721869 -31.473144) (xy 130.705801 -31.526551) (xy 130.682129 -31.577048) (xy 130.651356 -31.623561)
			(xy 130.614139 -31.665098) (xy 130.571271 -31.700773) (xy 130.523665 -31.729827) (xy 130.472336 -31.751639)
			(xy 130.418379 -31.765745) (xy 130.362942 -31.771845) (xy 130.307208 -31.769808) (xy 130.252365 -31.759678)
			(xy 130.199581 -31.741671) (xy 130.149981 -31.71617) (xy 130.104623 -31.683719) (xy 130.064474 -31.64501)
			(xy 130.030388 -31.600867) (xy 130.003092 -31.552232) (xy 129.983169 -31.500141) (xy 129.971043 -31.445704)
			(xy 129.966972 -31.390082) (xy 126.243588 -31.390082) (xy 126.243588 -33.19018) (xy 127.77419 -33.19018)
			(xy 127.778261 -33.134558) (xy 127.790387 -33.080121) (xy 127.81031 -33.02803) (xy 127.837606 -32.979395)
			(xy 127.871692 -32.935252) (xy 127.911841 -32.896543) (xy 127.957199 -32.864092) (xy 128.006799 -32.838591)
			(xy 128.059583 -32.820584) (xy 128.114426 -32.810454) (xy 128.17016 -32.808417) (xy 128.225597 -32.814517)
			(xy 128.279554 -32.828623) (xy 128.330883 -32.850435) (xy 128.378489 -32.879489) (xy 128.421357 -32.915164)
			(xy 128.458574 -32.956701) (xy 128.489347 -33.003214) (xy 128.513019 -33.053711) (xy 128.529087 -33.107118)
			(xy 128.537207 -33.162294) (xy 128.537716 -33.19018) (xy 129.966972 -33.19018) (xy 129.971043 -33.134558)
			(xy 129.983169 -33.080121) (xy 130.003092 -33.02803) (xy 130.030388 -32.979395) (xy 130.064474 -32.935252)
			(xy 130.104623 -32.896543) (xy 130.149981 -32.864092) (xy 130.199581 -32.838591) (xy 130.252365 -32.820584)
			(xy 130.307208 -32.810454) (xy 130.362942 -32.808417) (xy 130.418379 -32.814517) (xy 130.472336 -32.828623)
			(xy 130.523665 -32.850435) (xy 130.571271 -32.879489) (xy 130.614139 -32.915164) (xy 130.651356 -32.956701)
			(xy 130.682129 -33.003214) (xy 130.705801 -33.053711) (xy 130.721869 -33.107118) (xy 130.729989 -33.162294)
			(xy 130.730498 -33.19018) (xy 131.998972 -33.19018) (xy 132.003043 -33.134558) (xy 132.015169 -33.080121)
			(xy 132.035092 -33.02803) (xy 132.062388 -32.979395) (xy 132.096474 -32.935252) (xy 132.136623 -32.896543)
			(xy 132.181981 -32.864092) (xy 132.231581 -32.838591) (xy 132.284365 -32.820584) (xy 132.339208 -32.810454)
			(xy 132.394942 -32.808417) (xy 132.450379 -32.814517) (xy 132.504336 -32.828623) (xy 132.555665 -32.850435)
			(xy 132.603271 -32.879489) (xy 132.646139 -32.915164) (xy 132.683356 -32.956701) (xy 132.714129 -33.003214)
			(xy 132.737801 -33.053711) (xy 132.753869 -33.107118) (xy 132.761989 -33.162294) (xy 132.762498 -33.19018)
			(xy 132.761989 -33.218066) (xy 132.753869 -33.273242) (xy 132.737801 -33.326649) (xy 132.714129 -33.377146)
			(xy 132.683356 -33.423659) (xy 132.646139 -33.465196) (xy 132.619995 -33.486953) (xy 137.032452 -33.486953)
			(xy 137.032452 -33.432447) (xy 137.040209 -33.378497) (xy 137.055564 -33.326199) (xy 137.078207 -33.276619)
			(xy 137.107674 -33.230766) (xy 137.143367 -33.189573) (xy 137.184559 -33.153879) (xy 137.230412 -33.12441)
			(xy 137.279991 -33.101767) (xy 137.332289 -33.08641) (xy 137.386239 -33.078652) (xy 137.413492 -33.078166)
			(xy 137.439419 -33.078577) (xy 137.490798 -33.085584) (xy 137.540756 -33.099482) (xy 137.588371 -33.120017)
			(xy 137.632768 -33.14681) (xy 137.673128 -33.179367) (xy 137.708708 -33.217089) (xy 137.724134 -33.237932)
			(xy 137.729898 -33.245241) (xy 137.745383 -33.25554) (xy 137.75436 -33.257998) (xy 137.784586 -33.264856)
			(xy 137.79386 -33.266621) (xy 137.812526 -33.263868) (xy 137.820908 -33.259522) (xy 137.846885 -33.245229)
			(xy 137.901737 -33.222717) (xy 137.959039 -33.20749) (xy 138.01783 -33.199804) (xy 138.047476 -33.199324)
			(xy 138.077118 -33.199828) (xy 138.1359 -33.207548) (xy 138.193198 -33.222773) (xy 138.248059 -33.245249)
			(xy 138.274044 -33.259522) (xy 138.282465 -33.263749) (xy 138.301088 -33.266496) (xy 138.310366 -33.264856)
			(xy 138.340592 -33.257998) (xy 138.34959 -33.255585) (xy 138.365092 -33.245281) (xy 138.370818 -33.237932)
			(xy 138.386252 -33.217093) (xy 138.421821 -33.17936) (xy 138.462176 -33.146795) (xy 138.506572 -33.119999)
			(xy 138.554189 -33.099467) (xy 138.60415 -33.085576) (xy 138.655532 -33.078584) (xy 138.68146 -33.078166)
			(xy 138.708713 -33.078679) (xy 138.762664 -33.08643) (xy 138.814964 -33.101782) (xy 138.864545 -33.124421)
			(xy 138.9104 -33.153885) (xy 138.951595 -33.189577) (xy 138.987291 -33.230768) (xy 139.01676 -33.27662)
			(xy 139.039404 -33.326199) (xy 139.054761 -33.378496) (xy 139.062519 -33.432447) (xy 139.062519 -33.486953)
			(xy 139.054761 -33.540904) (xy 139.039404 -33.593201) (xy 139.01676 -33.64278) (xy 138.987291 -33.688632)
			(xy 138.951595 -33.729823) (xy 138.9104 -33.765515) (xy 138.864545 -33.794979) (xy 138.814964 -33.817618)
			(xy 138.762664 -33.83297) (xy 138.708713 -33.840721) (xy 138.68146 -33.841182) (xy 138.666667 -33.841042)
			(xy 138.637169 -33.838756) (xy 138.622532 -33.83661) (xy 138.61161 -33.834832) (xy 138.590274 -33.840928)
			(xy 138.522964 -33.898332) (xy 138.514923 -33.905888) (xy 138.505716 -33.925917) (xy 138.505184 -33.93694)
			(xy 138.505184 -34.241232) (xy 138.505709 -34.252252) (xy 138.514938 -34.272268) (xy 138.522964 -34.27984)
			(xy 138.590274 -34.337244) (xy 138.61161 -34.34334) (xy 138.622532 -34.341562) (xy 138.63717 -34.339422)
			(xy 138.666667 -34.337134) (xy 138.68146 -34.33699) (xy 138.708715 -34.337455) (xy 138.76267 -34.345207)
			(xy 138.814972 -34.360559) (xy 138.864557 -34.383199) (xy 138.910415 -34.412666) (xy 138.951612 -34.44836)
			(xy 138.98731 -34.489553) (xy 139.016781 -34.535408) (xy 139.039427 -34.584991) (xy 139.054785 -34.637291)
			(xy 139.062543 -34.691245) (xy 139.062543 -34.745755) (xy 139.054785 -34.799709) (xy 139.039427 -34.852009)
			(xy 139.016781 -34.901592) (xy 138.98731 -34.947447) (xy 138.951612 -34.98864) (xy 138.910415 -35.024334)
			(xy 138.864557 -35.053801) (xy 138.814972 -35.076441) (xy 138.76267 -35.091793) (xy 138.708715 -35.099545)
			(xy 138.68146 -35.100006) (xy 138.655533 -35.099601) (xy 138.604155 -35.092589) (xy 138.554199 -35.078687)
			(xy 138.506584 -35.058151) (xy 138.462188 -35.031358) (xy 138.421828 -34.998802) (xy 138.386246 -34.961082)
			(xy 138.370818 -34.94024) (xy 138.365076 -34.932911) (xy 138.349575 -34.922624) (xy 138.340592 -34.920174)
			(xy 138.310366 -34.913316) (xy 138.301089 -34.91157) (xy 138.282426 -34.914308) (xy 138.274044 -34.91865)
			(xy 138.24808 -34.932968) (xy 138.193223 -34.955472) (xy 138.135917 -34.970692) (xy 138.077123 -34.978371)
			(xy 138.047476 -34.978848) (xy 138.017834 -34.978326) (xy 137.959053 -34.970611) (xy 137.901755 -34.955392)
			(xy 137.846894 -34.932921) (xy 137.820908 -34.91865) (xy 137.812497 -34.914398) (xy 137.793865 -34.911668)
			(xy 137.784586 -34.913316) (xy 137.75436 -34.920174) (xy 137.745372 -34.922617) (xy 137.729866 -34.9329)
			(xy 137.724134 -34.94024) (xy 137.708722 -34.961095) (xy 137.673149 -34.998829) (xy 137.632791 -35.031394)
			(xy 137.588391 -35.058188) (xy 137.54077 -35.078718) (xy 137.490806 -35.092604) (xy 137.439421 -35.099591)
			(xy 137.413492 -35.100006) (xy 137.386241 -35.099524) (xy 137.332294 -35.091766) (xy 137.28 -35.07641)
			(xy 137.230423 -35.053769) (xy 137.184574 -35.024302) (xy 137.143384 -34.98861) (xy 137.107693 -34.94742)
			(xy 137.078228 -34.90157) (xy 137.055587 -34.851993) (xy 137.040232 -34.799698) (xy 137.032476 -34.745751)
			(xy 137.032476 -34.691249) (xy 137.040232 -34.637302) (xy 137.055587 -34.585007) (xy 137.078228 -34.53543)
			(xy 137.107693 -34.48958) (xy 137.143384 -34.44839) (xy 137.184574 -34.412698) (xy 137.230423 -34.383231)
			(xy 137.28 -34.36059) (xy 137.332294 -34.345234) (xy 137.386241 -34.337476) (xy 137.413492 -34.33699)
			(xy 137.428285 -34.337125) (xy 137.457783 -34.339414) (xy 137.47242 -34.341562) (xy 137.483342 -34.34334)
			(xy 137.504678 -34.337244) (xy 137.571988 -34.27984) (xy 137.579989 -34.272248) (xy 137.589221 -34.252246)
			(xy 137.589768 -34.241232) (xy 137.589768 -33.93694) (xy 137.589218 -33.925922) (xy 137.580008 -33.905905)
			(xy 137.571988 -33.898332) (xy 137.504678 -33.840928) (xy 137.483342 -33.834832) (xy 137.47242 -33.83661)
			(xy 137.457783 -33.838755) (xy 137.428285 -33.84104) (xy 137.413492 -33.841182) (xy 137.386239 -33.840748)
			(xy 137.332289 -33.83299) (xy 137.279991 -33.817633) (xy 137.230412 -33.79499) (xy 137.184559 -33.765521)
			(xy 137.143367 -33.729827) (xy 137.107674 -33.688634) (xy 137.078207 -33.642781) (xy 137.055564 -33.593201)
			(xy 137.040209 -33.540903) (xy 137.032452 -33.486953) (xy 132.619995 -33.486953) (xy 132.603271 -33.500871)
			(xy 132.555665 -33.529925) (xy 132.504336 -33.551737) (xy 132.450379 -33.565843) (xy 132.394942 -33.571943)
			(xy 132.339208 -33.569906) (xy 132.284365 -33.559776) (xy 132.231581 -33.541769) (xy 132.181981 -33.516268)
			(xy 132.136623 -33.483817) (xy 132.096474 -33.445108) (xy 132.062388 -33.400965) (xy 132.035092 -33.35233)
			(xy 132.015169 -33.300239) (xy 132.003043 -33.245802) (xy 131.998972 -33.19018) (xy 130.730498 -33.19018)
			(xy 130.729989 -33.218066) (xy 130.721869 -33.273242) (xy 130.705801 -33.326649) (xy 130.682129 -33.377146)
			(xy 130.651356 -33.423659) (xy 130.614139 -33.465196) (xy 130.571271 -33.500871) (xy 130.523665 -33.529925)
			(xy 130.472336 -33.551737) (xy 130.418379 -33.565843) (xy 130.362942 -33.571943) (xy 130.307208 -33.569906)
			(xy 130.252365 -33.559776) (xy 130.199581 -33.541769) (xy 130.149981 -33.516268) (xy 130.104623 -33.483817)
			(xy 130.064474 -33.445108) (xy 130.030388 -33.400965) (xy 130.003092 -33.35233) (xy 129.983169 -33.300239)
			(xy 129.971043 -33.245802) (xy 129.966972 -33.19018) (xy 128.537716 -33.19018) (xy 128.537207 -33.218066)
			(xy 128.529087 -33.273242) (xy 128.513019 -33.326649) (xy 128.489347 -33.377146) (xy 128.458574 -33.423659)
			(xy 128.421357 -33.465196) (xy 128.378489 -33.500871) (xy 128.330883 -33.529925) (xy 128.279554 -33.551737)
			(xy 128.225597 -33.565843) (xy 128.17016 -33.571943) (xy 128.114426 -33.569906) (xy 128.059583 -33.559776)
			(xy 128.006799 -33.541769) (xy 127.957199 -33.516268) (xy 127.911841 -33.483817) (xy 127.871692 -33.445108)
			(xy 127.837606 -33.400965) (xy 127.81031 -33.35233) (xy 127.790387 -33.300239) (xy 127.778261 -33.245802)
			(xy 127.77419 -33.19018) (xy 126.243588 -33.19018) (xy 126.243588 -34.990024) (xy 127.77292 -34.990024)
			(xy 127.776991 -34.934402) (xy 127.789117 -34.879965) (xy 127.80904 -34.827874) (xy 127.836336 -34.779239)
			(xy 127.870422 -34.735096) (xy 127.910571 -34.696387) (xy 127.955929 -34.663936) (xy 128.005529 -34.638435)
			(xy 128.058313 -34.620428) (xy 128.113156 -34.610298) (xy 128.16889 -34.608261) (xy 128.224327 -34.614361)
			(xy 128.278284 -34.628467) (xy 128.329613 -34.650279) (xy 128.377219 -34.679333) (xy 128.420087 -34.715008)
			(xy 128.457304 -34.756545) (xy 128.488077 -34.803058) (xy 128.511749 -34.853555) (xy 128.527817 -34.906962)
			(xy 128.535937 -34.962138) (xy 128.536446 -34.990024) (xy 128.967736 -34.990024) (xy 128.971807 -34.934402)
			(xy 128.983933 -34.879965) (xy 129.003856 -34.827874) (xy 129.031152 -34.779239) (xy 129.065238 -34.735096)
			(xy 129.105387 -34.696387) (xy 129.150745 -34.663936) (xy 129.200345 -34.638435) (xy 129.253129 -34.620428)
			(xy 129.307972 -34.610298) (xy 129.363706 -34.608261) (xy 129.419143 -34.614361) (xy 129.4731 -34.628467)
			(xy 129.524429 -34.650279) (xy 129.572035 -34.679333) (xy 129.614903 -34.715008) (xy 129.65212 -34.756545)
			(xy 129.682893 -34.803058) (xy 129.706565 -34.853555) (xy 129.722633 -34.906962) (xy 129.730753 -34.962138)
			(xy 129.731262 -34.990024) (xy 131.998972 -34.990024) (xy 132.003043 -34.934402) (xy 132.015169 -34.879965)
			(xy 132.035092 -34.827874) (xy 132.062388 -34.779239) (xy 132.096474 -34.735096) (xy 132.136623 -34.696387)
			(xy 132.181981 -34.663936) (xy 132.231581 -34.638435) (xy 132.284365 -34.620428) (xy 132.339208 -34.610298)
			(xy 132.394942 -34.608261) (xy 132.450379 -34.614361) (xy 132.504336 -34.628467) (xy 132.555665 -34.650279)
			(xy 132.603271 -34.679333) (xy 132.646139 -34.715008) (xy 132.683356 -34.756545) (xy 132.714129 -34.803058)
			(xy 132.737801 -34.853555) (xy 132.753869 -34.906962) (xy 132.761989 -34.962138) (xy 132.762498 -34.990024)
			(xy 132.761989 -35.01791) (xy 132.753869 -35.073086) (xy 132.737801 -35.126493) (xy 132.714129 -35.17699)
			(xy 132.683356 -35.223503) (xy 132.646139 -35.26504) (xy 132.603271 -35.300715) (xy 132.555665 -35.329769)
			(xy 132.504336 -35.351581) (xy 132.450379 -35.365687) (xy 132.394942 -35.371787) (xy 132.339208 -35.36975)
			(xy 132.284365 -35.35962) (xy 132.231581 -35.341613) (xy 132.181981 -35.316112) (xy 132.136623 -35.283661)
			(xy 132.096474 -35.244952) (xy 132.062388 -35.200809) (xy 132.035092 -35.152174) (xy 132.015169 -35.100083)
			(xy 132.003043 -35.045646) (xy 131.998972 -34.990024) (xy 129.731262 -34.990024) (xy 129.730753 -35.01791)
			(xy 129.722633 -35.073086) (xy 129.706565 -35.126493) (xy 129.682893 -35.17699) (xy 129.65212 -35.223503)
			(xy 129.614903 -35.26504) (xy 129.572035 -35.300715) (xy 129.524429 -35.329769) (xy 129.4731 -35.351581)
			(xy 129.419143 -35.365687) (xy 129.363706 -35.371787) (xy 129.307972 -35.36975) (xy 129.253129 -35.35962)
			(xy 129.200345 -35.341613) (xy 129.150745 -35.316112) (xy 129.105387 -35.283661) (xy 129.065238 -35.244952)
			(xy 129.031152 -35.200809) (xy 129.003856 -35.152174) (xy 128.983933 -35.100083) (xy 128.971807 -35.045646)
			(xy 128.967736 -34.990024) (xy 128.536446 -34.990024) (xy 128.535937 -35.01791) (xy 128.527817 -35.073086)
			(xy 128.511749 -35.126493) (xy 128.488077 -35.17699) (xy 128.457304 -35.223503) (xy 128.420087 -35.26504)
			(xy 128.377219 -35.300715) (xy 128.329613 -35.329769) (xy 128.278284 -35.351581) (xy 128.224327 -35.365687)
			(xy 128.16889 -35.371787) (xy 128.113156 -35.36975) (xy 128.058313 -35.35962) (xy 128.005529 -35.341613)
			(xy 127.955929 -35.316112) (xy 127.910571 -35.283661) (xy 127.870422 -35.244952) (xy 127.836336 -35.200809)
			(xy 127.80904 -35.152174) (xy 127.789117 -35.100083) (xy 127.776991 -35.045646) (xy 127.77292 -34.990024)
			(xy 126.243588 -34.990024) (xy 126.243588 -38.193438) (xy 127.198371 -38.193438) (xy 127.198371 -38.106562)
			(xy 127.206387 -38.020058) (xy 127.22235 -37.934662) (xy 127.246125 -37.851103) (xy 127.277508 -37.770094)
			(xy 127.316232 -37.692327) (xy 127.361967 -37.618464) (xy 127.414322 -37.549137) (xy 127.47285 -37.484936)
			(xy 127.537052 -37.426409) (xy 127.606381 -37.374056) (xy 127.680244 -37.328323) (xy 127.758012 -37.2896)
			(xy 127.839022 -37.258219) (xy 127.922581 -37.234445) (xy 128.007977 -37.218484) (xy 128.094482 -37.21047)
			(xy 128.13792 -37.209984) (xy 128.215898 -37.209984) (xy 128.225921 -37.209578) (xy 128.244441 -37.201906)
			(xy 128.258614 -37.187729) (xy 128.266281 -37.169207) (xy 128.266698 -37.159184) (xy 128.266698 -37.151564)
			(xy 128.26238 -37.137594) (xy 128.258316 -37.131244) (xy 128.234397 -37.094009) (xy 128.192696 -37.015944)
			(xy 128.158311 -36.93439) (xy 128.131533 -36.850033) (xy 128.112584 -36.76358) (xy 128.101624 -36.675755)
			(xy 128.098746 -36.587297) (xy 128.103973 -36.498946) (xy 128.117261 -36.411443) (xy 128.138499 -36.325524)
			(xy 128.167508 -36.241908) (xy 128.204046 -36.161296) (xy 128.247807 -36.084366) (xy 128.298421 -36.011762)
			(xy 128.355467 -35.944093) (xy 128.418464 -35.881927) (xy 128.486884 -35.825786) (xy 128.560154 -35.776139)
			(xy 128.637659 -35.733405) (xy 128.718748 -35.69794) (xy 128.802742 -35.670044) (xy 128.888936 -35.649948)
			(xy 128.976607 -35.637824) (xy 129.06502 -35.633771) (xy 129.153433 -35.637824) (xy 129.241104 -35.649948)
			(xy 129.327298 -35.670044) (xy 129.411292 -35.69794) (xy 129.492381 -35.733405) (xy 129.569886 -35.776139)
			(xy 129.643156 -35.825786) (xy 129.705252 -35.876738) (xy 134.817356 -35.876738) (xy 134.821427 -35.821116)
			(xy 134.833553 -35.766679) (xy 134.853476 -35.714588) (xy 134.880772 -35.665953) (xy 134.914858 -35.62181)
			(xy 134.955007 -35.583101) (xy 135.000365 -35.55065) (xy 135.049965 -35.525149) (xy 135.102749 -35.507142)
			(xy 135.157592 -35.497012) (xy 135.213326 -35.494975) (xy 135.268763 -35.501075) (xy 135.32272 -35.515181)
			(xy 135.374049 -35.536993) (xy 135.421655 -35.566047) (xy 135.464523 -35.601722) (xy 135.50174 -35.643259)
			(xy 135.532513 -35.689772) (xy 135.556185 -35.740269) (xy 135.572253 -35.793676) (xy 135.580373 -35.848852)
			(xy 135.580882 -35.876738) (xy 135.580373 -35.904624) (xy 135.572253 -35.9598) (xy 135.556185 -36.013207)
			(xy 135.532513 -36.063704) (xy 135.50174 -36.110217) (xy 135.464523 -36.151754) (xy 135.421655 -36.187429)
			(xy 135.374049 -36.216483) (xy 135.32272 -36.238295) (xy 135.268763 -36.252401) (xy 135.213326 -36.258501)
			(xy 135.157592 -36.256464) (xy 135.102749 -36.246334) (xy 135.049965 -36.228327) (xy 135.000365 -36.202826)
			(xy 134.955007 -36.170375) (xy 134.914858 -36.131666) (xy 134.880772 -36.087523) (xy 134.853476 -36.038888)
			(xy 134.833553 -35.986797) (xy 134.821427 -35.93236) (xy 134.817356 -35.876738) (xy 129.705252 -35.876738)
			(xy 129.711576 -35.881927) (xy 129.774573 -35.944093) (xy 129.831619 -36.011762) (xy 129.882233 -36.084366)
			(xy 129.925994 -36.161296) (xy 129.962532 -36.241908) (xy 129.991541 -36.325524) (xy 130.012779 -36.411443)
			(xy 130.026067 -36.498946) (xy 130.028492 -36.539928) (xy 136.638774 -36.539928) (xy 136.638774 -36.479992)
			(xy 136.646597 -36.42057) (xy 136.66211 -36.362677) (xy 136.685046 -36.307304) (xy 136.715013 -36.255398)
			(xy 136.7515 -36.207848) (xy 136.79388 -36.165468) (xy 136.84143 -36.128981) (xy 136.893336 -36.099014)
			(xy 136.948709 -36.076078) (xy 137.006602 -36.060565) (xy 137.066024 -36.052742) (xy 137.12596 -36.052742)
			(xy 137.185382 -36.060565) (xy 137.243275 -36.076078) (xy 137.298648 -36.099014) (xy 137.350554 -36.128981)
			(xy 137.398104 -36.165468) (xy 137.440484 -36.207848) (xy 137.476971 -36.255398) (xy 137.506938 -36.307304)
			(xy 137.529874 -36.362677) (xy 137.545387 -36.42057) (xy 137.55321 -36.479992) (xy 137.5537 -36.50996)
			(xy 137.55321 -36.539928) (xy 137.545387 -36.59935) (xy 137.529874 -36.657243) (xy 137.506938 -36.712616)
			(xy 137.476971 -36.764522) (xy 137.440484 -36.812072) (xy 137.398104 -36.854452) (xy 137.350554 -36.890939)
			(xy 137.298648 -36.920906) (xy 137.243275 -36.943842) (xy 137.185382 -36.959355) (xy 137.12596 -36.967178)
			(xy 137.066024 -36.967178) (xy 137.006602 -36.959355) (xy 136.948709 -36.943842) (xy 136.893336 -36.920906)
			(xy 136.84143 -36.890939) (xy 136.79388 -36.854452) (xy 136.7515 -36.812072) (xy 136.715013 -36.764522)
			(xy 136.685046 -36.712616) (xy 136.66211 -36.657243) (xy 136.646597 -36.59935) (xy 136.638774 -36.539928)
			(xy 130.028492 -36.539928) (xy 130.031294 -36.587297) (xy 130.028416 -36.675755) (xy 130.017456 -36.76358)
			(xy 129.998507 -36.850033) (xy 129.971729 -36.93439) (xy 129.937344 -37.015944) (xy 129.895643 -37.094009)
			(xy 129.871724 -37.131244) (xy 129.863342 -37.143944) (xy 129.863342 -37.159184) (xy 129.863733 -37.169209)
			(xy 129.871406 -37.187734) (xy 129.885588 -37.201909) (xy 129.904116 -37.209572) (xy 129.914142 -37.209984)
			(xy 129.99212 -37.209984) (xy 130.035559 -37.210411) (xy 130.122067 -37.218428) (xy 130.207466 -37.234394)
			(xy 130.291028 -37.258171) (xy 130.372039 -37.289556) (xy 130.449809 -37.328283) (xy 130.523674 -37.374019)
			(xy 130.593004 -37.426376) (xy 130.646515 -37.47516) (xy 133.859268 -37.47516) (xy 133.863339 -37.419538)
			(xy 133.875465 -37.365101) (xy 133.895388 -37.31301) (xy 133.922684 -37.264375) (xy 133.95677 -37.220232)
			(xy 133.996919 -37.181523) (xy 134.042277 -37.149072) (xy 134.091877 -37.123571) (xy 134.144661 -37.105564)
			(xy 134.199504 -37.095434) (xy 134.255238 -37.093397) (xy 134.310675 -37.099497) (xy 134.364632 -37.113603)
			(xy 134.415961 -37.135415) (xy 134.463567 -37.164469) (xy 134.506435 -37.200144) (xy 134.507286 -37.201094)
			(xy 137.816588 -37.201094) (xy 137.820659 -37.145472) (xy 137.832785 -37.091035) (xy 137.852708 -37.038944)
			(xy 137.880004 -36.990309) (xy 137.91409 -36.946166) (xy 137.954239 -36.907457) (xy 137.999597 -36.875006)
			(xy 138.049197 -36.849505) (xy 138.101981 -36.831498) (xy 138.156824 -36.821368) (xy 138.212558 -36.819331)
			(xy 138.267995 -36.825431) (xy 138.321952 -36.839537) (xy 138.373281 -36.861349) (xy 138.420887 -36.890403)
			(xy 138.463755 -36.926078) (xy 138.500972 -36.967615) (xy 138.531745 -37.014128) (xy 138.555417 -37.064625)
			(xy 138.571485 -37.118032) (xy 138.579605 -37.173208) (xy 138.580114 -37.201094) (xy 138.579605 -37.22898)
			(xy 138.571485 -37.284156) (xy 138.555417 -37.337563) (xy 138.531745 -37.38806) (xy 138.500972 -37.434573)
			(xy 138.463755 -37.47611) (xy 138.420887 -37.511785) (xy 138.373281 -37.540839) (xy 138.321952 -37.562651)
			(xy 138.267995 -37.576757) (xy 138.212558 -37.582857) (xy 138.156824 -37.58082) (xy 138.101981 -37.57069)
			(xy 138.049197 -37.552683) (xy 137.999597 -37.527182) (xy 137.954239 -37.494731) (xy 137.91409 -37.456022)
			(xy 137.880004 -37.411879) (xy 137.852708 -37.363244) (xy 137.832785 -37.311153) (xy 137.820659 -37.256716)
			(xy 137.816588 -37.201094) (xy 134.507286 -37.201094) (xy 134.543652 -37.241681) (xy 134.574425 -37.288194)
			(xy 134.598097 -37.338691) (xy 134.614165 -37.392098) (xy 134.622285 -37.447274) (xy 134.622794 -37.47516)
			(xy 134.622285 -37.503046) (xy 134.614165 -37.558222) (xy 134.598097 -37.611629) (xy 134.574425 -37.662126)
			(xy 134.554445 -37.692326) (xy 135.973294 -37.692326) (xy 135.973294 -37.63239) (xy 135.981117 -37.572968)
			(xy 135.99663 -37.515075) (xy 136.019566 -37.459702) (xy 136.049533 -37.407796) (xy 136.08602 -37.360246)
			(xy 136.1284 -37.317866) (xy 136.17595 -37.281379) (xy 136.227856 -37.251412) (xy 136.283229 -37.228476)
			(xy 136.341122 -37.212963) (xy 136.400544 -37.20514) (xy 136.46048 -37.20514) (xy 136.519902 -37.212963)
			(xy 136.577795 -37.228476) (xy 136.633168 -37.251412) (xy 136.685074 -37.281379) (xy 136.732624 -37.317866)
			(xy 136.775004 -37.360246) (xy 136.811491 -37.407796) (xy 136.841458 -37.459702) (xy 136.864394 -37.515075)
			(xy 136.879907 -37.572968) (xy 136.88773 -37.63239) (xy 136.88822 -37.662358) (xy 136.88773 -37.692326)
			(xy 136.879907 -37.751748) (xy 136.864394 -37.809641) (xy 136.841458 -37.865014) (xy 136.811491 -37.91692)
			(xy 136.775004 -37.96447) (xy 136.732624 -38.00685) (xy 136.685074 -38.043337) (xy 136.633168 -38.073304)
			(xy 136.577795 -38.09624) (xy 136.519902 -38.111753) (xy 136.46048 -38.119576) (xy 136.400544 -38.119576)
			(xy 136.341122 -38.111753) (xy 136.283229 -38.09624) (xy 136.227856 -38.073304) (xy 136.17595 -38.043337)
			(xy 136.1284 -38.00685) (xy 136.08602 -37.96447) (xy 136.049533 -37.91692) (xy 136.019566 -37.865014)
			(xy 135.99663 -37.809641) (xy 135.981117 -37.751748) (xy 135.973294 -37.692326) (xy 134.554445 -37.692326)
			(xy 134.543652 -37.708639) (xy 134.506435 -37.750176) (xy 134.463567 -37.785851) (xy 134.415961 -37.814905)
			(xy 134.364632 -37.836717) (xy 134.310675 -37.850823) (xy 134.255238 -37.856923) (xy 134.199504 -37.854886)
			(xy 134.144661 -37.844756) (xy 134.091877 -37.826749) (xy 134.042277 -37.801248) (xy 133.996919 -37.768797)
			(xy 133.95677 -37.730088) (xy 133.922684 -37.685945) (xy 133.895388 -37.63731) (xy 133.875465 -37.585219)
			(xy 133.863339 -37.530782) (xy 133.859268 -37.47516) (xy 130.646515 -37.47516) (xy 130.657207 -37.484907)
			(xy 130.715737 -37.549111) (xy 130.768092 -37.618442) (xy 130.813827 -37.692308) (xy 130.852552 -37.770079)
			(xy 130.883936 -37.851091) (xy 130.907711 -37.934653) (xy 130.923674 -38.020053) (xy 130.93169 -38.106561)
			(xy 130.93169 -38.193439) (xy 130.923674 -38.279947) (xy 130.907711 -38.365347) (xy 130.883936 -38.448909)
			(xy 130.867568 -38.49116) (xy 133.859268 -38.49116) (xy 133.863339 -38.435538) (xy 133.875465 -38.381101)
			(xy 133.895388 -38.32901) (xy 133.922684 -38.280375) (xy 133.95677 -38.236232) (xy 133.996919 -38.197523)
			(xy 134.042277 -38.165072) (xy 134.091877 -38.139571) (xy 134.144661 -38.121564) (xy 134.199504 -38.111434)
			(xy 134.255238 -38.109397) (xy 134.310675 -38.115497) (xy 134.364632 -38.129603) (xy 134.415961 -38.151415)
			(xy 134.463567 -38.180469) (xy 134.506435 -38.216144) (xy 134.543652 -38.257681) (xy 134.574425 -38.304194)
			(xy 134.598097 -38.354691) (xy 134.614165 -38.408098) (xy 134.622285 -38.463274) (xy 134.622794 -38.49116)
			(xy 134.622285 -38.519046) (xy 134.614165 -38.574222) (xy 134.598097 -38.627629) (xy 134.574425 -38.678126)
			(xy 134.559147 -38.701218) (xy 137.537696 -38.701218) (xy 137.541767 -38.645596) (xy 137.553893 -38.591159)
			(xy 137.573816 -38.539068) (xy 137.601112 -38.490433) (xy 137.635198 -38.44629) (xy 137.675347 -38.407581)
			(xy 137.720705 -38.37513) (xy 137.770305 -38.349629) (xy 137.823089 -38.331622) (xy 137.877932 -38.321492)
			(xy 137.933666 -38.319455) (xy 137.989103 -38.325555) (xy 138.04306 -38.339661) (xy 138.094389 -38.361473)
			(xy 138.141995 -38.390527) (xy 138.184863 -38.426202) (xy 138.22208 -38.467739) (xy 138.252853 -38.514252)
			(xy 138.276525 -38.564749) (xy 138.292593 -38.618156) (xy 138.300713 -38.673332) (xy 138.301222 -38.701218)
			(xy 138.300713 -38.729104) (xy 138.292593 -38.78428) (xy 138.276525 -38.837687) (xy 138.252853 -38.888184)
			(xy 138.22208 -38.934697) (xy 138.184863 -38.976234) (xy 138.141995 -39.011909) (xy 138.094389 -39.040963)
			(xy 138.04306 -39.062775) (xy 137.989103 -39.076881) (xy 137.933666 -39.082981) (xy 137.877932 -39.080944)
			(xy 137.823089 -39.070814) (xy 137.770305 -39.052807) (xy 137.720705 -39.027306) (xy 137.675347 -38.994855)
			(xy 137.635198 -38.956146) (xy 137.601112 -38.912003) (xy 137.573816 -38.863368) (xy 137.553893 -38.811277)
			(xy 137.541767 -38.75684) (xy 137.537696 -38.701218) (xy 134.559147 -38.701218) (xy 134.543652 -38.724639)
			(xy 134.506435 -38.766176) (xy 134.463567 -38.801851) (xy 134.415961 -38.830905) (xy 134.364632 -38.852717)
			(xy 134.310675 -38.866823) (xy 134.255238 -38.872923) (xy 134.199504 -38.870886) (xy 134.144661 -38.860756)
			(xy 134.091877 -38.842749) (xy 134.042277 -38.817248) (xy 133.996919 -38.784797) (xy 133.95677 -38.746088)
			(xy 133.922684 -38.701945) (xy 133.895388 -38.65331) (xy 133.875465 -38.601219) (xy 133.863339 -38.546782)
			(xy 133.859268 -38.49116) (xy 130.867568 -38.49116) (xy 130.852552 -38.529921) (xy 130.813827 -38.607692)
			(xy 130.768092 -38.681558) (xy 130.715737 -38.750889) (xy 130.657207 -38.815093) (xy 130.593004 -38.873624)
			(xy 130.523674 -38.925981) (xy 130.449809 -38.971717) (xy 130.372039 -39.010444) (xy 130.291028 -39.041829)
			(xy 130.207466 -39.065606) (xy 130.122067 -39.081572) (xy 130.035559 -39.089589) (xy 129.99212 -39.090092)
			(xy 128.13792 -39.090092) (xy 128.094482 -39.08953) (xy 128.007977 -39.081516) (xy 127.922581 -39.065555)
			(xy 127.839022 -39.041781) (xy 127.758012 -39.0104) (xy 127.680244 -38.971677) (xy 127.606381 -38.925944)
			(xy 127.537052 -38.873591) (xy 127.47285 -38.815064) (xy 127.414322 -38.750863) (xy 127.361967 -38.681536)
			(xy 127.316232 -38.607673) (xy 127.277508 -38.529906) (xy 127.246125 -38.448897) (xy 127.22235 -38.365338)
			(xy 127.206387 -38.279942) (xy 127.198371 -38.193438) (xy 126.243588 -38.193438) (xy 126.243588 -42.849038)
			(xy 136.992104 -42.849038) (xy 136.996175 -42.793416) (xy 137.008301 -42.738979) (xy 137.028224 -42.686888)
			(xy 137.05552 -42.638253) (xy 137.089606 -42.59411) (xy 137.129755 -42.555401) (xy 137.175113 -42.52295)
			(xy 137.224713 -42.497449) (xy 137.277497 -42.479442) (xy 137.33234 -42.469312) (xy 137.388074 -42.467275)
			(xy 137.443511 -42.473375) (xy 137.497468 -42.487481) (xy 137.548797 -42.509293) (xy 137.596403 -42.538347)
			(xy 137.639271 -42.574022) (xy 137.676488 -42.615559) (xy 137.707261 -42.662072) (xy 137.730933 -42.712569)
			(xy 137.747001 -42.765976) (xy 137.755121 -42.821152) (xy 137.75563 -42.849038) (xy 137.755121 -42.876924)
			(xy 137.747001 -42.9321) (xy 137.730933 -42.985507) (xy 137.707261 -43.036004) (xy 137.676488 -43.082517)
			(xy 137.639271 -43.124054) (xy 137.596403 -43.159729) (xy 137.548797 -43.188783) (xy 137.497468 -43.210595)
			(xy 137.443511 -43.224701) (xy 137.388074 -43.230801) (xy 137.33234 -43.228764) (xy 137.277497 -43.218634)
			(xy 137.224713 -43.200627) (xy 137.175113 -43.175126) (xy 137.129755 -43.142675) (xy 137.089606 -43.103966)
			(xy 137.05552 -43.059823) (xy 137.028224 -43.011188) (xy 137.008301 -42.959097) (xy 136.996175 -42.90466)
			(xy 136.992104 -42.849038) (xy 126.243588 -42.849038) (xy 126.243588 -43.766228) (xy 136.237962 -43.766228)
			(xy 136.237962 -43.706292) (xy 136.245785 -43.64687) (xy 136.261298 -43.588977) (xy 136.284234 -43.533604)
			(xy 136.314201 -43.481698) (xy 136.350688 -43.434148) (xy 136.393068 -43.391768) (xy 136.440618 -43.355281)
			(xy 136.492524 -43.325314) (xy 136.547897 -43.302378) (xy 136.60579 -43.286865) (xy 136.665212 -43.279042)
			(xy 136.725148 -43.279042) (xy 136.78457 -43.286865) (xy 136.842463 -43.302378) (xy 136.897836 -43.325314)
			(xy 136.949742 -43.355281) (xy 136.997292 -43.391768) (xy 137.039672 -43.434148) (xy 137.076159 -43.481698)
			(xy 137.106126 -43.533604) (xy 137.129062 -43.588977) (xy 137.144575 -43.64687) (xy 137.152398 -43.706292)
			(xy 137.152888 -43.73626) (xy 137.152398 -43.766228) (xy 137.144575 -43.82565) (xy 137.129062 -43.883543)
			(xy 137.106126 -43.938916) (xy 137.076159 -43.990822) (xy 137.039672 -44.038372) (xy 136.997292 -44.080752)
			(xy 136.949742 -44.117239) (xy 136.897836 -44.147206) (xy 136.842463 -44.170142) (xy 136.78457 -44.185655)
			(xy 136.725148 -44.193478) (xy 136.665212 -44.193478) (xy 136.60579 -44.185655) (xy 136.547897 -44.170142)
			(xy 136.492524 -44.147206) (xy 136.440618 -44.117239) (xy 136.393068 -44.080752) (xy 136.350688 -44.038372)
			(xy 136.314201 -43.990822) (xy 136.284234 -43.938916) (xy 136.261298 -43.883543) (xy 136.245785 -43.82565)
			(xy 136.237962 -43.766228) (xy 126.243588 -43.766228) (xy 126.243588 -43.847512) (xy 126.244047 -43.85739)
			(xy 126.251487 -43.875691) (xy 126.258066 -43.883072) (xy 126.25832 -43.883326) (xy 126.736348 -44.361354)
			(xy 126.736856 -44.361862) (xy 126.744238 -44.368443) (xy 126.762537 -44.375891) (xy 126.772416 -44.37634)
		)
		(stroke
			(width 0)
			(type solid)
		)
		(fill yes)
		(layer "B.Cu")
		(net "P12V_SSD4")
	)
	(gr_poly
		(pts
			(xy 164.577014 -44.37634) (xy 164.586892 -44.375882) (xy 164.605195 -44.368444) (xy 164.612574 -44.361862)
			(xy 164.612828 -44.361608) (xy 165.172136 -43.8023) (xy 165.172644 -43.801792) (xy 165.179234 -43.794413)
			(xy 165.186702 -43.776115) (xy 165.187122 -43.766232) (xy 165.187122 -36.349686) (xy 165.166548 -36.322762)
			(xy 165.149784 -36.31819) (xy 165.121137 -36.309832) (xy 165.066128 -36.286701) (xy 165.014591 -36.256618)
			(xy 164.967399 -36.220094) (xy 164.925353 -36.177748) (xy 164.889166 -36.130298) (xy 164.859451 -36.078547)
			(xy 164.836713 -36.023375) (xy 164.821335 -35.965716) (xy 164.81358 -35.906547) (xy 164.813579 -35.846873)
			(xy 164.821331 -35.787704) (xy 164.836706 -35.730044) (xy 164.859443 -35.674871) (xy 164.889155 -35.623119)
			(xy 164.92534 -35.575667) (xy 164.967384 -35.533319) (xy 165.014574 -35.496793) (xy 165.06611 -35.466708)
			(xy 165.121118 -35.443574) (xy 165.149784 -35.435286) (xy 165.166548 -35.430714) (xy 165.187122 -35.40379)
			(xy 165.187122 -26.653236) (xy 165.186961 -26.64786) (xy 165.18466 -26.637355) (xy 165.18255 -26.632408)
			(xy 165.170358 -26.604722) (xy 165.162738 -26.597864) (xy 165.144126 -26.579744) (xy 165.111478 -26.539342)
			(xy 165.084605 -26.49489) (xy 165.064003 -26.447206) (xy 165.050051 -26.39717) (xy 165.043009 -26.345706)
			(xy 165.042596 -26.319734) (xy 165.04316 -26.290084) (xy 165.052323 -26.231497) (xy 165.070421 -26.175027)
			(xy 165.083236 -26.148284) (xy 165.08857 -26.137616) (xy 165.089078 -26.114756) (xy 165.050724 -26.031698)
			(xy 165.045329 -26.021589) (xy 165.02766 -26.00705) (xy 165.016688 -26.003758) (xy 165.016434 -26.003758)
			(xy 164.986863 -25.996099) (xy 164.929917 -25.973996) (xy 164.876419 -25.944513) (xy 164.827318 -25.908175)
			(xy 164.783487 -25.865628) (xy 164.745707 -25.817628) (xy 164.714647 -25.765029) (xy 164.690862 -25.708765)
			(xy 164.674773 -25.649837) (xy 164.666666 -25.589293) (xy 164.666168 -25.55875) (xy 164.666704 -25.527478)
			(xy 164.675226 -25.465517) (xy 164.692102 -25.405292) (xy 164.71702 -25.347926) (xy 164.749516 -25.294486)
			(xy 164.788984 -25.245967) (xy 164.834689 -25.203273) (xy 164.885781 -25.167198) (xy 164.941309 -25.138414)
			(xy 165.000238 -25.117458) (xy 165.061471 -25.104718) (xy 165.092634 -25.102058) (xy 165.102286 -25.101296)
			(xy 165.119558 -25.093168) (xy 165.173406 -25.03551) (xy 165.175946 -25.032462) (xy 165.181059 -25.025538)
			(xy 165.186769 -25.009312) (xy 165.187122 -25.000712) (xy 165.187122 -19.808444) (xy 165.18667 -19.798602)
			(xy 165.179249 -19.780372) (xy 165.165489 -19.766297) (xy 165.156642 -19.761962) (xy 165.057582 -19.718528)
			(xy 165.027864 -19.723608) (xy 165.016688 -19.733768) (xy 164.99545 -19.752622) (xy 164.948437 -19.784478)
			(xy 164.897218 -19.809007) (xy 164.842927 -19.825666) (xy 164.786765 -19.834086) (xy 164.75837 -19.834606)
			(xy 164.731596 -19.834158) (xy 164.678574 -19.826676) (xy 164.62712 -19.811849) (xy 164.578246 -19.78997)
			(xy 164.532914 -19.761468) (xy 164.492016 -19.726903) (xy 164.456356 -19.686957) (xy 164.441124 -19.664934)
			(xy 164.435028 -19.656044) (xy 164.417502 -19.644614) (xy 164.333428 -19.631152) (xy 164.323065 -19.629979)
			(xy 164.30287 -19.635097) (xy 164.294312 -19.641058) (xy 164.274154 -19.656164) (xy 164.230622 -19.68151)
			(xy 164.184135 -19.700915) (xy 164.135502 -19.71404) (xy 164.085565 -19.720659) (xy 164.060378 -19.721068)
			(xy 164.052758 -19.721068) (xy 164.025862 -19.720074) (xy 163.972735 -19.711456) (xy 163.921348 -19.695456)
			(xy 163.872719 -19.672392) (xy 163.827816 -19.64272) (xy 163.787529 -19.607032) (xy 163.752659 -19.566034)
			(xy 163.723898 -19.520543) (xy 163.701818 -19.47146) (xy 163.686856 -19.41976) (xy 163.67931 -19.366471)
			(xy 163.67887 -19.33956) (xy 163.679358 -19.31231) (xy 163.68712 -19.258365) (xy 163.702478 -19.206074)
			(xy 163.725121 -19.156501) (xy 163.754588 -19.110654) (xy 163.790279 -19.069466) (xy 163.831468 -19.033777)
			(xy 163.877317 -19.004312) (xy 163.926891 -18.981672) (xy 163.979183 -18.966316) (xy 164.033128 -18.958557)
			(xy 164.060378 -18.958052) (xy 164.087151 -18.958503) (xy 164.14017 -18.96599) (xy 164.191621 -18.980821)
			(xy 164.240491 -19.002703) (xy 164.28582 -19.031206) (xy 164.326716 -19.065769) (xy 164.362375 -19.105714)
			(xy 164.377624 -19.127724) (xy 164.38372 -19.136614) (xy 164.401246 -19.148044) (xy 164.495734 -19.163284)
			(xy 164.516054 -19.158204) (xy 164.524436 -19.1516) (xy 164.547661 -19.134256) (xy 164.598301 -19.106058)
			(xy 164.652627 -19.085854) (xy 164.6809 -19.079464) (xy 164.694616 -19.07667) (xy 164.71519 -19.057874)
			(xy 164.744908 -18.95856) (xy 164.747142 -18.949727) (xy 164.745892 -18.931564) (xy 164.73836 -18.914989)
			(xy 164.732208 -18.908268) (xy 164.62629 -18.80235) (xy 164.616384 -18.798286) (xy 164.592689 -18.78833)
			(xy 164.547987 -18.762966) (xy 164.507094 -18.73183) (xy 164.470753 -18.695486) (xy 164.43962 -18.654592)
			(xy 164.414259 -18.609888) (xy 164.404294 -18.586196) (xy 164.40023 -18.57629) (xy 164.367464 -18.543524)
			(xy 164.360352 -18.536158) (xy 164.341556 -18.528538) (xy 152.628854 -18.528538) (xy 152.618788 -18.52897)
			(xy 152.600199 -18.536701) (xy 152.592786 -18.543524) (xy 152.258522 -18.877788) (xy 152.251156 -18.8849)
			(xy 152.243536 -18.903696) (xy 152.243536 -21.738336) (xy 153.516838 -21.738336) (xy 153.517339 -21.709596)
			(xy 153.52597 -21.652769) (xy 153.543026 -21.597878) (xy 153.568122 -21.546167) (xy 153.60069 -21.498805)
			(xy 153.619962 -21.477478) (xy 153.626566 -21.470366) (xy 153.633678 -21.45284) (xy 153.633678 -21.363432)
			(xy 153.626566 -21.345906) (xy 153.619962 -21.338794) (xy 153.600725 -21.317437) (xy 153.568156 -21.270081)
			(xy 153.54306 -21.218374) (xy 153.526005 -21.163488) (xy 153.517378 -21.106664) (xy 153.517374 -21.049189)
			(xy 153.525993 -20.992364) (xy 153.54304 -20.937475) (xy 153.568129 -20.885765) (xy 153.600692 -20.838404)
			(xy 153.619962 -20.817078) (xy 153.626566 -20.809966) (xy 153.633678 -20.79244) (xy 153.633678 -20.703032)
			(xy 153.626566 -20.685506) (xy 153.619962 -20.678394) (xy 153.600725 -20.657037) (xy 153.568156 -20.609681)
			(xy 153.54306 -20.557974) (xy 153.526005 -20.503088) (xy 153.517378 -20.446264) (xy 153.517374 -20.388789)
			(xy 153.525993 -20.331964) (xy 153.54304 -20.277075) (xy 153.568129 -20.225365) (xy 153.600692 -20.178004)
			(xy 153.619962 -20.156678) (xy 153.626566 -20.149566) (xy 153.633678 -20.13204) (xy 153.633678 -20.042632)
			(xy 153.626566 -20.025106) (xy 153.619962 -20.017994) (xy 153.600725 -19.996637) (xy 153.568156 -19.949281)
			(xy 153.54306 -19.897574) (xy 153.526005 -19.842688) (xy 153.517378 -19.785864) (xy 153.517374 -19.728389)
			(xy 153.525993 -19.671564) (xy 153.54304 -19.616675) (xy 153.568129 -19.564965) (xy 153.600692 -19.517604)
			(xy 153.619962 -19.496278) (xy 153.626566 -19.489166) (xy 153.633678 -19.47164) (xy 153.633678 -19.382232)
			(xy 153.626566 -19.364706) (xy 153.619962 -19.357594) (xy 153.600712 -19.336249) (xy 153.568142 -19.288892)
			(xy 153.543045 -19.237185) (xy 153.52599 -19.182298) (xy 153.517362 -19.125474) (xy 153.516838 -19.096736)
			(xy 153.517324 -19.069485) (xy 153.52508 -19.015537) (xy 153.540435 -18.963242) (xy 153.563077 -18.913665)
			(xy 153.592543 -18.867815) (xy 153.628234 -18.826624) (xy 153.669425 -18.790933) (xy 153.715275 -18.761467)
			(xy 153.764852 -18.738825) (xy 153.817147 -18.72347) (xy 153.871095 -18.715714) (xy 153.925597 -18.715714)
			(xy 153.979545 -18.72347) (xy 154.03184 -18.738825) (xy 154.081417 -18.761467) (xy 154.127267 -18.790933)
			(xy 154.168458 -18.826624) (xy 154.204149 -18.867815) (xy 154.233615 -18.913665) (xy 154.256257 -18.963242)
			(xy 154.271612 -19.015537) (xy 154.279368 -19.069485) (xy 154.279854 -19.096736) (xy 154.279338 -19.125475)
			(xy 154.270711 -19.182302) (xy 154.253658 -19.237192) (xy 154.228566 -19.288904) (xy 154.196 -19.336267)
			(xy 154.17673 -19.357594) (xy 154.170126 -19.364706) (xy 154.163014 -19.382232) (xy 154.163014 -19.47164)
			(xy 154.170126 -19.489166) (xy 154.17673 -19.496278) (xy 154.196034 -19.517575) (xy 154.228594 -19.564944)
			(xy 154.25368 -19.616661) (xy 154.270724 -19.671556) (xy 154.279342 -19.728386) (xy 154.279338 -19.785866)
			(xy 154.270713 -19.842695) (xy 154.25366 -19.897588) (xy 154.228567 -19.949301) (xy 154.196001 -19.996666)
			(xy 154.17673 -20.017994) (xy 154.170126 -20.025106) (xy 154.163014 -20.042632) (xy 154.163014 -20.13204)
			(xy 154.170126 -20.149566) (xy 154.17673 -20.156678) (xy 154.196034 -20.177975) (xy 154.228594 -20.225344)
			(xy 154.25368 -20.277061) (xy 154.270724 -20.331956) (xy 154.274303 -20.35556) (xy 163.67836 -20.35556)
			(xy 163.682431 -20.299938) (xy 163.694557 -20.245501) (xy 163.71448 -20.19341) (xy 163.741776 -20.144775)
			(xy 163.775862 -20.100632) (xy 163.816011 -20.061923) (xy 163.861369 -20.029472) (xy 163.910969 -20.003971)
			(xy 163.963753 -19.985964) (xy 164.018596 -19.975834) (xy 164.07433 -19.973797) (xy 164.129767 -19.979897)
			(xy 164.183724 -19.994003) (xy 164.235053 -20.015815) (xy 164.282659 -20.044869) (xy 164.325527 -20.080544)
			(xy 164.362744 -20.122081) (xy 164.393517 -20.168594) (xy 164.417189 -20.219091) (xy 164.433257 -20.272498)
			(xy 164.441377 -20.327674) (xy 164.441886 -20.35556) (xy 164.441377 -20.383446) (xy 164.433257 -20.438622)
			(xy 164.417189 -20.492029) (xy 164.393517 -20.542526) (xy 164.362744 -20.589039) (xy 164.325527 -20.630576)
			(xy 164.282659 -20.666251) (xy 164.235053 -20.695305) (xy 164.183724 -20.717117) (xy 164.129767 -20.731223)
			(xy 164.07433 -20.737323) (xy 164.018596 -20.735286) (xy 163.963753 -20.725156) (xy 163.910969 -20.707149)
			(xy 163.861369 -20.681648) (xy 163.816011 -20.649197) (xy 163.775862 -20.610488) (xy 163.741776 -20.566345)
			(xy 163.71448 -20.51771) (xy 163.694557 -20.465619) (xy 163.682431 -20.411182) (xy 163.67836 -20.35556)
			(xy 154.274303 -20.35556) (xy 154.279342 -20.388786) (xy 154.279338 -20.446266) (xy 154.270713 -20.503095)
			(xy 154.25366 -20.557988) (xy 154.228567 -20.609701) (xy 154.196001 -20.657066) (xy 154.17673 -20.678394)
			(xy 154.170126 -20.685506) (xy 154.163014 -20.703032) (xy 154.163014 -20.79244) (xy 154.170126 -20.809966)
			(xy 154.17673 -20.817078) (xy 154.196034 -20.838375) (xy 154.228594 -20.885744) (xy 154.25368 -20.937461)
			(xy 154.270724 -20.992356) (xy 154.279342 -21.049186) (xy 154.279338 -21.106666) (xy 154.270713 -21.163495)
			(xy 154.25366 -21.218388) (xy 154.228567 -21.270101) (xy 154.196001 -21.317466) (xy 154.17673 -21.338794)
			(xy 154.170126 -21.345906) (xy 154.163014 -21.363432) (xy 154.163014 -21.37156) (xy 163.67836 -21.37156)
			(xy 163.682431 -21.315938) (xy 163.694557 -21.261501) (xy 163.71448 -21.20941) (xy 163.741776 -21.160775)
			(xy 163.775862 -21.116632) (xy 163.816011 -21.077923) (xy 163.861369 -21.045472) (xy 163.910969 -21.019971)
			(xy 163.963753 -21.001964) (xy 164.018596 -20.991834) (xy 164.07433 -20.989797) (xy 164.129767 -20.995897)
			(xy 164.183724 -21.010003) (xy 164.235053 -21.031815) (xy 164.282659 -21.060869) (xy 164.325527 -21.096544)
			(xy 164.362744 -21.138081) (xy 164.393517 -21.184594) (xy 164.417189 -21.235091) (xy 164.433257 -21.288498)
			(xy 164.441377 -21.343674) (xy 164.441886 -21.37156) (xy 164.441377 -21.399446) (xy 164.433257 -21.454622)
			(xy 164.417189 -21.508029) (xy 164.393517 -21.558526) (xy 164.362744 -21.605039) (xy 164.325527 -21.646576)
			(xy 164.282659 -21.682251) (xy 164.235053 -21.711305) (xy 164.183724 -21.733117) (xy 164.129767 -21.747223)
			(xy 164.07433 -21.753323) (xy 164.018596 -21.751286) (xy 163.963753 -21.741156) (xy 163.910969 -21.723149)
			(xy 163.861369 -21.697648) (xy 163.816011 -21.665197) (xy 163.775862 -21.626488) (xy 163.741776 -21.582345)
			(xy 163.71448 -21.53371) (xy 163.694557 -21.481619) (xy 163.682431 -21.427182) (xy 163.67836 -21.37156)
			(xy 154.163014 -21.37156) (xy 154.163014 -21.45284) (xy 154.170126 -21.470366) (xy 154.17673 -21.477478)
			(xy 154.196013 -21.498795) (xy 154.228578 -21.546159) (xy 154.253669 -21.597873) (xy 154.270717 -21.652767)
			(xy 154.279336 -21.709596) (xy 154.279854 -21.738336) (xy 154.279368 -21.765587) (xy 154.271612 -21.819535)
			(xy 154.256257 -21.87183) (xy 154.233615 -21.921407) (xy 154.204149 -21.967257) (xy 154.168458 -22.008448)
			(xy 154.127267 -22.044139) (xy 154.081417 -22.073605) (xy 154.03184 -22.096247) (xy 153.979545 -22.111602)
			(xy 153.925597 -22.119358) (xy 153.871095 -22.119358) (xy 153.817147 -22.111602) (xy 153.764852 -22.096247)
			(xy 153.715275 -22.073605) (xy 153.669425 -22.044139) (xy 153.628234 -22.008448) (xy 153.592543 -21.967257)
			(xy 153.563077 -21.921407) (xy 153.540435 -21.87183) (xy 153.52508 -21.819535) (xy 153.517324 -21.765587)
			(xy 153.516838 -21.738336) (xy 152.243536 -21.738336) (xy 152.243536 -23.055066) (xy 153.387284 -23.055066)
			(xy 153.387284 -22.995131) (xy 153.395107 -22.935709) (xy 153.41062 -22.877816) (xy 153.433556 -22.822444)
			(xy 153.463524 -22.770538) (xy 153.50001 -22.722989) (xy 153.54239 -22.680609) (xy 153.58994 -22.644123)
			(xy 153.641845 -22.614155) (xy 153.697218 -22.591219) (xy 153.755111 -22.575707) (xy 153.814533 -22.567884)
			(xy 153.874468 -22.567884) (xy 153.93389 -22.575707) (xy 153.991783 -22.59122) (xy 154.047156 -22.614156)
			(xy 154.099061 -22.644123) (xy 154.146611 -22.680609) (xy 154.188991 -22.72299) (xy 154.225477 -22.77054)
			(xy 154.255444 -22.822445) (xy 154.278381 -22.877818) (xy 154.293893 -22.93571) (xy 154.301716 -22.995133)
			(xy 154.302206 -23.0251) (xy 154.301982 -23.045661) (xy 154.298293 -23.086618) (xy 154.29484 -23.106888)
			(xy 154.2923 -23.120604) (xy 154.30119 -23.145496) (xy 154.387804 -23.22068) (xy 154.413712 -23.226014)
			(xy 154.42692 -23.221696) (xy 154.456121 -23.212601) (xy 154.516484 -23.202782) (xy 154.547062 -23.202138)
			(xy 154.565989 -23.202399) (xy 154.603651 -23.206217) (xy 154.622246 -23.209758) (xy 154.634946 -23.212044)
			(xy 154.658568 -23.205186) (xy 154.737054 -23.128986) (xy 154.744674 -23.105618) (xy 154.742642 -23.092918)
			(xy 154.739582 -23.073888) (xy 154.736271 -23.035483) (xy 154.736038 -23.01621) (xy 154.736471 -22.986242)
			(xy 154.744293 -22.926819) (xy 154.759804 -22.868925) (xy 154.782739 -22.813551) (xy 154.812705 -22.761645)
			(xy 154.84919 -22.714093) (xy 154.891569 -22.671711) (xy 154.939118 -22.635223) (xy 154.991023 -22.605253)
			(xy 155.046395 -22.582314) (xy 155.104288 -22.566799) (xy 155.16371 -22.558973) (xy 155.223646 -22.558971)
			(xy 155.283069 -22.566791) (xy 155.340963 -22.5823) (xy 155.396338 -22.605234) (xy 155.448245 -22.635198)
			(xy 155.495797 -22.671682) (xy 155.538181 -22.71406) (xy 155.57467 -22.761608) (xy 155.604642 -22.813512)
			(xy 155.627582 -22.868884) (xy 155.643098 -22.926776) (xy 155.650926 -22.986198) (xy 155.65093 -23.046134)
			(xy 155.643112 -23.105557) (xy 155.627604 -23.163452) (xy 155.604672 -23.218827) (xy 155.574708 -23.270735)
			(xy 155.538226 -23.318288) (xy 155.495849 -23.360673) (xy 155.448302 -23.397164) (xy 155.396399 -23.427136)
			(xy 155.341028 -23.450078) (xy 155.283136 -23.465596) (xy 155.223714 -23.473425) (xy 155.193746 -23.473918)
			(xy 155.159501 -23.473311) (xy 155.091775 -23.463108) (xy 155.058872 -23.453598) (xy 155.04668 -23.449788)
			(xy 155.02255 -23.45436) (xy 154.936698 -23.522178) (xy 154.926792 -23.544784) (xy 154.927808 -23.557738)
			(xy 154.92857 -23.583646) (xy 154.928084 -23.610897) (xy 154.92678 -23.619964) (xy 158.109394 -23.619964)
			(xy 158.109394 -23.560028) (xy 158.117217 -23.500606) (xy 158.13273 -23.442713) (xy 158.155666 -23.38734)
			(xy 158.185633 -23.335434) (xy 158.22212 -23.287884) (xy 158.2645 -23.245504) (xy 158.31205 -23.209017)
			(xy 158.363956 -23.17905) (xy 158.419329 -23.156114) (xy 158.477222 -23.140601) (xy 158.536644 -23.132778)
			(xy 158.59658 -23.132778) (xy 158.656002 -23.140601) (xy 158.713895 -23.156114) (xy 158.769268 -23.17905)
			(xy 158.821174 -23.209017) (xy 158.868724 -23.245504) (xy 158.911104 -23.287884) (xy 158.947591 -23.335434)
			(xy 158.977558 -23.38734) (xy 159.000494 -23.442713) (xy 159.016007 -23.500606) (xy 159.02383 -23.560028)
			(xy 159.02432 -23.589996) (xy 159.02383 -23.619964) (xy 159.016007 -23.679386) (xy 159.000494 -23.737279)
			(xy 158.977558 -23.792652) (xy 158.947591 -23.844558) (xy 158.920151 -23.880318) (xy 159.340802 -23.880318)
			(xy 159.344873 -23.824696) (xy 159.356999 -23.770259) (xy 159.376922 -23.718168) (xy 159.404218 -23.669533)
			(xy 159.438304 -23.62539) (xy 159.478453 -23.586681) (xy 159.523811 -23.55423) (xy 159.573411 -23.528729)
			(xy 159.626195 -23.510722) (xy 159.681038 -23.500592) (xy 159.736772 -23.498555) (xy 159.792209 -23.504655)
			(xy 159.846166 -23.518761) (xy 159.897495 -23.540573) (xy 159.945101 -23.569627) (xy 159.987969 -23.605302)
			(xy 160.025186 -23.646839) (xy 160.055959 -23.693352) (xy 160.079631 -23.743849) (xy 160.095699 -23.797256)
			(xy 160.103819 -23.852432) (xy 160.104328 -23.880318) (xy 160.356802 -23.880318) (xy 160.360873 -23.824696)
			(xy 160.372999 -23.770259) (xy 160.392922 -23.718168) (xy 160.420218 -23.669533) (xy 160.454304 -23.62539)
			(xy 160.494453 -23.586681) (xy 160.539811 -23.55423) (xy 160.589411 -23.528729) (xy 160.642195 -23.510722)
			(xy 160.697038 -23.500592) (xy 160.752772 -23.498555) (xy 160.808209 -23.504655) (xy 160.862166 -23.518761)
			(xy 160.913495 -23.540573) (xy 160.961101 -23.569627) (xy 161.003969 -23.605302) (xy 161.041186 -23.646839)
			(xy 161.071959 -23.693352) (xy 161.095631 -23.743849) (xy 161.111699 -23.797256) (xy 161.119819 -23.852432)
			(xy 161.120328 -23.880318) (xy 161.372802 -23.880318) (xy 161.376873 -23.824696) (xy 161.388999 -23.770259)
			(xy 161.408922 -23.718168) (xy 161.436218 -23.669533) (xy 161.470304 -23.62539) (xy 161.510453 -23.586681)
			(xy 161.555811 -23.55423) (xy 161.605411 -23.528729) (xy 161.658195 -23.510722) (xy 161.713038 -23.500592)
			(xy 161.768772 -23.498555) (xy 161.824209 -23.504655) (xy 161.878166 -23.518761) (xy 161.929495 -23.540573)
			(xy 161.977101 -23.569627) (xy 162.019969 -23.605302) (xy 162.057186 -23.646839) (xy 162.087959 -23.693352)
			(xy 162.111631 -23.743849) (xy 162.127699 -23.797256) (xy 162.135819 -23.852432) (xy 162.136328 -23.880318)
			(xy 162.391088 -23.880318) (xy 162.395159 -23.824696) (xy 162.407285 -23.770259) (xy 162.427208 -23.718168)
			(xy 162.454504 -23.669533) (xy 162.48859 -23.62539) (xy 162.528739 -23.586681) (xy 162.574097 -23.55423)
			(xy 162.623697 -23.528729) (xy 162.676481 -23.510722) (xy 162.731324 -23.500592) (xy 162.787058 -23.498555)
			(xy 162.842495 -23.504655) (xy 162.896452 -23.518761) (xy 162.947781 -23.540573) (xy 162.995387 -23.569627)
			(xy 163.038255 -23.605302) (xy 163.075472 -23.646839) (xy 163.106245 -23.693352) (xy 163.129917 -23.743849)
			(xy 163.145985 -23.797256) (xy 163.154105 -23.852432) (xy 163.154614 -23.880318) (xy 163.154105 -23.908204)
			(xy 163.145985 -23.96338) (xy 163.129917 -24.016787) (xy 163.106245 -24.067284) (xy 163.075472 -24.113797)
			(xy 163.038255 -24.155334) (xy 162.995387 -24.191009) (xy 162.947781 -24.220063) (xy 162.896452 -24.241875)
			(xy 162.842495 -24.255981) (xy 162.787058 -24.262081) (xy 162.731324 -24.260044) (xy 162.676481 -24.249914)
			(xy 162.623697 -24.231907) (xy 162.574097 -24.206406) (xy 162.528739 -24.173955) (xy 162.48859 -24.135246)
			(xy 162.454504 -24.091103) (xy 162.427208 -24.042468) (xy 162.407285 -23.990377) (xy 162.395159 -23.93594)
			(xy 162.391088 -23.880318) (xy 162.136328 -23.880318) (xy 162.135819 -23.908204) (xy 162.127699 -23.96338)
			(xy 162.111631 -24.016787) (xy 162.087959 -24.067284) (xy 162.057186 -24.113797) (xy 162.019969 -24.155334)
			(xy 161.977101 -24.191009) (xy 161.929495 -24.220063) (xy 161.878166 -24.241875) (xy 161.824209 -24.255981)
			(xy 161.768772 -24.262081) (xy 161.713038 -24.260044) (xy 161.658195 -24.249914) (xy 161.605411 -24.231907)
			(xy 161.555811 -24.206406) (xy 161.510453 -24.173955) (xy 161.470304 -24.135246) (xy 161.436218 -24.091103)
			(xy 161.408922 -24.042468) (xy 161.388999 -23.990377) (xy 161.376873 -23.93594) (xy 161.372802 -23.880318)
			(xy 161.120328 -23.880318) (xy 161.119819 -23.908204) (xy 161.111699 -23.96338) (xy 161.095631 -24.016787)
			(xy 161.071959 -24.067284) (xy 161.041186 -24.113797) (xy 161.003969 -24.155334) (xy 160.961101 -24.191009)
			(xy 160.913495 -24.220063) (xy 160.862166 -24.241875) (xy 160.808209 -24.255981) (xy 160.752772 -24.262081)
			(xy 160.697038 -24.260044) (xy 160.642195 -24.249914) (xy 160.589411 -24.231907) (xy 160.539811 -24.206406)
			(xy 160.494453 -24.173955) (xy 160.454304 -24.135246) (xy 160.420218 -24.091103) (xy 160.392922 -24.042468)
			(xy 160.372999 -23.990377) (xy 160.360873 -23.93594) (xy 160.356802 -23.880318) (xy 160.104328 -23.880318)
			(xy 160.103819 -23.908204) (xy 160.095699 -23.96338) (xy 160.079631 -24.016787) (xy 160.055959 -24.067284)
			(xy 160.025186 -24.113797) (xy 159.987969 -24.155334) (xy 159.945101 -24.191009) (xy 159.897495 -24.220063)
			(xy 159.846166 -24.241875) (xy 159.792209 -24.255981) (xy 159.736772 -24.262081) (xy 159.681038 -24.260044)
			(xy 159.626195 -24.249914) (xy 159.573411 -24.231907) (xy 159.523811 -24.206406) (xy 159.478453 -24.173955)
			(xy 159.438304 -24.135246) (xy 159.404218 -24.091103) (xy 159.376922 -24.042468) (xy 159.356999 -23.990377)
			(xy 159.344873 -23.93594) (xy 159.340802 -23.880318) (xy 158.920151 -23.880318) (xy 158.911104 -23.892108)
			(xy 158.868724 -23.934488) (xy 158.821174 -23.970975) (xy 158.769268 -24.000942) (xy 158.713895 -24.023878)
			(xy 158.656002 -24.039391) (xy 158.59658 -24.047214) (xy 158.536644 -24.047214) (xy 158.477222 -24.039391)
			(xy 158.419329 -24.023878) (xy 158.363956 -24.000942) (xy 158.31205 -23.970975) (xy 158.2645 -23.934488)
			(xy 158.22212 -23.892108) (xy 158.185633 -23.844558) (xy 158.155666 -23.792652) (xy 158.13273 -23.737279)
			(xy 158.117217 -23.679386) (xy 158.109394 -23.619964) (xy 154.92678 -23.619964) (xy 154.920328 -23.664845)
			(xy 154.904973 -23.71714) (xy 154.882331 -23.766717) (xy 154.852865 -23.812567) (xy 154.817174 -23.853758)
			(xy 154.775983 -23.889449) (xy 154.730133 -23.918915) (xy 154.680556 -23.941557) (xy 154.628261 -23.956912)
			(xy 154.574313 -23.964668) (xy 154.519811 -23.964668) (xy 154.465863 -23.956912) (xy 154.413568 -23.941557)
			(xy 154.363991 -23.918915) (xy 154.318141 -23.889449) (xy 154.27695 -23.853758) (xy 154.241259 -23.812567)
			(xy 154.211793 -23.766717) (xy 154.189151 -23.71714) (xy 154.173796 -23.664845) (xy 154.16604 -23.610897)
			(xy 154.165554 -23.583646) (xy 154.167332 -23.548086) (xy 154.168602 -23.53437) (xy 154.15768 -23.51024)
			(xy 154.064716 -23.44293) (xy 154.0383 -23.439882) (xy 154.025854 -23.44547) (xy 153.997093 -23.457279)
			(xy 153.937189 -23.473919) (xy 153.875584 -23.482302) (xy 153.844498 -23.482808) (xy 153.814531 -23.482316)
			(xy 153.755108 -23.474492) (xy 153.697216 -23.45898) (xy 153.641843 -23.436044) (xy 153.589938 -23.406076)
			(xy 153.542388 -23.36959) (xy 153.500008 -23.327209) (xy 153.463522 -23.279659) (xy 153.433555 -23.227754)
			(xy 153.410619 -23.172381) (xy 153.395107 -23.114488) (xy 153.387284 -23.055066) (xy 152.243536 -23.055066)
			(xy 152.243536 -24.189944) (xy 153.39898 -24.189944) (xy 153.403051 -24.134322) (xy 153.415177 -24.079885)
			(xy 153.4351 -24.027794) (xy 153.462396 -23.979159) (xy 153.496482 -23.935016) (xy 153.536631 -23.896307)
			(xy 153.581989 -23.863856) (xy 153.631589 -23.838355) (xy 153.684373 -23.820348) (xy 153.739216 -23.810218)
			(xy 153.79495 -23.808181) (xy 153.850387 -23.814281) (xy 153.904344 -23.828387) (xy 153.955673 -23.850199)
			(xy 154.003279 -23.879253) (xy 154.046147 -23.914928) (xy 154.083364 -23.956465) (xy 154.114137 -24.002978)
			(xy 154.137809 -24.053475) (xy 154.153877 -24.106882) (xy 154.161997 -24.162058) (xy 154.162506 -24.189944)
			(xy 155.921962 -24.189944) (xy 155.926033 -24.134322) (xy 155.938159 -24.079885) (xy 155.958082 -24.027794)
			(xy 155.985378 -23.979159) (xy 156.019464 -23.935016) (xy 156.059613 -23.896307) (xy 156.104971 -23.863856)
			(xy 156.154571 -23.838355) (xy 156.207355 -23.820348) (xy 156.262198 -23.810218) (xy 156.317932 -23.808181)
			(xy 156.373369 -23.814281) (xy 156.427326 -23.828387) (xy 156.478655 -23.850199) (xy 156.526261 -23.879253)
			(xy 156.569129 -23.914928) (xy 156.606346 -23.956465) (xy 156.637119 -24.002978) (xy 156.660791 -24.053475)
			(xy 156.676859 -24.106882) (xy 156.684979 -24.162058) (xy 156.685488 -24.189944) (xy 156.684979 -24.21783)
			(xy 156.676859 -24.273006) (xy 156.660791 -24.326413) (xy 156.637119 -24.37691) (xy 156.606346 -24.423423)
			(xy 156.569129 -24.46496) (xy 156.526261 -24.500635) (xy 156.478655 -24.529689) (xy 156.427326 -24.551501)
			(xy 156.373369 -24.565607) (xy 156.317932 -24.571707) (xy 156.262198 -24.56967) (xy 156.207355 -24.55954)
			(xy 156.154571 -24.541533) (xy 156.104971 -24.516032) (xy 156.059613 -24.483581) (xy 156.019464 -24.444872)
			(xy 155.985378 -24.400729) (xy 155.958082 -24.352094) (xy 155.938159 -24.300003) (xy 155.926033 -24.245566)
			(xy 155.921962 -24.189944) (xy 154.162506 -24.189944) (xy 154.161997 -24.21783) (xy 154.153877 -24.273006)
			(xy 154.137809 -24.326413) (xy 154.114137 -24.37691) (xy 154.083364 -24.423423) (xy 154.046147 -24.46496)
			(xy 154.003279 -24.500635) (xy 153.955673 -24.529689) (xy 153.904344 -24.551501) (xy 153.850387 -24.565607)
			(xy 153.79495 -24.571707) (xy 153.739216 -24.56967) (xy 153.684373 -24.55954) (xy 153.631589 -24.541533)
			(xy 153.581989 -24.516032) (xy 153.536631 -24.483581) (xy 153.496482 -24.444872) (xy 153.462396 -24.400729)
			(xy 153.4351 -24.352094) (xy 153.415177 -24.300003) (xy 153.403051 -24.245566) (xy 153.39898 -24.189944)
			(xy 152.243536 -24.189944) (xy 152.243536 -25.390094) (xy 155.833572 -25.390094) (xy 155.834062 -25.360126)
			(xy 155.841885 -25.300704) (xy 155.857398 -25.242811) (xy 155.880334 -25.187438) (xy 155.910301 -25.135532)
			(xy 155.946788 -25.087982) (xy 155.989168 -25.045602) (xy 156.036718 -25.009115) (xy 156.088624 -24.979148)
			(xy 156.143997 -24.956212) (xy 156.20189 -24.940699) (xy 156.261312 -24.932876) (xy 156.321248 -24.932876)
			(xy 156.38067 -24.940699) (xy 156.438563 -24.956212) (xy 156.493936 -24.979148) (xy 156.545842 -25.009115)
			(xy 156.593392 -25.045602) (xy 156.635772 -25.087982) (xy 156.672259 -25.135532) (xy 156.702226 -25.187438)
			(xy 156.725162 -25.242811) (xy 156.740675 -25.300704) (xy 156.748498 -25.360126) (xy 156.748988 -25.390094)
			(xy 156.748558 -25.418879) (xy 156.74134 -25.475994) (xy 156.727016 -25.531752) (xy 156.705812 -25.585275)
			(xy 156.678064 -25.635715) (xy 156.64421 -25.682278) (xy 156.604783 -25.724228) (xy 156.582872 -25.7429)
			(xy 156.57449 -25.749758) (xy 156.564838 -25.769316) (xy 156.561536 -25.867106) (xy 156.569664 -25.887172)
			(xy 156.577792 -25.894792) (xy 156.596199 -25.912862) (xy 156.628434 -25.953131) (xy 156.654956 -25.997372)
			(xy 156.675282 -26.044781) (xy 156.689042 -26.094494) (xy 156.695985 -26.145607) (xy 156.69641 -26.171398)
			(xy 156.695924 -26.198649) (xy 156.688168 -26.252597) (xy 156.672813 -26.304892) (xy 156.650171 -26.354469)
			(xy 156.620705 -26.400319) (xy 156.585014 -26.44151) (xy 156.543823 -26.477201) (xy 156.497973 -26.506667)
			(xy 156.448396 -26.529309) (xy 156.396101 -26.544664) (xy 156.342153 -26.55242) (xy 156.287651 -26.55242)
			(xy 156.233703 -26.544664) (xy 156.181408 -26.529309) (xy 156.131831 -26.506667) (xy 156.085981 -26.477201)
			(xy 156.04479 -26.44151) (xy 156.009099 -26.400319) (xy 155.979633 -26.354469) (xy 155.956991 -26.304892)
			(xy 155.941636 -26.252597) (xy 155.93388 -26.198649) (xy 155.933394 -26.171398) (xy 155.933913 -26.142755)
			(xy 155.94251 -26.086116) (xy 155.959481 -26.031401) (xy 155.984445 -25.979839) (xy 156.016838 -25.93259)
			(xy 156.03601 -25.911302) (xy 156.043376 -25.903174) (xy 156.050234 -25.8826) (xy 156.04109 -25.785064)
			(xy 156.030422 -25.766268) (xy 156.021532 -25.759918) (xy 155.996991 -25.741359) (xy 155.952596 -25.698759)
			(xy 155.914304 -25.650598) (xy 155.882806 -25.597744) (xy 155.858669 -25.541148) (xy 155.842328 -25.48183)
			(xy 155.834077 -25.420858) (xy 155.833572 -25.390094) (xy 152.243536 -25.390094) (xy 152.243536 -25.990042)
			(xy 153.39898 -25.990042) (xy 153.403051 -25.93442) (xy 153.415177 -25.879983) (xy 153.4351 -25.827892)
			(xy 153.462396 -25.779257) (xy 153.496482 -25.735114) (xy 153.536631 -25.696405) (xy 153.581989 -25.663954)
			(xy 153.631589 -25.638453) (xy 153.684373 -25.620446) (xy 153.739216 -25.610316) (xy 153.79495 -25.608279)
			(xy 153.850387 -25.614379) (xy 153.904344 -25.628485) (xy 153.955673 -25.650297) (xy 154.003279 -25.679351)
			(xy 154.046147 -25.715026) (xy 154.083364 -25.756563) (xy 154.114137 -25.803076) (xy 154.137809 -25.853573)
			(xy 154.153877 -25.90698) (xy 154.161997 -25.962156) (xy 154.162506 -25.990042) (xy 154.161997 -26.017928)
			(xy 154.153877 -26.073104) (xy 154.137809 -26.126511) (xy 154.114137 -26.177008) (xy 154.083364 -26.223521)
			(xy 154.046147 -26.265058) (xy 154.003279 -26.300733) (xy 153.955673 -26.329787) (xy 153.904344 -26.351599)
			(xy 153.850387 -26.365705) (xy 153.79495 -26.371805) (xy 153.739216 -26.369768) (xy 153.684373 -26.359638)
			(xy 153.631589 -26.341631) (xy 153.581989 -26.31613) (xy 153.536631 -26.283679) (xy 153.496482 -26.24497)
			(xy 153.462396 -26.200827) (xy 153.4351 -26.152192) (xy 153.415177 -26.100101) (xy 153.403051 -26.045664)
			(xy 153.39898 -25.990042) (xy 152.243536 -25.990042) (xy 152.243536 -27.79014) (xy 153.462988 -27.79014)
			(xy 153.467059 -27.734518) (xy 153.479185 -27.680081) (xy 153.499108 -27.62799) (xy 153.526404 -27.579355)
			(xy 153.56049 -27.535212) (xy 153.600639 -27.496503) (xy 153.645997 -27.464052) (xy 153.695597 -27.438551)
			(xy 153.748381 -27.420544) (xy 153.803224 -27.410414) (xy 153.858958 -27.408377) (xy 153.914395 -27.414477)
			(xy 153.968352 -27.428583) (xy 154.019681 -27.450395) (xy 154.067287 -27.479449) (xy 154.110155 -27.515124)
			(xy 154.147372 -27.556661) (xy 154.178145 -27.603174) (xy 154.201817 -27.653671) (xy 154.217885 -27.707078)
			(xy 154.226005 -27.762254) (xy 154.226514 -27.79014) (xy 155.96692 -27.79014) (xy 155.970991 -27.734518)
			(xy 155.983117 -27.680081) (xy 156.00304 -27.62799) (xy 156.030336 -27.579355) (xy 156.064422 -27.535212)
			(xy 156.104571 -27.496503) (xy 156.149929 -27.464052) (xy 156.199529 -27.438551) (xy 156.252313 -27.420544)
			(xy 156.307156 -27.410414) (xy 156.36289 -27.408377) (xy 156.418327 -27.414477) (xy 156.472284 -27.428583)
			(xy 156.523613 -27.450395) (xy 156.571219 -27.479449) (xy 156.614087 -27.515124) (xy 156.651304 -27.556661)
			(xy 156.682077 -27.603174) (xy 156.705749 -27.653671) (xy 156.721817 -27.707078) (xy 156.729937 -27.762254)
			(xy 156.730446 -27.79014) (xy 156.729949 -27.817352) (xy 157.999895 -27.817352) (xy 157.999895 -27.762848)
			(xy 158.007652 -27.7089) (xy 158.023009 -27.656604) (xy 158.045652 -27.607027) (xy 158.07512 -27.561177)
			(xy 158.110814 -27.519987) (xy 158.152007 -27.484297) (xy 158.19786 -27.454833) (xy 158.24744 -27.432196)
			(xy 158.299737 -27.416844) (xy 158.353686 -27.409093) (xy 158.380938 -27.408632) (xy 158.406244 -27.409051)
			(xy 158.456416 -27.415714) (xy 158.505269 -27.428945) (xy 158.528766 -27.43835) (xy 158.536764 -27.441401)
			(xy 158.553841 -27.442483) (xy 158.570323 -27.437885) (xy 158.577534 -27.43327) (xy 158.602934 -27.41549)
			(xy 158.609811 -27.410204) (xy 158.619891 -27.396107) (xy 158.624692 -27.379456) (xy 158.624524 -27.370786)
			(xy 158.623508 -27.342846) (xy 158.623508 -26.479246) (xy 158.62427 -26.456894) (xy 158.624778 -26.444448)
			(xy 158.614364 -26.421842) (xy 158.529274 -26.355548) (xy 158.50489 -26.350976) (xy 158.492952 -26.354786)
			(xy 158.465617 -26.362634) (xy 158.409373 -26.371048) (xy 158.380938 -26.37155) (xy 158.353686 -26.371005)
			(xy 158.299737 -26.363254) (xy 158.247441 -26.347903) (xy 158.197861 -26.325265) (xy 158.152008 -26.295801)
			(xy 158.110816 -26.260111) (xy 158.075122 -26.218922) (xy 158.045653 -26.173072) (xy 158.023011 -26.123495)
			(xy 158.007654 -26.0712) (xy 157.999897 -26.017252) (xy 157.999897 -25.962748) (xy 158.007654 -25.9088)
			(xy 158.023011 -25.856505) (xy 158.045653 -25.806928) (xy 158.075122 -25.761078) (xy 158.110816 -25.719889)
			(xy 158.152008 -25.684199) (xy 158.197861 -25.654735) (xy 158.247441 -25.632097) (xy 158.299737 -25.616746)
			(xy 158.353686 -25.608995) (xy 158.380938 -25.608534) (xy 158.409891 -25.609042) (xy 158.467134 -25.617784)
			(xy 158.522397 -25.635076) (xy 158.574413 -25.660522) (xy 158.621985 -25.693537) (xy 158.664022 -25.733362)
			(xy 158.699556 -25.779083) (xy 158.727773 -25.829649) (xy 158.728671 -25.832054) (xy 160.288478 -25.832054)
			(xy 160.288977 -25.805452) (xy 160.296351 -25.752761) (xy 160.310977 -25.701607) (xy 160.332572 -25.652983)
			(xy 160.360716 -25.607832) (xy 160.394862 -25.567031) (xy 160.434348 -25.531373) (xy 160.456118 -25.516078)
			(xy 160.467592 -25.507737) (xy 160.485793 -25.485994) (xy 160.497307 -25.460082) (xy 160.501247 -25.432002)
			(xy 160.497309 -25.403922) (xy 160.485795 -25.37801) (xy 160.467596 -25.356266) (xy 160.456118 -25.34793)
			(xy 160.434348 -25.332635) (xy 160.39487 -25.296968) (xy 160.360727 -25.256164) (xy 160.332582 -25.211014)
			(xy 160.31098 -25.162393) (xy 160.296339 -25.111243) (xy 160.288943 -25.058556) (xy 160.288478 -25.031954)
			(xy 160.288964 -25.004703) (xy 160.29672 -24.950755) (xy 160.312075 -24.89846) (xy 160.334717 -24.848883)
			(xy 160.364183 -24.803033) (xy 160.399874 -24.761842) (xy 160.441065 -24.726151) (xy 160.486915 -24.696685)
			(xy 160.536492 -24.674043) (xy 160.588787 -24.658688) (xy 160.642735 -24.650932) (xy 160.697237 -24.650932)
			(xy 160.751185 -24.658688) (xy 160.80348 -24.674043) (xy 160.853057 -24.696685) (xy 160.898907 -24.726151)
			(xy 160.940098 -24.761842) (xy 160.963299 -24.788618) (xy 162.893484 -24.788618) (xy 162.893484 -24.728682)
			(xy 162.901307 -24.66926) (xy 162.91682 -24.611367) (xy 162.939756 -24.555994) (xy 162.969723 -24.504088)
			(xy 163.00621 -24.456538) (xy 163.04859 -24.414158) (xy 163.09614 -24.377671) (xy 163.148046 -24.347704)
			(xy 163.203419 -24.324768) (xy 163.261312 -24.309255) (xy 163.320734 -24.301432) (xy 163.38067 -24.301432)
			(xy 163.440092 -24.309255) (xy 163.497985 -24.324768) (xy 163.553358 -24.347704) (xy 163.605264 -24.377671)
			(xy 163.652814 -24.414158) (xy 163.695194 -24.456538) (xy 163.731681 -24.504088) (xy 163.761648 -24.555994)
			(xy 163.784584 -24.611367) (xy 163.800097 -24.66926) (xy 163.80792 -24.728682) (xy 163.80841 -24.75865)
			(xy 163.80792 -24.788618) (xy 163.800097 -24.84804) (xy 163.784584 -24.905933) (xy 163.761648 -24.961306)
			(xy 163.731681 -25.013212) (xy 163.695194 -25.060762) (xy 163.652814 -25.103142) (xy 163.605264 -25.139629)
			(xy 163.553358 -25.169596) (xy 163.497985 -25.192532) (xy 163.440092 -25.208045) (xy 163.38067 -25.215868)
			(xy 163.320734 -25.215868) (xy 163.261312 -25.208045) (xy 163.203419 -25.192532) (xy 163.148046 -25.169596)
			(xy 163.09614 -25.139629) (xy 163.04859 -25.103142) (xy 163.00621 -25.060762) (xy 162.969723 -25.013212)
			(xy 162.939756 -24.961306) (xy 162.91682 -24.905933) (xy 162.901307 -24.84804) (xy 162.893484 -24.788618)
			(xy 160.963299 -24.788618) (xy 160.975789 -24.803033) (xy 161.005255 -24.848883) (xy 161.027897 -24.89846)
			(xy 161.043252 -24.950755) (xy 161.051008 -25.004703) (xy 161.051494 -25.031954) (xy 161.051013 -25.058557)
			(xy 161.043637 -25.111249) (xy 161.029009 -25.162404) (xy 161.007412 -25.211029) (xy 160.979265 -25.256179)
			(xy 160.945115 -25.296979) (xy 160.905626 -25.332636) (xy 160.883854 -25.34793) (xy 160.872374 -25.356262)
			(xy 160.854179 -25.378009) (xy 160.842668 -25.403922) (xy 160.83873 -25.432002) (xy 160.842669 -25.460082)
			(xy 160.854181 -25.485995) (xy 160.872378 -25.507741) (xy 160.883854 -25.516078) (xy 160.905621 -25.531377)
			(xy 160.945101 -25.567042) (xy 160.979245 -25.607845) (xy 161.007391 -25.652994) (xy 161.028993 -25.701615)
			(xy 161.043634 -25.752765) (xy 161.05103 -25.805452) (xy 161.051494 -25.832054) (xy 161.051008 -25.859305)
			(xy 161.043252 -25.913253) (xy 161.027897 -25.965548) (xy 161.005255 -26.015125) (xy 160.975789 -26.060975)
			(xy 160.940098 -26.102166) (xy 160.898907 -26.137857) (xy 160.853057 -26.167323) (xy 160.80348 -26.189965)
			(xy 160.751185 -26.20532) (xy 160.697237 -26.213076) (xy 160.642735 -26.213076) (xy 160.588787 -26.20532)
			(xy 160.536492 -26.189965) (xy 160.486915 -26.167323) (xy 160.441065 -26.137857) (xy 160.399874 -26.102166)
			(xy 160.364183 -26.060975) (xy 160.334717 -26.015125) (xy 160.312075 -25.965548) (xy 160.29672 -25.913253)
			(xy 160.288964 -25.859305) (xy 160.288478 -25.832054) (xy 158.728671 -25.832054) (xy 158.748024 -25.883899)
			(xy 158.759843 -25.940586) (xy 158.761938 -25.969468) (xy 158.762446 -25.981914) (xy 158.775146 -26.00325)
			(xy 158.86684 -26.060654) (xy 158.891478 -26.062432) (xy 158.902908 -26.057606) (xy 158.931268 -26.046143)
			(xy 158.990265 -26.029985) (xy 159.050886 -26.021812) (xy 159.08147 -26.021284) (xy 159.111457 -26.021735)
			(xy 159.170918 -26.02956) (xy 159.228849 -26.045081) (xy 159.284258 -26.06803) (xy 159.336197 -26.098016)
			(xy 159.383777 -26.134526) (xy 159.426184 -26.176935) (xy 159.462692 -26.224516) (xy 159.492677 -26.276457)
			(xy 159.515625 -26.331866) (xy 159.523397 -26.360882) (xy 161.189668 -26.360882) (xy 161.193739 -26.30526)
			(xy 161.205865 -26.250823) (xy 161.225788 -26.198732) (xy 161.253084 -26.150097) (xy 161.28717 -26.105954)
			(xy 161.327319 -26.067245) (xy 161.372677 -26.034794) (xy 161.422277 -26.009293) (xy 161.475061 -25.991286)
			(xy 161.529904 -25.981156) (xy 161.585638 -25.979119) (xy 161.641075 -25.985219) (xy 161.695032 -25.999325)
			(xy 161.746361 -26.021137) (xy 161.793967 -26.050191) (xy 161.836835 -26.085866) (xy 161.874052 -26.127403)
			(xy 161.904825 -26.173916) (xy 161.928497 -26.224413) (xy 161.944565 -26.27782) (xy 161.952685 -26.332996)
			(xy 161.953194 -26.360882) (xy 162.205668 -26.360882) (xy 162.209739 -26.30526) (xy 162.221865 -26.250823)
			(xy 162.241788 -26.198732) (xy 162.269084 -26.150097) (xy 162.30317 -26.105954) (xy 162.343319 -26.067245)
			(xy 162.388677 -26.034794) (xy 162.438277 -26.009293) (xy 162.491061 -25.991286) (xy 162.545904 -25.981156)
			(xy 162.601638 -25.979119) (xy 162.657075 -25.985219) (xy 162.711032 -25.999325) (xy 162.762361 -26.021137)
			(xy 162.809967 -26.050191) (xy 162.852835 -26.085866) (xy 162.890052 -26.127403) (xy 162.920825 -26.173916)
			(xy 162.944497 -26.224413) (xy 162.960565 -26.27782) (xy 162.968685 -26.332996) (xy 162.969194 -26.360882)
			(xy 162.968685 -26.388768) (xy 162.960565 -26.443944) (xy 162.944497 -26.497351) (xy 162.920825 -26.547848)
			(xy 162.890052 -26.594361) (xy 162.852835 -26.635898) (xy 162.809967 -26.671573) (xy 162.762361 -26.700627)
			(xy 162.711032 -26.722439) (xy 162.657075 -26.736545) (xy 162.601638 -26.742645) (xy 162.545904 -26.740608)
			(xy 162.491061 -26.730478) (xy 162.438277 -26.712471) (xy 162.388677 -26.68697) (xy 162.343319 -26.654519)
			(xy 162.30317 -26.61581) (xy 162.269084 -26.571667) (xy 162.241788 -26.523032) (xy 162.221865 -26.470941)
			(xy 162.209739 -26.416504) (xy 162.205668 -26.360882) (xy 161.953194 -26.360882) (xy 161.952685 -26.388768)
			(xy 161.944565 -26.443944) (xy 161.928497 -26.497351) (xy 161.904825 -26.547848) (xy 161.874052 -26.594361)
			(xy 161.836835 -26.635898) (xy 161.793967 -26.671573) (xy 161.746361 -26.700627) (xy 161.695032 -26.722439)
			(xy 161.641075 -26.736545) (xy 161.585638 -26.742645) (xy 161.529904 -26.740608) (xy 161.475061 -26.730478)
			(xy 161.422277 -26.712471) (xy 161.372677 -26.68697) (xy 161.327319 -26.654519) (xy 161.28717 -26.61581)
			(xy 161.253084 -26.571667) (xy 161.225788 -26.523032) (xy 161.205865 -26.470941) (xy 161.193739 -26.416504)
			(xy 161.189668 -26.360882) (xy 159.523397 -26.360882) (xy 159.531143 -26.389798) (xy 159.538966 -26.449259)
			(xy 159.539432 -26.479246) (xy 159.539432 -26.971244) (xy 162.951158 -26.971244) (xy 162.955229 -26.915622)
			(xy 162.967355 -26.861185) (xy 162.987278 -26.809094) (xy 163.014574 -26.760459) (xy 163.04866 -26.716316)
			(xy 163.088809 -26.677607) (xy 163.134167 -26.645156) (xy 163.183767 -26.619655) (xy 163.236551 -26.601648)
			(xy 163.291394 -26.591518) (xy 163.347128 -26.589481) (xy 163.402565 -26.595581) (xy 163.456522 -26.609687)
			(xy 163.507851 -26.631499) (xy 163.555457 -26.660553) (xy 163.598325 -26.696228) (xy 163.635542 -26.737765)
			(xy 163.666315 -26.784278) (xy 163.689987 -26.834775) (xy 163.706055 -26.888182) (xy 163.714175 -26.943358)
			(xy 163.714684 -26.971244) (xy 163.714175 -26.99913) (xy 163.706055 -27.054306) (xy 163.689987 -27.107713)
			(xy 163.666315 -27.15821) (xy 163.635542 -27.204723) (xy 163.598325 -27.24626) (xy 163.555457 -27.281935)
			(xy 163.507851 -27.310989) (xy 163.456522 -27.332801) (xy 163.402565 -27.346907) (xy 163.347128 -27.353007)
			(xy 163.291394 -27.35097) (xy 163.236551 -27.34084) (xy 163.183767 -27.322833) (xy 163.134167 -27.297332)
			(xy 163.088809 -27.264881) (xy 163.04866 -27.226172) (xy 163.014574 -27.182029) (xy 162.987278 -27.133394)
			(xy 162.967355 -27.081303) (xy 162.955229 -27.026866) (xy 162.951158 -26.971244) (xy 159.539432 -26.971244)
			(xy 159.539432 -27.342846) (xy 159.539015 -27.372833) (xy 159.531181 -27.432292) (xy 159.515653 -27.49022)
			(xy 159.492697 -27.545626) (xy 159.462706 -27.597562) (xy 159.426193 -27.645139) (xy 159.383782 -27.687543)
			(xy 159.336199 -27.724048) (xy 159.284258 -27.754031) (xy 159.228848 -27.776978) (xy 159.170917 -27.792496)
			(xy 159.111457 -27.80032) (xy 159.08147 -27.800808) (xy 159.050333 -27.800279) (xy 158.988637 -27.791814)
			(xy 158.928652 -27.775083) (xy 158.89986 -27.763216) (xy 158.888684 -27.75839) (xy 158.865062 -27.75966)
			(xy 158.773876 -27.810968) (xy 158.760414 -27.830526) (xy 158.75889 -27.842464) (xy 158.754698 -27.869498)
			(xy 158.739517 -27.922058) (xy 158.716986 -27.971911) (xy 158.687567 -28.018036) (xy 158.651864 -28.059488)
			(xy 158.610608 -28.095417) (xy 158.564644 -28.125087) (xy 158.514914 -28.14789) (xy 158.462439 -28.163358)
			(xy 158.408292 -28.171176) (xy 158.380938 -28.171648) (xy 158.353686 -28.171107) (xy 158.299737 -28.163356)
			(xy 158.24744 -28.148004) (xy 158.19786 -28.125366) (xy 158.152007 -28.095903) (xy 158.110814 -28.060213)
			(xy 158.07512 -28.019023) (xy 158.045652 -27.973173) (xy 158.023009 -27.923596) (xy 158.007652 -27.8713)
			(xy 157.999895 -27.817352) (xy 156.729949 -27.817352) (xy 156.729937 -27.818026) (xy 156.721817 -27.873202)
			(xy 156.705749 -27.926609) (xy 156.682077 -27.977106) (xy 156.651304 -28.023619) (xy 156.614087 -28.065156)
			(xy 156.571219 -28.100831) (xy 156.523613 -28.129885) (xy 156.472284 -28.151697) (xy 156.418327 -28.165803)
			(xy 156.36289 -28.171903) (xy 156.307156 -28.169866) (xy 156.252313 -28.159736) (xy 156.199529 -28.141729)
			(xy 156.149929 -28.116228) (xy 156.104571 -28.083777) (xy 156.064422 -28.045068) (xy 156.030336 -28.000925)
			(xy 156.00304 -27.95229) (xy 155.983117 -27.900199) (xy 155.970991 -27.845762) (xy 155.96692 -27.79014)
			(xy 154.226514 -27.79014) (xy 154.226005 -27.818026) (xy 154.217885 -27.873202) (xy 154.201817 -27.926609)
			(xy 154.178145 -27.977106) (xy 154.147372 -28.023619) (xy 154.110155 -28.065156) (xy 154.067287 -28.100831)
			(xy 154.019681 -28.129885) (xy 153.968352 -28.151697) (xy 153.914395 -28.165803) (xy 153.858958 -28.171903)
			(xy 153.803224 -28.169866) (xy 153.748381 -28.159736) (xy 153.695597 -28.141729) (xy 153.645997 -28.116228)
			(xy 153.600639 -28.083777) (xy 153.56049 -28.045068) (xy 153.526404 -28.000925) (xy 153.499108 -27.95229)
			(xy 153.479185 -27.900199) (xy 153.467059 -27.845762) (xy 153.462988 -27.79014) (xy 152.243536 -27.79014)
			(xy 152.243536 -29.589984) (xy 153.462988 -29.589984) (xy 153.467059 -29.534362) (xy 153.479185 -29.479925)
			(xy 153.499108 -29.427834) (xy 153.526404 -29.379199) (xy 153.56049 -29.335056) (xy 153.600639 -29.296347)
			(xy 153.645997 -29.263896) (xy 153.695597 -29.238395) (xy 153.748381 -29.220388) (xy 153.803224 -29.210258)
			(xy 153.858958 -29.208221) (xy 153.914395 -29.214321) (xy 153.968352 -29.228427) (xy 154.019681 -29.250239)
			(xy 154.067287 -29.279293) (xy 154.110155 -29.314968) (xy 154.147372 -29.356505) (xy 154.178145 -29.403018)
			(xy 154.201817 -29.453515) (xy 154.217885 -29.506922) (xy 154.226005 -29.562098) (xy 154.226514 -29.589984)
			(xy 155.96692 -29.589984) (xy 155.970991 -29.534362) (xy 155.983117 -29.479925) (xy 156.00304 -29.427834)
			(xy 156.030336 -29.379199) (xy 156.064422 -29.335056) (xy 156.104571 -29.296347) (xy 156.149929 -29.263896)
			(xy 156.199529 -29.238395) (xy 156.252313 -29.220388) (xy 156.307156 -29.210258) (xy 156.36289 -29.208221)
			(xy 156.418327 -29.214321) (xy 156.472284 -29.228427) (xy 156.523613 -29.250239) (xy 156.571219 -29.279293)
			(xy 156.614087 -29.314968) (xy 156.651304 -29.356505) (xy 156.682077 -29.403018) (xy 156.705749 -29.453515)
			(xy 156.721817 -29.506922) (xy 156.729937 -29.562098) (xy 156.730446 -29.589984) (xy 157.99892 -29.589984)
			(xy 158.002991 -29.534362) (xy 158.015117 -29.479925) (xy 158.03504 -29.427834) (xy 158.062336 -29.379199)
			(xy 158.096422 -29.335056) (xy 158.136571 -29.296347) (xy 158.181929 -29.263896) (xy 158.231529 -29.238395)
			(xy 158.284313 -29.220388) (xy 158.339156 -29.210258) (xy 158.39489 -29.208221) (xy 158.450327 -29.214321)
			(xy 158.504284 -29.228427) (xy 158.555613 -29.250239) (xy 158.603219 -29.279293) (xy 158.646087 -29.314968)
			(xy 158.667761 -29.339158) (xy 160.390209 -29.339158) (xy 160.390209 -29.284642) (xy 160.397968 -29.230682)
			(xy 160.413327 -29.178375) (xy 160.435975 -29.128787) (xy 160.465449 -29.082927) (xy 160.501151 -29.041728)
			(xy 160.542352 -29.00603) (xy 160.588215 -28.97656) (xy 160.637805 -28.953916) (xy 160.690113 -28.938561)
			(xy 160.744074 -28.930807) (xy 160.771332 -28.930346) (xy 160.786125 -28.930487) (xy 160.815623 -28.932772)
			(xy 160.83026 -28.934918) (xy 160.841182 -28.936696) (xy 160.862518 -28.9306) (xy 160.929828 -28.873196)
			(xy 160.937855 -28.865628) (xy 160.94707 -28.845608) (xy 160.947608 -28.834588) (xy 160.947608 -28.530296)
			(xy 160.94707 -28.519277) (xy 160.93785 -28.499261) (xy 160.929828 -28.491688) (xy 160.862518 -28.434284)
			(xy 160.841182 -28.428188) (xy 160.83026 -28.429966) (xy 160.815622 -28.432106) (xy 160.786125 -28.434395)
			(xy 160.771332 -28.434538) (xy 160.74408 -28.434017) (xy 160.69013 -28.426264) (xy 160.637832 -28.410912)
			(xy 160.588252 -28.388273) (xy 160.542398 -28.358808) (xy 160.501205 -28.323118) (xy 160.465511 -28.281927)
			(xy 160.436042 -28.236076) (xy 160.413399 -28.186498) (xy 160.398043 -28.134202) (xy 160.390285 -28.080252)
			(xy 160.390285 -28.025748) (xy 160.398043 -27.971798) (xy 160.413399 -27.919502) (xy 160.436042 -27.869924)
			(xy 160.465511 -27.824073) (xy 160.501205 -27.782882) (xy 160.542398 -27.747192) (xy 160.588252 -27.717727)
			(xy 160.637832 -27.695088) (xy 160.69013 -27.679736) (xy 160.74408 -27.671983) (xy 160.771332 -27.671522)
			(xy 160.79726 -27.671922) (xy 160.848638 -27.678933) (xy 160.898595 -27.692835) (xy 160.94621 -27.713372)
			(xy 160.990606 -27.740166) (xy 161.030966 -27.772723) (xy 161.066547 -27.810445) (xy 161.081974 -27.831288)
			(xy 161.087713 -27.838619) (xy 161.103217 -27.848904) (xy 161.1122 -27.851354) (xy 161.142426 -27.858212)
			(xy 161.151704 -27.85995) (xy 161.170365 -27.857216) (xy 161.178748 -27.852878) (xy 161.204715 -27.838566)
			(xy 161.25957 -27.816059) (xy 161.316876 -27.800838) (xy 161.37567 -27.793157) (xy 161.405316 -27.79268)
			(xy 161.434958 -27.793202) (xy 161.493739 -27.800916) (xy 161.551037 -27.816135) (xy 161.605899 -27.838607)
			(xy 161.631884 -27.852878) (xy 161.640296 -27.857127) (xy 161.658927 -27.859858) (xy 161.668206 -27.858212)
			(xy 161.698432 -27.851354) (xy 161.707427 -27.848931) (xy 161.722931 -27.838635) (xy 161.728658 -27.831288)
			(xy 161.744083 -27.810442) (xy 161.779653 -27.772707) (xy 161.820008 -27.740141) (xy 161.864406 -27.713345)
			(xy 161.912025 -27.692814) (xy 161.961987 -27.678926) (xy 162.013371 -27.671938) (xy 162.0393 -27.671522)
			(xy 162.066553 -27.671948) (xy 162.120505 -27.679705) (xy 162.172804 -27.695061) (xy 162.222385 -27.717704)
			(xy 162.268239 -27.747173) (xy 162.309433 -27.782867) (xy 162.345127 -27.824061) (xy 162.374596 -27.869915)
			(xy 162.397239 -27.919496) (xy 162.412595 -27.971795) (xy 162.420352 -28.025747) (xy 162.420352 -28.080253)
			(xy 162.412595 -28.134205) (xy 162.397239 -28.186504) (xy 162.374596 -28.236085) (xy 162.345127 -28.281939)
			(xy 162.309433 -28.323133) (xy 162.268239 -28.358827) (xy 162.222385 -28.388296) (xy 162.172804 -28.410939)
			(xy 162.120505 -28.426295) (xy 162.066553 -28.434052) (xy 162.0393 -28.434538) (xy 162.024507 -28.434405)
			(xy 161.995009 -28.432115) (xy 161.980372 -28.429966) (xy 161.96945 -28.428188) (xy 161.948114 -28.434284)
			(xy 161.880804 -28.491688) (xy 161.872789 -28.499267) (xy 161.863566 -28.519279) (xy 161.863024 -28.530296)
			(xy 161.863024 -28.834588) (xy 161.863561 -28.845607) (xy 161.87278 -28.865624) (xy 161.880804 -28.873196)
			(xy 161.948114 -28.9306) (xy 161.96945 -28.936696) (xy 161.980372 -28.934918) (xy 161.995009 -28.932774)
			(xy 162.024507 -28.930488) (xy 162.0393 -28.930346) (xy 162.066548 -28.930924) (xy 162.120489 -28.93868)
			(xy 162.172777 -28.954033) (xy 162.222349 -28.976671) (xy 162.268194 -29.006134) (xy 162.309379 -29.041821)
			(xy 162.345066 -29.083006) (xy 162.374529 -29.128851) (xy 162.397167 -29.178423) (xy 162.41252 -29.230711)
			(xy 162.420276 -29.284652) (xy 162.420276 -29.339148) (xy 162.41252 -29.393089) (xy 162.397167 -29.445377)
			(xy 162.374529 -29.494949) (xy 162.345066 -29.540794) (xy 162.309379 -29.581979) (xy 162.268194 -29.617666)
			(xy 162.222349 -29.647129) (xy 162.172777 -29.669767) (xy 162.120489 -29.68512) (xy 162.066548 -29.692876)
			(xy 162.0393 -29.693362) (xy 162.013373 -29.692945) (xy 161.961995 -29.685938) (xy 161.912038 -29.67204)
			(xy 161.864423 -29.651506) (xy 161.820027 -29.624714) (xy 161.779666 -29.592159) (xy 161.744085 -29.554438)
			(xy 161.728658 -29.533596) (xy 161.722891 -29.526289) (xy 161.707408 -29.515989) (xy 161.698432 -29.51353)
			(xy 161.668206 -29.506672) (xy 161.658932 -29.504899) (xy 161.640266 -29.507657) (xy 161.631884 -29.512006)
			(xy 161.60591 -29.526305) (xy 161.551057 -29.548815) (xy 161.493754 -29.56404) (xy 161.434962 -29.571725)
			(xy 161.405316 -29.572204) (xy 161.375673 -29.571713) (xy 161.316891 -29.56399) (xy 161.259592 -29.548762)
			(xy 161.204732 -29.526281) (xy 161.178748 -29.512006) (xy 161.17033 -29.507772) (xy 161.151704 -29.505031)
			(xy 161.142426 -29.506672) (xy 161.1122 -29.51353) (xy 161.103198 -29.51593) (xy 161.087698 -29.526243)
			(xy 161.081974 -29.533596) (xy 161.066524 -29.554423) (xy 161.03096 -29.592159) (xy 160.990608 -29.624728)
			(xy 160.946215 -29.651526) (xy 160.8986 -29.672061) (xy 160.848641 -29.685952) (xy 160.79726 -29.692944)
			(xy 160.771332 -29.693362) (xy 160.744074 -29.692993) (xy 160.690113 -29.685239) (xy 160.637805 -29.669884)
			(xy 160.588215 -29.64724) (xy 160.542352 -29.61777) (xy 160.501151 -29.582072) (xy 160.465449 -29.540873)
			(xy 160.435975 -29.495013) (xy 160.413327 -29.445425) (xy 160.397968 -29.393118) (xy 160.390209 -29.339158)
			(xy 158.667761 -29.339158) (xy 158.683304 -29.356505) (xy 158.714077 -29.403018) (xy 158.737749 -29.453515)
			(xy 158.753817 -29.506922) (xy 158.761937 -29.562098) (xy 158.762446 -29.589984) (xy 158.761937 -29.61787)
			(xy 158.753817 -29.673046) (xy 158.737749 -29.726453) (xy 158.714077 -29.77695) (xy 158.683304 -29.823463)
			(xy 158.646087 -29.865) (xy 158.619944 -29.886756) (xy 163.032333 -29.886756) (xy 163.032333 -29.832244)
			(xy 163.040091 -29.778286) (xy 163.05545 -29.725982) (xy 163.078097 -29.676396) (xy 163.107571 -29.630539)
			(xy 163.143271 -29.589342) (xy 163.184471 -29.553647) (xy 163.230331 -29.524178) (xy 163.27992 -29.501536)
			(xy 163.332225 -29.486183) (xy 163.386184 -29.47843) (xy 163.41344 -29.47797) (xy 163.439367 -29.478385)
			(xy 163.490744 -29.485396) (xy 163.540699 -29.499297) (xy 163.588313 -29.519832) (xy 163.63271 -29.546623)
			(xy 163.673071 -29.579177) (xy 163.708654 -29.616895) (xy 163.724082 -29.637736) (xy 163.729828 -29.645061)
			(xy 163.745326 -29.655351) (xy 163.754308 -29.657802) (xy 163.784534 -29.66466) (xy 163.793812 -29.666397)
			(xy 163.812473 -29.663662) (xy 163.820856 -29.659326) (xy 163.846823 -29.645015) (xy 163.901678 -29.622507)
			(xy 163.958984 -29.607285) (xy 164.017778 -29.599605) (xy 164.047424 -29.599128) (xy 164.077066 -29.599653)
			(xy 164.135847 -29.607367) (xy 164.193145 -29.622586) (xy 164.248006 -29.645056) (xy 164.273992 -29.659326)
			(xy 164.282403 -29.663577) (xy 164.301035 -29.666309) (xy 164.310314 -29.66466) (xy 164.34054 -29.657802)
			(xy 164.34953 -29.655367) (xy 164.365036 -29.645079) (xy 164.370766 -29.637736) (xy 164.386171 -29.616875)
			(xy 164.421746 -29.579143) (xy 164.462106 -29.546579) (xy 164.506506 -29.519786) (xy 164.554128 -29.499257)
			(xy 164.604093 -29.485371) (xy 164.655478 -29.478385) (xy 164.681408 -29.47797) (xy 164.708657 -29.478501)
			(xy 164.762601 -29.486258) (xy 164.814892 -29.501613) (xy 164.864465 -29.524253) (xy 164.910312 -29.553718)
			(xy 164.951499 -29.589407) (xy 164.987187 -29.630595) (xy 165.016651 -29.676442) (xy 165.03929 -29.726016)
			(xy 165.054644 -29.778307) (xy 165.0624 -29.832251) (xy 165.0624 -29.886749) (xy 165.054644 -29.940693)
			(xy 165.03929 -29.992984) (xy 165.016651 -30.042558) (xy 164.987187 -30.088405) (xy 164.951499 -30.129593)
			(xy 164.910312 -30.165282) (xy 164.864465 -30.194747) (xy 164.814892 -30.217387) (xy 164.762601 -30.232742)
			(xy 164.708657 -30.240499) (xy 164.681408 -30.240986) (xy 164.666615 -30.240852) (xy 164.637117 -30.238562)
			(xy 164.62248 -30.236414) (xy 164.611558 -30.234636) (xy 164.590222 -30.240732) (xy 164.522912 -30.298136)
			(xy 164.514876 -30.305697) (xy 164.505664 -30.325722) (xy 164.505132 -30.336744) (xy 164.505132 -30.641036)
			(xy 164.50564 -30.652059) (xy 164.514879 -30.672076) (xy 164.522912 -30.679644) (xy 164.590222 -30.737048)
			(xy 164.611558 -30.743144) (xy 164.62248 -30.741366) (xy 164.637117 -30.739221) (xy 164.666615 -30.736936)
			(xy 164.681408 -30.736794) (xy 164.708659 -30.737276) (xy 164.762606 -30.745034) (xy 164.8149 -30.76039)
			(xy 164.864477 -30.783031) (xy 164.910326 -30.812498) (xy 164.951516 -30.84819) (xy 164.987207 -30.88938)
			(xy 165.016672 -30.93523) (xy 165.039313 -30.984807) (xy 165.054668 -31.037102) (xy 165.062424 -31.091049)
			(xy 165.062424 -31.145551) (xy 165.054668 -31.199498) (xy 165.039313 -31.251793) (xy 165.016672 -31.30137)
			(xy 164.987207 -31.34722) (xy 164.951516 -31.38841) (xy 164.910326 -31.424102) (xy 164.864477 -31.453569)
			(xy 164.8149 -31.47621) (xy 164.762606 -31.491566) (xy 164.708659 -31.499324) (xy 164.681408 -31.49981)
			(xy 164.655482 -31.499367) (xy 164.604106 -31.492362) (xy 164.55415 -31.478467) (xy 164.506536 -31.457936)
			(xy 164.46214 -31.431149) (xy 164.421778 -31.398599) (xy 164.386195 -31.360884) (xy 164.370766 -31.340044)
			(xy 164.365007 -31.332731) (xy 164.349518 -31.322435) (xy 164.34054 -31.319978) (xy 164.310314 -31.31312)
			(xy 164.30104 -31.311346) (xy 164.282373 -31.314103) (xy 164.273992 -31.318454) (xy 164.248019 -31.332754)
			(xy 164.193165 -31.355263) (xy 164.135862 -31.370487) (xy 164.07707 -31.378172) (xy 164.047424 -31.378652)
			(xy 164.017781 -31.378151) (xy 163.959 -31.370431) (xy 163.901701 -31.355205) (xy 163.846841 -31.332727)
			(xy 163.820856 -31.318454) (xy 163.812435 -31.314226) (xy 163.793812 -31.31148) (xy 163.784534 -31.31312)
			(xy 163.754308 -31.319978) (xy 163.745313 -31.322398) (xy 163.72981 -31.332697) (xy 163.724082 -31.340044)
			(xy 163.708641 -31.360878) (xy 163.673074 -31.398612) (xy 163.63272 -31.431178) (xy 163.588326 -31.457975)
			(xy 163.540709 -31.478508) (xy 163.490749 -31.492399) (xy 163.439368 -31.499392) (xy 163.41344 -31.49981)
			(xy 163.386185 -31.499345) (xy 163.33223 -31.491593) (xy 163.279928 -31.476241) (xy 163.230343 -31.453601)
			(xy 163.184485 -31.424134) (xy 163.143288 -31.38844) (xy 163.10759 -31.347247) (xy 163.078119 -31.301392)
			(xy 163.055473 -31.251809) (xy 163.040115 -31.199509) (xy 163.032357 -31.145555) (xy 163.032357 -31.091045)
			(xy 163.040115 -31.037091) (xy 163.055473 -30.984791) (xy 163.078119 -30.935208) (xy 163.10759 -30.889353)
			(xy 163.143288 -30.84816) (xy 163.184485 -30.812466) (xy 163.230343 -30.782999) (xy 163.279928 -30.760359)
			(xy 163.33223 -30.745007) (xy 163.386185 -30.737255) (xy 163.41344 -30.736794) (xy 163.428233 -30.736935)
			(xy 163.457731 -30.73922) (xy 163.472368 -30.741366) (xy 163.48329 -30.743144) (xy 163.504626 -30.737048)
			(xy 163.571936 -30.679644) (xy 163.579943 -30.672058) (xy 163.589169 -30.652051) (xy 163.589716 -30.641036)
			(xy 163.589716 -30.336744) (xy 163.589149 -30.325729) (xy 163.579949 -30.305712) (xy 163.571936 -30.298136)
			(xy 163.504626 -30.240732) (xy 163.48329 -30.234636) (xy 163.472368 -30.236414) (xy 163.45773 -30.238553)
			(xy 163.428233 -30.240842) (xy 163.41344 -30.240986) (xy 163.386184 -30.24057) (xy 163.332225 -30.232817)
			(xy 163.27992 -30.217464) (xy 163.230331 -30.194822) (xy 163.184471 -30.165353) (xy 163.143271 -30.129658)
			(xy 163.107571 -30.088461) (xy 163.078097 -30.042604) (xy 163.05545 -29.993018) (xy 163.040091 -29.940714)
			(xy 163.032333 -29.886756) (xy 158.619944 -29.886756) (xy 158.603219 -29.900675) (xy 158.555613 -29.929729)
			(xy 158.504284 -29.951541) (xy 158.450327 -29.965647) (xy 158.39489 -29.971747) (xy 158.339156 -29.96971)
			(xy 158.284313 -29.95958) (xy 158.231529 -29.941573) (xy 158.181929 -29.916072) (xy 158.136571 -29.883621)
			(xy 158.096422 -29.844912) (xy 158.062336 -29.800769) (xy 158.03504 -29.752134) (xy 158.015117 -29.700043)
			(xy 158.002991 -29.645606) (xy 157.99892 -29.589984) (xy 156.730446 -29.589984) (xy 156.729937 -29.61787)
			(xy 156.721817 -29.673046) (xy 156.705749 -29.726453) (xy 156.682077 -29.77695) (xy 156.651304 -29.823463)
			(xy 156.614087 -29.865) (xy 156.571219 -29.900675) (xy 156.523613 -29.929729) (xy 156.472284 -29.951541)
			(xy 156.418327 -29.965647) (xy 156.36289 -29.971747) (xy 156.307156 -29.96971) (xy 156.252313 -29.95958)
			(xy 156.199529 -29.941573) (xy 156.149929 -29.916072) (xy 156.104571 -29.883621) (xy 156.064422 -29.844912)
			(xy 156.030336 -29.800769) (xy 156.00304 -29.752134) (xy 155.983117 -29.700043) (xy 155.970991 -29.645606)
			(xy 155.96692 -29.589984) (xy 154.226514 -29.589984) (xy 154.226005 -29.61787) (xy 154.217885 -29.673046)
			(xy 154.201817 -29.726453) (xy 154.178145 -29.77695) (xy 154.147372 -29.823463) (xy 154.110155 -29.865)
			(xy 154.067287 -29.900675) (xy 154.019681 -29.929729) (xy 153.968352 -29.951541) (xy 153.914395 -29.965647)
			(xy 153.858958 -29.971747) (xy 153.803224 -29.96971) (xy 153.748381 -29.95958) (xy 153.695597 -29.941573)
			(xy 153.645997 -29.916072) (xy 153.600639 -29.883621) (xy 153.56049 -29.844912) (xy 153.526404 -29.800769)
			(xy 153.499108 -29.752134) (xy 153.479185 -29.700043) (xy 153.467059 -29.645606) (xy 153.462988 -29.589984)
			(xy 152.243536 -29.589984) (xy 152.243536 -31.642304) (xy 153.506676 -31.642304) (xy 153.510747 -31.586682)
			(xy 153.522873 -31.532245) (xy 153.542796 -31.480154) (xy 153.570092 -31.431519) (xy 153.604178 -31.387376)
			(xy 153.644327 -31.348667) (xy 153.689685 -31.316216) (xy 153.739285 -31.290715) (xy 153.792069 -31.272708)
			(xy 153.846912 -31.262578) (xy 153.902646 -31.260541) (xy 153.958083 -31.266641) (xy 154.01204 -31.280747)
			(xy 154.063369 -31.302559) (xy 154.110975 -31.331613) (xy 154.153843 -31.367288) (xy 154.174266 -31.390082)
			(xy 155.96692 -31.390082) (xy 155.970991 -31.33446) (xy 155.983117 -31.280023) (xy 156.00304 -31.227932)
			(xy 156.030336 -31.179297) (xy 156.064422 -31.135154) (xy 156.104571 -31.096445) (xy 156.149929 -31.063994)
			(xy 156.199529 -31.038493) (xy 156.252313 -31.020486) (xy 156.307156 -31.010356) (xy 156.36289 -31.008319)
			(xy 156.418327 -31.014419) (xy 156.472284 -31.028525) (xy 156.523613 -31.050337) (xy 156.571219 -31.079391)
			(xy 156.614087 -31.115066) (xy 156.651304 -31.156603) (xy 156.682077 -31.203116) (xy 156.705749 -31.253613)
			(xy 156.721817 -31.30702) (xy 156.729937 -31.362196) (xy 156.730446 -31.390082) (xy 157.99892 -31.390082)
			(xy 158.002991 -31.33446) (xy 158.015117 -31.280023) (xy 158.03504 -31.227932) (xy 158.062336 -31.179297)
			(xy 158.096422 -31.135154) (xy 158.136571 -31.096445) (xy 158.181929 -31.063994) (xy 158.231529 -31.038493)
			(xy 158.284313 -31.020486) (xy 158.339156 -31.010356) (xy 158.39489 -31.008319) (xy 158.450327 -31.014419)
			(xy 158.504284 -31.028525) (xy 158.555613 -31.050337) (xy 158.603219 -31.079391) (xy 158.646087 -31.115066)
			(xy 158.683304 -31.156603) (xy 158.714077 -31.203116) (xy 158.737749 -31.253613) (xy 158.753817 -31.30702)
			(xy 158.761937 -31.362196) (xy 158.762446 -31.390082) (xy 158.761937 -31.417968) (xy 158.753817 -31.473144)
			(xy 158.737749 -31.526551) (xy 158.714077 -31.577048) (xy 158.683304 -31.623561) (xy 158.646087 -31.665098)
			(xy 158.627873 -31.680256) (xy 160.390227 -31.680256) (xy 160.390227 -31.625744) (xy 160.397985 -31.571786)
			(xy 160.413344 -31.519482) (xy 160.435991 -31.469896) (xy 160.465464 -31.424038) (xy 160.501164 -31.382841)
			(xy 160.542363 -31.347145) (xy 160.588224 -31.317675) (xy 160.637812 -31.295033) (xy 160.690117 -31.279679)
			(xy 160.744076 -31.271925) (xy 160.771332 -31.271464) (xy 160.79726 -31.271846) (xy 160.848641 -31.278858)
			(xy 160.898598 -31.292762) (xy 160.946214 -31.313301) (xy 160.99061 -31.340098) (xy 161.030969 -31.372659)
			(xy 161.066548 -31.410385) (xy 161.081974 -31.43123) (xy 161.087725 -31.438551) (xy 161.10322 -31.448843)
			(xy 161.1122 -31.451296) (xy 161.142426 -31.458154) (xy 161.151704 -31.459887) (xy 161.170365 -31.457155)
			(xy 161.178748 -31.45282) (xy 161.204731 -31.43856) (xy 161.259603 -31.416149) (xy 161.316904 -31.400994)
			(xy 161.37568 -31.393347) (xy 161.405316 -31.392876) (xy 161.434954 -31.393309) (xy 161.493738 -31.400938)
			(xy 161.551041 -31.416104) (xy 161.605902 -31.438552) (xy 161.631884 -31.45282) (xy 161.640297 -31.457067)
			(xy 161.658927 -31.459801) (xy 161.668206 -31.458154) (xy 161.698432 -31.451296) (xy 161.707422 -31.448859)
			(xy 161.722928 -31.438572) (xy 161.728658 -31.43123) (xy 161.744067 -31.410372) (xy 161.779641 -31.372639)
			(xy 161.82 -31.340076) (xy 161.8644 -31.313283) (xy 161.912021 -31.292753) (xy 161.961986 -31.278867)
			(xy 162.013371 -31.27188) (xy 162.0393 -31.271464) (xy 162.066549 -31.272006) (xy 162.120493 -31.279762)
			(xy 162.172784 -31.295116) (xy 162.222357 -31.317756) (xy 162.268204 -31.34722) (xy 162.309391 -31.382909)
			(xy 162.34508 -31.424096) (xy 162.374544 -31.469943) (xy 162.397184 -31.519516) (xy 162.412538 -31.571807)
			(xy 162.420294 -31.625751) (xy 162.420294 -31.680249) (xy 162.412538 -31.734193) (xy 162.397184 -31.786484)
			(xy 162.374544 -31.836057) (xy 162.34508 -31.881904) (xy 162.309391 -31.923091) (xy 162.268204 -31.95878)
			(xy 162.222357 -31.988244) (xy 162.172784 -32.010884) (xy 162.120493 -32.026238) (xy 162.066549 -32.033994)
			(xy 162.0393 -32.03448) (xy 162.024507 -32.034347) (xy 161.995009 -32.032056) (xy 161.980372 -32.029908)
			(xy 161.96945 -32.02813) (xy 161.948114 -32.034226) (xy 161.880804 -32.09163) (xy 161.87277 -32.099192)
			(xy 161.863557 -32.119217) (xy 161.863024 -32.130238) (xy 161.863024 -32.43453) (xy 161.863538 -32.445552)
			(xy 161.872773 -32.465569) (xy 161.880804 -32.473138) (xy 161.948114 -32.530542) (xy 161.96945 -32.536638)
			(xy 161.980372 -32.53486) (xy 161.995009 -32.532716) (xy 162.024507 -32.53043) (xy 162.0393 -32.530288)
			(xy 162.066551 -32.530782) (xy 162.120498 -32.538538) (xy 162.172792 -32.553893) (xy 162.222369 -32.576534)
			(xy 162.268219 -32.606) (xy 162.309409 -32.641691) (xy 162.3451 -32.682881) (xy 162.374566 -32.728731)
			(xy 162.397207 -32.778308) (xy 162.412562 -32.830602) (xy 162.420318 -32.884549) (xy 162.420318 -32.939051)
			(xy 162.412562 -32.992998) (xy 162.397207 -33.045292) (xy 162.374566 -33.094869) (xy 162.3451 -33.140719)
			(xy 162.309409 -33.181909) (xy 162.268219 -33.2176) (xy 162.222369 -33.247066) (xy 162.172792 -33.269707)
			(xy 162.120498 -33.285062) (xy 162.066551 -33.292818) (xy 162.0393 -33.293304) (xy 162.013374 -33.29287)
			(xy 161.961997 -33.285863) (xy 161.912041 -33.271967) (xy 161.864427 -33.251435) (xy 161.820031 -33.224647)
			(xy 161.779669 -33.192095) (xy 161.744086 -33.154378) (xy 161.728658 -33.133538) (xy 161.722903 -33.126221)
			(xy 161.707411 -33.115928) (xy 161.698432 -33.113472) (xy 161.668206 -33.106614) (xy 161.658933 -33.104836)
			(xy 161.640265 -33.107596) (xy 161.631884 -33.111948) (xy 161.605893 -33.126193) (xy 161.551024 -33.148608)
			(xy 161.493726 -33.163768) (xy 161.434951 -33.171419) (xy 161.405316 -33.171892) (xy 161.375678 -33.171449)
			(xy 161.316895 -33.163824) (xy 161.259591 -33.148661) (xy 161.20473 -33.126215) (xy 161.178748 -33.111948)
			(xy 161.170329 -33.107716) (xy 161.151704 -33.104973) (xy 161.142426 -33.106614) (xy 161.1122 -33.113472)
			(xy 161.103204 -33.115891) (xy 161.087702 -33.126191) (xy 161.081974 -33.133538) (xy 161.066537 -33.154374)
			(xy 161.030968 -33.192109) (xy 160.990614 -33.224675) (xy 160.946219 -33.251471) (xy 160.898602 -33.272004)
			(xy 160.848642 -33.285895) (xy 160.79726 -33.292886) (xy 160.771332 -33.293304) (xy 160.744077 -33.292851)
			(xy 160.690122 -33.285097) (xy 160.63782 -33.269744) (xy 160.588236 -33.247103) (xy 160.542378 -33.217636)
			(xy 160.501181 -33.181942) (xy 160.465483 -33.140748) (xy 160.436012 -33.094893) (xy 160.413367 -33.04531)
			(xy 160.398009 -32.993009) (xy 160.390251 -32.939055) (xy 160.390251 -32.884545) (xy 160.398009 -32.830591)
			(xy 160.413367 -32.77829) (xy 160.436012 -32.728707) (xy 160.465483 -32.682852) (xy 160.501181 -32.641658)
			(xy 160.542378 -32.605964) (xy 160.588236 -32.576497) (xy 160.63782 -32.553856) (xy 160.690122 -32.538503)
			(xy 160.744077 -32.530749) (xy 160.771332 -32.530288) (xy 160.786125 -32.53043) (xy 160.815623 -32.532714)
			(xy 160.83026 -32.53486) (xy 160.841182 -32.536638) (xy 160.862518 -32.530542) (xy 160.929828 -32.473138)
			(xy 160.937837 -32.465553) (xy 160.947062 -32.445546) (xy 160.947608 -32.43453) (xy 160.947608 -32.130238)
			(xy 160.947047 -32.119222) (xy 160.937843 -32.099205) (xy 160.929828 -32.09163) (xy 160.862518 -32.034226)
			(xy 160.841182 -32.02813) (xy 160.83026 -32.029908) (xy 160.815622 -32.032048) (xy 160.786125 -32.034337)
			(xy 160.771332 -32.03448) (xy 160.744076 -32.034075) (xy 160.690117 -32.026321) (xy 160.637812 -32.010967)
			(xy 160.588224 -31.988325) (xy 160.542363 -31.958855) (xy 160.501164 -31.923159) (xy 160.465464 -31.881962)
			(xy 160.435991 -31.836104) (xy 160.413344 -31.786518) (xy 160.397985 -31.734214) (xy 160.390227 -31.680256)
			(xy 158.627873 -31.680256) (xy 158.603219 -31.700773) (xy 158.555613 -31.729827) (xy 158.504284 -31.751639)
			(xy 158.450327 -31.765745) (xy 158.39489 -31.771845) (xy 158.339156 -31.769808) (xy 158.284313 -31.759678)
			(xy 158.231529 -31.741671) (xy 158.181929 -31.71617) (xy 158.136571 -31.683719) (xy 158.096422 -31.64501)
			(xy 158.062336 -31.600867) (xy 158.03504 -31.552232) (xy 158.015117 -31.500141) (xy 158.002991 -31.445704)
			(xy 157.99892 -31.390082) (xy 156.730446 -31.390082) (xy 156.729937 -31.417968) (xy 156.721817 -31.473144)
			(xy 156.705749 -31.526551) (xy 156.682077 -31.577048) (xy 156.651304 -31.623561) (xy 156.614087 -31.665098)
			(xy 156.571219 -31.700773) (xy 156.523613 -31.729827) (xy 156.472284 -31.751639) (xy 156.418327 -31.765745)
			(xy 156.36289 -31.771845) (xy 156.307156 -31.769808) (xy 156.252313 -31.759678) (xy 156.199529 -31.741671)
			(xy 156.149929 -31.71617) (xy 156.104571 -31.683719) (xy 156.064422 -31.64501) (xy 156.030336 -31.600867)
			(xy 156.00304 -31.552232) (xy 155.983117 -31.500141) (xy 155.970991 -31.445704) (xy 155.96692 -31.390082)
			(xy 154.174266 -31.390082) (xy 154.19106 -31.408825) (xy 154.221833 -31.455338) (xy 154.245505 -31.505835)
			(xy 154.261573 -31.559242) (xy 154.269693 -31.614418) (xy 154.270202 -31.642304) (xy 154.269693 -31.67019)
			(xy 154.261573 -31.725366) (xy 154.245505 -31.778773) (xy 154.221833 -31.82927) (xy 154.19106 -31.875783)
			(xy 154.153843 -31.91732) (xy 154.110975 -31.952995) (xy 154.063369 -31.982049) (xy 154.01204 -32.003861)
			(xy 153.958083 -32.017967) (xy 153.902646 -32.024067) (xy 153.846912 -32.02203) (xy 153.792069 -32.0119)
			(xy 153.739285 -31.993893) (xy 153.689685 -31.968392) (xy 153.644327 -31.935941) (xy 153.604178 -31.897232)
			(xy 153.570092 -31.853089) (xy 153.542796 -31.804454) (xy 153.522873 -31.752363) (xy 153.510747 -31.697926)
			(xy 153.506676 -31.642304) (xy 152.243536 -31.642304) (xy 152.243536 -33.19018) (xy 153.774138 -33.19018)
			(xy 153.778209 -33.134558) (xy 153.790335 -33.080121) (xy 153.810258 -33.02803) (xy 153.837554 -32.979395)
			(xy 153.87164 -32.935252) (xy 153.911789 -32.896543) (xy 153.957147 -32.864092) (xy 154.006747 -32.838591)
			(xy 154.059531 -32.820584) (xy 154.114374 -32.810454) (xy 154.170108 -32.808417) (xy 154.225545 -32.814517)
			(xy 154.279502 -32.828623) (xy 154.330831 -32.850435) (xy 154.378437 -32.879489) (xy 154.421305 -32.915164)
			(xy 154.458522 -32.956701) (xy 154.489295 -33.003214) (xy 154.512967 -33.053711) (xy 154.529035 -33.107118)
			(xy 154.537155 -33.162294) (xy 154.537664 -33.19018) (xy 155.96692 -33.19018) (xy 155.970991 -33.134558)
			(xy 155.983117 -33.080121) (xy 156.00304 -33.02803) (xy 156.030336 -32.979395) (xy 156.064422 -32.935252)
			(xy 156.104571 -32.896543) (xy 156.149929 -32.864092) (xy 156.199529 -32.838591) (xy 156.252313 -32.820584)
			(xy 156.307156 -32.810454) (xy 156.36289 -32.808417) (xy 156.418327 -32.814517) (xy 156.472284 -32.828623)
			(xy 156.523613 -32.850435) (xy 156.571219 -32.879489) (xy 156.614087 -32.915164) (xy 156.651304 -32.956701)
			(xy 156.682077 -33.003214) (xy 156.705749 -33.053711) (xy 156.721817 -33.107118) (xy 156.729937 -33.162294)
			(xy 156.730446 -33.19018) (xy 157.99892 -33.19018) (xy 158.002991 -33.134558) (xy 158.015117 -33.080121)
			(xy 158.03504 -33.02803) (xy 158.062336 -32.979395) (xy 158.096422 -32.935252) (xy 158.136571 -32.896543)
			(xy 158.181929 -32.864092) (xy 158.231529 -32.838591) (xy 158.284313 -32.820584) (xy 158.339156 -32.810454)
			(xy 158.39489 -32.808417) (xy 158.450327 -32.814517) (xy 158.504284 -32.828623) (xy 158.555613 -32.850435)
			(xy 158.603219 -32.879489) (xy 158.646087 -32.915164) (xy 158.683304 -32.956701) (xy 158.714077 -33.003214)
			(xy 158.737749 -33.053711) (xy 158.753817 -33.107118) (xy 158.761937 -33.162294) (xy 158.762446 -33.19018)
			(xy 158.761937 -33.218066) (xy 158.753817 -33.273242) (xy 158.737749 -33.326649) (xy 158.714077 -33.377146)
			(xy 158.683304 -33.423659) (xy 158.646087 -33.465196) (xy 158.619938 -33.486957) (xy 163.032329 -33.486957)
			(xy 163.032329 -33.432443) (xy 163.040088 -33.378485) (xy 163.055447 -33.326181) (xy 163.078094 -33.276594)
			(xy 163.107567 -33.230736) (xy 163.143268 -33.18954) (xy 163.184468 -33.153843) (xy 163.23033 -33.124374)
			(xy 163.279918 -33.101733) (xy 163.332224 -33.086379) (xy 163.386183 -33.078626) (xy 163.41344 -33.078166)
			(xy 163.439369 -33.078541) (xy 163.490749 -33.085554) (xy 163.540707 -33.099459) (xy 163.588323 -33.12)
			(xy 163.632719 -33.146798) (xy 163.673078 -33.17936) (xy 163.708657 -33.217087) (xy 163.724082 -33.237932)
			(xy 163.72983 -33.245256) (xy 163.745327 -33.255546) (xy 163.754308 -33.257998) (xy 163.784534 -33.264856)
			(xy 163.793812 -33.266593) (xy 163.812473 -33.263859) (xy 163.820856 -33.259522) (xy 163.846823 -33.24521)
			(xy 163.901678 -33.222703) (xy 163.958984 -33.207481) (xy 164.017778 -33.199801) (xy 164.047424 -33.199324)
			(xy 164.077066 -33.19985) (xy 164.135847 -33.207564) (xy 164.193145 -33.222782) (xy 164.248006 -33.245252)
			(xy 164.273992 -33.259522) (xy 164.282403 -33.263773) (xy 164.301035 -33.266505) (xy 164.310314 -33.264856)
			(xy 164.34054 -33.257998) (xy 164.349531 -33.255564) (xy 164.365037 -33.245275) (xy 164.370766 -33.237932)
			(xy 164.38617 -33.21707) (xy 164.421745 -33.179338) (xy 164.462105 -33.146775) (xy 164.506506 -33.119982)
			(xy 164.554128 -33.099453) (xy 164.604093 -33.085567) (xy 164.655478 -33.078581) (xy 164.681408 -33.078166)
			(xy 164.708657 -33.078705) (xy 164.7626 -33.086462) (xy 164.81489 -33.101816) (xy 164.864463 -33.124456)
			(xy 164.910309 -33.153921) (xy 164.951496 -33.18961) (xy 164.987184 -33.230797) (xy 165.016647 -33.276644)
			(xy 165.039286 -33.326217) (xy 165.05464 -33.378508) (xy 165.062396 -33.432451) (xy 165.062396 -33.486949)
			(xy 165.05464 -33.540892) (xy 165.039286 -33.593183) (xy 165.016647 -33.642756) (xy 164.987184 -33.688603)
			(xy 164.951496 -33.72979) (xy 164.910309 -33.765479) (xy 164.864463 -33.794944) (xy 164.81489 -33.817584)
			(xy 164.7626 -33.832938) (xy 164.708657 -33.840695) (xy 164.681408 -33.841182) (xy 164.666615 -33.841048)
			(xy 164.637117 -33.838758) (xy 164.62248 -33.83661) (xy 164.611558 -33.834832) (xy 164.590222 -33.840928)
			(xy 164.522912 -33.898332) (xy 164.514878 -33.905895) (xy 164.505665 -33.925919) (xy 164.505132 -33.93694)
			(xy 164.505132 -34.241232) (xy 164.505642 -34.252255) (xy 164.51488 -34.272271) (xy 164.522912 -34.27984)
			(xy 164.590222 -34.337244) (xy 164.611558 -34.34334) (xy 164.62248 -34.341562) (xy 164.637117 -34.339417)
			(xy 164.666615 -34.337132) (xy 164.681408 -34.33699) (xy 164.708659 -34.33748) (xy 164.762605 -34.345238)
			(xy 164.814899 -34.360593) (xy 164.864475 -34.383235) (xy 164.910324 -34.412701) (xy 164.951513 -34.448393)
			(xy 164.987204 -34.489582) (xy 165.016669 -34.535432) (xy 165.039309 -34.585009) (xy 165.054664 -34.637303)
			(xy 165.06242 -34.691249) (xy 165.06242 -34.745751) (xy 165.054664 -34.799697) (xy 165.039309 -34.851991)
			(xy 165.016669 -34.901568) (xy 164.987204 -34.947418) (xy 164.951513 -34.988607) (xy 164.910324 -35.024299)
			(xy 164.864475 -35.053765) (xy 164.814899 -35.076407) (xy 164.762605 -35.091762) (xy 164.708659 -35.09952)
			(xy 164.681408 -35.100006) (xy 164.655482 -35.099565) (xy 164.604105 -35.09256) (xy 164.55415 -35.078664)
			(xy 164.506536 -35.058134) (xy 164.462139 -35.031346) (xy 164.421778 -34.998795) (xy 164.386194 -34.96108)
			(xy 164.370766 -34.94024) (xy 164.365007 -34.932926) (xy 164.349518 -34.922631) (xy 164.34054 -34.920174)
			(xy 164.310314 -34.913316) (xy 164.30104 -34.911542) (xy 164.282373 -34.914299) (xy 164.273992 -34.91865)
			(xy 164.248018 -34.932949) (xy 164.193165 -34.955458) (xy 164.135861 -34.970683) (xy 164.07707 -34.978368)
			(xy 164.047424 -34.978848) (xy 164.017781 -34.978348) (xy 163.959 -34.970627) (xy 163.901701 -34.955401)
			(xy 163.846841 -34.932924) (xy 163.820856 -34.91865) (xy 163.812435 -34.914422) (xy 163.793812 -34.911676)
			(xy 163.784534 -34.913316) (xy 163.754308 -34.920174) (xy 163.745313 -34.922595) (xy 163.72981 -34.932894)
			(xy 163.724082 -34.94024) (xy 163.70864 -34.961073) (xy 163.673073 -34.998807) (xy 163.63272 -35.031374)
			(xy 163.588325 -35.058171) (xy 163.540709 -35.078704) (xy 163.490749 -35.092595) (xy 163.439368 -35.099588)
			(xy 163.41344 -35.100006) (xy 163.386185 -35.099549) (xy 163.33223 -35.091797) (xy 163.279927 -35.076444)
			(xy 163.230341 -35.053804) (xy 163.184483 -35.024337) (xy 163.143285 -34.988643) (xy 163.107587 -34.947449)
			(xy 163.078115 -34.901594) (xy 163.05547 -34.852011) (xy 163.040112 -34.79971) (xy 163.032353 -34.745755)
			(xy 163.032353 -34.691245) (xy 163.040112 -34.63729) (xy 163.05547 -34.584989) (xy 163.078115 -34.535406)
			(xy 163.107587 -34.489551) (xy 163.143285 -34.448357) (xy 163.184483 -34.412663) (xy 163.230341 -34.383196)
			(xy 163.279927 -34.360556) (xy 163.33223 -34.345203) (xy 163.386185 -34.337451) (xy 163.41344 -34.33699)
			(xy 163.428233 -34.337131) (xy 163.457731 -34.339416) (xy 163.472368 -34.341562) (xy 163.48329 -34.34334)
			(xy 163.504626 -34.337244) (xy 163.571936 -34.27984) (xy 163.579945 -34.272255) (xy 163.58917 -34.252248)
			(xy 163.589716 -34.241232) (xy 163.589716 -33.93694) (xy 163.589151 -33.925925) (xy 163.57995 -33.905908)
			(xy 163.571936 -33.898332) (xy 163.504626 -33.840928) (xy 163.48329 -33.834832) (xy 163.472368 -33.83661)
			(xy 163.45773 -33.838749) (xy 163.428233 -33.841038) (xy 163.41344 -33.841182) (xy 163.386183 -33.840774)
			(xy 163.332224 -33.833021) (xy 163.279918 -33.817667) (xy 163.23033 -33.795026) (xy 163.184468 -33.765557)
			(xy 163.143268 -33.72986) (xy 163.107567 -33.688664) (xy 163.078094 -33.642806) (xy 163.055447 -33.593219)
			(xy 163.040088 -33.540915) (xy 163.032329 -33.486957) (xy 158.619938 -33.486957) (xy 158.603219 -33.500871)
			(xy 158.555613 -33.529925) (xy 158.504284 -33.551737) (xy 158.450327 -33.565843) (xy 158.39489 -33.571943)
			(xy 158.339156 -33.569906) (xy 158.284313 -33.559776) (xy 158.231529 -33.541769) (xy 158.181929 -33.516268)
			(xy 158.136571 -33.483817) (xy 158.096422 -33.445108) (xy 158.062336 -33.400965) (xy 158.03504 -33.35233)
			(xy 158.015117 -33.300239) (xy 158.002991 -33.245802) (xy 157.99892 -33.19018) (xy 156.730446 -33.19018)
			(xy 156.729937 -33.218066) (xy 156.721817 -33.273242) (xy 156.705749 -33.326649) (xy 156.682077 -33.377146)
			(xy 156.651304 -33.423659) (xy 156.614087 -33.465196) (xy 156.571219 -33.500871) (xy 156.523613 -33.529925)
			(xy 156.472284 -33.551737) (xy 156.418327 -33.565843) (xy 156.36289 -33.571943) (xy 156.307156 -33.569906)
			(xy 156.252313 -33.559776) (xy 156.199529 -33.541769) (xy 156.149929 -33.516268) (xy 156.104571 -33.483817)
			(xy 156.064422 -33.445108) (xy 156.030336 -33.400965) (xy 156.00304 -33.35233) (xy 155.983117 -33.300239)
			(xy 155.970991 -33.245802) (xy 155.96692 -33.19018) (xy 154.537664 -33.19018) (xy 154.537155 -33.218066)
			(xy 154.529035 -33.273242) (xy 154.512967 -33.326649) (xy 154.489295 -33.377146) (xy 154.458522 -33.423659)
			(xy 154.421305 -33.465196) (xy 154.378437 -33.500871) (xy 154.330831 -33.529925) (xy 154.279502 -33.551737)
			(xy 154.225545 -33.565843) (xy 154.170108 -33.571943) (xy 154.114374 -33.569906) (xy 154.059531 -33.559776)
			(xy 154.006747 -33.541769) (xy 153.957147 -33.516268) (xy 153.911789 -33.483817) (xy 153.87164 -33.445108)
			(xy 153.837554 -33.400965) (xy 153.810258 -33.35233) (xy 153.790335 -33.300239) (xy 153.778209 -33.245802)
			(xy 153.774138 -33.19018) (xy 152.243536 -33.19018) (xy 152.243536 -34.990024) (xy 153.772868 -34.990024)
			(xy 153.776939 -34.934402) (xy 153.789065 -34.879965) (xy 153.808988 -34.827874) (xy 153.836284 -34.779239)
			(xy 153.87037 -34.735096) (xy 153.910519 -34.696387) (xy 153.955877 -34.663936) (xy 154.005477 -34.638435)
			(xy 154.058261 -34.620428) (xy 154.113104 -34.610298) (xy 154.168838 -34.608261) (xy 154.224275 -34.614361)
			(xy 154.278232 -34.628467) (xy 154.329561 -34.650279) (xy 154.377167 -34.679333) (xy 154.420035 -34.715008)
			(xy 154.457252 -34.756545) (xy 154.488025 -34.803058) (xy 154.511697 -34.853555) (xy 154.527765 -34.906962)
			(xy 154.535885 -34.962138) (xy 154.536394 -34.990024) (xy 155.101034 -34.990024) (xy 155.105105 -34.934402)
			(xy 155.117231 -34.879965) (xy 155.137154 -34.827874) (xy 155.16445 -34.779239) (xy 155.198536 -34.735096)
			(xy 155.238685 -34.696387) (xy 155.284043 -34.663936) (xy 155.333643 -34.638435) (xy 155.386427 -34.620428)
			(xy 155.44127 -34.610298) (xy 155.497004 -34.608261) (xy 155.552441 -34.614361) (xy 155.606398 -34.628467)
			(xy 155.657727 -34.650279) (xy 155.705333 -34.679333) (xy 155.748201 -34.715008) (xy 155.785418 -34.756545)
			(xy 155.816191 -34.803058) (xy 155.839863 -34.853555) (xy 155.855931 -34.906962) (xy 155.864051 -34.962138)
			(xy 155.86456 -34.990024) (xy 157.99892 -34.990024) (xy 158.002991 -34.934402) (xy 158.015117 -34.879965)
			(xy 158.03504 -34.827874) (xy 158.062336 -34.779239) (xy 158.096422 -34.735096) (xy 158.136571 -34.696387)
			(xy 158.181929 -34.663936) (xy 158.231529 -34.638435) (xy 158.284313 -34.620428) (xy 158.339156 -34.610298)
			(xy 158.39489 -34.608261) (xy 158.450327 -34.614361) (xy 158.504284 -34.628467) (xy 158.555613 -34.650279)
			(xy 158.603219 -34.679333) (xy 158.646087 -34.715008) (xy 158.683304 -34.756545) (xy 158.714077 -34.803058)
			(xy 158.737749 -34.853555) (xy 158.753817 -34.906962) (xy 158.761937 -34.962138) (xy 158.762446 -34.990024)
			(xy 158.761937 -35.01791) (xy 158.753817 -35.073086) (xy 158.737749 -35.126493) (xy 158.714077 -35.17699)
			(xy 158.683304 -35.223503) (xy 158.646087 -35.26504) (xy 158.603219 -35.300715) (xy 158.555613 -35.329769)
			(xy 158.504284 -35.351581) (xy 158.450327 -35.365687) (xy 158.39489 -35.371787) (xy 158.339156 -35.36975)
			(xy 158.284313 -35.35962) (xy 158.231529 -35.341613) (xy 158.181929 -35.316112) (xy 158.136571 -35.283661)
			(xy 158.096422 -35.244952) (xy 158.062336 -35.200809) (xy 158.03504 -35.152174) (xy 158.015117 -35.100083)
			(xy 158.002991 -35.045646) (xy 157.99892 -34.990024) (xy 155.86456 -34.990024) (xy 155.864051 -35.01791)
			(xy 155.855931 -35.073086) (xy 155.839863 -35.126493) (xy 155.816191 -35.17699) (xy 155.785418 -35.223503)
			(xy 155.748201 -35.26504) (xy 155.705333 -35.300715) (xy 155.657727 -35.329769) (xy 155.606398 -35.351581)
			(xy 155.552441 -35.365687) (xy 155.497004 -35.371787) (xy 155.44127 -35.36975) (xy 155.386427 -35.35962)
			(xy 155.333643 -35.341613) (xy 155.284043 -35.316112) (xy 155.238685 -35.283661) (xy 155.198536 -35.244952)
			(xy 155.16445 -35.200809) (xy 155.137154 -35.152174) (xy 155.117231 -35.100083) (xy 155.105105 -35.045646)
			(xy 155.101034 -34.990024) (xy 154.536394 -34.990024) (xy 154.535885 -35.01791) (xy 154.527765 -35.073086)
			(xy 154.511697 -35.126493) (xy 154.488025 -35.17699) (xy 154.457252 -35.223503) (xy 154.420035 -35.26504)
			(xy 154.377167 -35.300715) (xy 154.329561 -35.329769) (xy 154.278232 -35.351581) (xy 154.224275 -35.365687)
			(xy 154.168838 -35.371787) (xy 154.113104 -35.36975) (xy 154.058261 -35.35962) (xy 154.005477 -35.341613)
			(xy 153.955877 -35.316112) (xy 153.910519 -35.283661) (xy 153.87037 -35.244952) (xy 153.836284 -35.200809)
			(xy 153.808988 -35.152174) (xy 153.789065 -35.100083) (xy 153.776939 -35.045646) (xy 153.772868 -34.990024)
			(xy 152.243536 -34.990024) (xy 152.243536 -38.193435) (xy 153.198386 -38.193435) (xy 153.198386 -38.106565)
			(xy 153.206401 -38.020064) (xy 153.222363 -37.934672) (xy 153.246136 -37.851118) (xy 153.277516 -37.770113)
			(xy 153.316237 -37.692349) (xy 153.361968 -37.618489) (xy 153.414319 -37.549164) (xy 153.472842 -37.484965)
			(xy 153.537039 -37.426439) (xy 153.606363 -37.374086) (xy 153.680221 -37.328353) (xy 153.757983 -37.289629)
			(xy 153.838987 -37.258246) (xy 153.922541 -37.23447) (xy 154.007933 -37.218505) (xy 154.094433 -37.210487)
			(xy 154.137868 -37.209984) (xy 154.215846 -37.209984) (xy 154.225859 -37.209549) (xy 154.244354 -37.201871)
			(xy 154.258506 -37.187702) (xy 154.266161 -37.169197) (xy 154.266646 -37.159184) (xy 154.266646 -37.151564)
			(xy 154.262328 -37.137594) (xy 154.258264 -37.131244) (xy 154.234345 -37.094009) (xy 154.192644 -37.015944)
			(xy 154.158259 -36.93439) (xy 154.131481 -36.850033) (xy 154.112532 -36.76358) (xy 154.101572 -36.675755)
			(xy 154.098694 -36.587297) (xy 154.103921 -36.498946) (xy 154.117209 -36.411443) (xy 154.138447 -36.325524)
			(xy 154.167456 -36.241908) (xy 154.203994 -36.161296) (xy 154.247755 -36.084366) (xy 154.298369 -36.011762)
			(xy 154.355415 -35.944093) (xy 154.418412 -35.881927) (xy 154.486832 -35.825786) (xy 154.560102 -35.776139)
			(xy 154.637607 -35.733405) (xy 154.718696 -35.69794) (xy 154.80269 -35.670044) (xy 154.888884 -35.649948)
			(xy 154.976555 -35.637824) (xy 155.064968 -35.633771) (xy 155.153381 -35.637824) (xy 155.241052 -35.649948)
			(xy 155.327246 -35.670044) (xy 155.41124 -35.69794) (xy 155.492329 -35.733405) (xy 155.569834 -35.776139)
			(xy 155.643104 -35.825786) (xy 155.7052 -35.876738) (xy 160.817304 -35.876738) (xy 160.821375 -35.821116)
			(xy 160.833501 -35.766679) (xy 160.853424 -35.714588) (xy 160.88072 -35.665953) (xy 160.914806 -35.62181)
			(xy 160.954955 -35.583101) (xy 161.000313 -35.55065) (xy 161.049913 -35.525149) (xy 161.102697 -35.507142)
			(xy 161.15754 -35.497012) (xy 161.213274 -35.494975) (xy 161.268711 -35.501075) (xy 161.322668 -35.515181)
			(xy 161.373997 -35.536993) (xy 161.421603 -35.566047) (xy 161.464471 -35.601722) (xy 161.501688 -35.643259)
			(xy 161.532461 -35.689772) (xy 161.556133 -35.740269) (xy 161.572201 -35.793676) (xy 161.580321 -35.848852)
			(xy 161.58083 -35.876738) (xy 161.580321 -35.904624) (xy 161.572201 -35.9598) (xy 161.556133 -36.013207)
			(xy 161.532461 -36.063704) (xy 161.501688 -36.110217) (xy 161.464471 -36.151754) (xy 161.421603 -36.187429)
			(xy 161.373997 -36.216483) (xy 161.322668 -36.238295) (xy 161.268711 -36.252401) (xy 161.213274 -36.258501)
			(xy 161.15754 -36.256464) (xy 161.102697 -36.246334) (xy 161.049913 -36.228327) (xy 161.000313 -36.202826)
			(xy 160.954955 -36.170375) (xy 160.914806 -36.131666) (xy 160.88072 -36.087523) (xy 160.853424 -36.038888)
			(xy 160.833501 -35.986797) (xy 160.821375 -35.93236) (xy 160.817304 -35.876738) (xy 155.7052 -35.876738)
			(xy 155.711524 -35.881927) (xy 155.774521 -35.944093) (xy 155.831567 -36.011762) (xy 155.882181 -36.084366)
			(xy 155.925942 -36.161296) (xy 155.96248 -36.241908) (xy 155.991489 -36.325524) (xy 156.012727 -36.411443)
			(xy 156.026015 -36.498946) (xy 156.02844 -36.539928) (xy 162.638722 -36.539928) (xy 162.638722 -36.479992)
			(xy 162.646545 -36.42057) (xy 162.662058 -36.362677) (xy 162.684994 -36.307304) (xy 162.714961 -36.255398)
			(xy 162.751448 -36.207848) (xy 162.793828 -36.165468) (xy 162.841378 -36.128981) (xy 162.893284 -36.099014)
			(xy 162.948657 -36.076078) (xy 163.00655 -36.060565) (xy 163.065972 -36.052742) (xy 163.125908 -36.052742)
			(xy 163.18533 -36.060565) (xy 163.243223 -36.076078) (xy 163.298596 -36.099014) (xy 163.350502 -36.128981)
			(xy 163.398052 -36.165468) (xy 163.440432 -36.207848) (xy 163.476919 -36.255398) (xy 163.506886 -36.307304)
			(xy 163.529822 -36.362677) (xy 163.545335 -36.42057) (xy 163.553158 -36.479992) (xy 163.553648 -36.50996)
			(xy 163.553158 -36.539928) (xy 163.545335 -36.59935) (xy 163.529822 -36.657243) (xy 163.506886 -36.712616)
			(xy 163.476919 -36.764522) (xy 163.440432 -36.812072) (xy 163.398052 -36.854452) (xy 163.350502 -36.890939)
			(xy 163.298596 -36.920906) (xy 163.243223 -36.943842) (xy 163.18533 -36.959355) (xy 163.125908 -36.967178)
			(xy 163.065972 -36.967178) (xy 163.00655 -36.959355) (xy 162.948657 -36.943842) (xy 162.893284 -36.920906)
			(xy 162.841378 -36.890939) (xy 162.793828 -36.854452) (xy 162.751448 -36.812072) (xy 162.714961 -36.764522)
			(xy 162.684994 -36.712616) (xy 162.662058 -36.657243) (xy 162.646545 -36.59935) (xy 162.638722 -36.539928)
			(xy 156.02844 -36.539928) (xy 156.031242 -36.587297) (xy 156.028364 -36.675755) (xy 156.017404 -36.76358)
			(xy 155.998455 -36.850033) (xy 155.971677 -36.93439) (xy 155.937292 -37.015944) (xy 155.895591 -37.094009)
			(xy 155.871672 -37.131244) (xy 155.86329 -37.143944) (xy 155.86329 -37.159184) (xy 155.863732 -37.169203)
			(xy 155.871395 -37.187718) (xy 155.88556 -37.20189) (xy 155.904071 -37.209563) (xy 155.91409 -37.209984)
			(xy 155.992068 -37.209984) (xy 156.03551 -37.210393) (xy 156.122022 -37.218407) (xy 156.207426 -37.234369)
			(xy 156.290993 -37.258143) (xy 156.37201 -37.289527) (xy 156.449786 -37.328252) (xy 156.523656 -37.373989)
			(xy 156.592991 -37.426346) (xy 156.646539 -37.47516) (xy 159.859216 -37.47516) (xy 159.863287 -37.419538)
			(xy 159.875413 -37.365101) (xy 159.895336 -37.31301) (xy 159.922632 -37.264375) (xy 159.956718 -37.220232)
			(xy 159.996867 -37.181523) (xy 160.042225 -37.149072) (xy 160.091825 -37.123571) (xy 160.144609 -37.105564)
			(xy 160.199452 -37.095434) (xy 160.255186 -37.093397) (xy 160.310623 -37.099497) (xy 160.36458 -37.113603)
			(xy 160.415909 -37.135415) (xy 160.463515 -37.164469) (xy 160.506383 -37.200144) (xy 160.507234 -37.201094)
			(xy 163.816536 -37.201094) (xy 163.820607 -37.145472) (xy 163.832733 -37.091035) (xy 163.852656 -37.038944)
			(xy 163.879952 -36.990309) (xy 163.914038 -36.946166) (xy 163.954187 -36.907457) (xy 163.999545 -36.875006)
			(xy 164.049145 -36.849505) (xy 164.101929 -36.831498) (xy 164.156772 -36.821368) (xy 164.212506 -36.819331)
			(xy 164.267943 -36.825431) (xy 164.3219 -36.839537) (xy 164.373229 -36.861349) (xy 164.420835 -36.890403)
			(xy 164.463703 -36.926078) (xy 164.50092 -36.967615) (xy 164.531693 -37.014128) (xy 164.555365 -37.064625)
			(xy 164.571433 -37.118032) (xy 164.579553 -37.173208) (xy 164.580062 -37.201094) (xy 164.579553 -37.22898)
			(xy 164.571433 -37.284156) (xy 164.555365 -37.337563) (xy 164.531693 -37.38806) (xy 164.50092 -37.434573)
			(xy 164.463703 -37.47611) (xy 164.420835 -37.511785) (xy 164.373229 -37.540839) (xy 164.3219 -37.562651)
			(xy 164.267943 -37.576757) (xy 164.212506 -37.582857) (xy 164.156772 -37.58082) (xy 164.101929 -37.57069)
			(xy 164.049145 -37.552683) (xy 163.999545 -37.527182) (xy 163.954187 -37.494731) (xy 163.914038 -37.456022)
			(xy 163.879952 -37.411879) (xy 163.852656 -37.363244) (xy 163.832733 -37.311153) (xy 163.820607 -37.256716)
			(xy 163.816536 -37.201094) (xy 160.507234 -37.201094) (xy 160.5436 -37.241681) (xy 160.574373 -37.288194)
			(xy 160.598045 -37.338691) (xy 160.614113 -37.392098) (xy 160.622233 -37.447274) (xy 160.622742 -37.47516)
			(xy 160.622233 -37.503046) (xy 160.614113 -37.558222) (xy 160.598045 -37.611629) (xy 160.574373 -37.662126)
			(xy 160.554393 -37.692326) (xy 161.973242 -37.692326) (xy 161.973242 -37.63239) (xy 161.981065 -37.572968)
			(xy 161.996578 -37.515075) (xy 162.019514 -37.459702) (xy 162.049481 -37.407796) (xy 162.085968 -37.360246)
			(xy 162.128348 -37.317866) (xy 162.175898 -37.281379) (xy 162.227804 -37.251412) (xy 162.283177 -37.228476)
			(xy 162.34107 -37.212963) (xy 162.400492 -37.20514) (xy 162.460428 -37.20514) (xy 162.51985 -37.212963)
			(xy 162.577743 -37.228476) (xy 162.633116 -37.251412) (xy 162.685022 -37.281379) (xy 162.732572 -37.317866)
			(xy 162.774952 -37.360246) (xy 162.811439 -37.407796) (xy 162.841406 -37.459702) (xy 162.864342 -37.515075)
			(xy 162.879855 -37.572968) (xy 162.887678 -37.63239) (xy 162.888168 -37.662358) (xy 162.887678 -37.692326)
			(xy 162.879855 -37.751748) (xy 162.864342 -37.809641) (xy 162.841406 -37.865014) (xy 162.811439 -37.91692)
			(xy 162.774952 -37.96447) (xy 162.732572 -38.00685) (xy 162.685022 -38.043337) (xy 162.633116 -38.073304)
			(xy 162.577743 -38.09624) (xy 162.51985 -38.111753) (xy 162.460428 -38.119576) (xy 162.400492 -38.119576)
			(xy 162.34107 -38.111753) (xy 162.283177 -38.09624) (xy 162.227804 -38.073304) (xy 162.175898 -38.043337)
			(xy 162.128348 -38.00685) (xy 162.085968 -37.96447) (xy 162.049481 -37.91692) (xy 162.019514 -37.865014)
			(xy 161.996578 -37.809641) (xy 161.981065 -37.751748) (xy 161.973242 -37.692326) (xy 160.554393 -37.692326)
			(xy 160.5436 -37.708639) (xy 160.506383 -37.750176) (xy 160.463515 -37.785851) (xy 160.415909 -37.814905)
			(xy 160.36458 -37.836717) (xy 160.310623 -37.850823) (xy 160.255186 -37.856923) (xy 160.199452 -37.854886)
			(xy 160.144609 -37.844756) (xy 160.091825 -37.826749) (xy 160.042225 -37.801248) (xy 159.996867 -37.768797)
			(xy 159.956718 -37.730088) (xy 159.922632 -37.685945) (xy 159.895336 -37.63731) (xy 159.875413 -37.585219)
			(xy 159.863287 -37.530782) (xy 159.859216 -37.47516) (xy 156.646539 -37.47516) (xy 156.6572 -37.484878)
			(xy 156.715733 -37.549084) (xy 156.768093 -37.618418) (xy 156.813832 -37.692286) (xy 156.85256 -37.770061)
			(xy 156.883946 -37.851076) (xy 156.907724 -37.934642) (xy 156.923689 -38.020046) (xy 156.931705 -38.106558)
			(xy 156.931705 -38.193442) (xy 156.923689 -38.279954) (xy 156.907724 -38.365358) (xy 156.883946 -38.448924)
			(xy 156.867583 -38.49116) (xy 159.859216 -38.49116) (xy 159.863287 -38.435538) (xy 159.875413 -38.381101)
			(xy 159.895336 -38.32901) (xy 159.922632 -38.280375) (xy 159.956718 -38.236232) (xy 159.996867 -38.197523)
			(xy 160.042225 -38.165072) (xy 160.091825 -38.139571) (xy 160.144609 -38.121564) (xy 160.199452 -38.111434)
			(xy 160.255186 -38.109397) (xy 160.310623 -38.115497) (xy 160.36458 -38.129603) (xy 160.415909 -38.151415)
			(xy 160.463515 -38.180469) (xy 160.506383 -38.216144) (xy 160.5436 -38.257681) (xy 160.574373 -38.304194)
			(xy 160.598045 -38.354691) (xy 160.614113 -38.408098) (xy 160.622233 -38.463274) (xy 160.622742 -38.49116)
			(xy 160.622233 -38.519046) (xy 160.614113 -38.574222) (xy 160.598045 -38.627629) (xy 160.574373 -38.678126)
			(xy 160.559095 -38.701218) (xy 163.537644 -38.701218) (xy 163.541715 -38.645596) (xy 163.553841 -38.591159)
			(xy 163.573764 -38.539068) (xy 163.60106 -38.490433) (xy 163.635146 -38.44629) (xy 163.675295 -38.407581)
			(xy 163.720653 -38.37513) (xy 163.770253 -38.349629) (xy 163.823037 -38.331622) (xy 163.87788 -38.321492)
			(xy 163.933614 -38.319455) (xy 163.989051 -38.325555) (xy 164.043008 -38.339661) (xy 164.094337 -38.361473)
			(xy 164.141943 -38.390527) (xy 164.184811 -38.426202) (xy 164.222028 -38.467739) (xy 164.252801 -38.514252)
			(xy 164.276473 -38.564749) (xy 164.292541 -38.618156) (xy 164.300661 -38.673332) (xy 164.30117 -38.701218)
			(xy 164.300661 -38.729104) (xy 164.292541 -38.78428) (xy 164.276473 -38.837687) (xy 164.252801 -38.888184)
			(xy 164.222028 -38.934697) (xy 164.184811 -38.976234) (xy 164.141943 -39.011909) (xy 164.094337 -39.040963)
			(xy 164.043008 -39.062775) (xy 163.989051 -39.076881) (xy 163.933614 -39.082981) (xy 163.87788 -39.080944)
			(xy 163.823037 -39.070814) (xy 163.770253 -39.052807) (xy 163.720653 -39.027306) (xy 163.675295 -38.994855)
			(xy 163.635146 -38.956146) (xy 163.60106 -38.912003) (xy 163.573764 -38.863368) (xy 163.553841 -38.811277)
			(xy 163.541715 -38.75684) (xy 163.537644 -38.701218) (xy 160.559095 -38.701218) (xy 160.5436 -38.724639)
			(xy 160.506383 -38.766176) (xy 160.463515 -38.801851) (xy 160.415909 -38.830905) (xy 160.36458 -38.852717)
			(xy 160.310623 -38.866823) (xy 160.255186 -38.872923) (xy 160.199452 -38.870886) (xy 160.144609 -38.860756)
			(xy 160.091825 -38.842749) (xy 160.042225 -38.817248) (xy 159.996867 -38.784797) (xy 159.956718 -38.746088)
			(xy 159.922632 -38.701945) (xy 159.895336 -38.65331) (xy 159.875413 -38.601219) (xy 159.863287 -38.546782)
			(xy 159.859216 -38.49116) (xy 156.867583 -38.49116) (xy 156.85256 -38.529939) (xy 156.813832 -38.607714)
			(xy 156.768093 -38.681582) (xy 156.715733 -38.750916) (xy 156.6572 -38.815122) (xy 156.592991 -38.873654)
			(xy 156.523656 -38.926011) (xy 156.449786 -38.971748) (xy 156.37201 -39.010473) (xy 156.290993 -39.041857)
			(xy 156.207426 -39.065631) (xy 156.122022 -39.081593) (xy 156.03551 -39.089607) (xy 155.992068 -39.090092)
			(xy 154.137868 -39.090092) (xy 154.094433 -39.089513) (xy 154.007933 -39.081495) (xy 153.922541 -39.06553)
			(xy 153.838987 -39.041754) (xy 153.757983 -39.010371) (xy 153.680221 -38.971647) (xy 153.606363 -38.925914)
			(xy 153.537039 -38.873561) (xy 153.472842 -38.815035) (xy 153.414319 -38.750836) (xy 153.361968 -38.681511)
			(xy 153.316237 -38.607651) (xy 153.277516 -38.529887) (xy 153.246136 -38.448882) (xy 153.222363 -38.365328)
			(xy 153.206401 -38.279936) (xy 153.198386 -38.193435) (xy 152.243536 -38.193435) (xy 152.243536 -42.849038)
			(xy 162.992052 -42.849038) (xy 162.996123 -42.793416) (xy 163.008249 -42.738979) (xy 163.028172 -42.686888)
			(xy 163.055468 -42.638253) (xy 163.089554 -42.59411) (xy 163.129703 -42.555401) (xy 163.175061 -42.52295)
			(xy 163.224661 -42.497449) (xy 163.277445 -42.479442) (xy 163.332288 -42.469312) (xy 163.388022 -42.467275)
			(xy 163.443459 -42.473375) (xy 163.497416 -42.487481) (xy 163.548745 -42.509293) (xy 163.596351 -42.538347)
			(xy 163.639219 -42.574022) (xy 163.676436 -42.615559) (xy 163.707209 -42.662072) (xy 163.730881 -42.712569)
			(xy 163.746949 -42.765976) (xy 163.755069 -42.821152) (xy 163.755578 -42.849038) (xy 163.755069 -42.876924)
			(xy 163.746949 -42.9321) (xy 163.730881 -42.985507) (xy 163.707209 -43.036004) (xy 163.676436 -43.082517)
			(xy 163.639219 -43.124054) (xy 163.596351 -43.159729) (xy 163.548745 -43.188783) (xy 163.497416 -43.210595)
			(xy 163.443459 -43.224701) (xy 163.388022 -43.230801) (xy 163.332288 -43.228764) (xy 163.277445 -43.218634)
			(xy 163.224661 -43.200627) (xy 163.175061 -43.175126) (xy 163.129703 -43.142675) (xy 163.089554 -43.103966)
			(xy 163.055468 -43.059823) (xy 163.028172 -43.011188) (xy 163.008249 -42.959097) (xy 162.996123 -42.90466)
			(xy 162.992052 -42.849038) (xy 152.243536 -42.849038) (xy 152.243536 -43.766228) (xy 162.23791 -43.766228)
			(xy 162.23791 -43.706292) (xy 162.245733 -43.64687) (xy 162.261246 -43.588977) (xy 162.284182 -43.533604)
			(xy 162.314149 -43.481698) (xy 162.350636 -43.434148) (xy 162.393016 -43.391768) (xy 162.440566 -43.355281)
			(xy 162.492472 -43.325314) (xy 162.547845 -43.302378) (xy 162.605738 -43.286865) (xy 162.66516 -43.279042)
			(xy 162.725096 -43.279042) (xy 162.784518 -43.286865) (xy 162.842411 -43.302378) (xy 162.897784 -43.325314)
			(xy 162.94969 -43.355281) (xy 162.99724 -43.391768) (xy 163.03962 -43.434148) (xy 163.076107 -43.481698)
			(xy 163.106074 -43.533604) (xy 163.12901 -43.588977) (xy 163.144523 -43.64687) (xy 163.152346 -43.706292)
			(xy 163.152836 -43.73626) (xy 163.152346 -43.766228) (xy 163.144523 -43.82565) (xy 163.12901 -43.883543)
			(xy 163.106074 -43.938916) (xy 163.076107 -43.990822) (xy 163.03962 -44.038372) (xy 162.99724 -44.080752)
			(xy 162.94969 -44.117239) (xy 162.897784 -44.147206) (xy 162.842411 -44.170142) (xy 162.784518 -44.185655)
			(xy 162.725096 -44.193478) (xy 162.66516 -44.193478) (xy 162.605738 -44.185655) (xy 162.547845 -44.170142)
			(xy 162.492472 -44.147206) (xy 162.440566 -44.117239) (xy 162.393016 -44.080752) (xy 162.350636 -44.038372)
			(xy 162.314149 -43.990822) (xy 162.284182 -43.938916) (xy 162.261246 -43.883543) (xy 162.245733 -43.82565)
			(xy 162.23791 -43.766228) (xy 152.243536 -43.766228) (xy 152.243536 -43.847512) (xy 152.243994 -43.857391)
			(xy 152.251428 -43.875697) (xy 152.258014 -43.883072) (xy 152.258268 -43.883326) (xy 152.736296 -44.361354)
			(xy 152.736804 -44.361862) (xy 152.744188 -44.368435) (xy 152.762487 -44.375866) (xy 152.772364 -44.37634)
		)
		(stroke
			(width 0)
			(type solid)
		)
		(fill yes)
		(layer "B.Cu")
		(net "P12V_SSD5")
	)
	(gr_poly
		(pts
			(xy 190.576962 -44.37634) (xy 190.586836 -44.375873) (xy 190.605127 -44.368423) (xy 190.612522 -44.361862)
			(xy 190.612776 -44.361608) (xy 191.172084 -43.8023) (xy 191.172592 -43.801792) (xy 191.179177 -43.794411)
			(xy 191.186638 -43.776113) (xy 191.18707 -43.766232) (xy 191.18707 -36.349686) (xy 191.166496 -36.322762)
			(xy 191.149732 -36.31819) (xy 191.121088 -36.30983) (xy 191.066084 -36.286694) (xy 191.014552 -36.256609)
			(xy 190.967366 -36.220083) (xy 190.925325 -36.177736) (xy 190.889142 -36.130286) (xy 190.859431 -36.078538)
			(xy 190.836696 -36.023368) (xy 190.82132 -35.965711) (xy 190.813566 -35.906546) (xy 190.813565 -35.846874)
			(xy 190.821316 -35.787709) (xy 190.836689 -35.730052) (xy 190.859422 -35.67488) (xy 190.889131 -35.62313)
			(xy 190.925312 -35.575679) (xy 190.967351 -35.53333) (xy 191.014535 -35.496803) (xy 191.066066 -35.466715)
			(xy 191.121069 -35.443577) (xy 191.149732 -35.435286) (xy 191.166496 -35.430714) (xy 191.18707 -35.40379)
			(xy 191.18707 -26.653236) (xy 191.186909 -26.64786) (xy 191.184605 -26.637356) (xy 191.182498 -26.632408)
			(xy 191.170306 -26.604722) (xy 191.162686 -26.597864) (xy 191.144077 -26.579743) (xy 191.111432 -26.53934)
			(xy 191.084563 -26.494887) (xy 191.063964 -26.447203) (xy 191.050015 -26.397168) (xy 191.042973 -26.345705)
			(xy 191.042544 -26.319734) (xy 191.043107 -26.290084) (xy 191.05227 -26.231497) (xy 191.070365 -26.175025)
			(xy 191.083184 -26.148284) (xy 191.088518 -26.137616) (xy 191.089026 -26.114756) (xy 191.050672 -26.031698)
			(xy 191.045273 -26.021595) (xy 191.0276 -26.007072) (xy 191.016636 -26.003758) (xy 191.016382 -26.003758)
			(xy 190.986809 -25.996102) (xy 190.929858 -25.974002) (xy 190.876354 -25.944522) (xy 190.827248 -25.908186)
			(xy 190.783413 -25.86564) (xy 190.745628 -25.817639) (xy 190.714565 -25.765038) (xy 190.690776 -25.708772)
			(xy 190.674685 -25.649842) (xy 190.666578 -25.589294) (xy 190.666116 -25.55875) (xy 190.666652 -25.527479)
			(xy 190.675174 -25.46552) (xy 190.692051 -25.405298) (xy 190.71697 -25.347935) (xy 190.749466 -25.294498)
			(xy 190.788935 -25.245982) (xy 190.834641 -25.203292) (xy 190.885734 -25.167222) (xy 190.941262 -25.138443)
			(xy 191.00019 -25.117493) (xy 191.061423 -25.104759) (xy 191.092582 -25.102058) (xy 191.102234 -25.101296)
			(xy 191.119506 -25.093168) (xy 191.173354 -25.03551) (xy 191.175894 -25.032462) (xy 191.181011 -25.02554)
			(xy 191.186727 -25.009313) (xy 191.18707 -25.000712) (xy 191.18707 -19.808444) (xy 191.186617 -19.798604)
			(xy 191.179192 -19.78038) (xy 191.165426 -19.766317) (xy 191.15659 -19.761962) (xy 191.05753 -19.718528)
			(xy 191.027812 -19.723608) (xy 191.016636 -19.733768) (xy 190.995397 -19.752619) (xy 190.948382 -19.784469)
			(xy 190.897163 -19.808991) (xy 190.842872 -19.825642) (xy 190.786712 -19.834055) (xy 190.758318 -19.834606)
			(xy 190.731546 -19.834154) (xy 190.678528 -19.826666) (xy 190.627079 -19.811834) (xy 190.57821 -19.789951)
			(xy 190.532884 -19.761446) (xy 190.491992 -19.72688) (xy 190.456337 -19.686933) (xy 190.441072 -19.664934)
			(xy 190.434976 -19.656044) (xy 190.41745 -19.644614) (xy 190.333376 -19.631152) (xy 190.32301 -19.629969)
			(xy 190.302803 -19.635072) (xy 190.29426 -19.641058) (xy 190.274103 -19.656166) (xy 190.230571 -19.681518)
			(xy 190.184086 -19.700928) (xy 190.135452 -19.71406) (xy 190.085514 -19.720685) (xy 190.060326 -19.721068)
			(xy 190.052706 -19.721068) (xy 190.025812 -19.72007) (xy 189.972691 -19.711447) (xy 189.92131 -19.695442)
			(xy 189.872688 -19.672375) (xy 189.827791 -19.642702) (xy 189.78751 -19.607014) (xy 189.752646 -19.566018)
			(xy 189.723889 -19.520528) (xy 189.701813 -19.471449) (xy 189.686853 -19.419753) (xy 189.679309 -19.366468)
			(xy 189.678818 -19.33956) (xy 189.679307 -19.312311) (xy 189.687068 -19.258369) (xy 189.702427 -19.206081)
			(xy 189.725071 -19.156511) (xy 189.754539 -19.110667) (xy 189.79023 -19.069484) (xy 189.83142 -19.033799)
			(xy 189.877269 -19.004339) (xy 189.926843 -18.981704) (xy 189.979134 -18.966354) (xy 190.033077 -18.958602)
			(xy 190.060326 -18.958052) (xy 190.0871 -18.9585) (xy 190.140124 -18.965981) (xy 190.19158 -18.980806)
			(xy 190.240455 -19.002683) (xy 190.28579 -19.031184) (xy 190.326692 -19.065746) (xy 190.362356 -19.10569)
			(xy 190.377572 -19.127724) (xy 190.383668 -19.136614) (xy 190.401194 -19.148044) (xy 190.495682 -19.163284)
			(xy 190.516002 -19.158204) (xy 190.524384 -19.1516) (xy 190.54761 -19.134259) (xy 190.598252 -19.106067)
			(xy 190.652579 -19.085869) (xy 190.680848 -19.079464) (xy 190.694564 -19.07667) (xy 190.715138 -19.057874)
			(xy 190.744856 -18.95856) (xy 190.747089 -18.949726) (xy 190.74584 -18.931562) (xy 190.738314 -18.914984)
			(xy 190.732156 -18.908268) (xy 190.626238 -18.80235) (xy 190.616332 -18.798286) (xy 190.592635 -18.788332)
			(xy 190.547928 -18.762972) (xy 190.507031 -18.731839) (xy 190.470685 -18.695496) (xy 190.439548 -18.654602)
			(xy 190.414184 -18.609898) (xy 190.404242 -18.586196) (xy 190.400178 -18.57629) (xy 190.367412 -18.543524)
			(xy 190.3603 -18.536158) (xy 190.341504 -18.528538) (xy 178.628802 -18.528538) (xy 178.618732 -18.528962)
			(xy 178.600131 -18.53668) (xy 178.592734 -18.543524) (xy 178.25847 -18.877788) (xy 178.251104 -18.8849)
			(xy 178.243484 -18.903696) (xy 178.243484 -21.738336) (xy 179.516786 -21.738336) (xy 179.517275 -21.709596)
			(xy 179.525906 -21.652767) (xy 179.542965 -21.597876) (xy 179.568064 -21.546165) (xy 179.600636 -21.498804)
			(xy 179.61991 -21.477478) (xy 179.626514 -21.470366) (xy 179.633626 -21.45284) (xy 179.633626 -21.363432)
			(xy 179.626514 -21.345906) (xy 179.61991 -21.338794) (xy 179.600675 -21.317436) (xy 179.56811 -21.270078)
			(xy 179.543018 -21.218372) (xy 179.525966 -21.163486) (xy 179.51734 -21.106663) (xy 179.517336 -21.049189)
			(xy 179.525954 -20.992365) (xy 179.542998 -20.937477) (xy 179.568084 -20.885767) (xy 179.600643 -20.838405)
			(xy 179.61991 -20.817078) (xy 179.626514 -20.809966) (xy 179.633626 -20.79244) (xy 179.633626 -20.703032)
			(xy 179.626514 -20.685506) (xy 179.61991 -20.678394) (xy 179.600675 -20.657036) (xy 179.56811 -20.609678)
			(xy 179.543018 -20.557972) (xy 179.525966 -20.503086) (xy 179.51734 -20.446263) (xy 179.517336 -20.388789)
			(xy 179.525954 -20.331965) (xy 179.542998 -20.277077) (xy 179.568084 -20.225367) (xy 179.600643 -20.178005)
			(xy 179.61991 -20.156678) (xy 179.626514 -20.149566) (xy 179.633626 -20.13204) (xy 179.633626 -20.042632)
			(xy 179.626514 -20.025106) (xy 179.61991 -20.017994) (xy 179.600675 -19.996636) (xy 179.56811 -19.949278)
			(xy 179.543018 -19.897572) (xy 179.525966 -19.842686) (xy 179.51734 -19.785863) (xy 179.517336 -19.728389)
			(xy 179.525954 -19.671565) (xy 179.542998 -19.616677) (xy 179.568084 -19.564967) (xy 179.600643 -19.517605)
			(xy 179.61991 -19.496278) (xy 179.626514 -19.489166) (xy 179.633626 -19.47164) (xy 179.633626 -19.382232)
			(xy 179.626514 -19.364706) (xy 179.61991 -19.357594) (xy 179.600652 -19.336256) (xy 179.568085 -19.288897)
			(xy 179.54299 -19.237188) (xy 179.525937 -19.182299) (xy 179.51731 -19.125474) (xy 179.516786 -19.096736)
			(xy 179.517272 -19.069485) (xy 179.525028 -19.015537) (xy 179.540383 -18.963242) (xy 179.563025 -18.913665)
			(xy 179.592491 -18.867815) (xy 179.628182 -18.826624) (xy 179.669373 -18.790933) (xy 179.715223 -18.761467)
			(xy 179.7648 -18.738825) (xy 179.817095 -18.72347) (xy 179.871043 -18.715714) (xy 179.925545 -18.715714)
			(xy 179.979493 -18.72347) (xy 180.031788 -18.738825) (xy 180.081365 -18.761467) (xy 180.127215 -18.790933)
			(xy 180.168406 -18.826624) (xy 180.204097 -18.867815) (xy 180.233563 -18.913665) (xy 180.256205 -18.963242)
			(xy 180.27156 -19.015537) (xy 180.279316 -19.069485) (xy 180.279802 -19.096736) (xy 180.2793 -19.125476)
			(xy 180.270672 -19.182304) (xy 180.253617 -19.237195) (xy 180.22852 -19.288906) (xy 180.195951 -19.336268)
			(xy 180.176678 -19.357594) (xy 180.170074 -19.364706) (xy 180.162962 -19.382232) (xy 180.162962 -19.47164)
			(xy 180.170074 -19.489166) (xy 180.176678 -19.496278) (xy 180.195984 -19.517574) (xy 180.228548 -19.564942)
			(xy 180.253638 -19.616659) (xy 180.270685 -19.671554) (xy 180.279304 -19.728386) (xy 180.2793 -19.785867)
			(xy 180.270673 -19.842697) (xy 180.253618 -19.89759) (xy 180.228522 -19.949304) (xy 180.195951 -19.996667)
			(xy 180.176678 -20.017994) (xy 180.170074 -20.025106) (xy 180.162962 -20.042632) (xy 180.162962 -20.13204)
			(xy 180.170074 -20.149566) (xy 180.176678 -20.156678) (xy 180.195984 -20.177974) (xy 180.228548 -20.225342)
			(xy 180.253638 -20.277059) (xy 180.270685 -20.331954) (xy 180.274265 -20.35556) (xy 189.678308 -20.35556)
			(xy 189.682379 -20.299938) (xy 189.694505 -20.245501) (xy 189.714428 -20.19341) (xy 189.741724 -20.144775)
			(xy 189.77581 -20.100632) (xy 189.815959 -20.061923) (xy 189.861317 -20.029472) (xy 189.910917 -20.003971)
			(xy 189.963701 -19.985964) (xy 190.018544 -19.975834) (xy 190.074278 -19.973797) (xy 190.129715 -19.979897)
			(xy 190.183672 -19.994003) (xy 190.235001 -20.015815) (xy 190.282607 -20.044869) (xy 190.325475 -20.080544)
			(xy 190.362692 -20.122081) (xy 190.393465 -20.168594) (xy 190.417137 -20.219091) (xy 190.433205 -20.272498)
			(xy 190.441325 -20.327674) (xy 190.441834 -20.35556) (xy 190.441325 -20.383446) (xy 190.433205 -20.438622)
			(xy 190.417137 -20.492029) (xy 190.393465 -20.542526) (xy 190.362692 -20.589039) (xy 190.325475 -20.630576)
			(xy 190.282607 -20.666251) (xy 190.235001 -20.695305) (xy 190.183672 -20.717117) (xy 190.129715 -20.731223)
			(xy 190.074278 -20.737323) (xy 190.018544 -20.735286) (xy 189.963701 -20.725156) (xy 189.910917 -20.707149)
			(xy 189.861317 -20.681648) (xy 189.815959 -20.649197) (xy 189.77581 -20.610488) (xy 189.741724 -20.566345)
			(xy 189.714428 -20.51771) (xy 189.694505 -20.465619) (xy 189.682379 -20.411182) (xy 189.678308 -20.35556)
			(xy 180.274265 -20.35556) (xy 180.279304 -20.388786) (xy 180.2793 -20.446267) (xy 180.270673 -20.503097)
			(xy 180.253618 -20.55799) (xy 180.228522 -20.609704) (xy 180.195951 -20.657067) (xy 180.176678 -20.678394)
			(xy 180.170074 -20.685506) (xy 180.162962 -20.703032) (xy 180.162962 -20.79244) (xy 180.170074 -20.809966)
			(xy 180.176678 -20.817078) (xy 180.195984 -20.838374) (xy 180.228548 -20.885742) (xy 180.253638 -20.937459)
			(xy 180.270685 -20.992354) (xy 180.279304 -21.049186) (xy 180.2793 -21.106667) (xy 180.270673 -21.163497)
			(xy 180.253618 -21.21839) (xy 180.228522 -21.270104) (xy 180.195951 -21.317467) (xy 180.176678 -21.338794)
			(xy 180.170074 -21.345906) (xy 180.162962 -21.363432) (xy 180.162962 -21.37156) (xy 189.678308 -21.37156)
			(xy 189.682379 -21.315938) (xy 189.694505 -21.261501) (xy 189.714428 -21.20941) (xy 189.741724 -21.160775)
			(xy 189.77581 -21.116632) (xy 189.815959 -21.077923) (xy 189.861317 -21.045472) (xy 189.910917 -21.019971)
			(xy 189.963701 -21.001964) (xy 190.018544 -20.991834) (xy 190.074278 -20.989797) (xy 190.129715 -20.995897)
			(xy 190.183672 -21.010003) (xy 190.235001 -21.031815) (xy 190.282607 -21.060869) (xy 190.325475 -21.096544)
			(xy 190.362692 -21.138081) (xy 190.393465 -21.184594) (xy 190.417137 -21.235091) (xy 190.433205 -21.288498)
			(xy 190.441325 -21.343674) (xy 190.441834 -21.37156) (xy 190.441325 -21.399446) (xy 190.433205 -21.454622)
			(xy 190.417137 -21.508029) (xy 190.393465 -21.558526) (xy 190.362692 -21.605039) (xy 190.325475 -21.646576)
			(xy 190.282607 -21.682251) (xy 190.235001 -21.711305) (xy 190.183672 -21.733117) (xy 190.129715 -21.747223)
			(xy 190.074278 -21.753323) (xy 190.018544 -21.751286) (xy 189.963701 -21.741156) (xy 189.910917 -21.723149)
			(xy 189.861317 -21.697648) (xy 189.815959 -21.665197) (xy 189.77581 -21.626488) (xy 189.741724 -21.582345)
			(xy 189.714428 -21.53371) (xy 189.694505 -21.481619) (xy 189.682379 -21.427182) (xy 189.678308 -21.37156)
			(xy 180.162962 -21.37156) (xy 180.162962 -21.45284) (xy 180.170074 -21.470366) (xy 180.176678 -21.477478)
			(xy 180.195968 -21.498788) (xy 180.228531 -21.546155) (xy 180.25362 -21.597871) (xy 180.270666 -21.652765)
			(xy 180.279284 -21.709596) (xy 180.279802 -21.738336) (xy 180.279316 -21.765587) (xy 180.27156 -21.819535)
			(xy 180.256205 -21.87183) (xy 180.233563 -21.921407) (xy 180.204097 -21.967257) (xy 180.168406 -22.008448)
			(xy 180.127215 -22.044139) (xy 180.081365 -22.073605) (xy 180.031788 -22.096247) (xy 179.979493 -22.111602)
			(xy 179.925545 -22.119358) (xy 179.871043 -22.119358) (xy 179.817095 -22.111602) (xy 179.7648 -22.096247)
			(xy 179.715223 -22.073605) (xy 179.669373 -22.044139) (xy 179.628182 -22.008448) (xy 179.592491 -21.967257)
			(xy 179.563025 -21.921407) (xy 179.540383 -21.87183) (xy 179.525028 -21.819535) (xy 179.517272 -21.765587)
			(xy 179.516786 -21.738336) (xy 178.243484 -21.738336) (xy 178.243484 -22.995158) (xy 179.387113 -22.995158)
			(xy 179.394933 -22.935725) (xy 179.410445 -22.877821) (xy 179.433382 -22.822437) (xy 179.463351 -22.770522)
			(xy 179.499841 -22.722962) (xy 179.542227 -22.680572) (xy 179.589783 -22.644077) (xy 179.641696 -22.614102)
			(xy 179.697077 -22.59116) (xy 179.75498 -22.575642) (xy 179.814412 -22.567816) (xy 179.874357 -22.567814)
			(xy 179.93379 -22.575636) (xy 179.991693 -22.59115) (xy 180.047076 -22.614088) (xy 180.098991 -22.64406)
			(xy 180.14655 -22.680552) (xy 180.188938 -22.722939) (xy 180.225431 -22.770496) (xy 180.255405 -22.82241)
			(xy 180.278345 -22.877792) (xy 180.293861 -22.935695) (xy 180.301685 -22.995127) (xy 180.302154 -23.0251)
			(xy 180.301931 -23.045661) (xy 180.298242 -23.086618) (xy 180.294788 -23.106888) (xy 180.292248 -23.120604)
			(xy 180.301138 -23.145496) (xy 180.387752 -23.22068) (xy 180.41366 -23.226014) (xy 180.426868 -23.221696)
			(xy 180.456072 -23.212613) (xy 180.516433 -23.202786) (xy 180.54701 -23.202138) (xy 180.565937 -23.202406)
			(xy 180.603599 -23.206219) (xy 180.622194 -23.209758) (xy 180.634894 -23.212044) (xy 180.658516 -23.205186)
			(xy 180.737002 -23.128986) (xy 180.744622 -23.105618) (xy 180.74259 -23.092918) (xy 180.73953 -23.073888)
			(xy 180.736219 -23.035483) (xy 180.735986 -23.01621) (xy 180.73645 -22.98624) (xy 180.744273 -22.926813)
			(xy 180.759785 -22.868915) (xy 180.782722 -22.813538) (xy 180.812691 -22.761628) (xy 180.849179 -22.714074)
			(xy 180.891563 -22.671689) (xy 180.939116 -22.635199) (xy 180.991024 -22.605229) (xy 181.046401 -22.58229)
			(xy 181.104299 -22.566776) (xy 181.163725 -22.558951) (xy 181.223665 -22.558951) (xy 181.283092 -22.566774)
			(xy 181.34099 -22.582287) (xy 181.396367 -22.605225) (xy 181.448277 -22.635194) (xy 181.49583 -22.671683)
			(xy 181.538214 -22.714067) (xy 181.574704 -22.76162) (xy 181.604674 -22.813529) (xy 181.627612 -22.868906)
			(xy 181.643125 -22.926804) (xy 181.650949 -22.986231) (xy 181.650949 -23.046171) (xy 181.643125 -23.105598)
			(xy 181.627611 -23.163495) (xy 181.604673 -23.218872) (xy 181.574703 -23.270781) (xy 181.538214 -23.318334)
			(xy 181.495829 -23.360718) (xy 181.448276 -23.397207) (xy 181.396366 -23.427176) (xy 181.340989 -23.450113)
			(xy 181.283091 -23.465626) (xy 181.223664 -23.473449) (xy 181.193694 -23.473918) (xy 181.159449 -23.473322)
			(xy 181.091723 -23.463112) (xy 181.05882 -23.453598) (xy 181.046628 -23.449788) (xy 181.022498 -23.45436)
			(xy 180.936646 -23.522178) (xy 180.92674 -23.544784) (xy 180.927756 -23.557738) (xy 180.928518 -23.583646)
			(xy 180.928032 -23.610897) (xy 180.926728 -23.619964) (xy 184.109342 -23.619964) (xy 184.109342 -23.560028)
			(xy 184.117165 -23.500606) (xy 184.132678 -23.442713) (xy 184.155614 -23.38734) (xy 184.185581 -23.335434)
			(xy 184.222068 -23.287884) (xy 184.264448 -23.245504) (xy 184.311998 -23.209017) (xy 184.363904 -23.17905)
			(xy 184.419277 -23.156114) (xy 184.47717 -23.140601) (xy 184.536592 -23.132778) (xy 184.596528 -23.132778)
			(xy 184.65595 -23.140601) (xy 184.713843 -23.156114) (xy 184.769216 -23.17905) (xy 184.821122 -23.209017)
			(xy 184.868672 -23.245504) (xy 184.911052 -23.287884) (xy 184.947539 -23.335434) (xy 184.977506 -23.38734)
			(xy 185.000442 -23.442713) (xy 185.015955 -23.500606) (xy 185.023778 -23.560028) (xy 185.024268 -23.589996)
			(xy 185.023778 -23.619964) (xy 185.015955 -23.679386) (xy 185.000442 -23.737279) (xy 184.977506 -23.792652)
			(xy 184.947539 -23.844558) (xy 184.920099 -23.880318) (xy 185.34075 -23.880318) (xy 185.344821 -23.824696)
			(xy 185.356947 -23.770259) (xy 185.37687 -23.718168) (xy 185.404166 -23.669533) (xy 185.438252 -23.62539)
			(xy 185.478401 -23.586681) (xy 185.523759 -23.55423) (xy 185.573359 -23.528729) (xy 185.626143 -23.510722)
			(xy 185.680986 -23.500592) (xy 185.73672 -23.498555) (xy 185.792157 -23.504655) (xy 185.846114 -23.518761)
			(xy 185.897443 -23.540573) (xy 185.945049 -23.569627) (xy 185.987917 -23.605302) (xy 186.025134 -23.646839)
			(xy 186.055907 -23.693352) (xy 186.079579 -23.743849) (xy 186.095647 -23.797256) (xy 186.103767 -23.852432)
			(xy 186.104276 -23.880318) (xy 186.35675 -23.880318) (xy 186.360821 -23.824696) (xy 186.372947 -23.770259)
			(xy 186.39287 -23.718168) (xy 186.420166 -23.669533) (xy 186.454252 -23.62539) (xy 186.494401 -23.586681)
			(xy 186.539759 -23.55423) (xy 186.589359 -23.528729) (xy 186.642143 -23.510722) (xy 186.696986 -23.500592)
			(xy 186.75272 -23.498555) (xy 186.808157 -23.504655) (xy 186.862114 -23.518761) (xy 186.913443 -23.540573)
			(xy 186.961049 -23.569627) (xy 187.003917 -23.605302) (xy 187.041134 -23.646839) (xy 187.071907 -23.693352)
			(xy 187.095579 -23.743849) (xy 187.111647 -23.797256) (xy 187.119767 -23.852432) (xy 187.120276 -23.880318)
			(xy 187.37275 -23.880318) (xy 187.376821 -23.824696) (xy 187.388947 -23.770259) (xy 187.40887 -23.718168)
			(xy 187.436166 -23.669533) (xy 187.470252 -23.62539) (xy 187.510401 -23.586681) (xy 187.555759 -23.55423)
			(xy 187.605359 -23.528729) (xy 187.658143 -23.510722) (xy 187.712986 -23.500592) (xy 187.76872 -23.498555)
			(xy 187.824157 -23.504655) (xy 187.878114 -23.518761) (xy 187.929443 -23.540573) (xy 187.977049 -23.569627)
			(xy 188.019917 -23.605302) (xy 188.057134 -23.646839) (xy 188.087907 -23.693352) (xy 188.111579 -23.743849)
			(xy 188.127647 -23.797256) (xy 188.135767 -23.852432) (xy 188.136276 -23.880318) (xy 188.391036 -23.880318)
			(xy 188.395107 -23.824696) (xy 188.407233 -23.770259) (xy 188.427156 -23.718168) (xy 188.454452 -23.669533)
			(xy 188.488538 -23.62539) (xy 188.528687 -23.586681) (xy 188.574045 -23.55423) (xy 188.623645 -23.528729)
			(xy 188.676429 -23.510722) (xy 188.731272 -23.500592) (xy 188.787006 -23.498555) (xy 188.842443 -23.504655)
			(xy 188.8964 -23.518761) (xy 188.947729 -23.540573) (xy 188.995335 -23.569627) (xy 189.038203 -23.605302)
			(xy 189.07542 -23.646839) (xy 189.106193 -23.693352) (xy 189.129865 -23.743849) (xy 189.145933 -23.797256)
			(xy 189.154053 -23.852432) (xy 189.154562 -23.880318) (xy 189.154053 -23.908204) (xy 189.145933 -23.96338)
			(xy 189.129865 -24.016787) (xy 189.106193 -24.067284) (xy 189.07542 -24.113797) (xy 189.038203 -24.155334)
			(xy 188.995335 -24.191009) (xy 188.947729 -24.220063) (xy 188.8964 -24.241875) (xy 188.842443 -24.255981)
			(xy 188.787006 -24.262081) (xy 188.731272 -24.260044) (xy 188.676429 -24.249914) (xy 188.623645 -24.231907)
			(xy 188.574045 -24.206406) (xy 188.528687 -24.173955) (xy 188.488538 -24.135246) (xy 188.454452 -24.091103)
			(xy 188.427156 -24.042468) (xy 188.407233 -23.990377) (xy 188.395107 -23.93594) (xy 188.391036 -23.880318)
			(xy 188.136276 -23.880318) (xy 188.135767 -23.908204) (xy 188.127647 -23.96338) (xy 188.111579 -24.016787)
			(xy 188.087907 -24.067284) (xy 188.057134 -24.113797) (xy 188.019917 -24.155334) (xy 187.977049 -24.191009)
			(xy 187.929443 -24.220063) (xy 187.878114 -24.241875) (xy 187.824157 -24.255981) (xy 187.76872 -24.262081)
			(xy 187.712986 -24.260044) (xy 187.658143 -24.249914) (xy 187.605359 -24.231907) (xy 187.555759 -24.206406)
			(xy 187.510401 -24.173955) (xy 187.470252 -24.135246) (xy 187.436166 -24.091103) (xy 187.40887 -24.042468)
			(xy 187.388947 -23.990377) (xy 187.376821 -23.93594) (xy 187.37275 -23.880318) (xy 187.120276 -23.880318)
			(xy 187.119767 -23.908204) (xy 187.111647 -23.96338) (xy 187.095579 -24.016787) (xy 187.071907 -24.067284)
			(xy 187.041134 -24.113797) (xy 187.003917 -24.155334) (xy 186.961049 -24.191009) (xy 186.913443 -24.220063)
			(xy 186.862114 -24.241875) (xy 186.808157 -24.255981) (xy 186.75272 -24.262081) (xy 186.696986 -24.260044)
			(xy 186.642143 -24.249914) (xy 186.589359 -24.231907) (xy 186.539759 -24.206406) (xy 186.494401 -24.173955)
			(xy 186.454252 -24.135246) (xy 186.420166 -24.091103) (xy 186.39287 -24.042468) (xy 186.372947 -23.990377)
			(xy 186.360821 -23.93594) (xy 186.35675 -23.880318) (xy 186.104276 -23.880318) (xy 186.103767 -23.908204)
			(xy 186.095647 -23.96338) (xy 186.079579 -24.016787) (xy 186.055907 -24.067284) (xy 186.025134 -24.113797)
			(xy 185.987917 -24.155334) (xy 185.945049 -24.191009) (xy 185.897443 -24.220063) (xy 185.846114 -24.241875)
			(xy 185.792157 -24.255981) (xy 185.73672 -24.262081) (xy 185.680986 -24.260044) (xy 185.626143 -24.249914)
			(xy 185.573359 -24.231907) (xy 185.523759 -24.206406) (xy 185.478401 -24.173955) (xy 185.438252 -24.135246)
			(xy 185.404166 -24.091103) (xy 185.37687 -24.042468) (xy 185.356947 -23.990377) (xy 185.344821 -23.93594)
			(xy 185.34075 -23.880318) (xy 184.920099 -23.880318) (xy 184.911052 -23.892108) (xy 184.868672 -23.934488)
			(xy 184.821122 -23.970975) (xy 184.769216 -24.000942) (xy 184.713843 -24.023878) (xy 184.65595 -24.039391)
			(xy 184.596528 -24.047214) (xy 184.536592 -24.047214) (xy 184.47717 -24.039391) (xy 184.419277 -24.023878)
			(xy 184.363904 -24.000942) (xy 184.311998 -23.970975) (xy 184.264448 -23.934488) (xy 184.222068 -23.892108)
			(xy 184.185581 -23.844558) (xy 184.155614 -23.792652) (xy 184.132678 -23.737279) (xy 184.117165 -23.679386)
			(xy 184.109342 -23.619964) (xy 180.926728 -23.619964) (xy 180.920276 -23.664845) (xy 180.904921 -23.71714)
			(xy 180.882279 -23.766717) (xy 180.852813 -23.812567) (xy 180.817122 -23.853758) (xy 180.775931 -23.889449)
			(xy 180.730081 -23.918915) (xy 180.680504 -23.941557) (xy 180.628209 -23.956912) (xy 180.574261 -23.964668)
			(xy 180.519759 -23.964668) (xy 180.465811 -23.956912) (xy 180.413516 -23.941557) (xy 180.363939 -23.918915)
			(xy 180.318089 -23.889449) (xy 180.276898 -23.853758) (xy 180.241207 -23.812567) (xy 180.211741 -23.766717)
			(xy 180.189099 -23.71714) (xy 180.173744 -23.664845) (xy 180.165988 -23.610897) (xy 180.165502 -23.583646)
			(xy 180.16728 -23.548086) (xy 180.16855 -23.53437) (xy 180.157628 -23.51024) (xy 180.064664 -23.44293)
			(xy 180.038248 -23.439882) (xy 180.025802 -23.44547) (xy 179.997048 -23.457295) (xy 179.93714 -23.473929)
			(xy 179.875533 -23.482305) (xy 179.844446 -23.482808) (xy 179.814473 -23.482388) (xy 179.75504 -23.47457)
			(xy 179.697136 -23.45906) (xy 179.641751 -23.436125) (xy 179.589834 -23.406157) (xy 179.542273 -23.369669)
			(xy 179.499882 -23.327284) (xy 179.463386 -23.27973) (xy 179.433409 -23.227818) (xy 179.410465 -23.172437)
			(xy 179.394945 -23.114535) (xy 179.387117 -23.055103) (xy 179.387113 -22.995158) (xy 178.243484 -22.995158)
			(xy 178.243484 -24.189944) (xy 179.398928 -24.189944) (xy 179.402999 -24.134322) (xy 179.415125 -24.079885)
			(xy 179.435048 -24.027794) (xy 179.462344 -23.979159) (xy 179.49643 -23.935016) (xy 179.536579 -23.896307)
			(xy 179.581937 -23.863856) (xy 179.631537 -23.838355) (xy 179.684321 -23.820348) (xy 179.739164 -23.810218)
			(xy 179.794898 -23.808181) (xy 179.850335 -23.814281) (xy 179.904292 -23.828387) (xy 179.955621 -23.850199)
			(xy 180.003227 -23.879253) (xy 180.046095 -23.914928) (xy 180.083312 -23.956465) (xy 180.114085 -24.002978)
			(xy 180.137757 -24.053475) (xy 180.153825 -24.106882) (xy 180.161945 -24.162058) (xy 180.162454 -24.189944)
			(xy 181.92191 -24.189944) (xy 181.925981 -24.134322) (xy 181.938107 -24.079885) (xy 181.95803 -24.027794)
			(xy 181.985326 -23.979159) (xy 182.019412 -23.935016) (xy 182.059561 -23.896307) (xy 182.104919 -23.863856)
			(xy 182.154519 -23.838355) (xy 182.207303 -23.820348) (xy 182.262146 -23.810218) (xy 182.31788 -23.808181)
			(xy 182.373317 -23.814281) (xy 182.427274 -23.828387) (xy 182.478603 -23.850199) (xy 182.526209 -23.879253)
			(xy 182.569077 -23.914928) (xy 182.606294 -23.956465) (xy 182.637067 -24.002978) (xy 182.660739 -24.053475)
			(xy 182.676807 -24.106882) (xy 182.684927 -24.162058) (xy 182.685436 -24.189944) (xy 182.684927 -24.21783)
			(xy 182.676807 -24.273006) (xy 182.660739 -24.326413) (xy 182.637067 -24.37691) (xy 182.606294 -24.423423)
			(xy 182.569077 -24.46496) (xy 182.526209 -24.500635) (xy 182.478603 -24.529689) (xy 182.427274 -24.551501)
			(xy 182.373317 -24.565607) (xy 182.31788 -24.571707) (xy 182.262146 -24.56967) (xy 182.207303 -24.55954)
			(xy 182.154519 -24.541533) (xy 182.104919 -24.516032) (xy 182.059561 -24.483581) (xy 182.019412 -24.444872)
			(xy 181.985326 -24.400729) (xy 181.95803 -24.352094) (xy 181.938107 -24.300003) (xy 181.925981 -24.245566)
			(xy 181.92191 -24.189944) (xy 180.162454 -24.189944) (xy 180.161945 -24.21783) (xy 180.153825 -24.273006)
			(xy 180.137757 -24.326413) (xy 180.114085 -24.37691) (xy 180.083312 -24.423423) (xy 180.046095 -24.46496)
			(xy 180.003227 -24.500635) (xy 179.955621 -24.529689) (xy 179.904292 -24.551501) (xy 179.850335 -24.565607)
			(xy 179.794898 -24.571707) (xy 179.739164 -24.56967) (xy 179.684321 -24.55954) (xy 179.631537 -24.541533)
			(xy 179.581937 -24.516032) (xy 179.536579 -24.483581) (xy 179.49643 -24.444872) (xy 179.462344 -24.400729)
			(xy 179.435048 -24.352094) (xy 179.415125 -24.300003) (xy 179.402999 -24.245566) (xy 179.398928 -24.189944)
			(xy 178.243484 -24.189944) (xy 178.243484 -25.390094) (xy 181.83352 -25.390094) (xy 181.83401 -25.360126)
			(xy 181.841833 -25.300704) (xy 181.857346 -25.242811) (xy 181.880282 -25.187438) (xy 181.910249 -25.135532)
			(xy 181.946736 -25.087982) (xy 181.989116 -25.045602) (xy 182.036666 -25.009115) (xy 182.088572 -24.979148)
			(xy 182.143945 -24.956212) (xy 182.201838 -24.940699) (xy 182.26126 -24.932876) (xy 182.321196 -24.932876)
			(xy 182.380618 -24.940699) (xy 182.438511 -24.956212) (xy 182.493884 -24.979148) (xy 182.54579 -25.009115)
			(xy 182.59334 -25.045602) (xy 182.63572 -25.087982) (xy 182.672207 -25.135532) (xy 182.702174 -25.187438)
			(xy 182.72511 -25.242811) (xy 182.740623 -25.300704) (xy 182.748446 -25.360126) (xy 182.748936 -25.390094)
			(xy 182.748489 -25.418878) (xy 182.741271 -25.475992) (xy 182.726949 -25.531749) (xy 182.705748 -25.585271)
			(xy 182.678003 -25.635712) (xy 182.644152 -25.682275) (xy 182.604729 -25.724227) (xy 182.58282 -25.7429)
			(xy 182.574438 -25.749758) (xy 182.564786 -25.769316) (xy 182.561484 -25.867106) (xy 182.569612 -25.887172)
			(xy 182.57774 -25.894792) (xy 182.596137 -25.912872) (xy 182.628376 -25.953138) (xy 182.6549 -25.997377)
			(xy 182.675228 -26.044784) (xy 182.688989 -26.094495) (xy 182.695933 -26.145607) (xy 182.696358 -26.171398)
			(xy 182.695872 -26.198649) (xy 182.688116 -26.252597) (xy 182.672761 -26.304892) (xy 182.650119 -26.354469)
			(xy 182.620653 -26.400319) (xy 182.584962 -26.44151) (xy 182.543771 -26.477201) (xy 182.497921 -26.506667)
			(xy 182.448344 -26.529309) (xy 182.396049 -26.544664) (xy 182.342101 -26.55242) (xy 182.287599 -26.55242)
			(xy 182.233651 -26.544664) (xy 182.181356 -26.529309) (xy 182.131779 -26.506667) (xy 182.085929 -26.477201)
			(xy 182.044738 -26.44151) (xy 182.009047 -26.400319) (xy 181.979581 -26.354469) (xy 181.956939 -26.304892)
			(xy 181.941584 -26.252597) (xy 181.933828 -26.198649) (xy 181.933342 -26.171398) (xy 181.933848 -26.142754)
			(xy 181.942447 -26.086115) (xy 181.95942 -26.031398) (xy 181.984386 -25.979836) (xy 182.016784 -25.932589)
			(xy 182.035958 -25.911302) (xy 182.043324 -25.903174) (xy 182.050182 -25.8826) (xy 182.041038 -25.785064)
			(xy 182.03037 -25.766268) (xy 182.02148 -25.759918) (xy 181.99695 -25.741345) (xy 181.952552 -25.698749)
			(xy 181.914258 -25.650592) (xy 181.882758 -25.59774) (xy 181.858619 -25.541146) (xy 181.842277 -25.481829)
			(xy 181.834025 -25.420857) (xy 181.83352 -25.390094) (xy 178.243484 -25.390094) (xy 178.243484 -25.990042)
			(xy 179.398928 -25.990042) (xy 179.402999 -25.93442) (xy 179.415125 -25.879983) (xy 179.435048 -25.827892)
			(xy 179.462344 -25.779257) (xy 179.49643 -25.735114) (xy 179.536579 -25.696405) (xy 179.581937 -25.663954)
			(xy 179.631537 -25.638453) (xy 179.684321 -25.620446) (xy 179.739164 -25.610316) (xy 179.794898 -25.608279)
			(xy 179.850335 -25.614379) (xy 179.904292 -25.628485) (xy 179.955621 -25.650297) (xy 180.003227 -25.679351)
			(xy 180.046095 -25.715026) (xy 180.083312 -25.756563) (xy 180.114085 -25.803076) (xy 180.137757 -25.853573)
			(xy 180.153825 -25.90698) (xy 180.161945 -25.962156) (xy 180.162454 -25.990042) (xy 180.161945 -26.017928)
			(xy 180.153825 -26.073104) (xy 180.137757 -26.126511) (xy 180.114085 -26.177008) (xy 180.083312 -26.223521)
			(xy 180.046095 -26.265058) (xy 180.003227 -26.300733) (xy 179.955621 -26.329787) (xy 179.904292 -26.351599)
			(xy 179.850335 -26.365705) (xy 179.794898 -26.371805) (xy 179.739164 -26.369768) (xy 179.684321 -26.359638)
			(xy 179.631537 -26.341631) (xy 179.581937 -26.31613) (xy 179.536579 -26.283679) (xy 179.49643 -26.24497)
			(xy 179.462344 -26.200827) (xy 179.435048 -26.152192) (xy 179.415125 -26.100101) (xy 179.402999 -26.045664)
			(xy 179.398928 -25.990042) (xy 178.243484 -25.990042) (xy 178.243484 -27.79014) (xy 179.462936 -27.79014)
			(xy 179.467007 -27.734518) (xy 179.479133 -27.680081) (xy 179.499056 -27.62799) (xy 179.526352 -27.579355)
			(xy 179.560438 -27.535212) (xy 179.600587 -27.496503) (xy 179.645945 -27.464052) (xy 179.695545 -27.438551)
			(xy 179.748329 -27.420544) (xy 179.803172 -27.410414) (xy 179.858906 -27.408377) (xy 179.914343 -27.414477)
			(xy 179.9683 -27.428583) (xy 180.019629 -27.450395) (xy 180.067235 -27.479449) (xy 180.110103 -27.515124)
			(xy 180.14732 -27.556661) (xy 180.178093 -27.603174) (xy 180.201765 -27.653671) (xy 180.217833 -27.707078)
			(xy 180.225953 -27.762254) (xy 180.226462 -27.79014) (xy 181.966868 -27.79014) (xy 181.970939 -27.734518)
			(xy 181.983065 -27.680081) (xy 182.002988 -27.62799) (xy 182.030284 -27.579355) (xy 182.06437 -27.535212)
			(xy 182.104519 -27.496503) (xy 182.149877 -27.464052) (xy 182.199477 -27.438551) (xy 182.252261 -27.420544)
			(xy 182.307104 -27.410414) (xy 182.362838 -27.408377) (xy 182.418275 -27.414477) (xy 182.472232 -27.428583)
			(xy 182.523561 -27.450395) (xy 182.571167 -27.479449) (xy 182.614035 -27.515124) (xy 182.651252 -27.556661)
			(xy 182.682025 -27.603174) (xy 182.705697 -27.653671) (xy 182.721765 -27.707078) (xy 182.729885 -27.762254)
			(xy 182.730394 -27.79014) (xy 182.729897 -27.817348) (xy 183.999918 -27.817348) (xy 183.999918 -27.762852)
			(xy 184.007673 -27.708911) (xy 184.023026 -27.656623) (xy 184.045664 -27.607052) (xy 184.075126 -27.561207)
			(xy 184.110812 -27.520022) (xy 184.151996 -27.484334) (xy 184.19784 -27.454871) (xy 184.24741 -27.432231)
			(xy 184.299698 -27.416876) (xy 184.353638 -27.409119) (xy 184.380886 -27.408632) (xy 184.406193 -27.409035)
			(xy 184.456365 -27.415705) (xy 184.505217 -27.428942) (xy 184.528714 -27.43835) (xy 184.536725 -27.44136)
			(xy 184.553793 -27.442458) (xy 184.57027 -27.437876) (xy 184.577482 -27.43327) (xy 184.602882 -27.41549)
			(xy 184.609768 -27.410215) (xy 184.619843 -27.396112) (xy 184.624641 -27.379457) (xy 184.624472 -27.370786)
			(xy 184.623456 -27.342846) (xy 184.623456 -26.479246) (xy 184.624218 -26.456894) (xy 184.624726 -26.444448)
			(xy 184.614312 -26.421842) (xy 184.529222 -26.355548) (xy 184.504838 -26.350976) (xy 184.4929 -26.354786)
			(xy 184.465562 -26.362623) (xy 184.409321 -26.371044) (xy 184.380886 -26.37155) (xy 184.353638 -26.370979)
			(xy 184.299698 -26.363222) (xy 184.247411 -26.347867) (xy 184.197841 -26.325228) (xy 184.151997 -26.295764)
			(xy 184.110813 -26.260077) (xy 184.075127 -26.218891) (xy 184.045666 -26.173047) (xy 184.023028 -26.123476)
			(xy 184.007675 -26.071188) (xy 183.99992 -26.017248) (xy 183.99992 -25.962752) (xy 184.007675 -25.908812)
			(xy 184.023028 -25.856524) (xy 184.045666 -25.806953) (xy 184.075127 -25.761109) (xy 184.110813 -25.719923)
			(xy 184.151997 -25.684236) (xy 184.197841 -25.654772) (xy 184.247411 -25.632133) (xy 184.299698 -25.616778)
			(xy 184.353638 -25.609021) (xy 184.380886 -25.608534) (xy 184.409838 -25.60909) (xy 184.467078 -25.617824)
			(xy 184.522341 -25.63511) (xy 184.574356 -25.660549) (xy 184.621929 -25.693559) (xy 184.663966 -25.733379)
			(xy 184.699502 -25.779095) (xy 184.72772 -25.829657) (xy 184.728615 -25.832054) (xy 186.288426 -25.832054)
			(xy 186.288904 -25.805451) (xy 186.296279 -25.752759) (xy 186.310908 -25.701603) (xy 186.332505 -25.652978)
			(xy 186.360652 -25.607827) (xy 186.394803 -25.567027) (xy 186.434293 -25.531371) (xy 186.456066 -25.516078)
			(xy 186.467545 -25.507741) (xy 186.485755 -25.486) (xy 186.497276 -25.460086) (xy 186.501218 -25.432002)
			(xy 186.497277 -25.403918) (xy 186.485757 -25.378004) (xy 186.467549 -25.356262) (xy 186.456066 -25.34793)
			(xy 186.434307 -25.33262) (xy 186.394826 -25.296957) (xy 186.360681 -25.256157) (xy 186.332534 -25.211009)
			(xy 186.31093 -25.16239) (xy 186.296287 -25.111242) (xy 186.288891 -25.058555) (xy 186.288426 -25.031954)
			(xy 186.288912 -25.004703) (xy 186.296668 -24.950755) (xy 186.312023 -24.89846) (xy 186.334665 -24.848883)
			(xy 186.364131 -24.803033) (xy 186.399822 -24.761842) (xy 186.441013 -24.726151) (xy 186.486863 -24.696685)
			(xy 186.53644 -24.674043) (xy 186.588735 -24.658688) (xy 186.642683 -24.650932) (xy 186.697185 -24.650932)
			(xy 186.751133 -24.658688) (xy 186.803428 -24.674043) (xy 186.853005 -24.696685) (xy 186.898855 -24.726151)
			(xy 186.940046 -24.761842) (xy 186.963247 -24.788618) (xy 188.893432 -24.788618) (xy 188.893432 -24.728682)
			(xy 188.901255 -24.66926) (xy 188.916768 -24.611367) (xy 188.939704 -24.555994) (xy 188.969671 -24.504088)
			(xy 189.006158 -24.456538) (xy 189.048538 -24.414158) (xy 189.096088 -24.377671) (xy 189.147994 -24.347704)
			(xy 189.203367 -24.324768) (xy 189.26126 -24.309255) (xy 189.320682 -24.301432) (xy 189.380618 -24.301432)
			(xy 189.44004 -24.309255) (xy 189.497933 -24.324768) (xy 189.553306 -24.347704) (xy 189.605212 -24.377671)
			(xy 189.652762 -24.414158) (xy 189.695142 -24.456538) (xy 189.731629 -24.504088) (xy 189.761596 -24.555994)
			(xy 189.784532 -24.611367) (xy 189.800045 -24.66926) (xy 189.807868 -24.728682) (xy 189.808358 -24.75865)
			(xy 189.807868 -24.788618) (xy 189.800045 -24.84804) (xy 189.784532 -24.905933) (xy 189.761596 -24.961306)
			(xy 189.731629 -25.013212) (xy 189.695142 -25.060762) (xy 189.652762 -25.103142) (xy 189.605212 -25.139629)
			(xy 189.553306 -25.169596) (xy 189.497933 -25.192532) (xy 189.44004 -25.208045) (xy 189.380618 -25.215868)
			(xy 189.320682 -25.215868) (xy 189.26126 -25.208045) (xy 189.203367 -25.192532) (xy 189.147994 -25.169596)
			(xy 189.096088 -25.139629) (xy 189.048538 -25.103142) (xy 189.006158 -25.060762) (xy 188.969671 -25.013212)
			(xy 188.939704 -24.961306) (xy 188.916768 -24.905933) (xy 188.901255 -24.84804) (xy 188.893432 -24.788618)
			(xy 186.963247 -24.788618) (xy 186.975737 -24.803033) (xy 187.005203 -24.848883) (xy 187.027845 -24.89846)
			(xy 187.0432 -24.950755) (xy 187.050956 -25.004703) (xy 187.051442 -25.031954) (xy 187.050984 -25.058558)
			(xy 187.043607 -25.111252) (xy 187.028976 -25.162408) (xy 187.007376 -25.211034) (xy 186.979225 -25.256185)
			(xy 186.945071 -25.296984) (xy 186.905577 -25.332638) (xy 186.883802 -25.34793) (xy 186.872318 -25.356259)
			(xy 186.854114 -25.378004) (xy 186.842597 -25.403919) (xy 186.838657 -25.432002) (xy 186.842598 -25.460086)
			(xy 186.854116 -25.486) (xy 186.872321 -25.507744) (xy 186.883802 -25.516078) (xy 186.905558 -25.531393)
			(xy 186.94504 -25.567054) (xy 186.979186 -25.607853) (xy 187.007335 -25.653) (xy 187.028939 -25.701618)
			(xy 187.043582 -25.752766) (xy 187.050978 -25.805453) (xy 187.051442 -25.832054) (xy 187.050956 -25.859305)
			(xy 187.0432 -25.913253) (xy 187.027845 -25.965548) (xy 187.005203 -26.015125) (xy 186.975737 -26.060975)
			(xy 186.940046 -26.102166) (xy 186.898855 -26.137857) (xy 186.853005 -26.167323) (xy 186.803428 -26.189965)
			(xy 186.751133 -26.20532) (xy 186.697185 -26.213076) (xy 186.642683 -26.213076) (xy 186.588735 -26.20532)
			(xy 186.53644 -26.189965) (xy 186.486863 -26.167323) (xy 186.441013 -26.137857) (xy 186.399822 -26.102166)
			(xy 186.364131 -26.060975) (xy 186.334665 -26.015125) (xy 186.312023 -25.965548) (xy 186.296668 -25.913253)
			(xy 186.288912 -25.859305) (xy 186.288426 -25.832054) (xy 184.728615 -25.832054) (xy 184.747971 -25.883903)
			(xy 184.759791 -25.940587) (xy 184.761886 -25.969468) (xy 184.762394 -25.981914) (xy 184.775094 -26.00325)
			(xy 184.866788 -26.060654) (xy 184.891426 -26.062432) (xy 184.902856 -26.057606) (xy 184.93121 -26.046128)
			(xy 184.99021 -26.029976) (xy 185.050833 -26.021809) (xy 185.081418 -26.021284) (xy 185.111406 -26.02169)
			(xy 185.170869 -26.029522) (xy 185.2288 -26.045047) (xy 185.28421 -26.068002) (xy 185.336149 -26.097993)
			(xy 185.383728 -26.134507) (xy 185.426135 -26.17692) (xy 185.462642 -26.224505) (xy 185.492626 -26.276448)
			(xy 185.515573 -26.33186) (xy 185.523347 -26.360882) (xy 187.189616 -26.360882) (xy 187.193687 -26.30526)
			(xy 187.205813 -26.250823) (xy 187.225736 -26.198732) (xy 187.253032 -26.150097) (xy 187.287118 -26.105954)
			(xy 187.327267 -26.067245) (xy 187.372625 -26.034794) (xy 187.422225 -26.009293) (xy 187.475009 -25.991286)
			(xy 187.529852 -25.981156) (xy 187.585586 -25.979119) (xy 187.641023 -25.985219) (xy 187.69498 -25.999325)
			(xy 187.746309 -26.021137) (xy 187.793915 -26.050191) (xy 187.836783 -26.085866) (xy 187.874 -26.127403)
			(xy 187.904773 -26.173916) (xy 187.928445 -26.224413) (xy 187.944513 -26.27782) (xy 187.952633 -26.332996)
			(xy 187.953142 -26.360882) (xy 188.205616 -26.360882) (xy 188.209687 -26.30526) (xy 188.221813 -26.250823)
			(xy 188.241736 -26.198732) (xy 188.269032 -26.150097) (xy 188.303118 -26.105954) (xy 188.343267 -26.067245)
			(xy 188.388625 -26.034794) (xy 188.438225 -26.009293) (xy 188.491009 -25.991286) (xy 188.545852 -25.981156)
			(xy 188.601586 -25.979119) (xy 188.657023 -25.985219) (xy 188.71098 -25.999325) (xy 188.762309 -26.021137)
			(xy 188.809915 -26.050191) (xy 188.852783 -26.085866) (xy 188.89 -26.127403) (xy 188.920773 -26.173916)
			(xy 188.944445 -26.224413) (xy 188.960513 -26.27782) (xy 188.968633 -26.332996) (xy 188.969142 -26.360882)
			(xy 188.968633 -26.388768) (xy 188.960513 -26.443944) (xy 188.944445 -26.497351) (xy 188.920773 -26.547848)
			(xy 188.89 -26.594361) (xy 188.852783 -26.635898) (xy 188.809915 -26.671573) (xy 188.762309 -26.700627)
			(xy 188.71098 -26.722439) (xy 188.657023 -26.736545) (xy 188.601586 -26.742645) (xy 188.545852 -26.740608)
			(xy 188.491009 -26.730478) (xy 188.438225 -26.712471) (xy 188.388625 -26.68697) (xy 188.343267 -26.654519)
			(xy 188.303118 -26.61581) (xy 188.269032 -26.571667) (xy 188.241736 -26.523032) (xy 188.221813 -26.470941)
			(xy 188.209687 -26.416504) (xy 188.205616 -26.360882) (xy 187.953142 -26.360882) (xy 187.952633 -26.388768)
			(xy 187.944513 -26.443944) (xy 187.928445 -26.497351) (xy 187.904773 -26.547848) (xy 187.874 -26.594361)
			(xy 187.836783 -26.635898) (xy 187.793915 -26.671573) (xy 187.746309 -26.700627) (xy 187.69498 -26.722439)
			(xy 187.641023 -26.736545) (xy 187.585586 -26.742645) (xy 187.529852 -26.740608) (xy 187.475009 -26.730478)
			(xy 187.422225 -26.712471) (xy 187.372625 -26.68697) (xy 187.327267 -26.654519) (xy 187.287118 -26.61581)
			(xy 187.253032 -26.571667) (xy 187.225736 -26.523032) (xy 187.205813 -26.470941) (xy 187.193687 -26.416504)
			(xy 187.189616 -26.360882) (xy 185.523347 -26.360882) (xy 185.531091 -26.389794) (xy 185.538914 -26.449258)
			(xy 185.53938 -26.479246) (xy 185.53938 -26.971244) (xy 188.951106 -26.971244) (xy 188.955177 -26.915622)
			(xy 188.967303 -26.861185) (xy 188.987226 -26.809094) (xy 189.014522 -26.760459) (xy 189.048608 -26.716316)
			(xy 189.088757 -26.677607) (xy 189.134115 -26.645156) (xy 189.183715 -26.619655) (xy 189.236499 -26.601648)
			(xy 189.291342 -26.591518) (xy 189.347076 -26.589481) (xy 189.402513 -26.595581) (xy 189.45647 -26.609687)
			(xy 189.507799 -26.631499) (xy 189.555405 -26.660553) (xy 189.598273 -26.696228) (xy 189.63549 -26.737765)
			(xy 189.666263 -26.784278) (xy 189.689935 -26.834775) (xy 189.706003 -26.888182) (xy 189.714123 -26.943358)
			(xy 189.714632 -26.971244) (xy 189.714123 -26.99913) (xy 189.706003 -27.054306) (xy 189.689935 -27.107713)
			(xy 189.666263 -27.15821) (xy 189.63549 -27.204723) (xy 189.598273 -27.24626) (xy 189.555405 -27.281935)
			(xy 189.507799 -27.310989) (xy 189.45647 -27.332801) (xy 189.402513 -27.346907) (xy 189.347076 -27.353007)
			(xy 189.291342 -27.35097) (xy 189.236499 -27.34084) (xy 189.183715 -27.322833) (xy 189.134115 -27.297332)
			(xy 189.088757 -27.264881) (xy 189.048608 -27.226172) (xy 189.014522 -27.182029) (xy 188.987226 -27.133394)
			(xy 188.967303 -27.081303) (xy 188.955177 -27.026866) (xy 188.951106 -26.971244) (xy 185.53938 -26.971244)
			(xy 185.53938 -27.342846) (xy 185.538915 -27.372831) (xy 185.531082 -27.432286) (xy 185.515556 -27.490211)
			(xy 185.492604 -27.545614) (xy 185.462616 -27.597547) (xy 185.426107 -27.645122) (xy 185.383701 -27.687526)
			(xy 185.336124 -27.724032) (xy 185.284189 -27.754016) (xy 185.228784 -27.776965) (xy 185.170859 -27.792488)
			(xy 185.111403 -27.800317) (xy 185.081418 -27.800808) (xy 185.050282 -27.800263) (xy 184.988586 -27.791804)
			(xy 184.928601 -27.77508) (xy 184.899808 -27.763216) (xy 184.888632 -27.75839) (xy 184.86501 -27.75966)
			(xy 184.773824 -27.810968) (xy 184.760362 -27.830526) (xy 184.758838 -27.842464) (xy 184.7546 -27.86949)
			(xy 184.739421 -27.922046) (xy 184.716894 -27.971896) (xy 184.68748 -28.018019) (xy 184.651782 -28.05947)
			(xy 184.610531 -28.095399) (xy 184.564573 -28.125071) (xy 184.51485 -28.147877) (xy 184.46238 -28.16335)
			(xy 184.408238 -28.171172) (xy 184.380886 -28.171648) (xy 184.353638 -28.171081) (xy 184.299698 -28.163324)
			(xy 184.24741 -28.147969) (xy 184.19784 -28.125329) (xy 184.151996 -28.095866) (xy 184.110812 -28.060178)
			(xy 184.075126 -28.018993) (xy 184.045664 -27.973148) (xy 184.023026 -27.923577) (xy 184.007673 -27.871289)
			(xy 183.999918 -27.817348) (xy 182.729897 -27.817348) (xy 182.729885 -27.818026) (xy 182.721765 -27.873202)
			(xy 182.705697 -27.926609) (xy 182.682025 -27.977106) (xy 182.651252 -28.023619) (xy 182.614035 -28.065156)
			(xy 182.571167 -28.100831) (xy 182.523561 -28.129885) (xy 182.472232 -28.151697) (xy 182.418275 -28.165803)
			(xy 182.362838 -28.171903) (xy 182.307104 -28.169866) (xy 182.252261 -28.159736) (xy 182.199477 -28.141729)
			(xy 182.149877 -28.116228) (xy 182.104519 -28.083777) (xy 182.06437 -28.045068) (xy 182.030284 -28.000925)
			(xy 182.002988 -27.95229) (xy 181.983065 -27.900199) (xy 181.970939 -27.845762) (xy 181.966868 -27.79014)
			(xy 180.226462 -27.79014) (xy 180.225953 -27.818026) (xy 180.217833 -27.873202) (xy 180.201765 -27.926609)
			(xy 180.178093 -27.977106) (xy 180.14732 -28.023619) (xy 180.110103 -28.065156) (xy 180.067235 -28.100831)
			(xy 180.019629 -28.129885) (xy 179.9683 -28.151697) (xy 179.914343 -28.165803) (xy 179.858906 -28.171903)
			(xy 179.803172 -28.169866) (xy 179.748329 -28.159736) (xy 179.695545 -28.141729) (xy 179.645945 -28.116228)
			(xy 179.600587 -28.083777) (xy 179.560438 -28.045068) (xy 179.526352 -28.000925) (xy 179.499056 -27.95229)
			(xy 179.479133 -27.900199) (xy 179.467007 -27.845762) (xy 179.462936 -27.79014) (xy 178.243484 -27.79014)
			(xy 178.243484 -29.589984) (xy 179.462936 -29.589984) (xy 179.467007 -29.534362) (xy 179.479133 -29.479925)
			(xy 179.499056 -29.427834) (xy 179.526352 -29.379199) (xy 179.560438 -29.335056) (xy 179.600587 -29.296347)
			(xy 179.645945 -29.263896) (xy 179.695545 -29.238395) (xy 179.748329 -29.220388) (xy 179.803172 -29.210258)
			(xy 179.858906 -29.208221) (xy 179.914343 -29.214321) (xy 179.9683 -29.228427) (xy 180.019629 -29.250239)
			(xy 180.067235 -29.279293) (xy 180.110103 -29.314968) (xy 180.14732 -29.356505) (xy 180.178093 -29.403018)
			(xy 180.201765 -29.453515) (xy 180.217833 -29.506922) (xy 180.225953 -29.562098) (xy 180.226462 -29.589984)
			(xy 181.966868 -29.589984) (xy 181.970939 -29.534362) (xy 181.983065 -29.479925) (xy 182.002988 -29.427834)
			(xy 182.030284 -29.379199) (xy 182.06437 -29.335056) (xy 182.104519 -29.296347) (xy 182.149877 -29.263896)
			(xy 182.199477 -29.238395) (xy 182.252261 -29.220388) (xy 182.307104 -29.210258) (xy 182.362838 -29.208221)
			(xy 182.418275 -29.214321) (xy 182.472232 -29.228427) (xy 182.523561 -29.250239) (xy 182.571167 -29.279293)
			(xy 182.614035 -29.314968) (xy 182.651252 -29.356505) (xy 182.682025 -29.403018) (xy 182.705697 -29.453515)
			(xy 182.721765 -29.506922) (xy 182.729885 -29.562098) (xy 182.730394 -29.589984) (xy 183.998868 -29.589984)
			(xy 184.002939 -29.534362) (xy 184.015065 -29.479925) (xy 184.034988 -29.427834) (xy 184.062284 -29.379199)
			(xy 184.09637 -29.335056) (xy 184.136519 -29.296347) (xy 184.181877 -29.263896) (xy 184.231477 -29.238395)
			(xy 184.284261 -29.220388) (xy 184.339104 -29.210258) (xy 184.394838 -29.208221) (xy 184.450275 -29.214321)
			(xy 184.504232 -29.228427) (xy 184.555561 -29.250239) (xy 184.603167 -29.279293) (xy 184.646035 -29.314968)
			(xy 184.667706 -29.339154) (xy 186.390232 -29.339154) (xy 186.390232 -29.284646) (xy 186.397989 -29.230694)
			(xy 186.413345 -29.178394) (xy 186.435987 -29.128813) (xy 186.465455 -29.082958) (xy 186.501149 -29.041763)
			(xy 186.542342 -29.006067) (xy 186.588195 -28.976597) (xy 186.637776 -28.953952) (xy 186.690074 -28.938593)
			(xy 186.744026 -28.930833) (xy 186.77128 -28.930346) (xy 186.786073 -28.930481) (xy 186.815571 -28.93277)
			(xy 186.830208 -28.934918) (xy 186.84113 -28.936696) (xy 186.862466 -28.9306) (xy 186.929776 -28.873196)
			(xy 186.937811 -28.865635) (xy 186.94702 -28.845609) (xy 186.947556 -28.834588) (xy 186.947556 -28.530296)
			(xy 186.947034 -28.519275) (xy 186.937805 -28.499258) (xy 186.929776 -28.491688) (xy 186.862466 -28.434284)
			(xy 186.84113 -28.428188) (xy 186.830208 -28.429966) (xy 186.815569 -28.4321) (xy 186.786073 -28.434393)
			(xy 186.77128 -28.434538) (xy 186.744032 -28.43399) (xy 186.690091 -28.426232) (xy 186.637802 -28.410877)
			(xy 186.588232 -28.388236) (xy 186.542387 -28.358772) (xy 186.501203 -28.323083) (xy 186.465516 -28.281897)
			(xy 186.436054 -28.236051) (xy 186.413416 -28.186479) (xy 186.398064 -28.13419) (xy 186.390308 -28.080248)
			(xy 186.390308 -28.025752) (xy 186.398064 -27.97181) (xy 186.413416 -27.919521) (xy 186.436054 -27.869949)
			(xy 186.465516 -27.824103) (xy 186.501203 -27.782917) (xy 186.542387 -27.747228) (xy 186.588232 -27.717764)
			(xy 186.637802 -27.695123) (xy 186.690091 -27.679768) (xy 186.744032 -27.67201) (xy 186.77128 -27.671522)
			(xy 186.797206 -27.671961) (xy 186.848583 -27.678964) (xy 186.898539 -27.69286) (xy 186.946154 -27.71339)
			(xy 186.990551 -27.740178) (xy 187.030912 -27.77273) (xy 187.066494 -27.810447) (xy 187.081922 -27.831288)
			(xy 187.087644 -27.838635) (xy 187.10316 -27.848911) (xy 187.112148 -27.851354) (xy 187.142374 -27.858212)
			(xy 187.151649 -27.859976) (xy 187.170314 -27.857225) (xy 187.178696 -27.852878) (xy 187.204673 -27.838586)
			(xy 187.259525 -27.816074) (xy 187.316828 -27.800847) (xy 187.375619 -27.793161) (xy 187.405264 -27.79268)
			(xy 187.434907 -27.793182) (xy 187.493689 -27.800902) (xy 187.550987 -27.816127) (xy 187.605847 -27.838604)
			(xy 187.631832 -27.852878) (xy 187.640255 -27.857101) (xy 187.658876 -27.859849) (xy 187.668154 -27.858212)
			(xy 187.69838 -27.851354) (xy 187.707381 -27.848951) (xy 187.722883 -27.838641) (xy 187.728606 -27.831288)
			(xy 187.744002 -27.81042) (xy 187.779576 -27.772685) (xy 187.819937 -27.740121) (xy 187.864339 -27.713328)
			(xy 187.911963 -27.6928) (xy 187.96193 -27.678917) (xy 188.013318 -27.671935) (xy 188.039248 -27.671522)
			(xy 188.066499 -27.671951) (xy 188.120446 -27.679714) (xy 188.172739 -27.695074) (xy 188.222314 -27.71772)
			(xy 188.268162 -27.74719) (xy 188.30935 -27.782884) (xy 188.345039 -27.824076) (xy 188.374503 -27.869928)
			(xy 188.397143 -27.919506) (xy 188.412496 -27.971801) (xy 188.420252 -28.025749) (xy 188.420252 -28.080251)
			(xy 188.412496 -28.134199) (xy 188.397143 -28.186494) (xy 188.374503 -28.236072) (xy 188.345039 -28.281924)
			(xy 188.30935 -28.323116) (xy 188.268162 -28.35881) (xy 188.222314 -28.38828) (xy 188.172739 -28.410926)
			(xy 188.120446 -28.426286) (xy 188.066499 -28.434049) (xy 188.039248 -28.434538) (xy 188.024455 -28.4344)
			(xy 187.994957 -28.432113) (xy 187.98032 -28.429966) (xy 187.969398 -28.428188) (xy 187.948062 -28.434284)
			(xy 187.880752 -28.491688) (xy 187.872729 -28.49926) (xy 187.863512 -28.519277) (xy 187.862972 -28.530296)
			(xy 187.862972 -28.834588) (xy 187.863525 -28.845605) (xy 187.872735 -28.865621) (xy 187.880752 -28.873196)
			(xy 187.948062 -28.9306) (xy 187.969398 -28.936696) (xy 187.98032 -28.934918) (xy 187.994958 -28.93278)
			(xy 188.024455 -28.93049) (xy 188.039248 -28.930346) (xy 188.066494 -28.930927) (xy 188.12043 -28.938689)
			(xy 188.172712 -28.954046) (xy 188.222277 -28.976687) (xy 188.268116 -29.006151) (xy 188.309296 -29.041838)
			(xy 188.344978 -29.083022) (xy 188.374436 -29.128865) (xy 188.397071 -29.178433) (xy 188.412422 -29.230717)
			(xy 188.420176 -29.284654) (xy 188.420176 -29.339146) (xy 188.412422 -29.393083) (xy 188.397071 -29.445367)
			(xy 188.374436 -29.494935) (xy 188.344978 -29.540778) (xy 188.309296 -29.581962) (xy 188.268116 -29.617649)
			(xy 188.222277 -29.647113) (xy 188.172712 -29.669754) (xy 188.12043 -29.685111) (xy 188.066494 -29.692873)
			(xy 188.039248 -29.693362) (xy 188.013322 -29.692909) (xy 187.961945 -29.685909) (xy 187.91199 -29.672016)
			(xy 187.864375 -29.651488) (xy 187.819978 -29.624702) (xy 187.779616 -29.592152) (xy 187.744034 -29.554436)
			(xy 187.728606 -29.533596) (xy 187.722857 -29.526273) (xy 187.707361 -29.515981) (xy 187.69838 -29.51353)
			(xy 187.668154 -29.506672) (xy 187.658877 -29.504925) (xy 187.640214 -29.507665) (xy 187.631832 -29.512006)
			(xy 187.605848 -29.526286) (xy 187.550999 -29.548801) (xy 187.493698 -29.564031) (xy 187.434909 -29.571722)
			(xy 187.405264 -29.572204) (xy 187.375622 -29.571692) (xy 187.31684 -29.563976) (xy 187.259542 -29.548753)
			(xy 187.204681 -29.526279) (xy 187.178696 -29.512006) (xy 187.170289 -29.507747) (xy 187.151654 -29.505022)
			(xy 187.142374 -29.506672) (xy 187.112148 -29.51353) (xy 187.103153 -29.51595) (xy 187.087649 -29.526248)
			(xy 187.081922 -29.533596) (xy 187.066504 -29.554447) (xy 187.030934 -29.592183) (xy 186.990577 -29.624749)
			(xy 186.946179 -29.651545) (xy 186.898558 -29.672075) (xy 186.848594 -29.685962) (xy 186.797209 -29.692948)
			(xy 186.77128 -29.693362) (xy 186.744026 -29.692967) (xy 186.690074 -29.685207) (xy 186.637776 -29.669848)
			(xy 186.588195 -29.647203) (xy 186.542342 -29.617733) (xy 186.501149 -29.582037) (xy 186.465455 -29.540842)
			(xy 186.435987 -29.494987) (xy 186.413345 -29.445406) (xy 186.397989 -29.393106) (xy 186.390232 -29.339154)
			(xy 184.667706 -29.339154) (xy 184.683252 -29.356505) (xy 184.714025 -29.403018) (xy 184.737697 -29.453515)
			(xy 184.753765 -29.506922) (xy 184.761885 -29.562098) (xy 184.762394 -29.589984) (xy 184.761885 -29.61787)
			(xy 184.753765 -29.673046) (xy 184.737697 -29.726453) (xy 184.714025 -29.77695) (xy 184.683252 -29.823463)
			(xy 184.646035 -29.865) (xy 184.619897 -29.886752) (xy 189.032356 -29.886752) (xy 189.032356 -29.832248)
			(xy 189.040112 -29.778298) (xy 189.055468 -29.726001) (xy 189.078109 -29.676422) (xy 189.107576 -29.630569)
			(xy 189.143269 -29.589377) (xy 189.18446 -29.553683) (xy 189.230311 -29.524215) (xy 189.27989 -29.501572)
			(xy 189.332186 -29.486215) (xy 189.386136 -29.478457) (xy 189.413388 -29.47797) (xy 189.439314 -29.478424)
			(xy 189.490689 -29.485428) (xy 189.540644 -29.499322) (xy 189.588258 -29.519851) (xy 189.632654 -29.546636)
			(xy 189.673016 -29.579185) (xy 189.708601 -29.616897) (xy 189.72403 -29.637736) (xy 189.729795 -29.645045)
			(xy 189.745279 -29.655343) (xy 189.754256 -29.657802) (xy 189.784482 -29.66466) (xy 189.793757 -29.666423)
			(xy 189.812422 -29.663671) (xy 189.820804 -29.659326) (xy 189.846782 -29.645035) (xy 189.901633 -29.622522)
			(xy 189.958936 -29.607295) (xy 190.017727 -29.599608) (xy 190.047372 -29.599128) (xy 190.077014 -29.599633)
			(xy 190.135796 -29.607353) (xy 190.193094 -29.622578) (xy 190.247955 -29.645053) (xy 190.27394 -29.659326)
			(xy 190.282362 -29.663551) (xy 190.300984 -29.666299) (xy 190.310262 -29.66466) (xy 190.340488 -29.657802)
			(xy 190.349485 -29.655387) (xy 190.364987 -29.645084) (xy 190.370714 -29.637736) (xy 190.38609 -29.616853)
			(xy 190.42167 -29.579121) (xy 190.462034 -29.546559) (xy 190.50644 -29.519769) (xy 190.554067 -29.499244)
			(xy 190.604036 -29.485363) (xy 190.655425 -29.478382) (xy 190.681356 -29.47797) (xy 190.708609 -29.478474)
			(xy 190.762562 -29.486226) (xy 190.814862 -29.501577) (xy 190.864445 -29.524216) (xy 190.910301 -29.553681)
			(xy 190.951496 -29.589372) (xy 190.987193 -29.630564) (xy 191.016663 -29.676417) (xy 191.039308 -29.725997)
			(xy 191.054665 -29.778295) (xy 191.062423 -29.832247) (xy 191.062423 -29.886753) (xy 191.054665 -29.940705)
			(xy 191.039308 -29.993003) (xy 191.016663 -30.042584) (xy 190.987193 -30.088436) (xy 190.951496 -30.129628)
			(xy 190.910301 -30.165319) (xy 190.864445 -30.194784) (xy 190.814862 -30.217423) (xy 190.762562 -30.232774)
			(xy 190.708609 -30.240526) (xy 190.681356 -30.240986) (xy 190.666563 -30.240846) (xy 190.637065 -30.23856)
			(xy 190.622428 -30.236414) (xy 190.611506 -30.234636) (xy 190.59017 -30.240732) (xy 190.52286 -30.298136)
			(xy 190.514816 -30.305689) (xy 190.505611 -30.325721) (xy 190.50508 -30.336744) (xy 190.50508 -30.641036)
			(xy 190.505605 -30.652056) (xy 190.514834 -30.672072) (xy 190.52286 -30.679644) (xy 190.59017 -30.737048)
			(xy 190.611506 -30.743144) (xy 190.622428 -30.741366) (xy 190.637066 -30.739227) (xy 190.666563 -30.736938)
			(xy 190.681356 -30.736794) (xy 190.708611 -30.73725) (xy 190.762567 -30.745002) (xy 190.81487 -30.760355)
			(xy 190.864456 -30.782995) (xy 190.910315 -30.812462) (xy 190.951513 -30.848155) (xy 190.987212 -30.88935)
			(xy 191.016684 -30.935205) (xy 191.03933 -30.984788) (xy 191.054688 -31.03709) (xy 191.062447 -31.091045)
			(xy 191.062447 -31.145555) (xy 191.054688 -31.19951) (xy 191.03933 -31.251812) (xy 191.016684 -31.301395)
			(xy 190.987212 -31.34725) (xy 190.951513 -31.388445) (xy 190.910315 -31.424138) (xy 190.864456 -31.453605)
			(xy 190.81487 -31.476245) (xy 190.762567 -31.491598) (xy 190.708611 -31.49935) (xy 190.681356 -31.49981)
			(xy 190.655429 -31.499406) (xy 190.604051 -31.492394) (xy 190.554095 -31.478492) (xy 190.50648 -31.457955)
			(xy 190.462084 -31.431162) (xy 190.421724 -31.398606) (xy 190.386142 -31.360886) (xy 190.370714 -31.340044)
			(xy 190.364973 -31.332714) (xy 190.349471 -31.322428) (xy 190.340488 -31.319978) (xy 190.310262 -31.31312)
			(xy 190.300985 -31.311371) (xy 190.282322 -31.314111) (xy 190.27394 -31.318454) (xy 190.247977 -31.332774)
			(xy 190.19312 -31.355278) (xy 190.135813 -31.370497) (xy 190.077019 -31.378176) (xy 190.047372 -31.378652)
			(xy 190.01773 -31.378131) (xy 189.958949 -31.370416) (xy 189.901651 -31.355196) (xy 189.846789 -31.332725)
			(xy 189.820804 -31.318454) (xy 189.812394 -31.3142) (xy 189.793762 -31.311471) (xy 189.784482 -31.31312)
			(xy 189.754256 -31.319978) (xy 189.745267 -31.322418) (xy 189.729761 -31.332703) (xy 189.72403 -31.340044)
			(xy 189.708621 -31.360902) (xy 189.673048 -31.398636) (xy 189.632689 -31.4312) (xy 189.588289 -31.457994)
			(xy 189.540667 -31.478523) (xy 189.490703 -31.492409) (xy 189.439317 -31.499395) (xy 189.413388 -31.49981)
			(xy 189.386137 -31.499319) (xy 189.332191 -31.491562) (xy 189.279898 -31.476205) (xy 189.230323 -31.453564)
			(xy 189.184474 -31.424097) (xy 189.143286 -31.388406) (xy 189.107596 -31.347216) (xy 189.07813 -31.301367)
			(xy 189.05549 -31.25179) (xy 189.040136 -31.199497) (xy 189.03238 -31.145551) (xy 189.03238 -31.091049)
			(xy 189.040136 -31.037103) (xy 189.05549 -30.98481) (xy 189.07813 -30.935233) (xy 189.107596 -30.889384)
			(xy 189.143286 -30.848194) (xy 189.184474 -30.812503) (xy 189.230323 -30.783036) (xy 189.279898 -30.760395)
			(xy 189.332191 -30.745038) (xy 189.386137 -30.737281) (xy 189.413388 -30.736794) (xy 189.428181 -30.736929)
			(xy 189.457679 -30.739218) (xy 189.472316 -30.741366) (xy 189.483238 -30.743144) (xy 189.504574 -30.737048)
			(xy 189.571884 -30.679644) (xy 189.579883 -30.67205) (xy 189.589115 -30.65205) (xy 189.589664 -30.641036)
			(xy 189.589664 -30.336744) (xy 189.589113 -30.325726) (xy 189.579904 -30.305709) (xy 189.571884 -30.298136)
			(xy 189.504574 -30.240732) (xy 189.483238 -30.234636) (xy 189.472316 -30.236414) (xy 189.457679 -30.238559)
			(xy 189.428181 -30.240844) (xy 189.413388 -30.240986) (xy 189.386136 -30.240543) (xy 189.332186 -30.232785)
			(xy 189.27989 -30.217428) (xy 189.230311 -30.194785) (xy 189.18446 -30.165317) (xy 189.143269 -30.129623)
			(xy 189.107576 -30.088431) (xy 189.078109 -30.042578) (xy 189.055468 -29.992999) (xy 189.040112 -29.940702)
			(xy 189.032356 -29.886752) (xy 184.619897 -29.886752) (xy 184.603167 -29.900675) (xy 184.555561 -29.929729)
			(xy 184.504232 -29.951541) (xy 184.450275 -29.965647) (xy 184.394838 -29.971747) (xy 184.339104 -29.96971)
			(xy 184.284261 -29.95958) (xy 184.231477 -29.941573) (xy 184.181877 -29.916072) (xy 184.136519 -29.883621)
			(xy 184.09637 -29.844912) (xy 184.062284 -29.800769) (xy 184.034988 -29.752134) (xy 184.015065 -29.700043)
			(xy 184.002939 -29.645606) (xy 183.998868 -29.589984) (xy 182.730394 -29.589984) (xy 182.729885 -29.61787)
			(xy 182.721765 -29.673046) (xy 182.705697 -29.726453) (xy 182.682025 -29.77695) (xy 182.651252 -29.823463)
			(xy 182.614035 -29.865) (xy 182.571167 -29.900675) (xy 182.523561 -29.929729) (xy 182.472232 -29.951541)
			(xy 182.418275 -29.965647) (xy 182.362838 -29.971747) (xy 182.307104 -29.96971) (xy 182.252261 -29.95958)
			(xy 182.199477 -29.941573) (xy 182.149877 -29.916072) (xy 182.104519 -29.883621) (xy 182.06437 -29.844912)
			(xy 182.030284 -29.800769) (xy 182.002988 -29.752134) (xy 181.983065 -29.700043) (xy 181.970939 -29.645606)
			(xy 181.966868 -29.589984) (xy 180.226462 -29.589984) (xy 180.225953 -29.61787) (xy 180.217833 -29.673046)
			(xy 180.201765 -29.726453) (xy 180.178093 -29.77695) (xy 180.14732 -29.823463) (xy 180.110103 -29.865)
			(xy 180.067235 -29.900675) (xy 180.019629 -29.929729) (xy 179.9683 -29.951541) (xy 179.914343 -29.965647)
			(xy 179.858906 -29.971747) (xy 179.803172 -29.96971) (xy 179.748329 -29.95958) (xy 179.695545 -29.941573)
			(xy 179.645945 -29.916072) (xy 179.600587 -29.883621) (xy 179.560438 -29.844912) (xy 179.526352 -29.800769)
			(xy 179.499056 -29.752134) (xy 179.479133 -29.700043) (xy 179.467007 -29.645606) (xy 179.462936 -29.589984)
			(xy 178.243484 -29.589984) (xy 178.243484 -31.642304) (xy 179.506624 -31.642304) (xy 179.510695 -31.586682)
			(xy 179.522821 -31.532245) (xy 179.542744 -31.480154) (xy 179.57004 -31.431519) (xy 179.604126 -31.387376)
			(xy 179.644275 -31.348667) (xy 179.689633 -31.316216) (xy 179.739233 -31.290715) (xy 179.792017 -31.272708)
			(xy 179.84686 -31.262578) (xy 179.902594 -31.260541) (xy 179.958031 -31.266641) (xy 180.011988 -31.280747)
			(xy 180.063317 -31.302559) (xy 180.110923 -31.331613) (xy 180.153791 -31.367288) (xy 180.174214 -31.390082)
			(xy 181.966868 -31.390082) (xy 181.970939 -31.33446) (xy 181.983065 -31.280023) (xy 182.002988 -31.227932)
			(xy 182.030284 -31.179297) (xy 182.06437 -31.135154) (xy 182.104519 -31.096445) (xy 182.149877 -31.063994)
			(xy 182.199477 -31.038493) (xy 182.252261 -31.020486) (xy 182.307104 -31.010356) (xy 182.362838 -31.008319)
			(xy 182.418275 -31.014419) (xy 182.472232 -31.028525) (xy 182.523561 -31.050337) (xy 182.571167 -31.079391)
			(xy 182.614035 -31.115066) (xy 182.651252 -31.156603) (xy 182.682025 -31.203116) (xy 182.705697 -31.253613)
			(xy 182.721765 -31.30702) (xy 182.729885 -31.362196) (xy 182.730394 -31.390082) (xy 183.998868 -31.390082)
			(xy 184.002939 -31.33446) (xy 184.015065 -31.280023) (xy 184.034988 -31.227932) (xy 184.062284 -31.179297)
			(xy 184.09637 -31.135154) (xy 184.136519 -31.096445) (xy 184.181877 -31.063994) (xy 184.231477 -31.038493)
			(xy 184.284261 -31.020486) (xy 184.339104 -31.010356) (xy 184.394838 -31.008319) (xy 184.450275 -31.014419)
			(xy 184.504232 -31.028525) (xy 184.555561 -31.050337) (xy 184.603167 -31.079391) (xy 184.646035 -31.115066)
			(xy 184.683252 -31.156603) (xy 184.714025 -31.203116) (xy 184.737697 -31.253613) (xy 184.753765 -31.30702)
			(xy 184.761885 -31.362196) (xy 184.762394 -31.390082) (xy 184.761885 -31.417968) (xy 184.753765 -31.473144)
			(xy 184.737697 -31.526551) (xy 184.714025 -31.577048) (xy 184.683252 -31.623561) (xy 184.646035 -31.665098)
			(xy 184.627826 -31.680252) (xy 186.39025 -31.680252) (xy 186.39025 -31.625748) (xy 186.398006 -31.571798)
			(xy 186.413362 -31.519501) (xy 186.436003 -31.469921) (xy 186.46547 -31.424068) (xy 186.501162 -31.382876)
			(xy 186.542352 -31.347182) (xy 186.588204 -31.317713) (xy 186.637782 -31.295069) (xy 186.690078 -31.279711)
			(xy 186.744028 -31.271951) (xy 186.77128 -31.271464) (xy 186.797207 -31.271885) (xy 186.848586 -31.27889)
			(xy 186.898543 -31.292787) (xy 186.946158 -31.31332) (xy 186.990555 -31.340111) (xy 187.030915 -31.372667)
			(xy 187.066496 -31.410387) (xy 187.081922 -31.43123) (xy 187.087656 -31.438567) (xy 187.103163 -31.44885)
			(xy 187.112148 -31.451296) (xy 187.142374 -31.458154) (xy 187.151649 -31.459913) (xy 187.170314 -31.457164)
			(xy 187.178696 -31.45282) (xy 187.20469 -31.43858) (xy 187.259557 -31.416164) (xy 187.316855 -31.401003)
			(xy 187.375629 -31.39335) (xy 187.405264 -31.392876) (xy 187.434902 -31.393332) (xy 187.493684 -31.400953)
			(xy 187.550987 -31.416113) (xy 187.605849 -31.438555) (xy 187.631832 -31.45282) (xy 187.640256 -31.457041)
			(xy 187.658877 -31.459792) (xy 187.668154 -31.458154) (xy 187.69838 -31.451296) (xy 187.707376 -31.448879)
			(xy 187.722879 -31.438578) (xy 187.728606 -31.43123) (xy 187.743985 -31.410349) (xy 187.779564 -31.372617)
			(xy 187.819929 -31.340056) (xy 187.864334 -31.313265) (xy 187.91196 -31.29274) (xy 187.961928 -31.278858)
			(xy 188.013317 -31.271876) (xy 188.039248 -31.271464) (xy 188.066495 -31.272009) (xy 188.120433 -31.279771)
			(xy 188.172719 -31.295129) (xy 188.222286 -31.317771) (xy 188.268127 -31.347237) (xy 188.309308 -31.382926)
			(xy 188.344992 -31.424111) (xy 188.374452 -31.469956) (xy 188.397088 -31.519526) (xy 188.412439 -31.571813)
			(xy 188.420194 -31.625753) (xy 188.420194 -31.680247) (xy 188.412439 -31.734187) (xy 188.397088 -31.786474)
			(xy 188.374452 -31.836044) (xy 188.344992 -31.881889) (xy 188.309308 -31.923074) (xy 188.268127 -31.958763)
			(xy 188.222286 -31.988229) (xy 188.172719 -32.010871) (xy 188.120433 -32.026229) (xy 188.066495 -32.033991)
			(xy 188.039248 -32.03448) (xy 188.024455 -32.034341) (xy 187.994957 -32.032055) (xy 187.98032 -32.029908)
			(xy 187.969398 -32.02813) (xy 187.948062 -32.034226) (xy 187.880752 -32.09163) (xy 187.87271 -32.099185)
			(xy 187.863504 -32.119215) (xy 187.862972 -32.130238) (xy 187.862972 -32.43453) (xy 187.863502 -32.44555)
			(xy 187.872728 -32.465566) (xy 187.880752 -32.473138) (xy 187.948062 -32.530542) (xy 187.969398 -32.536638)
			(xy 187.98032 -32.53486) (xy 187.994958 -32.532722) (xy 188.024455 -32.530432) (xy 188.039248 -32.530288)
			(xy 188.066497 -32.530785) (xy 188.120439 -32.538547) (xy 188.172727 -32.553906) (xy 188.222298 -32.57655)
			(xy 188.268142 -32.606017) (xy 188.309326 -32.641708) (xy 188.345012 -32.682897) (xy 188.374473 -32.728744)
			(xy 188.397111 -32.778318) (xy 188.412463 -32.830608) (xy 188.420218 -32.884551) (xy 188.420218 -32.939049)
			(xy 188.412463 -32.992992) (xy 188.397111 -33.045282) (xy 188.374473 -33.094856) (xy 188.345012 -33.140703)
			(xy 188.309326 -33.181892) (xy 188.268142 -33.217583) (xy 188.222298 -33.24705) (xy 188.172727 -33.269694)
			(xy 188.120439 -33.285053) (xy 188.066497 -33.292815) (xy 188.039248 -33.293304) (xy 188.013323 -33.292834)
			(xy 187.961948 -33.285834) (xy 187.911993 -33.271943) (xy 187.864379 -33.251418) (xy 187.819982 -33.224635)
			(xy 187.779619 -33.192088) (xy 187.744035 -33.154376) (xy 187.728606 -33.133538) (xy 187.722869 -33.126205)
			(xy 187.707364 -33.11592) (xy 187.69838 -33.113472) (xy 187.668154 -33.106614) (xy 187.658878 -33.104862)
			(xy 187.640214 -33.107604) (xy 187.631832 -33.111948) (xy 187.605831 -33.126174) (xy 187.550966 -33.148594)
			(xy 187.49367 -33.163759) (xy 187.434898 -33.171416) (xy 187.405264 -33.171892) (xy 187.375627 -33.171429)
			(xy 187.316844 -33.16381) (xy 187.259541 -33.148653) (xy 187.204679 -33.126212) (xy 187.178696 -33.111948)
			(xy 187.170288 -33.10769) (xy 187.151654 -33.104963) (xy 187.142374 -33.106614) (xy 187.112148 -33.113472)
			(xy 187.103159 -33.11591) (xy 187.087653 -33.126197) (xy 187.081922 -33.133538) (xy 187.066516 -33.154399)
			(xy 187.030943 -33.192132) (xy 186.990583 -33.224696) (xy 186.946183 -33.25149) (xy 186.898561 -33.272019)
			(xy 186.848596 -33.285904) (xy 186.79721 -33.29289) (xy 186.77128 -33.293304) (xy 186.744029 -33.292825)
			(xy 186.690083 -33.285066) (xy 186.63779 -33.269709) (xy 186.588215 -33.247066) (xy 186.542367 -33.217599)
			(xy 186.501178 -33.181907) (xy 186.465489 -33.140717) (xy 186.436024 -33.094867) (xy 186.413384 -33.045291)
			(xy 186.39803 -32.992997) (xy 186.390274 -32.939051) (xy 186.390274 -32.884549) (xy 186.39803 -32.830603)
			(xy 186.413384 -32.778309) (xy 186.436024 -32.728733) (xy 186.465489 -32.682883) (xy 186.501178 -32.641693)
			(xy 186.542367 -32.606001) (xy 186.588215 -32.576534) (xy 186.63779 -32.553891) (xy 186.690083 -32.538534)
			(xy 186.744029 -32.530775) (xy 186.77128 -32.530288) (xy 186.786073 -32.530424) (xy 186.815571 -32.532713)
			(xy 186.830208 -32.53486) (xy 186.84113 -32.536638) (xy 186.862466 -32.530542) (xy 186.929776 -32.473138)
			(xy 186.937792 -32.46556) (xy 186.947011 -32.445547) (xy 186.947556 -32.43453) (xy 186.947556 -32.130238)
			(xy 186.947011 -32.11922) (xy 186.937798 -32.099202) (xy 186.929776 -32.09163) (xy 186.862466 -32.034226)
			(xy 186.84113 -32.02813) (xy 186.830208 -32.029908) (xy 186.815569 -32.032043) (xy 186.786073 -32.034335)
			(xy 186.77128 -32.03448) (xy 186.744028 -32.034049) (xy 186.690078 -32.026289) (xy 186.637782 -32.010931)
			(xy 186.588204 -31.988287) (xy 186.542352 -31.958818) (xy 186.501162 -31.923124) (xy 186.46547 -31.881932)
			(xy 186.436003 -31.836079) (xy 186.413362 -31.786499) (xy 186.398006 -31.734202) (xy 186.39025 -31.680252)
			(xy 184.627826 -31.680252) (xy 184.603167 -31.700773) (xy 184.555561 -31.729827) (xy 184.504232 -31.751639)
			(xy 184.450275 -31.765745) (xy 184.394838 -31.771845) (xy 184.339104 -31.769808) (xy 184.284261 -31.759678)
			(xy 184.231477 -31.741671) (xy 184.181877 -31.71617) (xy 184.136519 -31.683719) (xy 184.09637 -31.64501)
			(xy 184.062284 -31.600867) (xy 184.034988 -31.552232) (xy 184.015065 -31.500141) (xy 184.002939 -31.445704)
			(xy 183.998868 -31.390082) (xy 182.730394 -31.390082) (xy 182.729885 -31.417968) (xy 182.721765 -31.473144)
			(xy 182.705697 -31.526551) (xy 182.682025 -31.577048) (xy 182.651252 -31.623561) (xy 182.614035 -31.665098)
			(xy 182.571167 -31.700773) (xy 182.523561 -31.729827) (xy 182.472232 -31.751639) (xy 182.418275 -31.765745)
			(xy 182.362838 -31.771845) (xy 182.307104 -31.769808) (xy 182.252261 -31.759678) (xy 182.199477 -31.741671)
			(xy 182.149877 -31.71617) (xy 182.104519 -31.683719) (xy 182.06437 -31.64501) (xy 182.030284 -31.600867)
			(xy 182.002988 -31.552232) (xy 181.983065 -31.500141) (xy 181.970939 -31.445704) (xy 181.966868 -31.390082)
			(xy 180.174214 -31.390082) (xy 180.191008 -31.408825) (xy 180.221781 -31.455338) (xy 180.245453 -31.505835)
			(xy 180.261521 -31.559242) (xy 180.269641 -31.614418) (xy 180.27015 -31.642304) (xy 180.269641 -31.67019)
			(xy 180.261521 -31.725366) (xy 180.245453 -31.778773) (xy 180.221781 -31.82927) (xy 180.191008 -31.875783)
			(xy 180.153791 -31.91732) (xy 180.110923 -31.952995) (xy 180.063317 -31.982049) (xy 180.011988 -32.003861)
			(xy 179.958031 -32.017967) (xy 179.902594 -32.024067) (xy 179.84686 -32.02203) (xy 179.792017 -32.0119)
			(xy 179.739233 -31.993893) (xy 179.689633 -31.968392) (xy 179.644275 -31.935941) (xy 179.604126 -31.897232)
			(xy 179.57004 -31.853089) (xy 179.542744 -31.804454) (xy 179.522821 -31.752363) (xy 179.510695 -31.697926)
			(xy 179.506624 -31.642304) (xy 178.243484 -31.642304) (xy 178.243484 -33.19018) (xy 179.774086 -33.19018)
			(xy 179.778157 -33.134558) (xy 179.790283 -33.080121) (xy 179.810206 -33.02803) (xy 179.837502 -32.979395)
			(xy 179.871588 -32.935252) (xy 179.911737 -32.896543) (xy 179.957095 -32.864092) (xy 180.006695 -32.838591)
			(xy 180.059479 -32.820584) (xy 180.114322 -32.810454) (xy 180.170056 -32.808417) (xy 180.225493 -32.814517)
			(xy 180.27945 -32.828623) (xy 180.330779 -32.850435) (xy 180.378385 -32.879489) (xy 180.421253 -32.915164)
			(xy 180.45847 -32.956701) (xy 180.489243 -33.003214) (xy 180.512915 -33.053711) (xy 180.528983 -33.107118)
			(xy 180.537103 -33.162294) (xy 180.537612 -33.19018) (xy 181.966868 -33.19018) (xy 181.970939 -33.134558)
			(xy 181.983065 -33.080121) (xy 182.002988 -33.02803) (xy 182.030284 -32.979395) (xy 182.06437 -32.935252)
			(xy 182.104519 -32.896543) (xy 182.149877 -32.864092) (xy 182.199477 -32.838591) (xy 182.252261 -32.820584)
			(xy 182.307104 -32.810454) (xy 182.362838 -32.808417) (xy 182.418275 -32.814517) (xy 182.472232 -32.828623)
			(xy 182.523561 -32.850435) (xy 182.571167 -32.879489) (xy 182.614035 -32.915164) (xy 182.651252 -32.956701)
			(xy 182.682025 -33.003214) (xy 182.705697 -33.053711) (xy 182.721765 -33.107118) (xy 182.729885 -33.162294)
			(xy 182.730394 -33.19018) (xy 183.998868 -33.19018) (xy 184.002939 -33.134558) (xy 184.015065 -33.080121)
			(xy 184.034988 -33.02803) (xy 184.062284 -32.979395) (xy 184.09637 -32.935252) (xy 184.136519 -32.896543)
			(xy 184.181877 -32.864092) (xy 184.231477 -32.838591) (xy 184.284261 -32.820584) (xy 184.339104 -32.810454)
			(xy 184.394838 -32.808417) (xy 184.450275 -32.814517) (xy 184.504232 -32.828623) (xy 184.555561 -32.850435)
			(xy 184.603167 -32.879489) (xy 184.646035 -32.915164) (xy 184.683252 -32.956701) (xy 184.714025 -33.003214)
			(xy 184.737697 -33.053711) (xy 184.753765 -33.107118) (xy 184.761885 -33.162294) (xy 184.762394 -33.19018)
			(xy 184.761885 -33.218066) (xy 184.753765 -33.273242) (xy 184.737697 -33.326649) (xy 184.714025 -33.377146)
			(xy 184.683252 -33.423659) (xy 184.646035 -33.465196) (xy 184.619891 -33.486953) (xy 189.032352 -33.486953)
			(xy 189.032352 -33.432447) (xy 189.040109 -33.378497) (xy 189.055464 -33.3262) (xy 189.078106 -33.27662)
			(xy 189.107573 -33.230767) (xy 189.143266 -33.189574) (xy 189.184457 -33.15388) (xy 189.230309 -33.124412)
			(xy 189.279888 -33.101768) (xy 189.332185 -33.086411) (xy 189.386135 -33.078653) (xy 189.413388 -33.078166)
			(xy 189.439315 -33.07858) (xy 189.490694 -33.085586) (xy 189.540651 -33.099484) (xy 189.588267 -33.120018)
			(xy 189.632663 -33.146811) (xy 189.673023 -33.179367) (xy 189.708604 -33.217089) (xy 189.72403 -33.237932)
			(xy 189.729796 -33.24524) (xy 189.74528 -33.255539) (xy 189.754256 -33.257998) (xy 189.784482 -33.264856)
			(xy 189.793757 -33.266619) (xy 189.812422 -33.263867) (xy 189.820804 -33.259522) (xy 189.846782 -33.245231)
			(xy 189.901633 -33.222718) (xy 189.958936 -33.207491) (xy 190.017726 -33.199804) (xy 190.047372 -33.199324)
			(xy 190.077014 -33.199829) (xy 190.135796 -33.207549) (xy 190.193094 -33.222774) (xy 190.247955 -33.245249)
			(xy 190.27394 -33.259522) (xy 190.282362 -33.263747) (xy 190.300984 -33.266495) (xy 190.310262 -33.264856)
			(xy 190.340488 -33.257998) (xy 190.349485 -33.255584) (xy 190.364988 -33.245281) (xy 190.370714 -33.237932)
			(xy 190.386089 -33.217048) (xy 190.421669 -33.179316) (xy 190.462034 -33.146755) (xy 190.50644 -33.119964)
			(xy 190.554066 -33.099439) (xy 190.604036 -33.085559) (xy 190.655425 -33.078578) (xy 190.681356 -33.078166)
			(xy 190.708609 -33.078678) (xy 190.762561 -33.08643) (xy 190.814861 -33.101781) (xy 190.864443 -33.124419)
			(xy 190.910298 -33.153884) (xy 190.951494 -33.189575) (xy 190.98719 -33.230766) (xy 191.01666 -33.276618)
			(xy 191.039304 -33.326198) (xy 191.054661 -33.378496) (xy 191.062419 -33.432447) (xy 191.062419 -33.486953)
			(xy 191.054661 -33.540904) (xy 191.039304 -33.593202) (xy 191.01666 -33.642782) (xy 190.98719 -33.688634)
			(xy 190.951494 -33.729825) (xy 190.910298 -33.765516) (xy 190.864443 -33.794981) (xy 190.814861 -33.817619)
			(xy 190.762561 -33.83297) (xy 190.708609 -33.840722) (xy 190.681356 -33.841182) (xy 190.666563 -33.841042)
			(xy 190.637065 -33.838756) (xy 190.622428 -33.83661) (xy 190.611506 -33.834832) (xy 190.59017 -33.840928)
			(xy 190.52286 -33.898332) (xy 190.514818 -33.905887) (xy 190.505612 -33.925917) (xy 190.50508 -33.93694)
			(xy 190.50508 -34.241232) (xy 190.505607 -34.252252) (xy 190.514835 -34.272268) (xy 190.52286 -34.27984)
			(xy 190.59017 -34.337244) (xy 190.611506 -34.34334) (xy 190.622428 -34.341562) (xy 190.637066 -34.339423)
			(xy 190.666563 -34.337134) (xy 190.681356 -34.33699) (xy 190.708611 -34.337454) (xy 190.762566 -34.345206)
			(xy 190.814869 -34.360558) (xy 190.864454 -34.383198) (xy 190.910313 -34.412665) (xy 190.951511 -34.448358)
			(xy 190.987209 -34.489552) (xy 191.016681 -34.535407) (xy 191.039326 -34.58499) (xy 191.054684 -34.637291)
			(xy 191.062443 -34.691245) (xy 191.062443 -34.745755) (xy 191.054684 -34.799709) (xy 191.039326 -34.85201)
			(xy 191.016681 -34.901593) (xy 190.987209 -34.947448) (xy 190.951511 -34.988642) (xy 190.910313 -35.024335)
			(xy 190.864454 -35.053802) (xy 190.814869 -35.076442) (xy 190.762566 -35.091794) (xy 190.708611 -35.099546)
			(xy 190.681356 -35.100006) (xy 190.655429 -35.099604) (xy 190.60405 -35.092592) (xy 190.554094 -35.078689)
			(xy 190.50648 -35.058152) (xy 190.462084 -35.031359) (xy 190.421723 -34.998803) (xy 190.386142 -34.961082)
			(xy 190.370714 -34.94024) (xy 190.364974 -34.932909) (xy 190.349471 -34.922623) (xy 190.340488 -34.920174)
			(xy 190.310262 -34.913316) (xy 190.300985 -34.911568) (xy 190.282322 -34.914308) (xy 190.27394 -34.91865)
			(xy 190.247977 -34.93297) (xy 190.19312 -34.955474) (xy 190.135813 -34.970693) (xy 190.077019 -34.978372)
			(xy 190.047372 -34.978848) (xy 190.01773 -34.978327) (xy 189.958949 -34.970613) (xy 189.901651 -34.955393)
			(xy 189.846789 -34.932921) (xy 189.820804 -34.91865) (xy 189.812394 -34.914396) (xy 189.793762 -34.911667)
			(xy 189.784482 -34.913316) (xy 189.754256 -34.920174) (xy 189.745268 -34.922615) (xy 189.729761 -34.932899)
			(xy 189.72403 -34.94024) (xy 189.70862 -34.961097) (xy 189.673047 -34.998831) (xy 189.632688 -35.031395)
			(xy 189.588289 -35.058189) (xy 189.540667 -35.078719) (xy 189.490703 -35.092605) (xy 189.439317 -35.099591)
			(xy 189.413388 -35.100006) (xy 189.386137 -35.099523) (xy 189.33219 -35.091765) (xy 189.279897 -35.076409)
			(xy 189.230321 -35.053767) (xy 189.184472 -35.0243) (xy 189.143283 -34.988609) (xy 189.107592 -34.947419)
			(xy 189.078127 -34.901569) (xy 189.055487 -34.851992) (xy 189.040132 -34.799698) (xy 189.032376 -34.745751)
			(xy 189.032376 -34.691249) (xy 189.040132 -34.637302) (xy 189.055487 -34.585008) (xy 189.078127 -34.535431)
			(xy 189.107592 -34.489581) (xy 189.143283 -34.448391) (xy 189.184472 -34.4127) (xy 189.230321 -34.383233)
			(xy 189.279897 -34.360591) (xy 189.33219 -34.345235) (xy 189.386137 -34.337477) (xy 189.413388 -34.33699)
			(xy 189.428181 -34.337125) (xy 189.457679 -34.339414) (xy 189.472316 -34.341562) (xy 189.483238 -34.34334)
			(xy 189.504574 -34.337244) (xy 189.571884 -34.27984) (xy 189.579884 -34.272247) (xy 189.589116 -34.252246)
			(xy 189.589664 -34.241232) (xy 189.589664 -33.93694) (xy 189.589115 -33.925922) (xy 189.579905 -33.905905)
			(xy 189.571884 -33.898332) (xy 189.504574 -33.840928) (xy 189.483238 -33.834832) (xy 189.472316 -33.83661)
			(xy 189.457679 -33.838755) (xy 189.428181 -33.84104) (xy 189.413388 -33.841182) (xy 189.386135 -33.840747)
			(xy 189.332185 -33.832989) (xy 189.279888 -33.817632) (xy 189.230309 -33.794988) (xy 189.184457 -33.76552)
			(xy 189.143266 -33.729826) (xy 189.107573 -33.688633) (xy 189.078106 -33.64278) (xy 189.055464 -33.5932)
			(xy 189.040109 -33.540903) (xy 189.032352 -33.486953) (xy 184.619891 -33.486953) (xy 184.603167 -33.500871)
			(xy 184.555561 -33.529925) (xy 184.504232 -33.551737) (xy 184.450275 -33.565843) (xy 184.394838 -33.571943)
			(xy 184.339104 -33.569906) (xy 184.284261 -33.559776) (xy 184.231477 -33.541769) (xy 184.181877 -33.516268)
			(xy 184.136519 -33.483817) (xy 184.09637 -33.445108) (xy 184.062284 -33.400965) (xy 184.034988 -33.35233)
			(xy 184.015065 -33.300239) (xy 184.002939 -33.245802) (xy 183.998868 -33.19018) (xy 182.730394 -33.19018)
			(xy 182.729885 -33.218066) (xy 182.721765 -33.273242) (xy 182.705697 -33.326649) (xy 182.682025 -33.377146)
			(xy 182.651252 -33.423659) (xy 182.614035 -33.465196) (xy 182.571167 -33.500871) (xy 182.523561 -33.529925)
			(xy 182.472232 -33.551737) (xy 182.418275 -33.565843) (xy 182.362838 -33.571943) (xy 182.307104 -33.569906)
			(xy 182.252261 -33.559776) (xy 182.199477 -33.541769) (xy 182.149877 -33.516268) (xy 182.104519 -33.483817)
			(xy 182.06437 -33.445108) (xy 182.030284 -33.400965) (xy 182.002988 -33.35233) (xy 181.983065 -33.300239)
			(xy 181.970939 -33.245802) (xy 181.966868 -33.19018) (xy 180.537612 -33.19018) (xy 180.537103 -33.218066)
			(xy 180.528983 -33.273242) (xy 180.512915 -33.326649) (xy 180.489243 -33.377146) (xy 180.45847 -33.423659)
			(xy 180.421253 -33.465196) (xy 180.378385 -33.500871) (xy 180.330779 -33.529925) (xy 180.27945 -33.551737)
			(xy 180.225493 -33.565843) (xy 180.170056 -33.571943) (xy 180.114322 -33.569906) (xy 180.059479 -33.559776)
			(xy 180.006695 -33.541769) (xy 179.957095 -33.516268) (xy 179.911737 -33.483817) (xy 179.871588 -33.445108)
			(xy 179.837502 -33.400965) (xy 179.810206 -33.35233) (xy 179.790283 -33.300239) (xy 179.778157 -33.245802)
			(xy 179.774086 -33.19018) (xy 178.243484 -33.19018) (xy 178.243484 -34.990024) (xy 179.772816 -34.990024)
			(xy 179.776887 -34.934402) (xy 179.789013 -34.879965) (xy 179.808936 -34.827874) (xy 179.836232 -34.779239)
			(xy 179.870318 -34.735096) (xy 179.910467 -34.696387) (xy 179.955825 -34.663936) (xy 180.005425 -34.638435)
			(xy 180.058209 -34.620428) (xy 180.113052 -34.610298) (xy 180.168786 -34.608261) (xy 180.224223 -34.614361)
			(xy 180.27818 -34.628467) (xy 180.329509 -34.650279) (xy 180.377115 -34.679333) (xy 180.419983 -34.715008)
			(xy 180.4572 -34.756545) (xy 180.487973 -34.803058) (xy 180.511645 -34.853555) (xy 180.527713 -34.906962)
			(xy 180.535833 -34.962138) (xy 180.536342 -34.990024) (xy 181.100982 -34.990024) (xy 181.105053 -34.934402)
			(xy 181.117179 -34.879965) (xy 181.137102 -34.827874) (xy 181.164398 -34.779239) (xy 181.198484 -34.735096)
			(xy 181.238633 -34.696387) (xy 181.283991 -34.663936) (xy 181.333591 -34.638435) (xy 181.386375 -34.620428)
			(xy 181.441218 -34.610298) (xy 181.496952 -34.608261) (xy 181.552389 -34.614361) (xy 181.606346 -34.628467)
			(xy 181.657675 -34.650279) (xy 181.705281 -34.679333) (xy 181.748149 -34.715008) (xy 181.785366 -34.756545)
			(xy 181.816139 -34.803058) (xy 181.839811 -34.853555) (xy 181.855879 -34.906962) (xy 181.863999 -34.962138)
			(xy 181.864508 -34.990024) (xy 183.998868 -34.990024) (xy 184.002939 -34.934402) (xy 184.015065 -34.879965)
			(xy 184.034988 -34.827874) (xy 184.062284 -34.779239) (xy 184.09637 -34.735096) (xy 184.136519 -34.696387)
			(xy 184.181877 -34.663936) (xy 184.231477 -34.638435) (xy 184.284261 -34.620428) (xy 184.339104 -34.610298)
			(xy 184.394838 -34.608261) (xy 184.450275 -34.614361) (xy 184.504232 -34.628467) (xy 184.555561 -34.650279)
			(xy 184.603167 -34.679333) (xy 184.646035 -34.715008) (xy 184.683252 -34.756545) (xy 184.714025 -34.803058)
			(xy 184.737697 -34.853555) (xy 184.753765 -34.906962) (xy 184.761885 -34.962138) (xy 184.762394 -34.990024)
			(xy 184.761885 -35.01791) (xy 184.753765 -35.073086) (xy 184.737697 -35.126493) (xy 184.714025 -35.17699)
			(xy 184.683252 -35.223503) (xy 184.646035 -35.26504) (xy 184.603167 -35.300715) (xy 184.555561 -35.329769)
			(xy 184.504232 -35.351581) (xy 184.450275 -35.365687) (xy 184.394838 -35.371787) (xy 184.339104 -35.36975)
			(xy 184.284261 -35.35962) (xy 184.231477 -35.341613) (xy 184.181877 -35.316112) (xy 184.136519 -35.283661)
			(xy 184.09637 -35.244952) (xy 184.062284 -35.200809) (xy 184.034988 -35.152174) (xy 184.015065 -35.100083)
			(xy 184.002939 -35.045646) (xy 183.998868 -34.990024) (xy 181.864508 -34.990024) (xy 181.863999 -35.01791)
			(xy 181.855879 -35.073086) (xy 181.839811 -35.126493) (xy 181.816139 -35.17699) (xy 181.785366 -35.223503)
			(xy 181.748149 -35.26504) (xy 181.705281 -35.300715) (xy 181.657675 -35.329769) (xy 181.606346 -35.351581)
			(xy 181.552389 -35.365687) (xy 181.496952 -35.371787) (xy 181.441218 -35.36975) (xy 181.386375 -35.35962)
			(xy 181.333591 -35.341613) (xy 181.283991 -35.316112) (xy 181.238633 -35.283661) (xy 181.198484 -35.244952)
			(xy 181.164398 -35.200809) (xy 181.137102 -35.152174) (xy 181.117179 -35.100083) (xy 181.105053 -35.045646)
			(xy 181.100982 -34.990024) (xy 180.536342 -34.990024) (xy 180.535833 -35.01791) (xy 180.527713 -35.073086)
			(xy 180.511645 -35.126493) (xy 180.487973 -35.17699) (xy 180.4572 -35.223503) (xy 180.419983 -35.26504)
			(xy 180.377115 -35.300715) (xy 180.329509 -35.329769) (xy 180.27818 -35.351581) (xy 180.224223 -35.365687)
			(xy 180.168786 -35.371787) (xy 180.113052 -35.36975) (xy 180.058209 -35.35962) (xy 180.005425 -35.341613)
			(xy 179.955825 -35.316112) (xy 179.910467 -35.283661) (xy 179.870318 -35.244952) (xy 179.836232 -35.200809)
			(xy 179.808936 -35.152174) (xy 179.789013 -35.100083) (xy 179.776887 -35.045646) (xy 179.772816 -34.990024)
			(xy 178.243484 -34.990024) (xy 178.243484 -38.193438) (xy 179.198271 -38.193438) (xy 179.198271 -38.106562)
			(xy 179.206287 -38.020058) (xy 179.22225 -37.934662) (xy 179.246025 -37.851104) (xy 179.277408 -37.770095)
			(xy 179.316132 -37.692328) (xy 179.361866 -37.618466) (xy 179.414221 -37.549138) (xy 179.472748 -37.484937)
			(xy 179.53695 -37.42641) (xy 179.606279 -37.374057) (xy 179.680142 -37.328324) (xy 179.75791 -37.289601)
			(xy 179.838919 -37.25822) (xy 179.922478 -37.234446) (xy 180.007874 -37.218484) (xy 180.094378 -37.21047)
			(xy 180.137816 -37.209984) (xy 180.215794 -37.209984) (xy 180.225817 -37.209575) (xy 180.244337 -37.201904)
			(xy 180.25851 -37.187728) (xy 180.266177 -37.169207) (xy 180.266594 -37.159184) (xy 180.266594 -37.151564)
			(xy 180.262276 -37.137594) (xy 180.258212 -37.131244) (xy 180.234293 -37.094009) (xy 180.192592 -37.015944)
			(xy 180.158207 -36.93439) (xy 180.131429 -36.850033) (xy 180.11248 -36.76358) (xy 180.10152 -36.675755)
			(xy 180.098642 -36.587297) (xy 180.103869 -36.498946) (xy 180.117157 -36.411443) (xy 180.138395 -36.325524)
			(xy 180.167404 -36.241908) (xy 180.203942 -36.161296) (xy 180.247703 -36.084366) (xy 180.298317 -36.011762)
			(xy 180.355363 -35.944093) (xy 180.41836 -35.881927) (xy 180.48678 -35.825786) (xy 180.56005 -35.776139)
			(xy 180.637555 -35.733405) (xy 180.718644 -35.69794) (xy 180.802638 -35.670044) (xy 180.888832 -35.649948)
			(xy 180.976503 -35.637824) (xy 181.064916 -35.633771) (xy 181.153329 -35.637824) (xy 181.241 -35.649948)
			(xy 181.327194 -35.670044) (xy 181.411188 -35.69794) (xy 181.492277 -35.733405) (xy 181.569782 -35.776139)
			(xy 181.643052 -35.825786) (xy 181.705148 -35.876738) (xy 186.817252 -35.876738) (xy 186.821323 -35.821116)
			(xy 186.833449 -35.766679) (xy 186.853372 -35.714588) (xy 186.880668 -35.665953) (xy 186.914754 -35.62181)
			(xy 186.954903 -35.583101) (xy 187.000261 -35.55065) (xy 187.049861 -35.525149) (xy 187.102645 -35.507142)
			(xy 187.157488 -35.497012) (xy 187.213222 -35.494975) (xy 187.268659 -35.501075) (xy 187.322616 -35.515181)
			(xy 187.373945 -35.536993) (xy 187.421551 -35.566047) (xy 187.464419 -35.601722) (xy 187.501636 -35.643259)
			(xy 187.532409 -35.689772) (xy 187.556081 -35.740269) (xy 187.572149 -35.793676) (xy 187.580269 -35.848852)
			(xy 187.580778 -35.876738) (xy 187.580269 -35.904624) (xy 187.572149 -35.9598) (xy 187.556081 -36.013207)
			(xy 187.532409 -36.063704) (xy 187.501636 -36.110217) (xy 187.464419 -36.151754) (xy 187.421551 -36.187429)
			(xy 187.373945 -36.216483) (xy 187.322616 -36.238295) (xy 187.268659 -36.252401) (xy 187.213222 -36.258501)
			(xy 187.157488 -36.256464) (xy 187.102645 -36.246334) (xy 187.049861 -36.228327) (xy 187.000261 -36.202826)
			(xy 186.954903 -36.170375) (xy 186.914754 -36.131666) (xy 186.880668 -36.087523) (xy 186.853372 -36.038888)
			(xy 186.833449 -35.986797) (xy 186.821323 -35.93236) (xy 186.817252 -35.876738) (xy 181.705148 -35.876738)
			(xy 181.711472 -35.881927) (xy 181.774469 -35.944093) (xy 181.831515 -36.011762) (xy 181.882129 -36.084366)
			(xy 181.92589 -36.161296) (xy 181.962428 -36.241908) (xy 181.991437 -36.325524) (xy 182.012675 -36.411443)
			(xy 182.025963 -36.498946) (xy 182.028388 -36.539928) (xy 188.63867 -36.539928) (xy 188.63867 -36.479992)
			(xy 188.646493 -36.42057) (xy 188.662006 -36.362677) (xy 188.684942 -36.307304) (xy 188.714909 -36.255398)
			(xy 188.751396 -36.207848) (xy 188.793776 -36.165468) (xy 188.841326 -36.128981) (xy 188.893232 -36.099014)
			(xy 188.948605 -36.076078) (xy 189.006498 -36.060565) (xy 189.06592 -36.052742) (xy 189.125856 -36.052742)
			(xy 189.185278 -36.060565) (xy 189.243171 -36.076078) (xy 189.298544 -36.099014) (xy 189.35045 -36.128981)
			(xy 189.398 -36.165468) (xy 189.44038 -36.207848) (xy 189.476867 -36.255398) (xy 189.506834 -36.307304)
			(xy 189.52977 -36.362677) (xy 189.545283 -36.42057) (xy 189.553106 -36.479992) (xy 189.553596 -36.50996)
			(xy 189.553106 -36.539928) (xy 189.545283 -36.59935) (xy 189.52977 -36.657243) (xy 189.506834 -36.712616)
			(xy 189.476867 -36.764522) (xy 189.44038 -36.812072) (xy 189.398 -36.854452) (xy 189.35045 -36.890939)
			(xy 189.298544 -36.920906) (xy 189.243171 -36.943842) (xy 189.185278 -36.959355) (xy 189.125856 -36.967178)
			(xy 189.06592 -36.967178) (xy 189.006498 -36.959355) (xy 188.948605 -36.943842) (xy 188.893232 -36.920906)
			(xy 188.841326 -36.890939) (xy 188.793776 -36.854452) (xy 188.751396 -36.812072) (xy 188.714909 -36.764522)
			(xy 188.684942 -36.712616) (xy 188.662006 -36.657243) (xy 188.646493 -36.59935) (xy 188.63867 -36.539928)
			(xy 182.028388 -36.539928) (xy 182.03119 -36.587297) (xy 182.028312 -36.675755) (xy 182.017352 -36.76358)
			(xy 181.998403 -36.850033) (xy 181.971625 -36.93439) (xy 181.93724 -37.015944) (xy 181.895539 -37.094009)
			(xy 181.87162 -37.131244) (xy 181.863238 -37.143944) (xy 181.863238 -37.159184) (xy 181.863633 -37.169209)
			(xy 181.871305 -37.187733) (xy 181.885486 -37.201907) (xy 181.904013 -37.209571) (xy 181.914038 -37.209984)
			(xy 181.992016 -37.209984) (xy 182.035455 -37.21041) (xy 182.121963 -37.218428) (xy 182.207363 -37.234393)
			(xy 182.290925 -37.25817) (xy 182.371936 -37.289555) (xy 182.449707 -37.328281) (xy 182.523572 -37.374018)
			(xy 182.592902 -37.426375) (xy 182.646416 -37.47516) (xy 185.859164 -37.47516) (xy 185.863235 -37.419538)
			(xy 185.875361 -37.365101) (xy 185.895284 -37.31301) (xy 185.92258 -37.264375) (xy 185.956666 -37.220232)
			(xy 185.996815 -37.181523) (xy 186.042173 -37.149072) (xy 186.091773 -37.123571) (xy 186.144557 -37.105564)
			(xy 186.1994 -37.095434) (xy 186.255134 -37.093397) (xy 186.310571 -37.099497) (xy 186.364528 -37.113603)
			(xy 186.415857 -37.135415) (xy 186.463463 -37.164469) (xy 186.506331 -37.200144) (xy 186.507182 -37.201094)
			(xy 189.816484 -37.201094) (xy 189.820555 -37.145472) (xy 189.832681 -37.091035) (xy 189.852604 -37.038944)
			(xy 189.8799 -36.990309) (xy 189.913986 -36.946166) (xy 189.954135 -36.907457) (xy 189.999493 -36.875006)
			(xy 190.049093 -36.849505) (xy 190.101877 -36.831498) (xy 190.15672 -36.821368) (xy 190.212454 -36.819331)
			(xy 190.267891 -36.825431) (xy 190.321848 -36.839537) (xy 190.373177 -36.861349) (xy 190.420783 -36.890403)
			(xy 190.463651 -36.926078) (xy 190.500868 -36.967615) (xy 190.531641 -37.014128) (xy 190.555313 -37.064625)
			(xy 190.571381 -37.118032) (xy 190.579501 -37.173208) (xy 190.58001 -37.201094) (xy 190.579501 -37.22898)
			(xy 190.571381 -37.284156) (xy 190.555313 -37.337563) (xy 190.531641 -37.38806) (xy 190.500868 -37.434573)
			(xy 190.463651 -37.47611) (xy 190.420783 -37.511785) (xy 190.373177 -37.540839) (xy 190.321848 -37.562651)
			(xy 190.267891 -37.576757) (xy 190.212454 -37.582857) (xy 190.15672 -37.58082) (xy 190.101877 -37.57069)
			(xy 190.049093 -37.552683) (xy 189.999493 -37.527182) (xy 189.954135 -37.494731) (xy 189.913986 -37.456022)
			(xy 189.8799 -37.411879) (xy 189.852604 -37.363244) (xy 189.832681 -37.311153) (xy 189.820555 -37.256716)
			(xy 189.816484 -37.201094) (xy 186.507182 -37.201094) (xy 186.543548 -37.241681) (xy 186.574321 -37.288194)
			(xy 186.597993 -37.338691) (xy 186.614061 -37.392098) (xy 186.622181 -37.447274) (xy 186.62269 -37.47516)
			(xy 186.622181 -37.503046) (xy 186.614061 -37.558222) (xy 186.597993 -37.611629) (xy 186.574321 -37.662126)
			(xy 186.554341 -37.692326) (xy 187.97319 -37.692326) (xy 187.97319 -37.63239) (xy 187.981013 -37.572968)
			(xy 187.996526 -37.515075) (xy 188.019462 -37.459702) (xy 188.049429 -37.407796) (xy 188.085916 -37.360246)
			(xy 188.128296 -37.317866) (xy 188.175846 -37.281379) (xy 188.227752 -37.251412) (xy 188.283125 -37.228476)
			(xy 188.341018 -37.212963) (xy 188.40044 -37.20514) (xy 188.460376 -37.20514) (xy 188.519798 -37.212963)
			(xy 188.577691 -37.228476) (xy 188.633064 -37.251412) (xy 188.68497 -37.281379) (xy 188.73252 -37.317866)
			(xy 188.7749 -37.360246) (xy 188.811387 -37.407796) (xy 188.841354 -37.459702) (xy 188.86429 -37.515075)
			(xy 188.879803 -37.572968) (xy 188.887626 -37.63239) (xy 188.888116 -37.662358) (xy 188.887626 -37.692326)
			(xy 188.879803 -37.751748) (xy 188.86429 -37.809641) (xy 188.841354 -37.865014) (xy 188.811387 -37.91692)
			(xy 188.7749 -37.96447) (xy 188.73252 -38.00685) (xy 188.68497 -38.043337) (xy 188.633064 -38.073304)
			(xy 188.577691 -38.09624) (xy 188.519798 -38.111753) (xy 188.460376 -38.119576) (xy 188.40044 -38.119576)
			(xy 188.341018 -38.111753) (xy 188.283125 -38.09624) (xy 188.227752 -38.073304) (xy 188.175846 -38.043337)
			(xy 188.128296 -38.00685) (xy 188.085916 -37.96447) (xy 188.049429 -37.91692) (xy 188.019462 -37.865014)
			(xy 187.996526 -37.809641) (xy 187.981013 -37.751748) (xy 187.97319 -37.692326) (xy 186.554341 -37.692326)
			(xy 186.543548 -37.708639) (xy 186.506331 -37.750176) (xy 186.463463 -37.785851) (xy 186.415857 -37.814905)
			(xy 186.364528 -37.836717) (xy 186.310571 -37.850823) (xy 186.255134 -37.856923) (xy 186.1994 -37.854886)
			(xy 186.144557 -37.844756) (xy 186.091773 -37.826749) (xy 186.042173 -37.801248) (xy 185.996815 -37.768797)
			(xy 185.956666 -37.730088) (xy 185.92258 -37.685945) (xy 185.895284 -37.63731) (xy 185.875361 -37.585219)
			(xy 185.863235 -37.530782) (xy 185.859164 -37.47516) (xy 182.646416 -37.47516) (xy 182.657106 -37.484905)
			(xy 182.715635 -37.54911) (xy 182.767991 -37.618441) (xy 182.813726 -37.692307) (xy 182.852451 -37.770078)
			(xy 182.883835 -37.85109) (xy 182.907611 -37.934653) (xy 182.923574 -38.020052) (xy 182.93159 -38.106561)
			(xy 182.93159 -38.193439) (xy 182.923574 -38.279948) (xy 182.907611 -38.365347) (xy 182.883835 -38.44891)
			(xy 182.867467 -38.49116) (xy 185.859164 -38.49116) (xy 185.863235 -38.435538) (xy 185.875361 -38.381101)
			(xy 185.895284 -38.32901) (xy 185.92258 -38.280375) (xy 185.956666 -38.236232) (xy 185.996815 -38.197523)
			(xy 186.042173 -38.165072) (xy 186.091773 -38.139571) (xy 186.144557 -38.121564) (xy 186.1994 -38.111434)
			(xy 186.255134 -38.109397) (xy 186.310571 -38.115497) (xy 186.364528 -38.129603) (xy 186.415857 -38.151415)
			(xy 186.463463 -38.180469) (xy 186.506331 -38.216144) (xy 186.543548 -38.257681) (xy 186.574321 -38.304194)
			(xy 186.597993 -38.354691) (xy 186.614061 -38.408098) (xy 186.622181 -38.463274) (xy 186.62269 -38.49116)
			(xy 186.622181 -38.519046) (xy 186.614061 -38.574222) (xy 186.597993 -38.627629) (xy 186.574321 -38.678126)
			(xy 186.559043 -38.701218) (xy 189.537592 -38.701218) (xy 189.541663 -38.645596) (xy 189.553789 -38.591159)
			(xy 189.573712 -38.539068) (xy 189.601008 -38.490433) (xy 189.635094 -38.44629) (xy 189.675243 -38.407581)
			(xy 189.720601 -38.37513) (xy 189.770201 -38.349629) (xy 189.822985 -38.331622) (xy 189.877828 -38.321492)
			(xy 189.933562 -38.319455) (xy 189.988999 -38.325555) (xy 190.042956 -38.339661) (xy 190.094285 -38.361473)
			(xy 190.141891 -38.390527) (xy 190.184759 -38.426202) (xy 190.221976 -38.467739) (xy 190.252749 -38.514252)
			(xy 190.276421 -38.564749) (xy 190.292489 -38.618156) (xy 190.300609 -38.673332) (xy 190.301118 -38.701218)
			(xy 190.300609 -38.729104) (xy 190.292489 -38.78428) (xy 190.276421 -38.837687) (xy 190.252749 -38.888184)
			(xy 190.221976 -38.934697) (xy 190.184759 -38.976234) (xy 190.141891 -39.011909) (xy 190.094285 -39.040963)
			(xy 190.042956 -39.062775) (xy 189.988999 -39.076881) (xy 189.933562 -39.082981) (xy 189.877828 -39.080944)
			(xy 189.822985 -39.070814) (xy 189.770201 -39.052807) (xy 189.720601 -39.027306) (xy 189.675243 -38.994855)
			(xy 189.635094 -38.956146) (xy 189.601008 -38.912003) (xy 189.573712 -38.863368) (xy 189.553789 -38.811277)
			(xy 189.541663 -38.75684) (xy 189.537592 -38.701218) (xy 186.559043 -38.701218) (xy 186.543548 -38.724639)
			(xy 186.506331 -38.766176) (xy 186.463463 -38.801851) (xy 186.415857 -38.830905) (xy 186.364528 -38.852717)
			(xy 186.310571 -38.866823) (xy 186.255134 -38.872923) (xy 186.1994 -38.870886) (xy 186.144557 -38.860756)
			(xy 186.091773 -38.842749) (xy 186.042173 -38.817248) (xy 185.996815 -38.784797) (xy 185.956666 -38.746088)
			(xy 185.92258 -38.701945) (xy 185.895284 -38.65331) (xy 185.875361 -38.601219) (xy 185.863235 -38.546782)
			(xy 185.859164 -38.49116) (xy 182.867467 -38.49116) (xy 182.852451 -38.529922) (xy 182.813726 -38.607693)
			(xy 182.767991 -38.681559) (xy 182.715635 -38.75089) (xy 182.657106 -38.815095) (xy 182.592902 -38.873625)
			(xy 182.523572 -38.925982) (xy 182.449707 -38.971719) (xy 182.371936 -39.010445) (xy 182.290925 -39.04183)
			(xy 182.207363 -39.065607) (xy 182.121963 -39.081572) (xy 182.035455 -39.08959) (xy 181.992016 -39.090092)
			(xy 180.137816 -39.090092) (xy 180.094378 -39.08953) (xy 180.007874 -39.081516) (xy 179.922478 -39.065554)
			(xy 179.838919 -39.04178) (xy 179.75791 -39.010399) (xy 179.680142 -38.971676) (xy 179.606279 -38.925943)
			(xy 179.53695 -38.87359) (xy 179.472748 -38.815063) (xy 179.414221 -38.750862) (xy 179.361866 -38.681534)
			(xy 179.316132 -38.607672) (xy 179.277408 -38.529905) (xy 179.246025 -38.448896) (xy 179.22225 -38.365338)
			(xy 179.206287 -38.279942) (xy 179.198271 -38.193438) (xy 178.243484 -38.193438) (xy 178.243484 -42.849038)
			(xy 188.992 -42.849038) (xy 188.996071 -42.793416) (xy 189.008197 -42.738979) (xy 189.02812 -42.686888)
			(xy 189.055416 -42.638253) (xy 189.089502 -42.59411) (xy 189.129651 -42.555401) (xy 189.175009 -42.52295)
			(xy 189.224609 -42.497449) (xy 189.277393 -42.479442) (xy 189.332236 -42.469312) (xy 189.38797 -42.467275)
			(xy 189.443407 -42.473375) (xy 189.497364 -42.487481) (xy 189.548693 -42.509293) (xy 189.596299 -42.538347)
			(xy 189.639167 -42.574022) (xy 189.676384 -42.615559) (xy 189.707157 -42.662072) (xy 189.730829 -42.712569)
			(xy 189.746897 -42.765976) (xy 189.755017 -42.821152) (xy 189.755526 -42.849038) (xy 189.755017 -42.876924)
			(xy 189.746897 -42.9321) (xy 189.730829 -42.985507) (xy 189.707157 -43.036004) (xy 189.676384 -43.082517)
			(xy 189.639167 -43.124054) (xy 189.596299 -43.159729) (xy 189.548693 -43.188783) (xy 189.497364 -43.210595)
			(xy 189.443407 -43.224701) (xy 189.38797 -43.230801) (xy 189.332236 -43.228764) (xy 189.277393 -43.218634)
			(xy 189.224609 -43.200627) (xy 189.175009 -43.175126) (xy 189.129651 -43.142675) (xy 189.089502 -43.103966)
			(xy 189.055416 -43.059823) (xy 189.02812 -43.011188) (xy 189.008197 -42.959097) (xy 188.996071 -42.90466)
			(xy 188.992 -42.849038) (xy 178.243484 -42.849038) (xy 178.243484 -43.766228) (xy 188.237858 -43.766228)
			(xy 188.237858 -43.706292) (xy 188.245681 -43.64687) (xy 188.261194 -43.588977) (xy 188.28413 -43.533604)
			(xy 188.314097 -43.481698) (xy 188.350584 -43.434148) (xy 188.392964 -43.391768) (xy 188.440514 -43.355281)
			(xy 188.49242 -43.325314) (xy 188.547793 -43.302378) (xy 188.605686 -43.286865) (xy 188.665108 -43.279042)
			(xy 188.725044 -43.279042) (xy 188.784466 -43.286865) (xy 188.842359 -43.302378) (xy 188.897732 -43.325314)
			(xy 188.949638 -43.355281) (xy 188.997188 -43.391768) (xy 189.039568 -43.434148) (xy 189.076055 -43.481698)
			(xy 189.106022 -43.533604) (xy 189.128958 -43.588977) (xy 189.144471 -43.64687) (xy 189.152294 -43.706292)
			(xy 189.152784 -43.73626) (xy 189.152294 -43.766228) (xy 189.144471 -43.82565) (xy 189.128958 -43.883543)
			(xy 189.106022 -43.938916) (xy 189.076055 -43.990822) (xy 189.039568 -44.038372) (xy 188.997188 -44.080752)
			(xy 188.949638 -44.117239) (xy 188.897732 -44.147206) (xy 188.842359 -44.170142) (xy 188.784466 -44.185655)
			(xy 188.725044 -44.193478) (xy 188.665108 -44.193478) (xy 188.605686 -44.185655) (xy 188.547793 -44.170142)
			(xy 188.49242 -44.147206) (xy 188.440514 -44.117239) (xy 188.392964 -44.080752) (xy 188.350584 -44.038372)
			(xy 188.314097 -43.990822) (xy 188.28413 -43.938916) (xy 188.261194 -43.883543) (xy 188.245681 -43.82565)
			(xy 188.237858 -43.766228) (xy 178.243484 -43.766228) (xy 178.243484 -43.847512) (xy 178.243943 -43.85739)
			(xy 178.251383 -43.875691) (xy 178.257962 -43.883072) (xy 178.258216 -43.883326) (xy 178.736244 -44.361354)
			(xy 178.736752 -44.361862) (xy 178.744134 -44.368443) (xy 178.762432 -44.375893) (xy 178.772312 -44.37634)
		)
		(stroke
			(width 0)
			(type solid)
		)
		(fill yes)
		(layer "B.Cu")
		(net "P12V_SSD6")
	)
	(gr_poly
		(pts
			(xy 252.422406 -44.252642) (xy 252.431388 -44.251848) (xy 252.447962 -44.244776) (xy 252.461036 -44.232376)
			(xy 252.465332 -44.224448) (xy 252.467364 -44.219876) (xy 252.506988 -44.116752) (xy 252.499622 -44.086272)
			(xy 252.487938 -44.075604) (xy 252.464666 -44.05382) (xy 252.423777 -44.004919) (xy 252.390077 -43.950813)
			(xy 252.364217 -43.89255) (xy 252.346701 -43.83126) (xy 252.337867 -43.768132) (xy 252.337316 -43.73626)
			(xy 252.337806 -43.706292) (xy 252.345629 -43.64687) (xy 252.361142 -43.588977) (xy 252.384078 -43.533604)
			(xy 252.414045 -43.481698) (xy 252.450532 -43.434148) (xy 252.492912 -43.391768) (xy 252.540462 -43.355281)
			(xy 252.592368 -43.325314) (xy 252.647741 -43.302378) (xy 252.705634 -43.286865) (xy 252.765056 -43.279042)
			(xy 252.824992 -43.279042) (xy 252.884414 -43.286865) (xy 252.942307 -43.302378) (xy 252.99768 -43.325314)
			(xy 253.049586 -43.355281) (xy 253.097136 -43.391768) (xy 253.139516 -43.434148) (xy 253.176003 -43.481698)
			(xy 253.20597 -43.533604) (xy 253.228906 -43.588977) (xy 253.244419 -43.64687) (xy 253.252242 -43.706292)
			(xy 253.252732 -43.73626) (xy 253.252177 -43.76813) (xy 253.243325 -43.831254) (xy 253.225801 -43.892538)
			(xy 253.199942 -43.950798) (xy 253.166251 -44.004907) (xy 253.125378 -44.053818) (xy 253.10211 -44.075604)
			(xy 253.090426 -44.086272) (xy 253.08306 -44.116752) (xy 253.122684 -44.219876) (xy 253.124716 -44.224448)
			(xy 253.129052 -44.232338) (xy 253.142143 -44.244681) (xy 253.15868 -44.251771) (xy 253.167642 -44.252642)
			(xy 253.170182 -44.252642) (xy 254.08382 -44.252642) (xy 254.093698 -44.252183) (xy 254.112 -44.244744)
			(xy 254.11938 -44.238164) (xy 254.119634 -44.23791) (xy 254.678942 -43.678602) (xy 254.67945 -43.678094)
			(xy 254.68604 -43.670715) (xy 254.693508 -43.652417) (xy 254.693928 -43.642534) (xy 254.693928 -37.58438)
			(xy 254.693764 -37.578369) (xy 254.690948 -37.566683) (xy 254.68834 -37.561266) (xy 254.684329 -37.554164)
			(xy 254.672667 -37.542772) (xy 254.66548 -37.538914) (xy 254.570738 -37.492178) (xy 254.542036 -37.494972)
			(xy 254.530606 -37.503862) (xy 254.510557 -37.51875) (xy 254.467307 -37.543713) (xy 254.421168 -37.562818)
			(xy 254.37293 -37.575736) (xy 254.323419 -37.582248) (xy 254.29845 -37.582602) (xy 254.271202 -37.582113)
			(xy 254.21726 -37.574351) (xy 254.164972 -37.558991) (xy 254.115402 -37.536348) (xy 254.069559 -37.506881)
			(xy 254.028375 -37.47119) (xy 253.992689 -37.430001) (xy 253.963228 -37.384154) (xy 253.940591 -37.334581)
			(xy 253.925239 -37.282291) (xy 253.917484 -37.228349) (xy 253.917484 -37.173851) (xy 253.925239 -37.119909)
			(xy 253.940591 -37.067619) (xy 253.963228 -37.018046) (xy 253.992689 -36.972199) (xy 254.028375 -36.93101)
			(xy 254.069559 -36.895319) (xy 254.115402 -36.865852) (xy 254.164972 -36.843209) (xy 254.21726 -36.827849)
			(xy 254.271202 -36.820087) (xy 254.29845 -36.819586) (xy 254.323415 -36.819996) (xy 254.372919 -36.826513)
			(xy 254.42115 -36.839429) (xy 254.467286 -36.858523) (xy 254.510538 -36.88347) (xy 254.530606 -36.898326)
			(xy 254.542036 -36.906962) (xy 254.570992 -36.91001) (xy 254.66548 -36.863274) (xy 254.672672 -36.859424)
			(xy 254.684334 -36.848028) (xy 254.68834 -36.840922) (xy 254.693928 -36.83) (xy 254.693928 -35.11169)
			(xy 254.674878 -35.085274) (xy 254.659384 -35.07994) (xy 254.632317 -35.070279) (xy 254.581217 -35.04398)
			(xy 254.534644 -35.010309) (xy 254.493652 -34.970029) (xy 254.475996 -34.947352) (xy 254.470662 -34.94024)
			(xy 254.44831 -34.925254) (xy 254.44436 -34.922819) (xy 254.435802 -34.919234) (xy 254.431292 -34.918142)
			(xy 254.401066 -34.911284) (xy 254.38227 -34.914078) (xy 254.373888 -34.91865) (xy 254.355506 -34.928876)
			(xy 254.317218 -34.946302) (xy 254.297434 -34.953448) (xy 254.273233 -34.96149) (xy 254.223499 -34.97278)
			(xy 254.172819 -34.978478) (xy 254.14732 -34.978848) (xy 254.12182 -34.978488) (xy 254.071138 -34.972796)
			(xy 254.021403 -34.961504) (xy 253.997206 -34.953448) (xy 253.977421 -34.946304) (xy 253.939132 -34.92888)
			(xy 253.920752 -34.91865) (xy 253.91237 -34.914078) (xy 253.893574 -34.911284) (xy 253.863348 -34.918142)
			(xy 253.858828 -34.919206) (xy 253.850262 -34.922785) (xy 253.84633 -34.925254) (xy 253.823978 -34.94024)
			(xy 253.818898 -34.947352) (xy 253.800748 -34.970654) (xy 253.75847 -35.011898) (xy 253.710339 -35.04613)
			(xy 253.657506 -35.072532) (xy 253.601234 -35.090473) (xy 253.542868 -35.099524) (xy 253.513336 -35.100006)
			(xy 253.502414 -35.100006) (xy 253.50216 -35.099752) (xy 253.475445 -35.098515) (xy 253.422732 -35.089492)
			(xy 253.371796 -35.073198) (xy 253.323633 -35.049952) (xy 253.279187 -35.020208) (xy 253.23933 -34.984551)
			(xy 253.204841 -34.943679) (xy 253.176396 -34.898391) (xy 253.154553 -34.849576) (xy 253.13974 -34.798189)
			(xy 253.132246 -34.745238) (xy 253.131828 -34.718498) (xy 253.132291 -34.691246) (xy 253.140049 -34.637297)
			(xy 253.155405 -34.585002) (xy 253.178049 -34.535424) (xy 253.207517 -34.489574) (xy 253.243211 -34.448384)
			(xy 253.284404 -34.412694) (xy 253.330258 -34.38323) (xy 253.379837 -34.360592) (xy 253.432135 -34.345241)
			(xy 253.486084 -34.337489) (xy 253.513336 -34.33699) (xy 253.528129 -34.337133) (xy 253.557626 -34.339422)
			(xy 253.572264 -34.341562) (xy 253.583186 -34.34334) (xy 253.604522 -34.337244) (xy 253.671578 -34.280094)
			(xy 253.679727 -34.27251) (xy 253.689106 -34.25235) (xy 253.689612 -34.241232) (xy 253.689612 -33.93694)
			(xy 253.689047 -33.925833) (xy 253.679694 -33.905682) (xy 253.671578 -33.898078) (xy 253.604522 -33.840928)
			(xy 253.583186 -33.834832) (xy 253.572264 -33.83661) (xy 253.557438 -33.838784) (xy 253.527558 -33.841076)
			(xy 253.512574 -33.841182) (xy 253.51232 -33.841182) (xy 253.485115 -33.840629) (xy 253.431275 -33.832759)
			(xy 253.379099 -33.817319) (xy 253.329647 -33.794622) (xy 253.283921 -33.765129) (xy 253.24285 -33.729437)
			(xy 253.207267 -33.688272) (xy 253.177895 -33.642469) (xy 253.155328 -33.592957) (xy 253.140026 -33.540741)
			(xy 253.132298 -33.48688) (xy 253.131828 -33.459674) (xy 253.132293 -33.432423) (xy 253.140053 -33.378477)
			(xy 253.155412 -33.326184) (xy 253.178056 -33.27661) (xy 253.207526 -33.230763) (xy 253.24322 -33.189576)
			(xy 253.284412 -33.153889) (xy 253.330264 -33.124427) (xy 253.379843 -33.10179) (xy 253.432138 -33.08644)
			(xy 253.486085 -33.078689) (xy 253.513336 -33.078166) (xy 253.51359 -33.078166) (xy 253.543095 -33.078723)
			(xy 253.6014 -33.087818) (xy 253.657611 -33.105776) (xy 253.710388 -33.132171) (xy 253.758476 -33.166372)
			(xy 253.800727 -33.207567) (xy 253.818898 -33.23082) (xy 253.823978 -33.237932) (xy 253.84633 -33.252918)
			(xy 253.850281 -33.255351) (xy 253.85884 -33.258931) (xy 253.863348 -33.26003) (xy 253.893574 -33.266888)
			(xy 253.91237 -33.264094) (xy 253.920752 -33.259522) (xy 253.939133 -33.249295) (xy 253.97742 -33.231865)
			(xy 253.997206 -33.224724) (xy 254.021406 -33.216679) (xy 254.07114 -33.205384) (xy 254.12182 -33.199679)
			(xy 254.14732 -33.199324) (xy 254.17282 -33.199686) (xy 254.223501 -33.205382) (xy 254.273234 -33.216677)
			(xy 254.297434 -33.224724) (xy 254.317218 -33.231869) (xy 254.355507 -33.249295) (xy 254.373888 -33.259522)
			(xy 254.38227 -33.264094) (xy 254.401066 -33.266888) (xy 254.431292 -33.26003) (xy 254.435814 -33.258971)
			(xy 254.444385 -33.255399) (xy 254.44831 -33.252918) (xy 254.470662 -33.237932) (xy 254.475996 -33.23082)
			(xy 254.493657 -33.208147) (xy 254.53465 -33.16787) (xy 254.581221 -33.134195) (xy 254.632315 -33.107886)
			(xy 254.659384 -33.098232) (xy 254.674878 -33.092898) (xy 254.693928 -33.066482) (xy 254.693928 -31.511494)
			(xy 254.674878 -31.485078) (xy 254.659384 -31.479744) (xy 254.632316 -31.470083) (xy 254.581217 -31.443784)
			(xy 254.534644 -31.410113) (xy 254.493651 -31.369833) (xy 254.475996 -31.347156) (xy 254.470662 -31.340044)
			(xy 254.44831 -31.325058) (xy 254.44436 -31.322623) (xy 254.435802 -31.319037) (xy 254.431292 -31.317946)
			(xy 254.401066 -31.311088) (xy 254.38227 -31.313882) (xy 254.373888 -31.318454) (xy 254.355506 -31.32868)
			(xy 254.317218 -31.346105) (xy 254.297434 -31.353252) (xy 254.273233 -31.361294) (xy 254.223499 -31.372584)
			(xy 254.172819 -31.378282) (xy 254.14732 -31.378652) (xy 254.12182 -31.378292) (xy 254.071138 -31.3726)
			(xy 254.021403 -31.361308) (xy 253.997206 -31.353252) (xy 253.977421 -31.346108) (xy 253.939132 -31.328685)
			(xy 253.920752 -31.318454) (xy 253.91237 -31.313882) (xy 253.893574 -31.311088) (xy 253.863348 -31.317946)
			(xy 253.858828 -31.31901) (xy 253.850262 -31.322589) (xy 253.84633 -31.325058) (xy 253.823978 -31.340044)
			(xy 253.818898 -31.347156) (xy 253.800748 -31.370458) (xy 253.75847 -31.411701) (xy 253.710339 -31.445933)
			(xy 253.657505 -31.472335) (xy 253.601233 -31.490276) (xy 253.542868 -31.499326) (xy 253.513336 -31.49981)
			(xy 253.502414 -31.49981) (xy 253.50216 -31.499556) (xy 253.475445 -31.498319) (xy 253.422732 -31.489296)
			(xy 253.371795 -31.473002) (xy 253.323632 -31.449756) (xy 253.279186 -31.420013) (xy 253.239328 -31.384356)
			(xy 253.204839 -31.343483) (xy 253.176394 -31.298196) (xy 253.154551 -31.24938) (xy 253.139737 -31.197993)
			(xy 253.132242 -31.145042) (xy 253.131828 -31.118302) (xy 253.132291 -31.09105) (xy 253.140048 -31.037101)
			(xy 253.155404 -30.984805) (xy 253.178047 -30.935227) (xy 253.207516 -30.889376) (xy 253.24321 -30.848186)
			(xy 253.284403 -30.812495) (xy 253.330257 -30.783031) (xy 253.379837 -30.760392) (xy 253.432134 -30.745041)
			(xy 253.486084 -30.737289) (xy 253.513336 -30.736794) (xy 253.528129 -30.736937) (xy 253.557626 -30.739226)
			(xy 253.572264 -30.741366) (xy 253.583186 -30.743144) (xy 253.604522 -30.737048) (xy 253.671578 -30.679898)
			(xy 253.679727 -30.672314) (xy 253.689108 -30.652154) (xy 253.689612 -30.641036) (xy 253.689612 -30.336744)
			(xy 253.689048 -30.325636) (xy 253.679696 -30.305484) (xy 253.671578 -30.297882) (xy 253.604522 -30.240732)
			(xy 253.583186 -30.234636) (xy 253.572264 -30.236414) (xy 253.557438 -30.238588) (xy 253.527558 -30.24088)
			(xy 253.512574 -30.240986) (xy 253.51232 -30.240986) (xy 253.485115 -30.240433) (xy 253.431275 -30.232563)
			(xy 253.379099 -30.217123) (xy 253.329646 -30.194426) (xy 253.28392 -30.164933) (xy 253.242849 -30.129242)
			(xy 253.207266 -30.088077) (xy 253.177893 -30.042274) (xy 253.155326 -29.992761) (xy 253.140023 -29.940545)
			(xy 253.132294 -29.886684) (xy 253.131828 -29.859478) (xy 253.132293 -29.832227) (xy 253.140053 -29.77828)
			(xy 253.155411 -29.725987) (xy 253.178055 -29.676412) (xy 253.207524 -29.630564) (xy 253.243218 -29.589377)
			(xy 253.284411 -29.553689) (xy 253.330263 -29.524227) (xy 253.379842 -29.501591) (xy 253.432137 -29.48624)
			(xy 253.486085 -29.478489) (xy 253.513336 -29.47797) (xy 253.51359 -29.47797) (xy 253.543095 -29.478527)
			(xy 253.6014 -29.487622) (xy 253.65761 -29.50558) (xy 253.710388 -29.531975) (xy 253.758475 -29.566177)
			(xy 253.800726 -29.607372) (xy 253.818898 -29.630624) (xy 253.823978 -29.637736) (xy 253.84633 -29.652722)
			(xy 253.850281 -29.655155) (xy 253.85884 -29.658735) (xy 253.863348 -29.659834) (xy 253.893574 -29.666692)
			(xy 253.91237 -29.663898) (xy 253.920752 -29.659326) (xy 253.939133 -29.649099) (xy 253.97742 -29.631669)
			(xy 253.997206 -29.624528) (xy 254.021406 -29.616483) (xy 254.07114 -29.605187) (xy 254.12182 -29.599483)
			(xy 254.14732 -29.599128) (xy 254.17282 -29.59949) (xy 254.223501 -29.605186) (xy 254.273234 -29.616481)
			(xy 254.297434 -29.624528) (xy 254.317218 -29.631673) (xy 254.355507 -29.649099) (xy 254.373888 -29.659326)
			(xy 254.38227 -29.663898) (xy 254.401066 -29.666692) (xy 254.431292 -29.659834) (xy 254.435814 -29.658775)
			(xy 254.444385 -29.655203) (xy 254.44831 -29.652722) (xy 254.470662 -29.637736) (xy 254.475996 -29.630624)
			(xy 254.493657 -29.607951) (xy 254.53465 -29.567673) (xy 254.58122 -29.533998) (xy 254.632314 -29.507689)
			(xy 254.659384 -29.498036) (xy 254.674878 -29.492702) (xy 254.693928 -29.466286) (xy 254.693928 -19.828002)
			(xy 254.693587 -19.819114) (xy 254.687495 -19.802414) (xy 254.676047 -19.788815) (xy 254.668528 -19.78406)
			(xy 254.643323 -19.768993) (xy 254.597455 -19.732329) (xy 254.557754 -19.689064) (xy 254.54102 -19.664934)
			(xy 254.534924 -19.656044) (xy 254.517398 -19.644614) (xy 254.433324 -19.631152) (xy 254.422961 -19.629979)
			(xy 254.402767 -19.635099) (xy 254.394208 -19.641058) (xy 254.37405 -19.656164) (xy 254.330517 -19.68151)
			(xy 254.284031 -19.700913) (xy 254.235398 -19.714038) (xy 254.185461 -19.720656) (xy 254.160274 -19.721068)
			(xy 254.152654 -19.721068) (xy 254.125758 -19.720074) (xy 254.072632 -19.711455) (xy 254.021245 -19.695455)
			(xy 253.972617 -19.67239) (xy 253.927714 -19.642719) (xy 253.887428 -19.60703) (xy 253.852558 -19.566033)
			(xy 253.823798 -19.520541) (xy 253.801717 -19.471459) (xy 253.786756 -19.419759) (xy 253.77921 -19.36647)
			(xy 253.778766 -19.33956) (xy 253.779254 -19.31231) (xy 253.787015 -19.258365) (xy 253.802374 -19.206074)
			(xy 253.825017 -19.1565) (xy 253.854484 -19.110653) (xy 253.890175 -19.069465) (xy 253.931364 -19.033775)
			(xy 253.977212 -19.00431) (xy 254.026787 -18.981669) (xy 254.079079 -18.966313) (xy 254.133024 -18.958553)
			(xy 254.160274 -18.958052) (xy 254.165862 -18.958052) (xy 254.18161 -18.958306) (xy 254.207264 -18.941542)
			(xy 254.249936 -18.84045) (xy 254.253477 -18.830963) (xy 254.253576 -18.810729) (xy 254.245876 -18.792017)
			(xy 254.239014 -18.78457) (xy 253.87427 -18.419826) (xy 253.867158 -18.41246) (xy 253.848362 -18.40484)
			(xy 242.13566 -18.40484) (xy 242.125594 -18.405272) (xy 242.107004 -18.413001) (xy 242.099592 -18.419826)
			(xy 241.765328 -18.75409) (xy 241.757962 -18.761202) (xy 241.750342 -18.779998) (xy 241.750342 -21.738336)
			(xy 243.616734 -21.738336) (xy 243.617236 -21.709597) (xy 243.625867 -21.652769) (xy 243.642923 -21.597879)
			(xy 243.668019 -21.546167) (xy 243.700586 -21.498805) (xy 243.719858 -21.477478) (xy 243.726462 -21.470366)
			(xy 243.733574 -21.45284) (xy 243.733574 -21.363432) (xy 243.726462 -21.345906) (xy 243.719858 -21.338794)
			(xy 243.700621 -21.317437) (xy 243.668052 -21.270081) (xy 243.642956 -21.218374) (xy 243.625902 -21.163488)
			(xy 243.617275 -21.106664) (xy 243.617271 -21.049189) (xy 243.62589 -20.992364) (xy 243.642937 -20.937475)
			(xy 243.668026 -20.885765) (xy 243.700588 -20.838404) (xy 243.719858 -20.817078) (xy 243.726462 -20.809966)
			(xy 243.733574 -20.79244) (xy 243.733574 -20.703032) (xy 243.726462 -20.685506) (xy 243.719858 -20.678394)
			(xy 243.700621 -20.657037) (xy 243.668052 -20.609681) (xy 243.642956 -20.557974) (xy 243.625902 -20.503088)
			(xy 243.617275 -20.446264) (xy 243.617271 -20.388789) (xy 243.62589 -20.331964) (xy 243.642937 -20.277075)
			(xy 243.668026 -20.225365) (xy 243.700588 -20.178004) (xy 243.719858 -20.156678) (xy 243.726462 -20.149566)
			(xy 243.733574 -20.13204) (xy 243.733574 -20.042632) (xy 243.726462 -20.025106) (xy 243.719858 -20.017994)
			(xy 243.700621 -19.996637) (xy 243.668052 -19.949281) (xy 243.642956 -19.897574) (xy 243.625902 -19.842688)
			(xy 243.617275 -19.785864) (xy 243.617271 -19.728389) (xy 243.62589 -19.671564) (xy 243.642937 -19.616675)
			(xy 243.668026 -19.564965) (xy 243.700588 -19.517604) (xy 243.719858 -19.496278) (xy 243.726462 -19.489166)
			(xy 243.733574 -19.47164) (xy 243.733574 -19.382232) (xy 243.726462 -19.364706) (xy 243.719858 -19.357594)
			(xy 243.700608 -19.336249) (xy 243.668038 -19.288892) (xy 243.642941 -19.237185) (xy 243.625886 -19.182298)
			(xy 243.617258 -19.125474) (xy 243.616734 -19.096736) (xy 243.61722 -19.069485) (xy 243.624976 -19.015537)
			(xy 243.640331 -18.963242) (xy 243.662973 -18.913665) (xy 243.692439 -18.867815) (xy 243.72813 -18.826624)
			(xy 243.769321 -18.790933) (xy 243.815171 -18.761467) (xy 243.864748 -18.738825) (xy 243.917043 -18.72347)
			(xy 243.970991 -18.715714) (xy 244.025493 -18.715714) (xy 244.079441 -18.72347) (xy 244.131736 -18.738825)
			(xy 244.181313 -18.761467) (xy 244.227163 -18.790933) (xy 244.268354 -18.826624) (xy 244.304045 -18.867815)
			(xy 244.333511 -18.913665) (xy 244.356153 -18.963242) (xy 244.371508 -19.015537) (xy 244.379264 -19.069485)
			(xy 244.37975 -19.096736) (xy 244.379235 -19.125475) (xy 244.370608 -19.182302) (xy 244.353555 -19.237193)
			(xy 244.328462 -19.288904) (xy 244.295897 -19.336267) (xy 244.276626 -19.357594) (xy 244.270022 -19.364706)
			(xy 244.26291 -19.382232) (xy 244.26291 -19.47164) (xy 244.270022 -19.489166) (xy 244.276626 -19.496278)
			(xy 244.29593 -19.517575) (xy 244.32849 -19.564944) (xy 244.353576 -19.616661) (xy 244.370621 -19.671556)
			(xy 244.379239 -19.728386) (xy 244.379235 -19.785866) (xy 244.37061 -19.842696) (xy 244.353557 -19.897588)
			(xy 244.328464 -19.949302) (xy 244.295897 -19.996666) (xy 244.276626 -20.017994) (xy 244.270022 -20.025106)
			(xy 244.26291 -20.042632) (xy 244.26291 -20.13204) (xy 244.270022 -20.149566) (xy 244.276626 -20.156678)
			(xy 244.29593 -20.177975) (xy 244.32849 -20.225344) (xy 244.353576 -20.277061) (xy 244.370621 -20.331956)
			(xy 244.3742 -20.35556) (xy 253.778256 -20.35556) (xy 253.782327 -20.299938) (xy 253.794453 -20.245501)
			(xy 253.814376 -20.19341) (xy 253.841672 -20.144775) (xy 253.875758 -20.100632) (xy 253.915907 -20.061923)
			(xy 253.961265 -20.029472) (xy 254.010865 -20.003971) (xy 254.063649 -19.985964) (xy 254.118492 -19.975834)
			(xy 254.174226 -19.973797) (xy 254.229663 -19.979897) (xy 254.28362 -19.994003) (xy 254.334949 -20.015815)
			(xy 254.382555 -20.044869) (xy 254.425423 -20.080544) (xy 254.46264 -20.122081) (xy 254.493413 -20.168594)
			(xy 254.517085 -20.219091) (xy 254.533153 -20.272498) (xy 254.541273 -20.327674) (xy 254.541782 -20.35556)
			(xy 254.541273 -20.383446) (xy 254.533153 -20.438622) (xy 254.517085 -20.492029) (xy 254.493413 -20.542526)
			(xy 254.46264 -20.589039) (xy 254.425423 -20.630576) (xy 254.382555 -20.666251) (xy 254.334949 -20.695305)
			(xy 254.28362 -20.717117) (xy 254.229663 -20.731223) (xy 254.174226 -20.737323) (xy 254.118492 -20.735286)
			(xy 254.063649 -20.725156) (xy 254.010865 -20.707149) (xy 253.961265 -20.681648) (xy 253.915907 -20.649197)
			(xy 253.875758 -20.610488) (xy 253.841672 -20.566345) (xy 253.814376 -20.51771) (xy 253.794453 -20.465619)
			(xy 253.782327 -20.411182) (xy 253.778256 -20.35556) (xy 244.3742 -20.35556) (xy 244.379239 -20.388786)
			(xy 244.379235 -20.446266) (xy 244.37061 -20.503096) (xy 244.353557 -20.557988) (xy 244.328464 -20.609702)
			(xy 244.295897 -20.657066) (xy 244.276626 -20.678394) (xy 244.270022 -20.685506) (xy 244.26291 -20.703032)
			(xy 244.26291 -20.79244) (xy 244.270022 -20.809966) (xy 244.276626 -20.817078) (xy 244.29593 -20.838375)
			(xy 244.32849 -20.885744) (xy 244.353576 -20.937461) (xy 244.370621 -20.992356) (xy 244.379239 -21.049186)
			(xy 244.379235 -21.106666) (xy 244.37061 -21.163496) (xy 244.353557 -21.218388) (xy 244.328464 -21.270102)
			(xy 244.295897 -21.317466) (xy 244.276626 -21.338794) (xy 244.270022 -21.345906) (xy 244.26291 -21.363432)
			(xy 244.26291 -21.37156) (xy 253.778256 -21.37156) (xy 253.782327 -21.315938) (xy 253.794453 -21.261501)
			(xy 253.814376 -21.20941) (xy 253.841672 -21.160775) (xy 253.875758 -21.116632) (xy 253.915907 -21.077923)
			(xy 253.961265 -21.045472) (xy 254.010865 -21.019971) (xy 254.063649 -21.001964) (xy 254.118492 -20.991834)
			(xy 254.174226 -20.989797) (xy 254.229663 -20.995897) (xy 254.28362 -21.010003) (xy 254.334949 -21.031815)
			(xy 254.382555 -21.060869) (xy 254.425423 -21.096544) (xy 254.46264 -21.138081) (xy 254.493413 -21.184594)
			(xy 254.517085 -21.235091) (xy 254.533153 -21.288498) (xy 254.541273 -21.343674) (xy 254.541782 -21.37156)
			(xy 254.541273 -21.399446) (xy 254.533153 -21.454622) (xy 254.517085 -21.508029) (xy 254.493413 -21.558526)
			(xy 254.46264 -21.605039) (xy 254.425423 -21.646576) (xy 254.382555 -21.682251) (xy 254.334949 -21.711305)
			(xy 254.28362 -21.733117) (xy 254.229663 -21.747223) (xy 254.174226 -21.753323) (xy 254.118492 -21.751286)
			(xy 254.063649 -21.741156) (xy 254.010865 -21.723149) (xy 253.961265 -21.697648) (xy 253.915907 -21.665197)
			(xy 253.875758 -21.626488) (xy 253.841672 -21.582345) (xy 253.814376 -21.53371) (xy 253.794453 -21.481619)
			(xy 253.782327 -21.427182) (xy 253.778256 -21.37156) (xy 244.26291 -21.37156) (xy 244.26291 -21.45284)
			(xy 244.270022 -21.470366) (xy 244.276626 -21.477478) (xy 244.295908 -21.498796) (xy 244.328474 -21.54616)
			(xy 244.353565 -21.597873) (xy 244.370613 -21.652767) (xy 244.379232 -21.709596) (xy 244.37975 -21.738336)
			(xy 244.379264 -21.765587) (xy 244.371508 -21.819535) (xy 244.356153 -21.87183) (xy 244.333511 -21.921407)
			(xy 244.304045 -21.967257) (xy 244.268354 -22.008448) (xy 244.227163 -22.044139) (xy 244.181313 -22.073605)
			(xy 244.131736 -22.096247) (xy 244.079441 -22.111602) (xy 244.025493 -22.119358) (xy 243.970991 -22.119358)
			(xy 243.917043 -22.111602) (xy 243.864748 -22.096247) (xy 243.815171 -22.073605) (xy 243.769321 -22.044139)
			(xy 243.72813 -22.008448) (xy 243.692439 -21.967257) (xy 243.662973 -21.921407) (xy 243.640331 -21.87183)
			(xy 243.624976 -21.819535) (xy 243.61722 -21.765587) (xy 243.616734 -21.738336) (xy 241.750342 -21.738336)
			(xy 241.750342 -23.055063) (xy 243.487188 -23.055063) (xy 243.487188 -22.995129) (xy 243.495012 -22.935707)
			(xy 243.510524 -22.877815) (xy 243.533461 -22.822443) (xy 243.563428 -22.770539) (xy 243.599914 -22.72299)
			(xy 243.642295 -22.68061) (xy 243.689844 -22.644125) (xy 243.741749 -22.614158) (xy 243.797121 -22.591222)
			(xy 243.855013 -22.575711) (xy 243.914435 -22.567888) (xy 243.974369 -22.567888) (xy 244.033791 -22.575711)
			(xy 244.091683 -22.591224) (xy 244.147055 -22.61416) (xy 244.198959 -22.644127) (xy 244.246508 -22.680613)
			(xy 244.288888 -22.722993) (xy 244.325374 -22.770542) (xy 244.355341 -22.822447) (xy 244.378277 -22.877819)
			(xy 244.393789 -22.935711) (xy 244.401612 -22.995133) (xy 244.402102 -23.0251) (xy 244.401878 -23.045661)
			(xy 244.398189 -23.086618) (xy 244.394736 -23.106888) (xy 244.392196 -23.120604) (xy 244.401086 -23.145496)
			(xy 244.4877 -23.22068) (xy 244.513608 -23.226014) (xy 244.526816 -23.221696) (xy 244.556017 -23.212602)
			(xy 244.61638 -23.202782) (xy 244.646958 -23.202138) (xy 244.665885 -23.202399) (xy 244.703547 -23.206217)
			(xy 244.722142 -23.209758) (xy 244.734842 -23.212044) (xy 244.758464 -23.205186) (xy 244.83695 -23.128986)
			(xy 244.84457 -23.105618) (xy 244.842538 -23.092918) (xy 244.839478 -23.073888) (xy 244.836167 -23.035483)
			(xy 244.835934 -23.01621) (xy 244.836371 -22.986242) (xy 244.844193 -22.926819) (xy 244.859704 -22.868925)
			(xy 244.882639 -22.813551) (xy 244.912605 -22.761644) (xy 244.94909 -22.714093) (xy 244.99147 -22.671711)
			(xy 245.039019 -22.635222) (xy 245.090924 -22.605253) (xy 245.146296 -22.582314) (xy 245.204189 -22.566799)
			(xy 245.263611 -22.558973) (xy 245.323547 -22.558971) (xy 245.382971 -22.566791) (xy 245.440865 -22.582301)
			(xy 245.496239 -22.605234) (xy 245.548147 -22.635199) (xy 245.595699 -22.671683) (xy 245.638082 -22.714062)
			(xy 245.674572 -22.76161) (xy 245.704543 -22.813514) (xy 245.727483 -22.868886) (xy 245.742999 -22.926778)
			(xy 245.750826 -22.986201) (xy 245.75083 -23.046137) (xy 245.743011 -23.10556) (xy 245.727503 -23.163455)
			(xy 245.70457 -23.21883) (xy 245.674607 -23.270738) (xy 245.638124 -23.318291) (xy 245.595746 -23.360675)
			(xy 245.548199 -23.397166) (xy 245.496296 -23.427138) (xy 245.440924 -23.450079) (xy 245.383032 -23.465597)
			(xy 245.32361 -23.473425) (xy 245.293642 -23.473918) (xy 245.259397 -23.473312) (xy 245.191671 -23.463109)
			(xy 245.158768 -23.453598) (xy 245.146576 -23.449788) (xy 245.122446 -23.45436) (xy 245.036594 -23.522178)
			(xy 245.026688 -23.544784) (xy 245.027704 -23.557738) (xy 245.028466 -23.583646) (xy 245.02798 -23.610897)
			(xy 245.026676 -23.619964) (xy 248.20929 -23.619964) (xy 248.20929 -23.560028) (xy 248.217113 -23.500606)
			(xy 248.232626 -23.442713) (xy 248.255562 -23.38734) (xy 248.285529 -23.335434) (xy 248.322016 -23.287884)
			(xy 248.364396 -23.245504) (xy 248.411946 -23.209017) (xy 248.463852 -23.17905) (xy 248.519225 -23.156114)
			(xy 248.577118 -23.140601) (xy 248.63654 -23.132778) (xy 248.696476 -23.132778) (xy 248.755898 -23.140601)
			(xy 248.813791 -23.156114) (xy 248.869164 -23.17905) (xy 248.92107 -23.209017) (xy 248.96862 -23.245504)
			(xy 249.011 -23.287884) (xy 249.047487 -23.335434) (xy 249.077454 -23.38734) (xy 249.10039 -23.442713)
			(xy 249.115903 -23.500606) (xy 249.123726 -23.560028) (xy 249.124216 -23.589996) (xy 249.123726 -23.619964)
			(xy 249.115903 -23.679386) (xy 249.10039 -23.737279) (xy 249.077454 -23.792652) (xy 249.047487 -23.844558)
			(xy 249.020047 -23.880318) (xy 249.440698 -23.880318) (xy 249.444769 -23.824696) (xy 249.456895 -23.770259)
			(xy 249.476818 -23.718168) (xy 249.504114 -23.669533) (xy 249.5382 -23.62539) (xy 249.578349 -23.586681)
			(xy 249.623707 -23.55423) (xy 249.673307 -23.528729) (xy 249.726091 -23.510722) (xy 249.780934 -23.500592)
			(xy 249.836668 -23.498555) (xy 249.892105 -23.504655) (xy 249.946062 -23.518761) (xy 249.997391 -23.540573)
			(xy 250.044997 -23.569627) (xy 250.087865 -23.605302) (xy 250.125082 -23.646839) (xy 250.155855 -23.693352)
			(xy 250.179527 -23.743849) (xy 250.195595 -23.797256) (xy 250.203715 -23.852432) (xy 250.204224 -23.880318)
			(xy 250.456698 -23.880318) (xy 250.460769 -23.824696) (xy 250.472895 -23.770259) (xy 250.492818 -23.718168)
			(xy 250.520114 -23.669533) (xy 250.5542 -23.62539) (xy 250.594349 -23.586681) (xy 250.639707 -23.55423)
			(xy 250.689307 -23.528729) (xy 250.742091 -23.510722) (xy 250.796934 -23.500592) (xy 250.852668 -23.498555)
			(xy 250.908105 -23.504655) (xy 250.962062 -23.518761) (xy 251.013391 -23.540573) (xy 251.060997 -23.569627)
			(xy 251.103865 -23.605302) (xy 251.141082 -23.646839) (xy 251.171855 -23.693352) (xy 251.195527 -23.743849)
			(xy 251.211595 -23.797256) (xy 251.219715 -23.852432) (xy 251.220224 -23.880318) (xy 251.472698 -23.880318)
			(xy 251.476769 -23.824696) (xy 251.488895 -23.770259) (xy 251.508818 -23.718168) (xy 251.536114 -23.669533)
			(xy 251.5702 -23.62539) (xy 251.610349 -23.586681) (xy 251.655707 -23.55423) (xy 251.705307 -23.528729)
			(xy 251.758091 -23.510722) (xy 251.812934 -23.500592) (xy 251.868668 -23.498555) (xy 251.924105 -23.504655)
			(xy 251.978062 -23.518761) (xy 252.029391 -23.540573) (xy 252.076997 -23.569627) (xy 252.119865 -23.605302)
			(xy 252.157082 -23.646839) (xy 252.187855 -23.693352) (xy 252.211527 -23.743849) (xy 252.227595 -23.797256)
			(xy 252.235715 -23.852432) (xy 252.236224 -23.880318) (xy 252.490984 -23.880318) (xy 252.495055 -23.824696)
			(xy 252.507181 -23.770259) (xy 252.527104 -23.718168) (xy 252.5544 -23.669533) (xy 252.588486 -23.62539)
			(xy 252.628635 -23.586681) (xy 252.673993 -23.55423) (xy 252.723593 -23.528729) (xy 252.776377 -23.510722)
			(xy 252.83122 -23.500592) (xy 252.886954 -23.498555) (xy 252.942391 -23.504655) (xy 252.996348 -23.518761)
			(xy 253.047677 -23.540573) (xy 253.095283 -23.569627) (xy 253.138151 -23.605302) (xy 253.175368 -23.646839)
			(xy 253.206141 -23.693352) (xy 253.229813 -23.743849) (xy 253.245881 -23.797256) (xy 253.254001 -23.852432)
			(xy 253.25451 -23.880318) (xy 253.254001 -23.908204) (xy 253.245881 -23.96338) (xy 253.229813 -24.016787)
			(xy 253.206141 -24.067284) (xy 253.175368 -24.113797) (xy 253.138151 -24.155334) (xy 253.095283 -24.191009)
			(xy 253.047677 -24.220063) (xy 252.996348 -24.241875) (xy 252.942391 -24.255981) (xy 252.886954 -24.262081)
			(xy 252.83122 -24.260044) (xy 252.776377 -24.249914) (xy 252.723593 -24.231907) (xy 252.673993 -24.206406)
			(xy 252.628635 -24.173955) (xy 252.588486 -24.135246) (xy 252.5544 -24.091103) (xy 252.527104 -24.042468)
			(xy 252.507181 -23.990377) (xy 252.495055 -23.93594) (xy 252.490984 -23.880318) (xy 252.236224 -23.880318)
			(xy 252.235715 -23.908204) (xy 252.227595 -23.96338) (xy 252.211527 -24.016787) (xy 252.187855 -24.067284)
			(xy 252.157082 -24.113797) (xy 252.119865 -24.155334) (xy 252.076997 -24.191009) (xy 252.029391 -24.220063)
			(xy 251.978062 -24.241875) (xy 251.924105 -24.255981) (xy 251.868668 -24.262081) (xy 251.812934 -24.260044)
			(xy 251.758091 -24.249914) (xy 251.705307 -24.231907) (xy 251.655707 -24.206406) (xy 251.610349 -24.173955)
			(xy 251.5702 -24.135246) (xy 251.536114 -24.091103) (xy 251.508818 -24.042468) (xy 251.488895 -23.990377)
			(xy 251.476769 -23.93594) (xy 251.472698 -23.880318) (xy 251.220224 -23.880318) (xy 251.219715 -23.908204)
			(xy 251.211595 -23.96338) (xy 251.195527 -24.016787) (xy 251.171855 -24.067284) (xy 251.141082 -24.113797)
			(xy 251.103865 -24.155334) (xy 251.060997 -24.191009) (xy 251.013391 -24.220063) (xy 250.962062 -24.241875)
			(xy 250.908105 -24.255981) (xy 250.852668 -24.262081) (xy 250.796934 -24.260044) (xy 250.742091 -24.249914)
			(xy 250.689307 -24.231907) (xy 250.639707 -24.206406) (xy 250.594349 -24.173955) (xy 250.5542 -24.135246)
			(xy 250.520114 -24.091103) (xy 250.492818 -24.042468) (xy 250.472895 -23.990377) (xy 250.460769 -23.93594)
			(xy 250.456698 -23.880318) (xy 250.204224 -23.880318) (xy 250.203715 -23.908204) (xy 250.195595 -23.96338)
			(xy 250.179527 -24.016787) (xy 250.155855 -24.067284) (xy 250.125082 -24.113797) (xy 250.087865 -24.155334)
			(xy 250.044997 -24.191009) (xy 249.997391 -24.220063) (xy 249.946062 -24.241875) (xy 249.892105 -24.255981)
			(xy 249.836668 -24.262081) (xy 249.780934 -24.260044) (xy 249.726091 -24.249914) (xy 249.673307 -24.231907)
			(xy 249.623707 -24.206406) (xy 249.578349 -24.173955) (xy 249.5382 -24.135246) (xy 249.504114 -24.091103)
			(xy 249.476818 -24.042468) (xy 249.456895 -23.990377) (xy 249.444769 -23.93594) (xy 249.440698 -23.880318)
			(xy 249.020047 -23.880318) (xy 249.011 -23.892108) (xy 248.96862 -23.934488) (xy 248.92107 -23.970975)
			(xy 248.869164 -24.000942) (xy 248.813791 -24.023878) (xy 248.755898 -24.039391) (xy 248.696476 -24.047214)
			(xy 248.63654 -24.047214) (xy 248.577118 -24.039391) (xy 248.519225 -24.023878) (xy 248.463852 -24.000942)
			(xy 248.411946 -23.970975) (xy 248.364396 -23.934488) (xy 248.322016 -23.892108) (xy 248.285529 -23.844558)
			(xy 248.255562 -23.792652) (xy 248.232626 -23.737279) (xy 248.217113 -23.679386) (xy 248.20929 -23.619964)
			(xy 245.026676 -23.619964) (xy 245.020224 -23.664845) (xy 245.004869 -23.71714) (xy 244.982227 -23.766717)
			(xy 244.952761 -23.812567) (xy 244.91707 -23.853758) (xy 244.875879 -23.889449) (xy 244.830029 -23.918915)
			(xy 244.780452 -23.941557) (xy 244.728157 -23.956912) (xy 244.674209 -23.964668) (xy 244.619707 -23.964668)
			(xy 244.565759 -23.956912) (xy 244.513464 -23.941557) (xy 244.463887 -23.918915) (xy 244.418037 -23.889449)
			(xy 244.376846 -23.853758) (xy 244.341155 -23.812567) (xy 244.311689 -23.766717) (xy 244.289047 -23.71714)
			(xy 244.273692 -23.664845) (xy 244.265936 -23.610897) (xy 244.26545 -23.583646) (xy 244.267228 -23.548086)
			(xy 244.268498 -23.53437) (xy 244.257576 -23.51024) (xy 244.164612 -23.44293) (xy 244.138196 -23.439882)
			(xy 244.12575 -23.44547) (xy 244.09699 -23.45728) (xy 244.037085 -23.473919) (xy 243.97548 -23.482302)
			(xy 243.944394 -23.482808) (xy 243.914427 -23.482312) (xy 243.855005 -23.474488) (xy 243.797113 -23.458975)
			(xy 243.741742 -23.436038) (xy 243.689837 -23.406071) (xy 243.642289 -23.369584) (xy 243.599909 -23.327204)
			(xy 243.563424 -23.279654) (xy 243.533457 -23.227749) (xy 243.510522 -23.172377) (xy 243.49501 -23.114485)
			(xy 243.487188 -23.055063) (xy 241.750342 -23.055063) (xy 241.750342 -24.189944) (xy 243.498876 -24.189944)
			(xy 243.502947 -24.134322) (xy 243.515073 -24.079885) (xy 243.534996 -24.027794) (xy 243.562292 -23.979159)
			(xy 243.596378 -23.935016) (xy 243.636527 -23.896307) (xy 243.681885 -23.863856) (xy 243.731485 -23.838355)
			(xy 243.784269 -23.820348) (xy 243.839112 -23.810218) (xy 243.894846 -23.808181) (xy 243.950283 -23.814281)
			(xy 244.00424 -23.828387) (xy 244.055569 -23.850199) (xy 244.103175 -23.879253) (xy 244.146043 -23.914928)
			(xy 244.18326 -23.956465) (xy 244.214033 -24.002978) (xy 244.237705 -24.053475) (xy 244.253773 -24.106882)
			(xy 244.261893 -24.162058) (xy 244.262402 -24.189944) (xy 246.021858 -24.189944) (xy 246.025929 -24.134322)
			(xy 246.038055 -24.079885) (xy 246.057978 -24.027794) (xy 246.085274 -23.979159) (xy 246.11936 -23.935016)
			(xy 246.159509 -23.896307) (xy 246.204867 -23.863856) (xy 246.254467 -23.838355) (xy 246.307251 -23.820348)
			(xy 246.362094 -23.810218) (xy 246.417828 -23.808181) (xy 246.473265 -23.814281) (xy 246.527222 -23.828387)
			(xy 246.578551 -23.850199) (xy 246.626157 -23.879253) (xy 246.669025 -23.914928) (xy 246.706242 -23.956465)
			(xy 246.737015 -24.002978) (xy 246.760687 -24.053475) (xy 246.776755 -24.106882) (xy 246.784875 -24.162058)
			(xy 246.785384 -24.189944) (xy 246.784875 -24.21783) (xy 246.776755 -24.273006) (xy 246.760687 -24.326413)
			(xy 246.737015 -24.37691) (xy 246.706242 -24.423423) (xy 246.669025 -24.46496) (xy 246.626157 -24.500635)
			(xy 246.578551 -24.529689) (xy 246.527222 -24.551501) (xy 246.473265 -24.565607) (xy 246.417828 -24.571707)
			(xy 246.362094 -24.56967) (xy 246.307251 -24.55954) (xy 246.254467 -24.541533) (xy 246.204867 -24.516032)
			(xy 246.159509 -24.483581) (xy 246.11936 -24.444872) (xy 246.085274 -24.400729) (xy 246.057978 -24.352094)
			(xy 246.038055 -24.300003) (xy 246.025929 -24.245566) (xy 246.021858 -24.189944) (xy 244.262402 -24.189944)
			(xy 244.261893 -24.21783) (xy 244.253773 -24.273006) (xy 244.237705 -24.326413) (xy 244.214033 -24.37691)
			(xy 244.18326 -24.423423) (xy 244.146043 -24.46496) (xy 244.103175 -24.500635) (xy 244.055569 -24.529689)
			(xy 244.00424 -24.551501) (xy 243.950283 -24.565607) (xy 243.894846 -24.571707) (xy 243.839112 -24.56967)
			(xy 243.784269 -24.55954) (xy 243.731485 -24.541533) (xy 243.681885 -24.516032) (xy 243.636527 -24.483581)
			(xy 243.596378 -24.444872) (xy 243.562292 -24.400729) (xy 243.534996 -24.352094) (xy 243.515073 -24.300003)
			(xy 243.502947 -24.245566) (xy 243.498876 -24.189944) (xy 241.750342 -24.189944) (xy 241.750342 -25.390094)
			(xy 245.933468 -25.390094) (xy 245.933958 -25.360126) (xy 245.941781 -25.300704) (xy 245.957294 -25.242811)
			(xy 245.98023 -25.187438) (xy 246.010197 -25.135532) (xy 246.046684 -25.087982) (xy 246.089064 -25.045602)
			(xy 246.136614 -25.009115) (xy 246.18852 -24.979148) (xy 246.243893 -24.956212) (xy 246.301786 -24.940699)
			(xy 246.361208 -24.932876) (xy 246.421144 -24.932876) (xy 246.480566 -24.940699) (xy 246.538459 -24.956212)
			(xy 246.593832 -24.979148) (xy 246.645738 -25.009115) (xy 246.693288 -25.045602) (xy 246.735668 -25.087982)
			(xy 246.772155 -25.135532) (xy 246.802122 -25.187438) (xy 246.825058 -25.242811) (xy 246.840571 -25.300704)
			(xy 246.848394 -25.360126) (xy 246.848884 -25.390094) (xy 246.848456 -25.418879) (xy 246.841237 -25.475994)
			(xy 246.826913 -25.531753) (xy 246.805709 -25.585275) (xy 246.777961 -25.635716) (xy 246.744106 -25.682279)
			(xy 246.70468 -25.724228) (xy 246.682768 -25.7429) (xy 246.674386 -25.749758) (xy 246.664734 -25.769316)
			(xy 246.661432 -25.867106) (xy 246.66956 -25.887172) (xy 246.677688 -25.894792) (xy 246.696094 -25.912863)
			(xy 246.72833 -25.953132) (xy 246.754852 -25.997373) (xy 246.775178 -26.044781) (xy 246.788938 -26.094494)
			(xy 246.795881 -26.145607) (xy 246.796306 -26.171398) (xy 246.79582 -26.198649) (xy 246.788064 -26.252597)
			(xy 246.772709 -26.304892) (xy 246.750067 -26.354469) (xy 246.720601 -26.400319) (xy 246.68491 -26.44151)
			(xy 246.643719 -26.477201) (xy 246.597869 -26.506667) (xy 246.548292 -26.529309) (xy 246.495997 -26.544664)
			(xy 246.442049 -26.55242) (xy 246.387547 -26.55242) (xy 246.333599 -26.544664) (xy 246.281304 -26.529309)
			(xy 246.231727 -26.506667) (xy 246.185877 -26.477201) (xy 246.144686 -26.44151) (xy 246.108995 -26.400319)
			(xy 246.079529 -26.354469) (xy 246.056887 -26.304892) (xy 246.041532 -26.252597) (xy 246.033776 -26.198649)
			(xy 246.03329 -26.171398) (xy 246.03381 -26.142755) (xy 246.042407 -26.086117) (xy 246.059378 -26.031401)
			(xy 246.084341 -25.979839) (xy 246.116734 -25.93259) (xy 246.135906 -25.911302) (xy 246.143272 -25.903174)
			(xy 246.15013 -25.8826) (xy 246.140986 -25.785064) (xy 246.130318 -25.766268) (xy 246.121428 -25.759918)
			(xy 246.096886 -25.74136) (xy 246.052491 -25.69876) (xy 246.0142 -25.650599) (xy 245.982702 -25.597745)
			(xy 245.958565 -25.541149) (xy 245.942224 -25.48183) (xy 245.933973 -25.420858) (xy 245.933468 -25.390094)
			(xy 241.750342 -25.390094) (xy 241.750342 -25.506934) (xy 241.750824 -25.516898) (xy 241.758408 -25.535327)
			(xy 241.765074 -25.542748) (xy 241.822732 -25.600914) (xy 241.840766 -25.608534) (xy 241.85118 -25.608534)
			(xy 241.878322 -25.609175) (xy 241.932017 -25.617193) (xy 241.984033 -25.632743) (xy 242.033319 -25.655511)
			(xy 242.078879 -25.685036) (xy 242.119792 -25.720722) (xy 242.155233 -25.761848) (xy 242.184486 -25.807584)
			(xy 242.206958 -25.857005) (xy 242.222197 -25.909113) (xy 242.229894 -25.962855) (xy 242.229894 -25.990042)
			(xy 243.498876 -25.990042) (xy 243.502947 -25.93442) (xy 243.515073 -25.879983) (xy 243.534996 -25.827892)
			(xy 243.562292 -25.779257) (xy 243.596378 -25.735114) (xy 243.636527 -25.696405) (xy 243.681885 -25.663954)
			(xy 243.731485 -25.638453) (xy 243.784269 -25.620446) (xy 243.839112 -25.610316) (xy 243.894846 -25.608279)
			(xy 243.950283 -25.614379) (xy 244.00424 -25.628485) (xy 244.055569 -25.650297) (xy 244.103175 -25.679351)
			(xy 244.146043 -25.715026) (xy 244.18326 -25.756563) (xy 244.214033 -25.803076) (xy 244.237705 -25.853573)
			(xy 244.253773 -25.90698) (xy 244.261893 -25.962156) (xy 244.262402 -25.990042) (xy 244.261893 -26.017928)
			(xy 244.253773 -26.073104) (xy 244.237705 -26.126511) (xy 244.214033 -26.177008) (xy 244.18326 -26.223521)
			(xy 244.146043 -26.265058) (xy 244.103175 -26.300733) (xy 244.055569 -26.329787) (xy 244.00424 -26.351599)
			(xy 243.950283 -26.365705) (xy 243.894846 -26.371805) (xy 243.839112 -26.369768) (xy 243.784269 -26.359638)
			(xy 243.731485 -26.341631) (xy 243.681885 -26.31613) (xy 243.636527 -26.283679) (xy 243.596378 -26.24497)
			(xy 243.562292 -26.200827) (xy 243.534996 -26.152192) (xy 243.515073 -26.100101) (xy 243.502947 -26.045664)
			(xy 243.498876 -25.990042) (xy 242.229894 -25.990042) (xy 242.229894 -26.017145) (xy 242.222197 -26.070887)
			(xy 242.206958 -26.122995) (xy 242.184485 -26.172416) (xy 242.155233 -26.218152) (xy 242.119792 -26.259278)
			(xy 242.078878 -26.294964) (xy 242.033318 -26.32449) (xy 241.984032 -26.347257) (xy 241.932016 -26.362807)
			(xy 241.878321 -26.370825) (xy 241.85118 -26.37155) (xy 241.840766 -26.37155) (xy 241.822732 -26.37917)
			(xy 241.765074 -26.437336) (xy 241.758398 -26.444749) (xy 241.750833 -26.463185) (xy 241.750342 -26.47315)
			(xy 241.750342 -27.307032) (xy 241.750823 -27.316996) (xy 241.758407 -27.335425) (xy 241.765074 -27.342846)
			(xy 241.822732 -27.401012) (xy 241.840766 -27.408632) (xy 241.85118 -27.408632) (xy 241.878322 -27.409273)
			(xy 241.932017 -27.417291) (xy 241.984033 -27.432841) (xy 242.033319 -27.455609) (xy 242.07888 -27.485134)
			(xy 242.119794 -27.520821) (xy 242.155235 -27.561947) (xy 242.184487 -27.607683) (xy 242.20696 -27.657104)
			(xy 242.222199 -27.709213) (xy 242.229896 -27.762955) (xy 242.229896 -27.79014) (xy 243.562884 -27.79014)
			(xy 243.566955 -27.734518) (xy 243.579081 -27.680081) (xy 243.599004 -27.62799) (xy 243.6263 -27.579355)
			(xy 243.660386 -27.535212) (xy 243.700535 -27.496503) (xy 243.745893 -27.464052) (xy 243.795493 -27.438551)
			(xy 243.848277 -27.420544) (xy 243.90312 -27.410414) (xy 243.958854 -27.408377) (xy 244.014291 -27.414477)
			(xy 244.068248 -27.428583) (xy 244.119577 -27.450395) (xy 244.167183 -27.479449) (xy 244.210051 -27.515124)
			(xy 244.247268 -27.556661) (xy 244.278041 -27.603174) (xy 244.301713 -27.653671) (xy 244.317781 -27.707078)
			(xy 244.325901 -27.762254) (xy 244.32641 -27.79014) (xy 246.066816 -27.79014) (xy 246.070887 -27.734518)
			(xy 246.083013 -27.680081) (xy 246.102936 -27.62799) (xy 246.130232 -27.579355) (xy 246.164318 -27.535212)
			(xy 246.204467 -27.496503) (xy 246.249825 -27.464052) (xy 246.299425 -27.438551) (xy 246.352209 -27.420544)
			(xy 246.407052 -27.410414) (xy 246.462786 -27.408377) (xy 246.518223 -27.414477) (xy 246.57218 -27.428583)
			(xy 246.623509 -27.450395) (xy 246.671115 -27.479449) (xy 246.713983 -27.515124) (xy 246.7512 -27.556661)
			(xy 246.781973 -27.603174) (xy 246.805645 -27.653671) (xy 246.821713 -27.707078) (xy 246.829833 -27.762254)
			(xy 246.830342 -27.79014) (xy 246.829845 -27.817352) (xy 248.099795 -27.817352) (xy 248.099795 -27.762848)
			(xy 248.107552 -27.7089) (xy 248.122909 -27.656605) (xy 248.145551 -27.607028) (xy 248.175019 -27.561178)
			(xy 248.210713 -27.519989) (xy 248.251905 -27.484299) (xy 248.297758 -27.454835) (xy 248.347337 -27.432197)
			(xy 248.399633 -27.416845) (xy 248.453582 -27.409093) (xy 248.480834 -27.408632) (xy 248.506142 -27.40902)
			(xy 248.556314 -27.415696) (xy 248.605166 -27.428939) (xy 248.628662 -27.43835) (xy 248.636661 -27.441398)
			(xy 248.653737 -27.442481) (xy 248.670219 -27.437884) (xy 248.67743 -27.43327) (xy 248.70283 -27.41549)
			(xy 248.709706 -27.410203) (xy 248.719787 -27.396107) (xy 248.724588 -27.379456) (xy 248.72442 -27.370786)
			(xy 248.723404 -27.342846) (xy 248.723404 -26.479246) (xy 248.724166 -26.456894) (xy 248.724674 -26.444448)
			(xy 248.71426 -26.421842) (xy 248.62917 -26.355548) (xy 248.604786 -26.350976) (xy 248.592848 -26.354786)
			(xy 248.565513 -26.362635) (xy 248.509269 -26.371048) (xy 248.480834 -26.37155) (xy 248.453583 -26.371005)
			(xy 248.399634 -26.363253) (xy 248.347338 -26.347902) (xy 248.297759 -26.325263) (xy 248.251906 -26.2958)
			(xy 248.210714 -26.26011) (xy 248.175021 -26.218921) (xy 248.145553 -26.173071) (xy 248.12291 -26.123494)
			(xy 248.107554 -26.071199) (xy 248.099797 -26.017251) (xy 248.099797 -25.962749) (xy 248.107554 -25.908801)
			(xy 248.12291 -25.856506) (xy 248.145553 -25.806929) (xy 248.175021 -25.761079) (xy 248.210714 -25.71989)
			(xy 248.251906 -25.6842) (xy 248.297759 -25.654737) (xy 248.347338 -25.632098) (xy 248.399634 -25.616747)
			(xy 248.453583 -25.608995) (xy 248.480834 -25.608534) (xy 248.509787 -25.609045) (xy 248.567029 -25.617787)
			(xy 248.622293 -25.635079) (xy 248.674308 -25.660524) (xy 248.721881 -25.693539) (xy 248.763917 -25.733364)
			(xy 248.799452 -25.779084) (xy 248.827669 -25.82965) (xy 248.828566 -25.832054) (xy 250.388374 -25.832054)
			(xy 250.388831 -25.80545) (xy 250.396207 -25.752756) (xy 250.410838 -25.701599) (xy 250.432438 -25.652973)
			(xy 250.460589 -25.607822) (xy 250.494744 -25.567023) (xy 250.534239 -25.53137) (xy 250.556014 -25.516078)
			(xy 250.567489 -25.507738) (xy 250.58569 -25.485995) (xy 250.597205 -25.460083) (xy 250.601145 -25.432002)
			(xy 250.597206 -25.403922) (xy 250.585692 -25.378009) (xy 250.567492 -25.356265) (xy 250.556014 -25.34793)
			(xy 250.534243 -25.332636) (xy 250.494765 -25.296969) (xy 250.460623 -25.256165) (xy 250.432478 -25.211015)
			(xy 250.410876 -25.162393) (xy 250.396235 -25.111243) (xy 250.388839 -25.058556) (xy 250.388374 -25.031954)
			(xy 250.38886 -25.004703) (xy 250.396616 -24.950755) (xy 250.411971 -24.89846) (xy 250.434613 -24.848883)
			(xy 250.464079 -24.803033) (xy 250.49977 -24.761842) (xy 250.540961 -24.726151) (xy 250.586811 -24.696685)
			(xy 250.636388 -24.674043) (xy 250.688683 -24.658688) (xy 250.742631 -24.650932) (xy 250.797133 -24.650932)
			(xy 250.851081 -24.658688) (xy 250.903376 -24.674043) (xy 250.952953 -24.696685) (xy 250.998803 -24.726151)
			(xy 251.039994 -24.761842) (xy 251.063195 -24.788618) (xy 252.99338 -24.788618) (xy 252.99338 -24.728682)
			(xy 253.001203 -24.66926) (xy 253.016716 -24.611367) (xy 253.039652 -24.555994) (xy 253.069619 -24.504088)
			(xy 253.106106 -24.456538) (xy 253.148486 -24.414158) (xy 253.196036 -24.377671) (xy 253.247942 -24.347704)
			(xy 253.303315 -24.324768) (xy 253.361208 -24.309255) (xy 253.42063 -24.301432) (xy 253.480566 -24.301432)
			(xy 253.539988 -24.309255) (xy 253.597881 -24.324768) (xy 253.653254 -24.347704) (xy 253.70516 -24.377671)
			(xy 253.75271 -24.414158) (xy 253.79509 -24.456538) (xy 253.831577 -24.504088) (xy 253.861544 -24.555994)
			(xy 253.88448 -24.611367) (xy 253.899993 -24.66926) (xy 253.907816 -24.728682) (xy 253.908306 -24.75865)
			(xy 253.907816 -24.788618) (xy 253.899993 -24.84804) (xy 253.88448 -24.905933) (xy 253.861544 -24.961306)
			(xy 253.831577 -25.013212) (xy 253.79509 -25.060762) (xy 253.75271 -25.103142) (xy 253.70516 -25.139629)
			(xy 253.653254 -25.169596) (xy 253.597881 -25.192532) (xy 253.539988 -25.208045) (xy 253.480566 -25.215868)
			(xy 253.42063 -25.215868) (xy 253.361208 -25.208045) (xy 253.303315 -25.192532) (xy 253.247942 -25.169596)
			(xy 253.196036 -25.139629) (xy 253.148486 -25.103142) (xy 253.106106 -25.060762) (xy 253.069619 -25.013212)
			(xy 253.039652 -24.961306) (xy 253.016716 -24.905933) (xy 253.001203 -24.84804) (xy 252.99338 -24.788618)
			(xy 251.063195 -24.788618) (xy 251.075685 -24.803033) (xy 251.105151 -24.848883) (xy 251.127793 -24.89846)
			(xy 251.143148 -24.950755) (xy 251.150904 -25.004703) (xy 251.15139 -25.031954) (xy 251.150911 -25.058557)
			(xy 251.143535 -25.111249) (xy 251.128906 -25.162404) (xy 251.107309 -25.211029) (xy 251.079162 -25.25618)
			(xy 251.045012 -25.29698) (xy 251.005522 -25.332636) (xy 250.98375 -25.34793) (xy 250.972261 -25.356256)
			(xy 250.954049 -25.377999) (xy 250.942526 -25.403915) (xy 250.938584 -25.432002) (xy 250.942527 -25.460089)
			(xy 250.954051 -25.486005) (xy 250.972265 -25.507747) (xy 250.98375 -25.516078) (xy 251.005517 -25.531378)
			(xy 251.044996 -25.567043) (xy 251.07914 -25.607846) (xy 251.107286 -25.652995) (xy 251.128889 -25.701615)
			(xy 251.14353 -25.752765) (xy 251.150926 -25.805452) (xy 251.15139 -25.832054) (xy 251.150904 -25.859305)
			(xy 251.143148 -25.913253) (xy 251.127793 -25.965548) (xy 251.105151 -26.015125) (xy 251.075685 -26.060975)
			(xy 251.039994 -26.102166) (xy 250.998803 -26.137857) (xy 250.952953 -26.167323) (xy 250.903376 -26.189965)
			(xy 250.851081 -26.20532) (xy 250.797133 -26.213076) (xy 250.742631 -26.213076) (xy 250.688683 -26.20532)
			(xy 250.636388 -26.189965) (xy 250.586811 -26.167323) (xy 250.540961 -26.137857) (xy 250.49977 -26.102166)
			(xy 250.464079 -26.060975) (xy 250.434613 -26.015125) (xy 250.411971 -25.965548) (xy 250.396616 -25.913253)
			(xy 250.38886 -25.859305) (xy 250.388374 -25.832054) (xy 248.828566 -25.832054) (xy 248.84792 -25.883899)
			(xy 248.859739 -25.940586) (xy 248.861834 -25.969468) (xy 248.862342 -25.981914) (xy 248.875042 -26.00325)
			(xy 248.966736 -26.060654) (xy 248.991374 -26.062432) (xy 249.002804 -26.057606) (xy 249.031164 -26.046144)
			(xy 249.090161 -26.029986) (xy 249.150782 -26.021812) (xy 249.181366 -26.021284) (xy 249.211353 -26.021739)
			(xy 249.270814 -26.029564) (xy 249.328744 -26.045083) (xy 249.384153 -26.068032) (xy 249.436093 -26.098018)
			(xy 249.483673 -26.134528) (xy 249.52608 -26.176936) (xy 249.562588 -26.224517) (xy 249.592573 -26.276457)
			(xy 249.615521 -26.331867) (xy 249.623293 -26.360882) (xy 251.289564 -26.360882) (xy 251.293635 -26.30526)
			(xy 251.305761 -26.250823) (xy 251.325684 -26.198732) (xy 251.35298 -26.150097) (xy 251.387066 -26.105954)
			(xy 251.427215 -26.067245) (xy 251.472573 -26.034794) (xy 251.522173 -26.009293) (xy 251.574957 -25.991286)
			(xy 251.6298 -25.981156) (xy 251.685534 -25.979119) (xy 251.740971 -25.985219) (xy 251.794928 -25.999325)
			(xy 251.846257 -26.021137) (xy 251.893863 -26.050191) (xy 251.936731 -26.085866) (xy 251.973948 -26.127403)
			(xy 252.004721 -26.173916) (xy 252.028393 -26.224413) (xy 252.044461 -26.27782) (xy 252.052581 -26.332996)
			(xy 252.05309 -26.360882) (xy 252.305564 -26.360882) (xy 252.309635 -26.30526) (xy 252.321761 -26.250823)
			(xy 252.341684 -26.198732) (xy 252.36898 -26.150097) (xy 252.403066 -26.105954) (xy 252.443215 -26.067245)
			(xy 252.488573 -26.034794) (xy 252.538173 -26.009293) (xy 252.590957 -25.991286) (xy 252.6458 -25.981156)
			(xy 252.701534 -25.979119) (xy 252.756971 -25.985219) (xy 252.810928 -25.999325) (xy 252.862257 -26.021137)
			(xy 252.909863 -26.050191) (xy 252.952731 -26.085866) (xy 252.989948 -26.127403) (xy 253.020721 -26.173916)
			(xy 253.044393 -26.224413) (xy 253.060461 -26.27782) (xy 253.068581 -26.332996) (xy 253.06909 -26.360882)
			(xy 253.068581 -26.388768) (xy 253.060461 -26.443944) (xy 253.044393 -26.497351) (xy 253.020721 -26.547848)
			(xy 252.989948 -26.594361) (xy 252.952731 -26.635898) (xy 252.909863 -26.671573) (xy 252.862257 -26.700627)
			(xy 252.810928 -26.722439) (xy 252.756971 -26.736545) (xy 252.701534 -26.742645) (xy 252.6458 -26.740608)
			(xy 252.590957 -26.730478) (xy 252.538173 -26.712471) (xy 252.488573 -26.68697) (xy 252.443215 -26.654519)
			(xy 252.403066 -26.61581) (xy 252.36898 -26.571667) (xy 252.341684 -26.523032) (xy 252.321761 -26.470941)
			(xy 252.309635 -26.416504) (xy 252.305564 -26.360882) (xy 252.05309 -26.360882) (xy 252.052581 -26.388768)
			(xy 252.044461 -26.443944) (xy 252.028393 -26.497351) (xy 252.004721 -26.547848) (xy 251.973948 -26.594361)
			(xy 251.936731 -26.635898) (xy 251.893863 -26.671573) (xy 251.846257 -26.700627) (xy 251.794928 -26.722439)
			(xy 251.740971 -26.736545) (xy 251.685534 -26.742645) (xy 251.6298 -26.740608) (xy 251.574957 -26.730478)
			(xy 251.522173 -26.712471) (xy 251.472573 -26.68697) (xy 251.427215 -26.654519) (xy 251.387066 -26.61581)
			(xy 251.35298 -26.571667) (xy 251.325684 -26.523032) (xy 251.305761 -26.470941) (xy 251.293635 -26.416504)
			(xy 251.289564 -26.360882) (xy 249.623293 -26.360882) (xy 249.631039 -26.389798) (xy 249.638862 -26.449259)
			(xy 249.639328 -26.479246) (xy 249.639328 -26.971244) (xy 253.051054 -26.971244) (xy 253.055125 -26.915622)
			(xy 253.067251 -26.861185) (xy 253.087174 -26.809094) (xy 253.11447 -26.760459) (xy 253.148556 -26.716316)
			(xy 253.188705 -26.677607) (xy 253.234063 -26.645156) (xy 253.283663 -26.619655) (xy 253.336447 -26.601648)
			(xy 253.39129 -26.591518) (xy 253.447024 -26.589481) (xy 253.502461 -26.595581) (xy 253.556418 -26.609687)
			(xy 253.607747 -26.631499) (xy 253.655353 -26.660553) (xy 253.698221 -26.696228) (xy 253.735438 -26.737765)
			(xy 253.766211 -26.784278) (xy 253.789883 -26.834775) (xy 253.805951 -26.888182) (xy 253.814071 -26.943358)
			(xy 253.81458 -26.971244) (xy 253.814071 -26.99913) (xy 253.805951 -27.054306) (xy 253.789883 -27.107713)
			(xy 253.766211 -27.15821) (xy 253.735438 -27.204723) (xy 253.698221 -27.24626) (xy 253.655353 -27.281935)
			(xy 253.607747 -27.310989) (xy 253.556418 -27.332801) (xy 253.502461 -27.346907) (xy 253.447024 -27.353007)
			(xy 253.39129 -27.35097) (xy 253.336447 -27.34084) (xy 253.283663 -27.322833) (xy 253.234063 -27.297332)
			(xy 253.188705 -27.264881) (xy 253.148556 -27.226172) (xy 253.11447 -27.182029) (xy 253.087174 -27.133394)
			(xy 253.067251 -27.081303) (xy 253.055125 -27.026866) (xy 253.051054 -26.971244) (xy 249.639328 -26.971244)
			(xy 249.639328 -27.342846) (xy 249.638915 -27.372833) (xy 249.631081 -27.432293) (xy 249.615553 -27.490221)
			(xy 249.592597 -27.545627) (xy 249.562605 -27.597563) (xy 249.526091 -27.64514) (xy 249.48368 -27.687544)
			(xy 249.436097 -27.72405) (xy 249.384155 -27.754032) (xy 249.328745 -27.776979) (xy 249.270814 -27.792496)
			(xy 249.211353 -27.80032) (xy 249.181366 -27.800808) (xy 249.150229 -27.80028) (xy 249.088533 -27.791814)
			(xy 249.028548 -27.775083) (xy 248.999756 -27.763216) (xy 248.98858 -27.75839) (xy 248.964958 -27.75966)
			(xy 248.873772 -27.810968) (xy 248.86031 -27.830526) (xy 248.858786 -27.842464) (xy 248.854598 -27.869499)
			(xy 248.839416 -27.922059) (xy 248.816885 -27.971912) (xy 248.787466 -28.018038) (xy 248.751762 -28.059489)
			(xy 248.710506 -28.095419) (xy 248.664541 -28.125088) (xy 248.614812 -28.147891) (xy 248.562335 -28.163359)
			(xy 248.508188 -28.171176) (xy 248.480834 -28.171648) (xy 248.453582 -28.171107) (xy 248.399633 -28.163355)
			(xy 248.347337 -28.148003) (xy 248.297758 -28.125365) (xy 248.251905 -28.095901) (xy 248.210713 -28.060211)
			(xy 248.175019 -28.019022) (xy 248.145551 -27.973172) (xy 248.122909 -27.923595) (xy 248.107552 -27.8713)
			(xy 248.099795 -27.817352) (xy 246.829845 -27.817352) (xy 246.829833 -27.818026) (xy 246.821713 -27.873202)
			(xy 246.805645 -27.926609) (xy 246.781973 -27.977106) (xy 246.7512 -28.023619) (xy 246.713983 -28.065156)
			(xy 246.671115 -28.100831) (xy 246.623509 -28.129885) (xy 246.57218 -28.151697) (xy 246.518223 -28.165803)
			(xy 246.462786 -28.171903) (xy 246.407052 -28.169866) (xy 246.352209 -28.159736) (xy 246.299425 -28.141729)
			(xy 246.249825 -28.116228) (xy 246.204467 -28.083777) (xy 246.164318 -28.045068) (xy 246.130232 -28.000925)
			(xy 246.102936 -27.95229) (xy 246.083013 -27.900199) (xy 246.070887 -27.845762) (xy 246.066816 -27.79014)
			(xy 244.32641 -27.79014) (xy 244.325901 -27.818026) (xy 244.317781 -27.873202) (xy 244.301713 -27.926609)
			(xy 244.278041 -27.977106) (xy 244.247268 -28.023619) (xy 244.210051 -28.065156) (xy 244.167183 -28.100831)
			(xy 244.119577 -28.129885) (xy 244.068248 -28.151697) (xy 244.014291 -28.165803) (xy 243.958854 -28.171903)
			(xy 243.90312 -28.169866) (xy 243.848277 -28.159736) (xy 243.795493 -28.141729) (xy 243.745893 -28.116228)
			(xy 243.700535 -28.083777) (xy 243.660386 -28.045068) (xy 243.6263 -28.000925) (xy 243.599004 -27.95229)
			(xy 243.579081 -27.900199) (xy 243.566955 -27.845762) (xy 243.562884 -27.79014) (xy 242.229896 -27.79014)
			(xy 242.229896 -27.817246) (xy 242.222199 -27.870988) (xy 242.20696 -27.923096) (xy 242.184487 -27.972517)
			(xy 242.155235 -28.018253) (xy 242.119793 -28.05938) (xy 242.078879 -28.095066) (xy 242.033319 -28.124591)
			(xy 241.984033 -28.147359) (xy 241.932017 -28.162909) (xy 241.878322 -28.170927) (xy 241.85118 -28.171648)
			(xy 241.840766 -28.171648) (xy 241.822732 -28.179268) (xy 241.765074 -28.237434) (xy 241.758398 -28.244847)
			(xy 241.750832 -28.263283) (xy 241.750342 -28.273248) (xy 241.750342 -29.106876) (xy 241.750831 -29.116836)
			(xy 241.758426 -29.135254) (xy 241.765074 -29.14269) (xy 241.822732 -29.200856) (xy 241.840766 -29.208476)
			(xy 241.85118 -29.208476) (xy 241.878326 -29.209117) (xy 241.932029 -29.217136) (xy 241.984053 -29.232688)
			(xy 242.033346 -29.255459) (xy 242.078914 -29.284989) (xy 242.119834 -29.320681) (xy 242.15528 -29.361813)
			(xy 242.184537 -29.407556) (xy 242.207013 -29.456984) (xy 242.222254 -29.5091) (xy 242.229952 -29.562851)
			(xy 242.229952 -29.589984) (xy 243.562884 -29.589984) (xy 243.566955 -29.534362) (xy 243.579081 -29.479925)
			(xy 243.599004 -29.427834) (xy 243.6263 -29.379199) (xy 243.660386 -29.335056) (xy 243.700535 -29.296347)
			(xy 243.745893 -29.263896) (xy 243.795493 -29.238395) (xy 243.848277 -29.220388) (xy 243.90312 -29.210258)
			(xy 243.958854 -29.208221) (xy 244.014291 -29.214321) (xy 244.068248 -29.228427) (xy 244.119577 -29.250239)
			(xy 244.167183 -29.279293) (xy 244.210051 -29.314968) (xy 244.247268 -29.356505) (xy 244.278041 -29.403018)
			(xy 244.301713 -29.453515) (xy 244.317781 -29.506922) (xy 244.325901 -29.562098) (xy 244.32641 -29.589984)
			(xy 246.066816 -29.589984) (xy 246.070887 -29.534362) (xy 246.083013 -29.479925) (xy 246.102936 -29.427834)
			(xy 246.130232 -29.379199) (xy 246.164318 -29.335056) (xy 246.204467 -29.296347) (xy 246.249825 -29.263896)
			(xy 246.299425 -29.238395) (xy 246.352209 -29.220388) (xy 246.407052 -29.210258) (xy 246.462786 -29.208221)
			(xy 246.518223 -29.214321) (xy 246.57218 -29.228427) (xy 246.623509 -29.250239) (xy 246.671115 -29.279293)
			(xy 246.713983 -29.314968) (xy 246.7512 -29.356505) (xy 246.781973 -29.403018) (xy 246.805645 -29.453515)
			(xy 246.821713 -29.506922) (xy 246.829833 -29.562098) (xy 246.830342 -29.589984) (xy 248.098816 -29.589984)
			(xy 248.102887 -29.534362) (xy 248.115013 -29.479925) (xy 248.134936 -29.427834) (xy 248.162232 -29.379199)
			(xy 248.196318 -29.335056) (xy 248.236467 -29.296347) (xy 248.281825 -29.263896) (xy 248.331425 -29.238395)
			(xy 248.384209 -29.220388) (xy 248.439052 -29.210258) (xy 248.494786 -29.208221) (xy 248.550223 -29.214321)
			(xy 248.60418 -29.228427) (xy 248.655509 -29.250239) (xy 248.703115 -29.279293) (xy 248.745983 -29.314968)
			(xy 248.767656 -29.339157) (xy 250.490109 -29.339157) (xy 250.490109 -29.284643) (xy 250.497868 -29.230683)
			(xy 250.513227 -29.178376) (xy 250.535874 -29.128788) (xy 250.565348 -29.082928) (xy 250.60105 -29.04173)
			(xy 250.642251 -29.006032) (xy 250.688113 -28.976561) (xy 250.737702 -28.953917) (xy 250.79001 -28.938562)
			(xy 250.843971 -28.930807) (xy 250.871228 -28.930346) (xy 250.886021 -28.930476) (xy 250.915519 -28.932768)
			(xy 250.930156 -28.934918) (xy 250.941078 -28.936696) (xy 250.962414 -28.9306) (xy 251.029724 -28.873196)
			(xy 251.037751 -28.865627) (xy 251.046966 -28.845608) (xy 251.047504 -28.834588) (xy 251.047504 -28.530296)
			(xy 251.046967 -28.519277) (xy 251.037747 -28.49926) (xy 251.029724 -28.491688) (xy 250.962414 -28.434284)
			(xy 250.941078 -28.428188) (xy 250.930156 -28.429966) (xy 250.915518 -28.432106) (xy 250.886021 -28.434395)
			(xy 250.871228 -28.434538) (xy 250.843976 -28.434017) (xy 250.790026 -28.426264) (xy 250.737729 -28.410911)
			(xy 250.688149 -28.388272) (xy 250.642296 -28.358807) (xy 250.601104 -28.323116) (xy 250.56541 -28.281926)
			(xy 250.535941 -28.236075) (xy 250.513299 -28.186497) (xy 250.497942 -28.134201) (xy 250.490185 -28.080252)
			(xy 250.490185 -28.025748) (xy 250.497942 -27.971799) (xy 250.513299 -27.919503) (xy 250.535941 -27.869925)
			(xy 250.56541 -27.824074) (xy 250.601104 -27.782884) (xy 250.642296 -27.747193) (xy 250.688149 -27.717728)
			(xy 250.737729 -27.695089) (xy 250.790026 -27.679736) (xy 250.843976 -27.671983) (xy 250.871228 -27.671522)
			(xy 250.897155 -27.671925) (xy 250.948534 -27.678935) (xy 250.998491 -27.692837) (xy 251.046106 -27.713373)
			(xy 251.090502 -27.740167) (xy 251.130862 -27.772724) (xy 251.166443 -27.810445) (xy 251.18187 -27.831288)
			(xy 251.187611 -27.838618) (xy 251.203113 -27.848903) (xy 251.212096 -27.851354) (xy 251.242322 -27.858212)
			(xy 251.2516 -27.859948) (xy 251.270261 -27.857215) (xy 251.278644 -27.852878) (xy 251.304612 -27.838567)
			(xy 251.359467 -27.81606) (xy 251.416772 -27.800839) (xy 251.475566 -27.793157) (xy 251.505212 -27.79268)
			(xy 251.534854 -27.793204) (xy 251.593635 -27.800917) (xy 251.650933 -27.816136) (xy 251.705795 -27.838607)
			(xy 251.73178 -27.852878) (xy 251.740193 -27.857125) (xy 251.758823 -27.859858) (xy 251.768102 -27.858212)
			(xy 251.798328 -27.851354) (xy 251.807322 -27.848929) (xy 251.822827 -27.838635) (xy 251.828554 -27.831288)
			(xy 251.843982 -27.810444) (xy 251.879551 -27.772709) (xy 251.919906 -27.740143) (xy 251.964303 -27.713346)
			(xy 252.011922 -27.692815) (xy 252.061884 -27.678926) (xy 252.113267 -27.671938) (xy 252.139196 -27.671522)
			(xy 252.166451 -27.671925) (xy 252.220407 -27.679682) (xy 252.272709 -27.695039) (xy 252.322294 -27.717683)
			(xy 252.368151 -27.747153) (xy 252.409348 -27.782849) (xy 252.445045 -27.824046) (xy 252.474515 -27.869903)
			(xy 252.49716 -27.919487) (xy 252.512517 -27.971789) (xy 252.520275 -28.025745) (xy 252.520275 -28.080255)
			(xy 252.512517 -28.134211) (xy 252.49716 -28.186513) (xy 252.474515 -28.236097) (xy 252.445045 -28.281954)
			(xy 252.409348 -28.323151) (xy 252.368151 -28.358847) (xy 252.322294 -28.388317) (xy 252.272709 -28.410961)
			(xy 252.220407 -28.426318) (xy 252.166451 -28.434075) (xy 252.139196 -28.434538) (xy 252.124403 -28.434406)
			(xy 252.094905 -28.432115) (xy 252.080268 -28.429966) (xy 252.069346 -28.428188) (xy 252.04801 -28.434284)
			(xy 251.9807 -28.491688) (xy 251.972684 -28.499267) (xy 251.963462 -28.519279) (xy 251.96292 -28.530296)
			(xy 251.96292 -28.834588) (xy 251.963458 -28.845607) (xy 251.972677 -28.865624) (xy 251.9807 -28.873196)
			(xy 252.04801 -28.9306) (xy 252.069346 -28.936696) (xy 252.080268 -28.934918) (xy 252.094906 -28.932775)
			(xy 252.124403 -28.930488) (xy 252.139196 -28.930346) (xy 252.166446 -28.930901) (xy 252.220391 -28.938657)
			(xy 252.272683 -28.95401) (xy 252.322257 -28.97665) (xy 252.368105 -29.006114) (xy 252.409294 -29.041804)
			(xy 252.444983 -29.082991) (xy 252.474448 -29.128839) (xy 252.497088 -29.178414) (xy 252.512443 -29.230705)
			(xy 252.520199 -29.28465) (xy 252.520199 -29.33915) (xy 252.512443 -29.393095) (xy 252.497088 -29.445386)
			(xy 252.474448 -29.494961) (xy 252.444983 -29.540809) (xy 252.409294 -29.581996) (xy 252.368105 -29.617686)
			(xy 252.322257 -29.64715) (xy 252.272683 -29.66979) (xy 252.220391 -29.685143) (xy 252.166446 -29.692899)
			(xy 252.139196 -29.693362) (xy 252.113269 -29.692948) (xy 252.06189 -29.685941) (xy 252.011934 -29.672042)
			(xy 251.964319 -29.651507) (xy 251.919922 -29.624715) (xy 251.879562 -29.592159) (xy 251.843981 -29.554439)
			(xy 251.828554 -29.533596) (xy 251.822788 -29.526288) (xy 251.807305 -29.515988) (xy 251.798328 -29.51353)
			(xy 251.768102 -29.506672) (xy 251.758822 -29.504951) (xy 251.740163 -29.507674) (xy 251.73178 -29.512006)
			(xy 251.705807 -29.526306) (xy 251.650954 -29.548816) (xy 251.59365 -29.564041) (xy 251.534858 -29.571725)
			(xy 251.505212 -29.572204) (xy 251.475569 -29.571715) (xy 251.416787 -29.563992) (xy 251.359488 -29.548763)
			(xy 251.304628 -29.526282) (xy 251.278644 -29.512006) (xy 251.270227 -29.50777) (xy 251.2516 -29.505031)
			(xy 251.242322 -29.506672) (xy 251.212096 -29.51353) (xy 251.203093 -29.515929) (xy 251.187593 -29.526242)
			(xy 251.18187 -29.533596) (xy 251.166423 -29.554425) (xy 251.130858 -29.592161) (xy 251.090506 -29.624729)
			(xy 251.046113 -29.651528) (xy 250.998497 -29.672062) (xy 250.948537 -29.685953) (xy 250.897156 -29.692944)
			(xy 250.871228 -29.693362) (xy 250.843971 -29.692993) (xy 250.79001 -29.685238) (xy 250.737702 -29.669883)
			(xy 250.688113 -29.647239) (xy 250.642251 -29.617768) (xy 250.60105 -29.58207) (xy 250.565348 -29.540872)
			(xy 250.535874 -29.495012) (xy 250.513227 -29.445424) (xy 250.497868 -29.393117) (xy 250.490109 -29.339157)
			(xy 248.767656 -29.339157) (xy 248.7832 -29.356505) (xy 248.813973 -29.403018) (xy 248.837645 -29.453515)
			(xy 248.853713 -29.506922) (xy 248.861833 -29.562098) (xy 248.862342 -29.589984) (xy 248.861833 -29.61787)
			(xy 248.853713 -29.673046) (xy 248.837645 -29.726453) (xy 248.813973 -29.77695) (xy 248.7832 -29.823463)
			(xy 248.745983 -29.865) (xy 248.703115 -29.900675) (xy 248.655509 -29.929729) (xy 248.60418 -29.951541)
			(xy 248.550223 -29.965647) (xy 248.494786 -29.971747) (xy 248.439052 -29.96971) (xy 248.384209 -29.95958)
			(xy 248.331425 -29.941573) (xy 248.281825 -29.916072) (xy 248.236467 -29.883621) (xy 248.196318 -29.844912)
			(xy 248.162232 -29.800769) (xy 248.134936 -29.752134) (xy 248.115013 -29.700043) (xy 248.102887 -29.645606)
			(xy 248.098816 -29.589984) (xy 246.830342 -29.589984) (xy 246.829833 -29.61787) (xy 246.821713 -29.673046)
			(xy 246.805645 -29.726453) (xy 246.781973 -29.77695) (xy 246.7512 -29.823463) (xy 246.713983 -29.865)
			(xy 246.671115 -29.900675) (xy 246.623509 -29.929729) (xy 246.57218 -29.951541) (xy 246.518223 -29.965647)
			(xy 246.462786 -29.971747) (xy 246.407052 -29.96971) (xy 246.352209 -29.95958) (xy 246.299425 -29.941573)
			(xy 246.249825 -29.916072) (xy 246.204467 -29.883621) (xy 246.164318 -29.844912) (xy 246.130232 -29.800769)
			(xy 246.102936 -29.752134) (xy 246.083013 -29.700043) (xy 246.070887 -29.645606) (xy 246.066816 -29.589984)
			(xy 244.32641 -29.589984) (xy 244.325901 -29.61787) (xy 244.317781 -29.673046) (xy 244.301713 -29.726453)
			(xy 244.278041 -29.77695) (xy 244.247268 -29.823463) (xy 244.210051 -29.865) (xy 244.167183 -29.900675)
			(xy 244.119577 -29.929729) (xy 244.068248 -29.951541) (xy 244.014291 -29.965647) (xy 243.958854 -29.971747)
			(xy 243.90312 -29.96971) (xy 243.848277 -29.95958) (xy 243.795493 -29.941573) (xy 243.745893 -29.916072)
			(xy 243.700535 -29.883621) (xy 243.660386 -29.844912) (xy 243.6263 -29.800769) (xy 243.599004 -29.752134)
			(xy 243.579081 -29.700043) (xy 243.566955 -29.645606) (xy 243.562884 -29.589984) (xy 242.229952 -29.589984)
			(xy 242.229952 -29.617149) (xy 242.222254 -29.6709) (xy 242.207013 -29.723015) (xy 242.184537 -29.772444)
			(xy 242.15528 -29.818187) (xy 242.119834 -29.859319) (xy 242.078914 -29.895011) (xy 242.033347 -29.924541)
			(xy 241.984053 -29.947312) (xy 241.932029 -29.962864) (xy 241.878326 -29.970883) (xy 241.85118 -29.971492)
			(xy 241.840766 -29.971492) (xy 241.822732 -29.979112) (xy 241.765074 -30.037278) (xy 241.758389 -30.044688)
			(xy 241.750803 -30.063123) (xy 241.750342 -30.073092) (xy 241.750342 -30.850586) (xy 244.311422 -30.850586)
			(xy 244.315493 -30.794964) (xy 244.327619 -30.740527) (xy 244.347542 -30.688436) (xy 244.374838 -30.639801)
			(xy 244.408924 -30.595658) (xy 244.449073 -30.556949) (xy 244.494431 -30.524498) (xy 244.544031 -30.498997)
			(xy 244.596815 -30.48099) (xy 244.651658 -30.47086) (xy 244.707392 -30.468823) (xy 244.762829 -30.474923)
			(xy 244.816786 -30.489029) (xy 244.868115 -30.510841) (xy 244.915721 -30.539895) (xy 244.958589 -30.57557)
			(xy 244.995806 -30.617107) (xy 245.026579 -30.66362) (xy 245.050251 -30.714117) (xy 245.066319 -30.767524)
			(xy 245.074439 -30.8227) (xy 245.074948 -30.850586) (xy 245.074439 -30.878472) (xy 245.066319 -30.933648)
			(xy 245.050251 -30.987055) (xy 245.026579 -31.037552) (xy 244.995806 -31.084065) (xy 244.958589 -31.125602)
			(xy 244.915721 -31.161277) (xy 244.868115 -31.190331) (xy 244.816786 -31.212143) (xy 244.762829 -31.226249)
			(xy 244.707392 -31.232349) (xy 244.651658 -31.230312) (xy 244.596815 -31.220182) (xy 244.544031 -31.202175)
			(xy 244.494431 -31.176674) (xy 244.449073 -31.144223) (xy 244.408924 -31.105514) (xy 244.374838 -31.061371)
			(xy 244.347542 -31.012736) (xy 244.327619 -30.960645) (xy 244.315493 -30.906208) (xy 244.311422 -30.850586)
			(xy 241.750342 -30.850586) (xy 241.750342 -30.906974) (xy 241.750831 -30.916935) (xy 241.758425 -30.935353)
			(xy 241.765074 -30.942788) (xy 241.822732 -31.000954) (xy 241.840766 -31.008574) (xy 241.85118 -31.008574)
			(xy 241.878326 -31.009215) (xy 241.93203 -31.017234) (xy 241.984054 -31.032786) (xy 242.033347 -31.055558)
			(xy 242.078915 -31.085087) (xy 242.119835 -31.120779) (xy 242.155282 -31.161912) (xy 242.184539 -31.207655)
			(xy 242.207015 -31.257084) (xy 242.222256 -31.3092) (xy 242.229954 -31.36295) (xy 242.229954 -31.390082)
			(xy 246.066816 -31.390082) (xy 246.070887 -31.33446) (xy 246.083013 -31.280023) (xy 246.102936 -31.227932)
			(xy 246.130232 -31.179297) (xy 246.164318 -31.135154) (xy 246.204467 -31.096445) (xy 246.249825 -31.063994)
			(xy 246.299425 -31.038493) (xy 246.352209 -31.020486) (xy 246.407052 -31.010356) (xy 246.462786 -31.008319)
			(xy 246.518223 -31.014419) (xy 246.57218 -31.028525) (xy 246.623509 -31.050337) (xy 246.671115 -31.079391)
			(xy 246.713983 -31.115066) (xy 246.7512 -31.156603) (xy 246.781973 -31.203116) (xy 246.805645 -31.253613)
			(xy 246.821713 -31.30702) (xy 246.829833 -31.362196) (xy 246.830342 -31.390082) (xy 248.098816 -31.390082)
			(xy 248.102887 -31.33446) (xy 248.115013 -31.280023) (xy 248.134936 -31.227932) (xy 248.162232 -31.179297)
			(xy 248.196318 -31.135154) (xy 248.236467 -31.096445) (xy 248.281825 -31.063994) (xy 248.331425 -31.038493)
			(xy 248.384209 -31.020486) (xy 248.439052 -31.010356) (xy 248.494786 -31.008319) (xy 248.550223 -31.014419)
			(xy 248.60418 -31.028525) (xy 248.655509 -31.050337) (xy 248.703115 -31.079391) (xy 248.745983 -31.115066)
			(xy 248.7832 -31.156603) (xy 248.813973 -31.203116) (xy 248.837645 -31.253613) (xy 248.853713 -31.30702)
			(xy 248.861833 -31.362196) (xy 248.862342 -31.390082) (xy 248.861833 -31.417968) (xy 248.853713 -31.473144)
			(xy 248.837645 -31.526551) (xy 248.813973 -31.577048) (xy 248.7832 -31.623561) (xy 248.745983 -31.665098)
			(xy 248.727769 -31.680256) (xy 250.490127 -31.680256) (xy 250.490127 -31.625744) (xy 250.497885 -31.571786)
			(xy 250.513244 -31.519482) (xy 250.53589 -31.469897) (xy 250.565363 -31.424039) (xy 250.601062 -31.382842)
			(xy 250.642261 -31.347146) (xy 250.688121 -31.317677) (xy 250.737709 -31.295034) (xy 250.790014 -31.279679)
			(xy 250.843972 -31.271925) (xy 250.871228 -31.271464) (xy 250.897156 -31.271849) (xy 250.948536 -31.27886)
			(xy 250.998494 -31.292764) (xy 251.04611 -31.313303) (xy 251.090506 -31.340099) (xy 251.130865 -31.37266)
			(xy 251.166444 -31.410385) (xy 251.18187 -31.43123) (xy 251.187622 -31.43855) (xy 251.203116 -31.448843)
			(xy 251.212096 -31.451296) (xy 251.242322 -31.458154) (xy 251.2516 -31.459885) (xy 251.270261 -31.457155)
			(xy 251.278644 -31.45282) (xy 251.304628 -31.438561) (xy 251.359499 -31.41615) (xy 251.4168 -31.400994)
			(xy 251.475576 -31.393347) (xy 251.505212 -31.392876) (xy 251.53485 -31.393311) (xy 251.593634 -31.400939)
			(xy 251.650937 -31.416104) (xy 251.705798 -31.438552) (xy 251.73178 -31.45282) (xy 251.740194 -31.457065)
			(xy 251.758823 -31.4598) (xy 251.768102 -31.458154) (xy 251.798328 -31.451296) (xy 251.807317 -31.448858)
			(xy 251.822824 -31.438572) (xy 251.828554 -31.43123) (xy 251.843965 -31.410374) (xy 251.879539 -31.372641)
			(xy 251.919898 -31.340078) (xy 251.964297 -31.313284) (xy 252.011918 -31.292754) (xy 252.061882 -31.278868)
			(xy 252.113267 -31.27188) (xy 252.139196 -31.271464) (xy 252.166447 -31.271983) (xy 252.220394 -31.279739)
			(xy 252.272689 -31.295093) (xy 252.322266 -31.317734) (xy 252.368116 -31.3472) (xy 252.409306 -31.382891)
			(xy 252.444998 -31.424081) (xy 252.474464 -31.469931) (xy 252.497105 -31.519507) (xy 252.51246 -31.571802)
			(xy 252.520217 -31.625749) (xy 252.520217 -31.680251) (xy 252.51246 -31.734198) (xy 252.497105 -31.786493)
			(xy 252.474464 -31.836069) (xy 252.444998 -31.881919) (xy 252.409306 -31.923109) (xy 252.368116 -31.9588)
			(xy 252.322266 -31.988266) (xy 252.272689 -32.010907) (xy 252.220394 -32.026261) (xy 252.166447 -32.034017)
			(xy 252.139196 -32.03448) (xy 252.124403 -32.034347) (xy 252.094905 -32.032057) (xy 252.080268 -32.029908)
			(xy 252.069346 -32.02813) (xy 252.04801 -32.034226) (xy 251.9807 -32.09163) (xy 251.972665 -32.099192)
			(xy 251.963453 -32.119217) (xy 251.96292 -32.130238) (xy 251.96292 -32.43453) (xy 251.963435 -32.445552)
			(xy 251.97267 -32.465569) (xy 251.9807 -32.473138) (xy 252.04801 -32.530542) (xy 252.069346 -32.536638)
			(xy 252.080268 -32.53486) (xy 252.094905 -32.532716) (xy 252.124403 -32.53043) (xy 252.139196 -32.530288)
			(xy 252.166449 -32.530759) (xy 252.2204 -32.538515) (xy 252.272697 -32.553871) (xy 252.322277 -32.576513)
			(xy 252.368131 -32.605981) (xy 252.409323 -32.641674) (xy 252.445017 -32.682866) (xy 252.474485 -32.728719)
			(xy 252.497128 -32.778299) (xy 252.512484 -32.830597) (xy 252.520241 -32.884547) (xy 252.520241 -32.939053)
			(xy 252.512484 -32.993003) (xy 252.497128 -33.045301) (xy 252.474485 -33.094881) (xy 252.445017 -33.140734)
			(xy 252.409323 -33.181926) (xy 252.368131 -33.217619) (xy 252.322277 -33.247087) (xy 252.272697 -33.269729)
			(xy 252.2204 -33.285085) (xy 252.166449 -33.292841) (xy 252.139196 -33.293304) (xy 252.11327 -33.292873)
			(xy 252.061893 -33.285866) (xy 252.011937 -33.271969) (xy 251.964323 -33.251437) (xy 251.919926 -33.224648)
			(xy 251.879565 -33.192095) (xy 251.843982 -33.154379) (xy 251.828554 -33.133538) (xy 251.8228 -33.12622)
			(xy 251.807307 -33.115927) (xy 251.798328 -33.113472) (xy 251.768102 -33.106614) (xy 251.758823 -33.104888)
			(xy 251.740163 -33.107613) (xy 251.73178 -33.111948) (xy 251.70579 -33.126194) (xy 251.650921 -33.14861)
			(xy 251.593622 -33.163769) (xy 251.534847 -33.171419) (xy 251.505212 -33.171892) (xy 251.475574 -33.171451)
			(xy 251.416791 -33.163825) (xy 251.359487 -33.148662) (xy 251.304626 -33.126215) (xy 251.278644 -33.111948)
			(xy 251.270226 -33.107714) (xy 251.2516 -33.104972) (xy 251.242322 -33.106614) (xy 251.212096 -33.113472)
			(xy 251.2031 -33.115889) (xy 251.187598 -33.126191) (xy 251.18187 -33.133538) (xy 251.166435 -33.154376)
			(xy 251.130866 -33.19211) (xy 251.090512 -33.224676) (xy 251.046117 -33.251473) (xy 250.998499 -33.272006)
			(xy 250.948538 -33.285895) (xy 250.897156 -33.292886) (xy 250.871228 -33.293304) (xy 250.843974 -33.292851)
			(xy 250.790019 -33.285097) (xy 250.737717 -33.269743) (xy 250.688133 -33.247102) (xy 250.642276 -33.217634)
			(xy 250.60108 -33.18194) (xy 250.565383 -33.140746) (xy 250.535912 -33.094891) (xy 250.513267 -33.045309)
			(xy 250.497909 -32.993008) (xy 250.490151 -32.939054) (xy 250.490151 -32.884546) (xy 250.497909 -32.830592)
			(xy 250.513267 -32.778291) (xy 250.535912 -32.728709) (xy 250.565383 -32.682854) (xy 250.60108 -32.64166)
			(xy 250.642276 -32.605966) (xy 250.688133 -32.576498) (xy 250.737717 -32.553857) (xy 250.790019 -32.538503)
			(xy 250.843974 -32.530749) (xy 250.871228 -32.530288) (xy 250.886021 -32.530418) (xy 250.915519 -32.532711)
			(xy 250.930156 -32.53486) (xy 250.941078 -32.536638) (xy 250.962414 -32.530542) (xy 251.029724 -32.473138)
			(xy 251.037732 -32.465552) (xy 251.046958 -32.445546) (xy 251.047504 -32.43453) (xy 251.047504 -32.130238)
			(xy 251.046944 -32.119222) (xy 251.03774 -32.099205) (xy 251.029724 -32.09163) (xy 250.962414 -32.034226)
			(xy 250.941078 -32.02813) (xy 250.930156 -32.029908) (xy 250.915518 -32.032049) (xy 250.886021 -32.034337)
			(xy 250.871228 -32.03448) (xy 250.843972 -32.034075) (xy 250.790014 -32.026321) (xy 250.737709 -32.010966)
			(xy 250.688121 -31.988323) (xy 250.642261 -31.958854) (xy 250.601062 -31.923158) (xy 250.565363 -31.881961)
			(xy 250.53589 -31.836103) (xy 250.513244 -31.786518) (xy 250.497885 -31.734214) (xy 250.490127 -31.680256)
			(xy 248.727769 -31.680256) (xy 248.703115 -31.700773) (xy 248.655509 -31.729827) (xy 248.60418 -31.751639)
			(xy 248.550223 -31.765745) (xy 248.494786 -31.771845) (xy 248.439052 -31.769808) (xy 248.384209 -31.759678)
			(xy 248.331425 -31.741671) (xy 248.281825 -31.71617) (xy 248.236467 -31.683719) (xy 248.196318 -31.64501)
			(xy 248.162232 -31.600867) (xy 248.134936 -31.552232) (xy 248.115013 -31.500141) (xy 248.102887 -31.445704)
			(xy 248.098816 -31.390082) (xy 246.830342 -31.390082) (xy 246.829833 -31.417968) (xy 246.821713 -31.473144)
			(xy 246.805645 -31.526551) (xy 246.781973 -31.577048) (xy 246.7512 -31.623561) (xy 246.713983 -31.665098)
			(xy 246.671115 -31.700773) (xy 246.623509 -31.729827) (xy 246.57218 -31.751639) (xy 246.518223 -31.765745)
			(xy 246.462786 -31.771845) (xy 246.407052 -31.769808) (xy 246.352209 -31.759678) (xy 246.299425 -31.741671)
			(xy 246.249825 -31.71617) (xy 246.204467 -31.683719) (xy 246.164318 -31.64501) (xy 246.130232 -31.600867)
			(xy 246.102936 -31.552232) (xy 246.083013 -31.500141) (xy 246.070887 -31.445704) (xy 246.066816 -31.390082)
			(xy 242.229954 -31.390082) (xy 242.229954 -31.417249) (xy 242.222256 -31.471) (xy 242.207015 -31.523116)
			(xy 242.184539 -31.572545) (xy 242.155282 -31.618288) (xy 242.119835 -31.659421) (xy 242.078915 -31.695113)
			(xy 242.033348 -31.724642) (xy 241.984054 -31.747413) (xy 241.93203 -31.762966) (xy 241.878326 -31.770985)
			(xy 241.85118 -31.77159) (xy 241.840766 -31.77159) (xy 241.822732 -31.77921) (xy 241.765074 -31.837376)
			(xy 241.758389 -31.844785) (xy 241.750802 -31.863221) (xy 241.750342 -31.87319) (xy 241.750342 -32.707072)
			(xy 241.75083 -32.717033) (xy 241.758424 -32.735452) (xy 241.765074 -32.742886) (xy 241.822732 -32.801052)
			(xy 241.840766 -32.808672) (xy 241.85118 -32.808672) (xy 241.878326 -32.809313) (xy 241.93203 -32.817332)
			(xy 241.984055 -32.832885) (xy 242.033348 -32.855656) (xy 242.078916 -32.885186) (xy 242.119836 -32.920878)
			(xy 242.155283 -32.962011) (xy 242.18454 -33.007754) (xy 242.207017 -33.057183) (xy 242.222258 -33.109299)
			(xy 242.229956 -33.16305) (xy 242.229956 -33.19018) (xy 243.874034 -33.19018) (xy 243.878105 -33.134558)
			(xy 243.890231 -33.080121) (xy 243.910154 -33.02803) (xy 243.93745 -32.979395) (xy 243.971536 -32.935252)
			(xy 244.011685 -32.896543) (xy 244.057043 -32.864092) (xy 244.106643 -32.838591) (xy 244.159427 -32.820584)
			(xy 244.21427 -32.810454) (xy 244.270004 -32.808417) (xy 244.325441 -32.814517) (xy 244.379398 -32.828623)
			(xy 244.430727 -32.850435) (xy 244.478333 -32.879489) (xy 244.521201 -32.915164) (xy 244.558418 -32.956701)
			(xy 244.589191 -33.003214) (xy 244.612863 -33.053711) (xy 244.628931 -33.107118) (xy 244.637051 -33.162294)
			(xy 244.63756 -33.19018) (xy 246.066816 -33.19018) (xy 246.070887 -33.134558) (xy 246.083013 -33.080121)
			(xy 246.102936 -33.02803) (xy 246.130232 -32.979395) (xy 246.164318 -32.935252) (xy 246.204467 -32.896543)
			(xy 246.249825 -32.864092) (xy 246.299425 -32.838591) (xy 246.352209 -32.820584) (xy 246.407052 -32.810454)
			(xy 246.462786 -32.808417) (xy 246.518223 -32.814517) (xy 246.57218 -32.828623) (xy 246.623509 -32.850435)
			(xy 246.671115 -32.879489) (xy 246.713983 -32.915164) (xy 246.7512 -32.956701) (xy 246.781973 -33.003214)
			(xy 246.805645 -33.053711) (xy 246.821713 -33.107118) (xy 246.829833 -33.162294) (xy 246.830342 -33.19018)
			(xy 248.098816 -33.19018) (xy 248.102887 -33.134558) (xy 248.115013 -33.080121) (xy 248.134936 -33.02803)
			(xy 248.162232 -32.979395) (xy 248.196318 -32.935252) (xy 248.236467 -32.896543) (xy 248.281825 -32.864092)
			(xy 248.331425 -32.838591) (xy 248.384209 -32.820584) (xy 248.439052 -32.810454) (xy 248.494786 -32.808417)
			(xy 248.550223 -32.814517) (xy 248.60418 -32.828623) (xy 248.655509 -32.850435) (xy 248.703115 -32.879489)
			(xy 248.745983 -32.915164) (xy 248.7832 -32.956701) (xy 248.813973 -33.003214) (xy 248.837645 -33.053711)
			(xy 248.853713 -33.107118) (xy 248.861833 -33.162294) (xy 248.862342 -33.19018) (xy 248.861833 -33.218066)
			(xy 248.853713 -33.273242) (xy 248.837645 -33.326649) (xy 248.813973 -33.377146) (xy 248.7832 -33.423659)
			(xy 248.745983 -33.465196) (xy 248.703115 -33.500871) (xy 248.655509 -33.529925) (xy 248.60418 -33.551737)
			(xy 248.550223 -33.565843) (xy 248.494786 -33.571943) (xy 248.439052 -33.569906) (xy 248.384209 -33.559776)
			(xy 248.331425 -33.541769) (xy 248.281825 -33.516268) (xy 248.236467 -33.483817) (xy 248.196318 -33.445108)
			(xy 248.162232 -33.400965) (xy 248.134936 -33.35233) (xy 248.115013 -33.300239) (xy 248.102887 -33.245802)
			(xy 248.098816 -33.19018) (xy 246.830342 -33.19018) (xy 246.829833 -33.218066) (xy 246.821713 -33.273242)
			(xy 246.805645 -33.326649) (xy 246.781973 -33.377146) (xy 246.7512 -33.423659) (xy 246.713983 -33.465196)
			(xy 246.671115 -33.500871) (xy 246.623509 -33.529925) (xy 246.57218 -33.551737) (xy 246.518223 -33.565843)
			(xy 246.462786 -33.571943) (xy 246.407052 -33.569906) (xy 246.352209 -33.559776) (xy 246.299425 -33.541769)
			(xy 246.249825 -33.516268) (xy 246.204467 -33.483817) (xy 246.164318 -33.445108) (xy 246.130232 -33.400965)
			(xy 246.102936 -33.35233) (xy 246.083013 -33.300239) (xy 246.070887 -33.245802) (xy 246.066816 -33.19018)
			(xy 244.63756 -33.19018) (xy 244.637051 -33.218066) (xy 244.628931 -33.273242) (xy 244.612863 -33.326649)
			(xy 244.589191 -33.377146) (xy 244.558418 -33.423659) (xy 244.521201 -33.465196) (xy 244.478333 -33.500871)
			(xy 244.430727 -33.529925) (xy 244.379398 -33.551737) (xy 244.325441 -33.565843) (xy 244.270004 -33.571943)
			(xy 244.21427 -33.569906) (xy 244.159427 -33.559776) (xy 244.106643 -33.541769) (xy 244.057043 -33.516268)
			(xy 244.011685 -33.483817) (xy 243.971536 -33.445108) (xy 243.93745 -33.400965) (xy 243.910154 -33.35233)
			(xy 243.890231 -33.300239) (xy 243.878105 -33.245802) (xy 243.874034 -33.19018) (xy 242.229956 -33.19018)
			(xy 242.229956 -33.21735) (xy 242.222258 -33.2711) (xy 242.207017 -33.323217) (xy 242.184541 -33.372646)
			(xy 242.155283 -33.418389) (xy 242.119837 -33.459522) (xy 242.078916 -33.495214) (xy 242.033349 -33.524744)
			(xy 241.984055 -33.547515) (xy 241.93203 -33.563068) (xy 241.878327 -33.571087) (xy 241.85118 -33.571688)
			(xy 241.840766 -33.571688) (xy 241.822732 -33.579308) (xy 241.765074 -33.637474) (xy 241.758388 -33.644883)
			(xy 241.750801 -33.663319) (xy 241.750342 -33.673288) (xy 241.750342 -34.506916) (xy 241.75082 -34.516881)
			(xy 241.7584 -34.535315) (xy 241.765074 -34.54273) (xy 241.822732 -34.600896) (xy 241.840766 -34.608516)
			(xy 241.85118 -34.608516) (xy 241.878323 -34.609157) (xy 241.932021 -34.617176) (xy 241.984039 -34.632726)
			(xy 242.033327 -34.655495) (xy 242.078889 -34.685021) (xy 242.119805 -34.720709) (xy 242.155248 -34.761838)
			(xy 242.184501 -34.807575) (xy 242.206975 -34.856999) (xy 242.222214 -34.909109) (xy 242.229912 -34.962854)
			(xy 242.229912 -34.990024) (xy 243.872764 -34.990024) (xy 243.876835 -34.934402) (xy 243.888961 -34.879965)
			(xy 243.908884 -34.827874) (xy 243.93618 -34.779239) (xy 243.970266 -34.735096) (xy 244.010415 -34.696387)
			(xy 244.055773 -34.663936) (xy 244.105373 -34.638435) (xy 244.158157 -34.620428) (xy 244.213 -34.610298)
			(xy 244.268734 -34.608261) (xy 244.324171 -34.614361) (xy 244.378128 -34.628467) (xy 244.429457 -34.650279)
			(xy 244.477063 -34.679333) (xy 244.519931 -34.715008) (xy 244.557148 -34.756545) (xy 244.587921 -34.803058)
			(xy 244.611593 -34.853555) (xy 244.627661 -34.906962) (xy 244.635781 -34.962138) (xy 244.63629 -34.990024)
			(xy 245.07012 -34.990024) (xy 245.074191 -34.934402) (xy 245.086317 -34.879965) (xy 245.10624 -34.827874)
			(xy 245.133536 -34.779239) (xy 245.167622 -34.735096) (xy 245.207771 -34.696387) (xy 245.253129 -34.663936)
			(xy 245.302729 -34.638435) (xy 245.355513 -34.620428) (xy 245.410356 -34.610298) (xy 245.46609 -34.608261)
			(xy 245.521527 -34.614361) (xy 245.575484 -34.628467) (xy 245.626813 -34.650279) (xy 245.674419 -34.679333)
			(xy 245.717287 -34.715008) (xy 245.754504 -34.756545) (xy 245.785277 -34.803058) (xy 245.808949 -34.853555)
			(xy 245.825017 -34.906962) (xy 245.833137 -34.962138) (xy 245.833646 -34.990024) (xy 248.098816 -34.990024)
			(xy 248.102887 -34.934402) (xy 248.115013 -34.879965) (xy 248.134936 -34.827874) (xy 248.162232 -34.779239)
			(xy 248.196318 -34.735096) (xy 248.236467 -34.696387) (xy 248.281825 -34.663936) (xy 248.331425 -34.638435)
			(xy 248.384209 -34.620428) (xy 248.439052 -34.610298) (xy 248.494786 -34.608261) (xy 248.550223 -34.614361)
			(xy 248.60418 -34.628467) (xy 248.655509 -34.650279) (xy 248.703115 -34.679333) (xy 248.745983 -34.715008)
			(xy 248.7832 -34.756545) (xy 248.813973 -34.803058) (xy 248.837645 -34.853555) (xy 248.853713 -34.906962)
			(xy 248.861833 -34.962138) (xy 248.862342 -34.990024) (xy 248.861833 -35.01791) (xy 248.853713 -35.073086)
			(xy 248.837645 -35.126493) (xy 248.813973 -35.17699) (xy 248.7832 -35.223503) (xy 248.745983 -35.26504)
			(xy 248.703115 -35.300715) (xy 248.655509 -35.329769) (xy 248.60418 -35.351581) (xy 248.550223 -35.365687)
			(xy 248.494786 -35.371787) (xy 248.439052 -35.36975) (xy 248.384209 -35.35962) (xy 248.331425 -35.341613)
			(xy 248.281825 -35.316112) (xy 248.236467 -35.283661) (xy 248.196318 -35.244952) (xy 248.162232 -35.200809)
			(xy 248.134936 -35.152174) (xy 248.115013 -35.100083) (xy 248.102887 -35.045646) (xy 248.098816 -34.990024)
			(xy 245.833646 -34.990024) (xy 245.833137 -35.01791) (xy 245.825017 -35.073086) (xy 245.808949 -35.126493)
			(xy 245.785277 -35.17699) (xy 245.754504 -35.223503) (xy 245.717287 -35.26504) (xy 245.674419 -35.300715)
			(xy 245.626813 -35.329769) (xy 245.575484 -35.351581) (xy 245.521527 -35.365687) (xy 245.46609 -35.371787)
			(xy 245.410356 -35.36975) (xy 245.355513 -35.35962) (xy 245.302729 -35.341613) (xy 245.253129 -35.316112)
			(xy 245.207771 -35.283661) (xy 245.167622 -35.244952) (xy 245.133536 -35.200809) (xy 245.10624 -35.152174)
			(xy 245.086317 -35.100083) (xy 245.074191 -35.045646) (xy 245.07012 -34.990024) (xy 244.63629 -34.990024)
			(xy 244.635781 -35.01791) (xy 244.627661 -35.073086) (xy 244.611593 -35.126493) (xy 244.587921 -35.17699)
			(xy 244.557148 -35.223503) (xy 244.519931 -35.26504) (xy 244.477063 -35.300715) (xy 244.429457 -35.329769)
			(xy 244.378128 -35.351581) (xy 244.324171 -35.365687) (xy 244.268734 -35.371787) (xy 244.213 -35.36975)
			(xy 244.158157 -35.35962) (xy 244.105373 -35.341613) (xy 244.055773 -35.316112) (xy 244.010415 -35.283661)
			(xy 243.970266 -35.244952) (xy 243.93618 -35.200809) (xy 243.908884 -35.152174) (xy 243.888961 -35.100083)
			(xy 243.876835 -35.045646) (xy 243.872764 -34.990024) (xy 242.229912 -34.990024) (xy 242.229912 -35.017147)
			(xy 242.222214 -35.070891) (xy 242.206975 -35.123001) (xy 242.184501 -35.172425) (xy 242.155248 -35.218163)
			(xy 242.119805 -35.259291) (xy 242.078889 -35.294979) (xy 242.033327 -35.324505) (xy 241.984039 -35.347274)
			(xy 241.93202 -35.362824) (xy 241.878323 -35.370843) (xy 241.85118 -35.371532) (xy 241.840766 -35.371532)
			(xy 241.822732 -35.379152) (xy 241.765074 -35.437318) (xy 241.758395 -35.44473) (xy 241.750824 -35.463166)
			(xy 241.750342 -35.473132) (xy 241.750342 -38.193435) (xy 243.298286 -38.193435) (xy 243.298286 -38.106565)
			(xy 243.306301 -38.020065) (xy 243.322263 -37.934673) (xy 243.346035 -37.851118) (xy 243.377416 -37.770114)
			(xy 243.416137 -37.69235) (xy 243.461867 -37.61849) (xy 243.514217 -37.549165) (xy 243.572741 -37.484966)
			(xy 243.636938 -37.42644) (xy 243.706261 -37.374088) (xy 243.780118 -37.328354) (xy 243.857881 -37.289631)
			(xy 243.938884 -37.258247) (xy 244.022438 -37.234471) (xy 244.107829 -37.218506) (xy 244.194329 -37.210487)
			(xy 244.237764 -37.209984) (xy 244.315742 -37.209984) (xy 244.325754 -37.209546) (xy 244.34425 -37.20187)
			(xy 244.358402 -37.187701) (xy 244.366057 -37.169197) (xy 244.366542 -37.159184) (xy 244.366542 -37.151564)
			(xy 244.362224 -37.137594) (xy 244.35816 -37.131244) (xy 244.334755 -37.094771) (xy 244.293763 -37.01841)
			(xy 244.259777 -36.938683) (xy 244.233072 -36.856232) (xy 244.213861 -36.77172) (xy 244.2023 -36.685827)
			(xy 244.198481 -36.599243) (xy 244.202436 -36.512666) (xy 244.214131 -36.42679) (xy 244.233474 -36.342309)
			(xy 244.260309 -36.2599) (xy 244.294419 -36.180227) (xy 244.335531 -36.10393) (xy 244.383314 -36.031624)
			(xy 244.437382 -35.96389) (xy 244.497303 -35.901273) (xy 244.562592 -35.844276) (xy 244.632726 -35.793359)
			(xy 244.70714 -35.74893) (xy 244.785235 -35.711348) (xy 244.866384 -35.680913) (xy 244.949933 -35.657872)
			(xy 245.03521 -35.64241) (xy 245.12153 -35.63465) (xy 245.164864 -35.634168) (xy 245.165118 -35.634168)
			(xy 245.20845 -35.634632) (xy 245.294765 -35.642406) (xy 245.380036 -35.657881) (xy 245.463578 -35.680933)
			(xy 245.544719 -35.711376) (xy 245.622807 -35.748966) (xy 245.697213 -35.793399) (xy 245.76734 -35.84432)
			(xy 245.80447 -35.876738) (xy 250.9172 -35.876738) (xy 250.921271 -35.821116) (xy 250.933397 -35.766679)
			(xy 250.95332 -35.714588) (xy 250.980616 -35.665953) (xy 251.014702 -35.62181) (xy 251.054851 -35.583101)
			(xy 251.100209 -35.55065) (xy 251.149809 -35.525149) (xy 251.202593 -35.507142) (xy 251.257436 -35.497012)
			(xy 251.31317 -35.494975) (xy 251.368607 -35.501075) (xy 251.422564 -35.515181) (xy 251.473893 -35.536993)
			(xy 251.521499 -35.566047) (xy 251.564367 -35.601722) (xy 251.601584 -35.643259) (xy 251.632357 -35.689772)
			(xy 251.656029 -35.740269) (xy 251.672097 -35.793676) (xy 251.680217 -35.848852) (xy 251.680726 -35.876738)
			(xy 251.680217 -35.904624) (xy 251.672097 -35.9598) (xy 251.656029 -36.013207) (xy 251.632357 -36.063704)
			(xy 251.601584 -36.110217) (xy 251.564367 -36.151754) (xy 251.521499 -36.187429) (xy 251.473893 -36.216483)
			(xy 251.422564 -36.238295) (xy 251.368607 -36.252401) (xy 251.31317 -36.258501) (xy 251.257436 -36.256464)
			(xy 251.202593 -36.246334) (xy 251.149809 -36.228327) (xy 251.100209 -36.202826) (xy 251.054851 -36.170375)
			(xy 251.014702 -36.131666) (xy 250.980616 -36.087523) (xy 250.95332 -36.038888) (xy 250.933397 -35.986797)
			(xy 250.921271 -35.93236) (xy 250.9172 -35.876738) (xy 245.80447 -35.876738) (xy 245.832623 -35.901318)
			(xy 245.892537 -35.963935) (xy 245.946602 -36.031667) (xy 245.994381 -36.103971) (xy 246.035491 -36.180264)
			(xy 246.069601 -36.259933) (xy 246.096437 -36.342337) (xy 246.115783 -36.426815) (xy 246.127484 -36.512685)
			(xy 246.12873 -36.539928) (xy 252.738618 -36.539928) (xy 252.738618 -36.479992) (xy 252.746441 -36.42057)
			(xy 252.761954 -36.362677) (xy 252.78489 -36.307304) (xy 252.814857 -36.255398) (xy 252.851344 -36.207848)
			(xy 252.893724 -36.165468) (xy 252.941274 -36.128981) (xy 252.99318 -36.099014) (xy 253.048553 -36.076078)
			(xy 253.106446 -36.060565) (xy 253.165868 -36.052742) (xy 253.225804 -36.052742) (xy 253.285226 -36.060565)
			(xy 253.343119 -36.076078) (xy 253.398492 -36.099014) (xy 253.450398 -36.128981) (xy 253.497948 -36.165468)
			(xy 253.540328 -36.207848) (xy 253.576815 -36.255398) (xy 253.606782 -36.307304) (xy 253.629718 -36.362677)
			(xy 253.645231 -36.42057) (xy 253.653054 -36.479992) (xy 253.653544 -36.50996) (xy 253.653054 -36.539928)
			(xy 253.645231 -36.59935) (xy 253.629718 -36.657243) (xy 253.606782 -36.712616) (xy 253.576815 -36.764522)
			(xy 253.540328 -36.812072) (xy 253.497948 -36.854452) (xy 253.450398 -36.890939) (xy 253.398492 -36.920906)
			(xy 253.343119 -36.943842) (xy 253.285226 -36.959355) (xy 253.225804 -36.967178) (xy 253.165868 -36.967178)
			(xy 253.106446 -36.959355) (xy 253.048553 -36.943842) (xy 252.99318 -36.920906) (xy 252.941274 -36.890939)
			(xy 252.893724 -36.854452) (xy 252.851344 -36.812072) (xy 252.814857 -36.764522) (xy 252.78489 -36.712616)
			(xy 252.761954 -36.657243) (xy 252.746441 -36.59935) (xy 252.738618 -36.539928) (xy 246.12873 -36.539928)
			(xy 246.131445 -36.599259) (xy 246.127635 -36.685839) (xy 246.116084 -36.77173) (xy 246.096885 -36.85624)
			(xy 246.070192 -36.938691) (xy 246.036221 -37.01842) (xy 245.995244 -37.094784) (xy 245.971822 -37.131244)
			(xy 245.96344 -37.143944) (xy 245.96344 -37.159184) (xy 245.963833 -37.169209) (xy 245.971506 -37.187734)
			(xy 245.985687 -37.201908) (xy 246.004215 -37.209571) (xy 246.01424 -37.209984) (xy 246.091964 -37.209984)
			(xy 246.135406 -37.210393) (xy 246.221919 -37.218406) (xy 246.307323 -37.234368) (xy 246.39089 -37.258142)
			(xy 246.471908 -37.289526) (xy 246.549683 -37.328251) (xy 246.623554 -37.373987) (xy 246.69289 -37.426345)
			(xy 246.74644 -37.47516) (xy 249.959112 -37.47516) (xy 249.963183 -37.419538) (xy 249.975309 -37.365101)
			(xy 249.995232 -37.31301) (xy 250.022528 -37.264375) (xy 250.056614 -37.220232) (xy 250.096763 -37.181523)
			(xy 250.142121 -37.149072) (xy 250.191721 -37.123571) (xy 250.244505 -37.105564) (xy 250.299348 -37.095434)
			(xy 250.355082 -37.093397) (xy 250.410519 -37.099497) (xy 250.464476 -37.113603) (xy 250.515805 -37.135415)
			(xy 250.563411 -37.164469) (xy 250.606279 -37.200144) (xy 250.643496 -37.241681) (xy 250.674269 -37.288194)
			(xy 250.697941 -37.338691) (xy 250.714009 -37.392098) (xy 250.722129 -37.447274) (xy 250.722638 -37.47516)
			(xy 250.722129 -37.503046) (xy 250.714009 -37.558222) (xy 250.697941 -37.611629) (xy 250.674269 -37.662126)
			(xy 250.654289 -37.692326) (xy 252.073138 -37.692326) (xy 252.073138 -37.63239) (xy 252.080961 -37.572968)
			(xy 252.096474 -37.515075) (xy 252.11941 -37.459702) (xy 252.149377 -37.407796) (xy 252.185864 -37.360246)
			(xy 252.228244 -37.317866) (xy 252.275794 -37.281379) (xy 252.3277 -37.251412) (xy 252.383073 -37.228476)
			(xy 252.440966 -37.212963) (xy 252.500388 -37.20514) (xy 252.560324 -37.20514) (xy 252.619746 -37.212963)
			(xy 252.677639 -37.228476) (xy 252.733012 -37.251412) (xy 252.784918 -37.281379) (xy 252.832468 -37.317866)
			(xy 252.874848 -37.360246) (xy 252.911335 -37.407796) (xy 252.941302 -37.459702) (xy 252.964238 -37.515075)
			(xy 252.979751 -37.572968) (xy 252.987574 -37.63239) (xy 252.988064 -37.662358) (xy 252.987574 -37.692326)
			(xy 252.979751 -37.751748) (xy 252.964238 -37.809641) (xy 252.941302 -37.865014) (xy 252.911335 -37.91692)
			(xy 252.874848 -37.96447) (xy 252.832468 -38.00685) (xy 252.784918 -38.043337) (xy 252.733012 -38.073304)
			(xy 252.677639 -38.09624) (xy 252.619746 -38.111753) (xy 252.560324 -38.119576) (xy 252.500388 -38.119576)
			(xy 252.440966 -38.111753) (xy 252.383073 -38.09624) (xy 252.3277 -38.073304) (xy 252.275794 -38.043337)
			(xy 252.228244 -38.00685) (xy 252.185864 -37.96447) (xy 252.149377 -37.91692) (xy 252.11941 -37.865014)
			(xy 252.096474 -37.809641) (xy 252.080961 -37.751748) (xy 252.073138 -37.692326) (xy 250.654289 -37.692326)
			(xy 250.643496 -37.708639) (xy 250.606279 -37.750176) (xy 250.563411 -37.785851) (xy 250.515805 -37.814905)
			(xy 250.464476 -37.836717) (xy 250.410519 -37.850823) (xy 250.355082 -37.856923) (xy 250.299348 -37.854886)
			(xy 250.244505 -37.844756) (xy 250.191721 -37.826749) (xy 250.142121 -37.801248) (xy 250.096763 -37.768797)
			(xy 250.056614 -37.730088) (xy 250.022528 -37.685945) (xy 249.995232 -37.63731) (xy 249.975309 -37.585219)
			(xy 249.963183 -37.530782) (xy 249.959112 -37.47516) (xy 246.74644 -37.47516) (xy 246.757098 -37.484876)
			(xy 246.815632 -37.549083) (xy 246.867992 -37.618416) (xy 246.913731 -37.692285) (xy 246.952459 -37.77006)
			(xy 246.983846 -37.851075) (xy 247.007623 -37.934642) (xy 247.023589 -38.020046) (xy 247.031605 -38.106558)
			(xy 247.031605 -38.193442) (xy 247.023589 -38.279954) (xy 247.007623 -38.365358) (xy 246.983846 -38.448924)
			(xy 246.967483 -38.49116) (xy 249.959112 -38.49116) (xy 249.963183 -38.435538) (xy 249.975309 -38.381101)
			(xy 249.995232 -38.32901) (xy 250.022528 -38.280375) (xy 250.056614 -38.236232) (xy 250.096763 -38.197523)
			(xy 250.142121 -38.165072) (xy 250.191721 -38.139571) (xy 250.244505 -38.121564) (xy 250.299348 -38.111434)
			(xy 250.355082 -38.109397) (xy 250.410519 -38.115497) (xy 250.464476 -38.129603) (xy 250.515805 -38.151415)
			(xy 250.563411 -38.180469) (xy 250.606279 -38.216144) (xy 250.643496 -38.257681) (xy 250.674269 -38.304194)
			(xy 250.697941 -38.354691) (xy 250.714009 -38.408098) (xy 250.722129 -38.463274) (xy 250.722638 -38.49116)
			(xy 250.722129 -38.519046) (xy 250.714009 -38.574222) (xy 250.697941 -38.627629) (xy 250.674269 -38.678126)
			(xy 250.658991 -38.701218) (xy 253.63754 -38.701218) (xy 253.641611 -38.645596) (xy 253.653737 -38.591159)
			(xy 253.67366 -38.539068) (xy 253.700956 -38.490433) (xy 253.735042 -38.44629) (xy 253.775191 -38.407581)
			(xy 253.820549 -38.37513) (xy 253.870149 -38.349629) (xy 253.922933 -38.331622) (xy 253.977776 -38.321492)
			(xy 254.03351 -38.319455) (xy 254.088947 -38.325555) (xy 254.142904 -38.339661) (xy 254.194233 -38.361473)
			(xy 254.241839 -38.390527) (xy 254.284707 -38.426202) (xy 254.321924 -38.467739) (xy 254.352697 -38.514252)
			(xy 254.376369 -38.564749) (xy 254.392437 -38.618156) (xy 254.400557 -38.673332) (xy 254.401066 -38.701218)
			(xy 254.400557 -38.729104) (xy 254.392437 -38.78428) (xy 254.376369 -38.837687) (xy 254.352697 -38.888184)
			(xy 254.321924 -38.934697) (xy 254.284707 -38.976234) (xy 254.241839 -39.011909) (xy 254.194233 -39.040963)
			(xy 254.142904 -39.062775) (xy 254.088947 -39.076881) (xy 254.03351 -39.082981) (xy 253.977776 -39.080944)
			(xy 253.922933 -39.070814) (xy 253.870149 -39.052807) (xy 253.820549 -39.027306) (xy 253.775191 -38.994855)
			(xy 253.735042 -38.956146) (xy 253.700956 -38.912003) (xy 253.67366 -38.863368) (xy 253.653737 -38.811277)
			(xy 253.641611 -38.75684) (xy 253.63754 -38.701218) (xy 250.658991 -38.701218) (xy 250.643496 -38.724639)
			(xy 250.606279 -38.766176) (xy 250.563411 -38.801851) (xy 250.515805 -38.830905) (xy 250.464476 -38.852717)
			(xy 250.410519 -38.866823) (xy 250.355082 -38.872923) (xy 250.299348 -38.870886) (xy 250.244505 -38.860756)
			(xy 250.191721 -38.842749) (xy 250.142121 -38.817248) (xy 250.096763 -38.784797) (xy 250.056614 -38.746088)
			(xy 250.022528 -38.701945) (xy 249.995232 -38.65331) (xy 249.975309 -38.601219) (xy 249.963183 -38.546782)
			(xy 249.959112 -38.49116) (xy 246.967483 -38.49116) (xy 246.952459 -38.52994) (xy 246.913731 -38.607715)
			(xy 246.867992 -38.681584) (xy 246.815632 -38.750917) (xy 246.757098 -38.815124) (xy 246.69289 -38.873655)
			(xy 246.623554 -38.926013) (xy 246.549683 -38.971749) (xy 246.471908 -39.010474) (xy 246.39089 -39.041858)
			(xy 246.307323 -39.065632) (xy 246.221919 -39.081594) (xy 246.135406 -39.089607) (xy 246.091964 -39.090092)
			(xy 244.237764 -39.090092) (xy 244.194329 -39.089513) (xy 244.107829 -39.081494) (xy 244.022438 -39.065529)
			(xy 243.938884 -39.041753) (xy 243.857881 -39.010369) (xy 243.780118 -38.971646) (xy 243.706261 -38.925912)
			(xy 243.636938 -38.87356) (xy 243.572741 -38.815034) (xy 243.514217 -38.750835) (xy 243.461867 -38.68151)
			(xy 243.416137 -38.60765) (xy 243.377416 -38.529886) (xy 243.346035 -38.448882) (xy 243.322263 -38.365327)
			(xy 243.306301 -38.279935) (xy 243.298286 -38.193435) (xy 241.750342 -38.193435) (xy 241.750342 -42.849038)
			(xy 253.091948 -42.849038) (xy 253.096019 -42.793416) (xy 253.108145 -42.738979) (xy 253.128068 -42.686888)
			(xy 253.155364 -42.638253) (xy 253.18945 -42.59411) (xy 253.229599 -42.555401) (xy 253.274957 -42.52295)
			(xy 253.324557 -42.497449) (xy 253.377341 -42.479442) (xy 253.432184 -42.469312) (xy 253.487918 -42.467275)
			(xy 253.543355 -42.473375) (xy 253.597312 -42.487481) (xy 253.648641 -42.509293) (xy 253.696247 -42.538347)
			(xy 253.739115 -42.574022) (xy 253.776332 -42.615559) (xy 253.807105 -42.662072) (xy 253.830777 -42.712569)
			(xy 253.846845 -42.765976) (xy 253.854965 -42.821152) (xy 253.855474 -42.849038) (xy 253.854965 -42.876924)
			(xy 253.846845 -42.9321) (xy 253.830777 -42.985507) (xy 253.807105 -43.036004) (xy 253.776332 -43.082517)
			(xy 253.739115 -43.124054) (xy 253.696247 -43.159729) (xy 253.648641 -43.188783) (xy 253.597312 -43.210595)
			(xy 253.543355 -43.224701) (xy 253.487918 -43.230801) (xy 253.432184 -43.228764) (xy 253.377341 -43.218634)
			(xy 253.324557 -43.200627) (xy 253.274957 -43.175126) (xy 253.229599 -43.142675) (xy 253.18945 -43.103966)
			(xy 253.155364 -43.059823) (xy 253.128068 -43.011188) (xy 253.108145 -42.959097) (xy 253.096019 -42.90466)
			(xy 253.091948 -42.849038) (xy 241.750342 -42.849038) (xy 241.750342 -43.723814) (xy 241.7508 -43.733693)
			(xy 241.758236 -43.751997) (xy 241.76482 -43.759374) (xy 241.765074 -43.759628) (xy 242.243102 -44.237656)
			(xy 242.24361 -44.238164) (xy 242.250989 -44.244752) (xy 242.269288 -44.252216) (xy 242.27917 -44.252642)
			(xy 252.419866 -44.252642)
		)
		(stroke
			(width 0)
			(type solid)
		)
		(fill yes)
		(layer "B.Cu")
		(net "P12V_SSD8")
	)
	(gr_poly
		(pts
			(xy 72.21474 -44.24807) (xy 72.224919 -44.247627) (xy 72.243679 -44.239722) (xy 72.257879 -44.225136)
			(xy 72.261984 -44.215812) (xy 72.30237 -44.112942) (xy 72.295512 -44.082716) (xy 72.283828 -44.072048)
			(xy 72.261136 -44.050301) (xy 72.221321 -44.001668) (xy 72.188531 -43.948047) (xy 72.163382 -43.890446)
			(xy 72.146346 -43.829947) (xy 72.137742 -43.767686) (xy 72.13727 -43.73626) (xy 72.13776 -43.706292)
			(xy 72.145583 -43.64687) (xy 72.161096 -43.588977) (xy 72.184032 -43.533604) (xy 72.213999 -43.481698)
			(xy 72.250486 -43.434148) (xy 72.292866 -43.391768) (xy 72.340416 -43.355281) (xy 72.392322 -43.325314)
			(xy 72.447695 -43.302378) (xy 72.505588 -43.286865) (xy 72.56501 -43.279042) (xy 72.624946 -43.279042)
			(xy 72.684368 -43.286865) (xy 72.742261 -43.302378) (xy 72.797634 -43.325314) (xy 72.84954 -43.355281)
			(xy 72.89709 -43.391768) (xy 72.93947 -43.434148) (xy 72.975957 -43.481698) (xy 73.005924 -43.533604)
			(xy 73.02886 -43.588977) (xy 73.044373 -43.64687) (xy 73.052196 -43.706292) (xy 73.052686 -43.73626)
			(xy 73.05217 -43.767686) (xy 73.04358 -43.829947) (xy 73.026558 -43.89045) (xy 73.001422 -43.948056)
			(xy 72.968645 -44.001684) (xy 72.928843 -44.050326) (xy 72.906128 -44.072048) (xy 72.894444 -44.082716)
			(xy 72.887586 -44.112942) (xy 72.927972 -44.215812) (xy 72.932111 -44.225113) (xy 72.946311 -44.239675)
			(xy 72.965047 -44.247592) (xy 72.975216 -44.24807) (xy 73.877424 -44.24807) (xy 73.8873 -44.247608)
			(xy 73.905594 -44.24016) (xy 73.912984 -44.233592) (xy 73.913238 -44.233338) (xy 74.472546 -43.67403)
			(xy 74.473054 -43.673522) (xy 74.479632 -43.66614) (xy 74.487074 -43.64784) (xy 74.487532 -43.637962)
			(xy 74.487532 -37.58946) (xy 74.487105 -37.580069) (xy 74.480366 -37.562537) (xy 74.467795 -37.548581)
			(xy 74.459592 -37.543994) (xy 74.37882 -37.5031) (xy 74.370213 -37.499258) (xy 74.351471 -37.497422)
			(xy 74.33332 -37.502438) (xy 74.32548 -37.507672) (xy 74.300685 -37.525306) (xy 74.24667 -37.553308)
			(xy 74.188895 -37.57238) (xy 74.128825 -37.582039) (xy 74.098404 -37.582602) (xy 74.071151 -37.582139)
			(xy 74.017201 -37.574383) (xy 73.964903 -37.559027) (xy 73.915324 -37.536385) (xy 73.869471 -37.506918)
			(xy 73.828278 -37.471225) (xy 73.792585 -37.430033) (xy 73.763117 -37.38418) (xy 73.740474 -37.3346)
			(xy 73.725118 -37.282303) (xy 73.717361 -37.228353) (xy 73.717361 -37.173847) (xy 73.725118 -37.119897)
			(xy 73.740474 -37.0676) (xy 73.763117 -37.01802) (xy 73.792585 -36.972167) (xy 73.828278 -36.930975)
			(xy 73.869471 -36.895282) (xy 73.915324 -36.865815) (xy 73.964903 -36.843173) (xy 74.017201 -36.827817)
			(xy 74.071151 -36.820061) (xy 74.098404 -36.819586) (xy 74.128824 -36.820178) (xy 74.188892 -36.829832)
			(xy 74.246668 -36.848893) (xy 74.300687 -36.876881) (xy 74.32548 -36.894516) (xy 74.333266 -36.899863)
			(xy 74.351452 -36.904915) (xy 74.370231 -36.90302) (xy 74.37882 -36.899088) (xy 74.459592 -36.858194)
			(xy 74.467824 -36.853639) (xy 74.480434 -36.839694) (xy 74.487144 -36.822131) (xy 74.487532 -36.812728)
			(xy 74.487532 -35.109658) (xy 74.46899 -35.083496) (xy 74.45375 -35.078162) (xy 74.427476 -35.068321)
			(xy 74.377911 -35.042034) (xy 74.332727 -35.008776) (xy 74.292899 -34.969261) (xy 74.275696 -34.947098)
			(xy 74.270362 -34.939986) (xy 74.248264 -34.925254) (xy 74.244312 -34.922823) (xy 74.235753 -34.919245)
			(xy 74.231246 -34.918142) (xy 74.20102 -34.911284) (xy 74.182224 -34.914078) (xy 74.173842 -34.91865)
			(xy 74.155461 -34.928878) (xy 74.117174 -34.946308) (xy 74.097388 -34.953448) (xy 74.073188 -34.961493)
			(xy 74.023454 -34.972789) (xy 73.972774 -34.978493) (xy 73.947274 -34.978848) (xy 73.921774 -34.978485)
			(xy 73.871093 -34.972789) (xy 73.821361 -34.961492) (xy 73.79716 -34.953448) (xy 73.777376 -34.946302)
			(xy 73.739088 -34.928875) (xy 73.720706 -34.91865) (xy 73.712324 -34.914078) (xy 73.693528 -34.911284)
			(xy 73.663302 -34.918142) (xy 73.65878 -34.919201) (xy 73.650209 -34.922772) (xy 73.646284 -34.925254)
			(xy 73.623932 -34.94024) (xy 73.618852 -34.947352) (xy 73.600701 -34.970652) (xy 73.558422 -35.01189)
			(xy 73.51029 -35.046117) (xy 73.457456 -35.072513) (xy 73.401185 -35.090447) (xy 73.342821 -35.09949)
			(xy 73.31329 -35.100006) (xy 73.302368 -35.100006) (xy 73.302114 -35.099752) (xy 73.275401 -35.098512)
			(xy 73.222693 -35.089484) (xy 73.171762 -35.073186) (xy 73.123605 -35.049937) (xy 73.079165 -35.020193)
			(xy 73.039313 -34.984536) (xy 73.004829 -34.943664) (xy 72.976388 -34.898379) (xy 72.954549 -34.849567)
			(xy 72.939737 -34.798183) (xy 72.932244 -34.745235) (xy 72.931782 -34.718498) (xy 72.932268 -34.691247)
			(xy 72.940025 -34.637299) (xy 72.95538 -34.585003) (xy 72.978021 -34.535426) (xy 73.007487 -34.489575)
			(xy 73.043178 -34.448384) (xy 73.084369 -34.412692) (xy 73.130219 -34.383225) (xy 73.179796 -34.360583)
			(xy 73.232091 -34.345226) (xy 73.286039 -34.337468) (xy 73.31329 -34.33699) (xy 73.328083 -34.337132)
			(xy 73.357581 -34.339417) (xy 73.372218 -34.341562) (xy 73.38314 -34.34334) (xy 73.404476 -34.337244)
			(xy 73.480168 -34.272728) (xy 73.489312 -34.252662) (xy 73.489312 -33.93694) (xy 73.489312 -33.92551)
			(xy 73.480168 -33.905444) (xy 73.404476 -33.840928) (xy 73.38314 -33.834832) (xy 73.372218 -33.83661)
			(xy 73.357392 -33.838782) (xy 73.327512 -33.84107) (xy 73.312528 -33.841182) (xy 73.312274 -33.841182)
			(xy 73.285071 -33.840626) (xy 73.231236 -33.832751) (xy 73.179066 -33.817307) (xy 73.129619 -33.794607)
			(xy 73.083899 -33.765112) (xy 73.042834 -33.729421) (xy 73.007256 -33.688257) (xy 72.977888 -33.642456)
			(xy 72.955324 -33.592947) (xy 72.940024 -33.540735) (xy 72.932298 -33.486878) (xy 72.931782 -33.459674)
			(xy 72.93227 -33.432424) (xy 72.940029 -33.378478) (xy 72.955386 -33.326186) (xy 72.978029 -33.276611)
			(xy 73.007496 -33.230764) (xy 73.043187 -33.189576) (xy 73.084376 -33.153886) (xy 73.130226 -33.124421)
			(xy 73.179801 -33.101781) (xy 73.232094 -33.086426) (xy 73.28604 -33.078668) (xy 73.31329 -33.078166)
			(xy 73.313544 -33.078166) (xy 73.34305 -33.07872) (xy 73.401359 -33.087808) (xy 73.457575 -33.105762)
			(xy 73.510358 -33.132152) (xy 73.558451 -33.166352) (xy 73.600708 -33.207545) (xy 73.618852 -33.23082)
			(xy 73.623932 -33.237932) (xy 73.646284 -33.252918) (xy 73.650234 -33.255354) (xy 73.658791 -33.258942)
			(xy 73.663302 -33.26003) (xy 73.693528 -33.266888) (xy 73.712324 -33.264094) (xy 73.720706 -33.259522)
			(xy 73.739088 -33.249297) (xy 73.777377 -33.231871) (xy 73.79716 -33.224724) (xy 73.821361 -33.216682)
			(xy 73.871095 -33.205392) (xy 73.921775 -33.199694) (xy 73.947274 -33.199324) (xy 73.972774 -33.199684)
			(xy 74.023457 -33.205374) (xy 74.073192 -33.216665) (xy 74.097388 -33.224724) (xy 74.117173 -33.231867)
			(xy 74.155463 -33.24929) (xy 74.173842 -33.259522) (xy 74.182224 -33.264094) (xy 74.20102 -33.266888)
			(xy 74.231246 -33.26003) (xy 74.235766 -33.258966) (xy 74.244331 -33.255386) (xy 74.248264 -33.252918)
			(xy 74.270362 -33.238186) (xy 74.275696 -33.231074) (xy 74.292897 -33.208908) (xy 74.332721 -33.169387)
			(xy 74.377904 -33.136125) (xy 74.427471 -33.109839) (xy 74.45375 -33.10001) (xy 74.46899 -33.094676)
			(xy 74.487532 -33.068514) (xy 74.487532 -31.509462) (xy 74.46899 -31.4833) (xy 74.45375 -31.477966)
			(xy 74.427476 -31.468125) (xy 74.377911 -31.441839) (xy 74.332727 -31.40858) (xy 74.292898 -31.369066)
			(xy 74.275696 -31.346902) (xy 74.270362 -31.33979) (xy 74.248264 -31.325058) (xy 74.244312 -31.322627)
			(xy 74.235753 -31.319049) (xy 74.231246 -31.317946) (xy 74.20102 -31.311088) (xy 74.182224 -31.313882)
			(xy 74.173842 -31.318454) (xy 74.155461 -31.328682) (xy 74.117174 -31.346112) (xy 74.097388 -31.353252)
			(xy 74.073188 -31.361297) (xy 74.023454 -31.372592) (xy 73.972774 -31.378296) (xy 73.947274 -31.378652)
			(xy 73.921774 -31.378289) (xy 73.871093 -31.372593) (xy 73.82136 -31.361296) (xy 73.79716 -31.353252)
			(xy 73.777376 -31.346106) (xy 73.739088 -31.328679) (xy 73.720706 -31.318454) (xy 73.712324 -31.313882)
			(xy 73.693528 -31.311088) (xy 73.663302 -31.317946) (xy 73.65878 -31.319005) (xy 73.650209 -31.322577)
			(xy 73.646284 -31.325058) (xy 73.623932 -31.340044) (xy 73.618852 -31.347156) (xy 73.600701 -31.370456)
			(xy 73.558422 -31.411694) (xy 73.51029 -31.44592) (xy 73.457456 -31.472316) (xy 73.401185 -31.490249)
			(xy 73.342821 -31.499293) (xy 73.31329 -31.49981) (xy 73.302368 -31.49981) (xy 73.302114 -31.499556)
			(xy 73.275401 -31.498316) (xy 73.222693 -31.489288) (xy 73.171762 -31.47299) (xy 73.123604 -31.449741)
			(xy 73.079164 -31.419997) (xy 73.039311 -31.38434) (xy 73.004827 -31.343469) (xy 72.976386 -31.298183)
			(xy 72.954546 -31.249371) (xy 72.939734 -31.197988) (xy 72.93224 -31.14504) (xy 72.931782 -31.118302)
			(xy 72.932268 -31.09105) (xy 72.940024 -31.037102) (xy 72.955379 -30.984806) (xy 72.97802 -30.935228)
			(xy 73.007486 -30.889377) (xy 73.043177 -30.848186) (xy 73.084367 -30.812493) (xy 73.130218 -30.783025)
			(xy 73.179795 -30.760383) (xy 73.23209 -30.745026) (xy 73.286038 -30.737268) (xy 73.31329 -30.736794)
			(xy 73.328083 -30.736936) (xy 73.357581 -30.739221) (xy 73.372218 -30.741366) (xy 73.38314 -30.743144)
			(xy 73.404476 -30.737048) (xy 73.480168 -30.672532) (xy 73.489312 -30.652466) (xy 73.489312 -30.336744)
			(xy 73.489312 -30.325314) (xy 73.480168 -30.305248) (xy 73.404476 -30.240732) (xy 73.38314 -30.234636)
			(xy 73.372218 -30.236414) (xy 73.357392 -30.238586) (xy 73.327512 -30.240874) (xy 73.312528 -30.240986)
			(xy 73.312274 -30.240986) (xy 73.285071 -30.24043) (xy 73.231236 -30.232555) (xy 73.179065 -30.217111)
			(xy 73.129619 -30.194411) (xy 73.083898 -30.164917) (xy 73.042833 -30.129225) (xy 73.007254 -30.088062)
			(xy 72.977885 -30.042261) (xy 72.955322 -29.992752) (xy 72.940021 -29.940539) (xy 72.932294 -29.886682)
			(xy 72.931782 -29.859478) (xy 72.932269 -29.832228) (xy 72.940028 -29.778282) (xy 72.955385 -29.725989)
			(xy 72.978027 -29.676414) (xy 73.007494 -29.630565) (xy 73.043186 -29.589377) (xy 73.084375 -29.553687)
			(xy 73.130224 -29.524222) (xy 73.1798 -29.501581) (xy 73.232093 -29.486226) (xy 73.28604 -29.478468)
			(xy 73.31329 -29.47797) (xy 73.313544 -29.47797) (xy 73.34305 -29.478524) (xy 73.401359 -29.487612)
			(xy 73.457575 -29.505566) (xy 73.510358 -29.531957) (xy 73.55845 -29.566156) (xy 73.600707 -29.60735)
			(xy 73.618852 -29.630624) (xy 73.623932 -29.637736) (xy 73.646284 -29.652722) (xy 73.650234 -29.655158)
			(xy 73.658791 -29.658746) (xy 73.663302 -29.659834) (xy 73.693528 -29.666692) (xy 73.712324 -29.663898)
			(xy 73.720706 -29.659326) (xy 73.739088 -29.649101) (xy 73.777377 -29.631675) (xy 73.79716 -29.624528)
			(xy 73.821361 -29.616486) (xy 73.871095 -29.605196) (xy 73.921775 -29.599498) (xy 73.947274 -29.599128)
			(xy 73.972774 -29.599488) (xy 74.023457 -29.605178) (xy 74.073192 -29.616469) (xy 74.097388 -29.624528)
			(xy 74.117173 -29.631672) (xy 74.155463 -29.649094) (xy 74.173842 -29.659326) (xy 74.182224 -29.663898)
			(xy 74.20102 -29.666692) (xy 74.231246 -29.659834) (xy 74.235766 -29.65877) (xy 74.244332 -29.655191)
			(xy 74.248264 -29.652722) (xy 74.270362 -29.63799) (xy 74.275696 -29.630878) (xy 74.292897 -29.608712)
			(xy 74.332721 -29.569191) (xy 74.377903 -29.535928) (xy 74.42747 -29.509642) (xy 74.45375 -29.499814)
			(xy 74.46899 -29.49448) (xy 74.487532 -29.468318) (xy 74.487532 -19.837908) (xy 74.487323 -19.831327)
			(xy 74.48398 -19.818596) (xy 74.480928 -19.812762) (xy 74.465688 -19.786346) (xy 74.45756 -19.77771)
			(xy 74.452226 -19.774154) (xy 74.430427 -19.759651) (xy 74.390641 -19.725614) (xy 74.355881 -19.686459)
			(xy 74.340974 -19.664934) (xy 74.34072 -19.66468) (xy 74.34072 -19.664426) (xy 74.334434 -19.656124)
			(xy 74.316875 -19.644968) (xy 74.306684 -19.642836) (xy 74.233278 -19.631152) (xy 74.222918 -19.629989)
			(xy 74.202735 -19.635122) (xy 74.194162 -19.641058) (xy 74.174005 -19.656167) (xy 74.130473 -19.681519)
			(xy 74.083988 -19.700929) (xy 74.035354 -19.714061) (xy 73.985416 -19.720686) (xy 73.960228 -19.721068)
			(xy 73.952608 -19.721068) (xy 73.925714 -19.72007) (xy 73.872593 -19.711447) (xy 73.821211 -19.695443)
			(xy 73.772589 -19.672376) (xy 73.727692 -19.642703) (xy 73.687411 -19.607015) (xy 73.652546 -19.566019)
			(xy 73.62379 -19.520529) (xy 73.601713 -19.471449) (xy 73.586753 -19.419754) (xy 73.579209 -19.366468)
			(xy 73.57872 -19.33956) (xy 73.579209 -19.312311) (xy 73.58697 -19.25837) (xy 73.602329 -19.206081)
			(xy 73.624973 -19.156511) (xy 73.654441 -19.110668) (xy 73.690133 -19.069484) (xy 73.731322 -19.0338)
			(xy 73.777171 -19.00434) (xy 73.826745 -18.981705) (xy 73.879036 -18.966356) (xy 73.932979 -18.958604)
			(xy 73.960228 -18.958052) (xy 73.964292 -18.958052) (xy 73.979532 -18.958306) (xy 74.005694 -18.941288)
			(xy 74.048112 -18.840196) (xy 74.05166 -18.83075) (xy 74.051769 -18.810589) (xy 74.044059 -18.79196)
			(xy 74.03719 -18.78457) (xy 73.667874 -18.415254) (xy 73.660762 -18.407888) (xy 73.641966 -18.400268)
			(xy 61.929264 -18.400268) (xy 61.919196 -18.400697) (xy 61.900598 -18.408417) (xy 61.893196 -18.415254)
			(xy 61.558932 -18.749518) (xy 61.551566 -18.75663) (xy 61.543946 -18.775426) (xy 61.543946 -21.738336)
			(xy 63.416688 -21.738336) (xy 63.417176 -21.709596) (xy 63.425808 -21.652767) (xy 63.442866 -21.597876)
			(xy 63.467966 -21.546165) (xy 63.500538 -21.498804) (xy 63.519812 -21.477478) (xy 63.526416 -21.470366)
			(xy 63.533528 -21.45284) (xy 63.533528 -21.363432) (xy 63.526416 -21.345906) (xy 63.519812 -21.338794)
			(xy 63.500577 -21.317436) (xy 63.468012 -21.270079) (xy 63.442919 -21.218372) (xy 63.425867 -21.163486)
			(xy 63.417241 -21.106663) (xy 63.417238 -21.049189) (xy 63.425855 -20.992365) (xy 63.4429 -20.937477)
			(xy 63.467986 -20.885767) (xy 63.500544 -20.838405) (xy 63.519812 -20.817078) (xy 63.526416 -20.809966)
			(xy 63.533528 -20.79244) (xy 63.533528 -20.703032) (xy 63.526416 -20.685506) (xy 63.519812 -20.678394)
			(xy 63.500577 -20.657036) (xy 63.468012 -20.609679) (xy 63.442919 -20.557972) (xy 63.425867 -20.503086)
			(xy 63.417241 -20.446263) (xy 63.417238 -20.388789) (xy 63.425855 -20.331965) (xy 63.4429 -20.277077)
			(xy 63.467986 -20.225367) (xy 63.500544 -20.178005) (xy 63.519812 -20.156678) (xy 63.526416 -20.149566)
			(xy 63.533528 -20.13204) (xy 63.533528 -20.042632) (xy 63.526416 -20.025106) (xy 63.519812 -20.017994)
			(xy 63.500577 -19.996636) (xy 63.468012 -19.949279) (xy 63.442919 -19.897572) (xy 63.425867 -19.842686)
			(xy 63.417241 -19.785863) (xy 63.417238 -19.728389) (xy 63.425855 -19.671565) (xy 63.4429 -19.616677)
			(xy 63.467986 -19.564967) (xy 63.500544 -19.517605) (xy 63.519812 -19.496278) (xy 63.526416 -19.489166)
			(xy 63.533528 -19.47164) (xy 63.533528 -19.382232) (xy 63.526416 -19.364706) (xy 63.519812 -19.357594)
			(xy 63.500554 -19.336256) (xy 63.467987 -19.288897) (xy 63.442893 -19.237188) (xy 63.425839 -19.182299)
			(xy 63.417212 -19.125474) (xy 63.416688 -19.096736) (xy 63.417174 -19.069485) (xy 63.42493 -19.015537)
			(xy 63.440285 -18.963242) (xy 63.462927 -18.913665) (xy 63.492393 -18.867815) (xy 63.528084 -18.826624)
			(xy 63.569275 -18.790933) (xy 63.615125 -18.761467) (xy 63.664702 -18.738825) (xy 63.716997 -18.72347)
			(xy 63.770945 -18.715714) (xy 63.825447 -18.715714) (xy 63.879395 -18.72347) (xy 63.93169 -18.738825)
			(xy 63.981267 -18.761467) (xy 64.027117 -18.790933) (xy 64.068308 -18.826624) (xy 64.103999 -18.867815)
			(xy 64.133465 -18.913665) (xy 64.156107 -18.963242) (xy 64.171462 -19.015537) (xy 64.179218 -19.069485)
			(xy 64.179704 -19.096736) (xy 64.179201 -19.125476) (xy 64.170573 -19.182304) (xy 64.153518 -19.237195)
			(xy 64.128422 -19.288906) (xy 64.095853 -19.336268) (xy 64.07658 -19.357594) (xy 64.069976 -19.364706)
			(xy 64.062864 -19.382232) (xy 64.062864 -19.47164) (xy 64.069976 -19.489166) (xy 64.07658 -19.496278)
			(xy 64.095886 -19.517574) (xy 64.12845 -19.564942) (xy 64.153539 -19.616659) (xy 64.170587 -19.671554)
			(xy 64.179206 -19.728386) (xy 64.179202 -19.785867) (xy 64.170575 -19.842697) (xy 64.15352 -19.89759)
			(xy 64.128424 -19.949304) (xy 64.095853 -19.996667) (xy 64.07658 -20.017994) (xy 64.069976 -20.025106)
			(xy 64.062864 -20.042632) (xy 64.062864 -20.13204) (xy 64.069976 -20.149566) (xy 64.07658 -20.156678)
			(xy 64.095886 -20.177974) (xy 64.12845 -20.225342) (xy 64.153539 -20.277059) (xy 64.170587 -20.331954)
			(xy 64.174167 -20.35556) (xy 73.57821 -20.35556) (xy 73.582281 -20.299938) (xy 73.594407 -20.245501)
			(xy 73.61433 -20.19341) (xy 73.641626 -20.144775) (xy 73.675712 -20.100632) (xy 73.715861 -20.061923)
			(xy 73.761219 -20.029472) (xy 73.810819 -20.003971) (xy 73.863603 -19.985964) (xy 73.918446 -19.975834)
			(xy 73.97418 -19.973797) (xy 74.029617 -19.979897) (xy 74.083574 -19.994003) (xy 74.134903 -20.015815)
			(xy 74.182509 -20.044869) (xy 74.225377 -20.080544) (xy 74.262594 -20.122081) (xy 74.293367 -20.168594)
			(xy 74.317039 -20.219091) (xy 74.333107 -20.272498) (xy 74.341227 -20.327674) (xy 74.341736 -20.35556)
			(xy 74.341227 -20.383446) (xy 74.333107 -20.438622) (xy 74.317039 -20.492029) (xy 74.293367 -20.542526)
			(xy 74.262594 -20.589039) (xy 74.225377 -20.630576) (xy 74.182509 -20.666251) (xy 74.134903 -20.695305)
			(xy 74.083574 -20.717117) (xy 74.029617 -20.731223) (xy 73.97418 -20.737323) (xy 73.918446 -20.735286)
			(xy 73.863603 -20.725156) (xy 73.810819 -20.707149) (xy 73.761219 -20.681648) (xy 73.715861 -20.649197)
			(xy 73.675712 -20.610488) (xy 73.641626 -20.566345) (xy 73.61433 -20.51771) (xy 73.594407 -20.465619)
			(xy 73.582281 -20.411182) (xy 73.57821 -20.35556) (xy 64.174167 -20.35556) (xy 64.179206 -20.388786)
			(xy 64.179202 -20.446267) (xy 64.170575 -20.503097) (xy 64.15352 -20.55799) (xy 64.128424 -20.609704)
			(xy 64.095853 -20.657067) (xy 64.07658 -20.678394) (xy 64.069976 -20.685506) (xy 64.062864 -20.703032)
			(xy 64.062864 -20.79244) (xy 64.069976 -20.809966) (xy 64.07658 -20.817078) (xy 64.095886 -20.838374)
			(xy 64.12845 -20.885742) (xy 64.153539 -20.937459) (xy 64.170587 -20.992354) (xy 64.179206 -21.049186)
			(xy 64.179202 -21.106667) (xy 64.170575 -21.163497) (xy 64.15352 -21.21839) (xy 64.128424 -21.270104)
			(xy 64.095853 -21.317467) (xy 64.07658 -21.338794) (xy 64.069976 -21.345906) (xy 64.062864 -21.363432)
			(xy 64.062864 -21.37156) (xy 73.57821 -21.37156) (xy 73.582281 -21.315938) (xy 73.594407 -21.261501)
			(xy 73.61433 -21.20941) (xy 73.641626 -21.160775) (xy 73.675712 -21.116632) (xy 73.715861 -21.077923)
			(xy 73.761219 -21.045472) (xy 73.810819 -21.019971) (xy 73.863603 -21.001964) (xy 73.918446 -20.991834)
			(xy 73.97418 -20.989797) (xy 74.029617 -20.995897) (xy 74.083574 -21.010003) (xy 74.134903 -21.031815)
			(xy 74.182509 -21.060869) (xy 74.225377 -21.096544) (xy 74.262594 -21.138081) (xy 74.293367 -21.184594)
			(xy 74.317039 -21.235091) (xy 74.333107 -21.288498) (xy 74.341227 -21.343674) (xy 74.341736 -21.37156)
			(xy 74.341227 -21.399446) (xy 74.333107 -21.454622) (xy 74.317039 -21.508029) (xy 74.293367 -21.558526)
			(xy 74.262594 -21.605039) (xy 74.225377 -21.646576) (xy 74.182509 -21.682251) (xy 74.134903 -21.711305)
			(xy 74.083574 -21.733117) (xy 74.029617 -21.747223) (xy 73.97418 -21.753323) (xy 73.918446 -21.751286)
			(xy 73.863603 -21.741156) (xy 73.810819 -21.723149) (xy 73.761219 -21.697648) (xy 73.715861 -21.665197)
			(xy 73.675712 -21.626488) (xy 73.641626 -21.582345) (xy 73.61433 -21.53371) (xy 73.594407 -21.481619)
			(xy 73.582281 -21.427182) (xy 73.57821 -21.37156) (xy 64.062864 -21.37156) (xy 64.062864 -21.45284)
			(xy 64.069976 -21.470366) (xy 64.07658 -21.477478) (xy 64.095871 -21.498788) (xy 64.128434 -21.546155)
			(xy 64.153522 -21.597871) (xy 64.170568 -21.652765) (xy 64.179186 -21.709596) (xy 64.179704 -21.738336)
			(xy 64.179218 -21.765587) (xy 64.171462 -21.819535) (xy 64.156107 -21.87183) (xy 64.133465 -21.921407)
			(xy 64.103999 -21.967257) (xy 64.068308 -22.008448) (xy 64.027117 -22.044139) (xy 63.981267 -22.073605)
			(xy 63.93169 -22.096247) (xy 63.879395 -22.111602) (xy 63.825447 -22.119358) (xy 63.770945 -22.119358)
			(xy 63.716997 -22.111602) (xy 63.664702 -22.096247) (xy 63.615125 -22.073605) (xy 63.569275 -22.044139)
			(xy 63.528084 -22.008448) (xy 63.492393 -21.967257) (xy 63.462927 -21.921407) (xy 63.440285 -21.87183)
			(xy 63.42493 -21.819535) (xy 63.417174 -21.765587) (xy 63.416688 -21.738336) (xy 61.543946 -21.738336)
			(xy 61.543946 -22.995159) (xy 63.287011 -22.995159) (xy 63.294831 -22.935726) (xy 63.310343 -22.877822)
			(xy 63.333279 -22.822438) (xy 63.363249 -22.770521) (xy 63.399739 -22.722961) (xy 63.442125 -22.680571)
			(xy 63.489681 -22.644076) (xy 63.541594 -22.614101) (xy 63.596976 -22.591158) (xy 63.654879 -22.575641)
			(xy 63.714311 -22.567814) (xy 63.774257 -22.567812) (xy 63.83369 -22.575634) (xy 63.891594 -22.591148)
			(xy 63.946977 -22.614086) (xy 63.998892 -22.644058) (xy 64.046451 -22.68055) (xy 64.08884 -22.722937)
			(xy 64.125333 -22.770495) (xy 64.155306 -22.822409) (xy 64.178247 -22.877791) (xy 64.193763 -22.935694)
			(xy 64.201587 -22.995127) (xy 64.202056 -23.0251) (xy 64.201833 -23.045661) (xy 64.198144 -23.086618)
			(xy 64.19469 -23.106888) (xy 64.19215 -23.120604) (xy 64.20104 -23.145496) (xy 64.287654 -23.22068)
			(xy 64.313562 -23.226014) (xy 64.32677 -23.221696) (xy 64.355974 -23.212613) (xy 64.416335 -23.202786)
			(xy 64.446912 -23.202138) (xy 64.465839 -23.202406) (xy 64.503501 -23.206219) (xy 64.522096 -23.209758)
			(xy 64.534796 -23.212044) (xy 64.558418 -23.205186) (xy 64.636904 -23.128986) (xy 64.644524 -23.105618)
			(xy 64.642492 -23.092918) (xy 64.639432 -23.073888) (xy 64.636121 -23.035483) (xy 64.635888 -23.01621)
			(xy 64.63635 -22.98624) (xy 64.644173 -22.926813) (xy 64.659685 -22.868915) (xy 64.682622 -22.813538)
			(xy 64.712591 -22.761628) (xy 64.749079 -22.714074) (xy 64.791462 -22.671689) (xy 64.839015 -22.6352)
			(xy 64.890924 -22.605229) (xy 64.946301 -22.58229) (xy 65.004198 -22.566776) (xy 65.063625 -22.558951)
			(xy 65.123565 -22.558951) (xy 65.182992 -22.566774) (xy 65.240889 -22.582287) (xy 65.296266 -22.605224)
			(xy 65.348176 -22.635194) (xy 65.39573 -22.671682) (xy 65.438114 -22.714066) (xy 65.474603 -22.761619)
			(xy 65.504573 -22.813528) (xy 65.527511 -22.868905) (xy 65.543025 -22.926803) (xy 65.550849 -22.986229)
			(xy 65.550849 -23.046169) (xy 65.543025 -23.105596) (xy 65.527512 -23.163493) (xy 65.504574 -23.218871)
			(xy 65.474604 -23.27078) (xy 65.438115 -23.318333) (xy 65.395731 -23.360717) (xy 65.348177 -23.397206)
			(xy 65.296268 -23.427175) (xy 65.24089 -23.450113) (xy 65.182993 -23.465626) (xy 65.123566 -23.473449)
			(xy 65.093596 -23.473918) (xy 65.059351 -23.473322) (xy 64.991625 -23.463112) (xy 64.958722 -23.453598)
			(xy 64.94653 -23.449788) (xy 64.9224 -23.45436) (xy 64.836548 -23.522178) (xy 64.826642 -23.544784)
			(xy 64.827658 -23.557738) (xy 64.82842 -23.583646) (xy 64.827934 -23.610897) (xy 64.82663 -23.619964)
			(xy 68.009244 -23.619964) (xy 68.009244 -23.560028) (xy 68.017067 -23.500606) (xy 68.03258 -23.442713)
			(xy 68.055516 -23.38734) (xy 68.085483 -23.335434) (xy 68.12197 -23.287884) (xy 68.16435 -23.245504)
			(xy 68.2119 -23.209017) (xy 68.263806 -23.17905) (xy 68.319179 -23.156114) (xy 68.377072 -23.140601)
			(xy 68.436494 -23.132778) (xy 68.49643 -23.132778) (xy 68.555852 -23.140601) (xy 68.613745 -23.156114)
			(xy 68.669118 -23.17905) (xy 68.721024 -23.209017) (xy 68.768574 -23.245504) (xy 68.810954 -23.287884)
			(xy 68.847441 -23.335434) (xy 68.877408 -23.38734) (xy 68.900344 -23.442713) (xy 68.915857 -23.500606)
			(xy 68.92368 -23.560028) (xy 68.92417 -23.589996) (xy 68.92368 -23.619964) (xy 68.915857 -23.679386)
			(xy 68.900344 -23.737279) (xy 68.877408 -23.792652) (xy 68.847441 -23.844558) (xy 68.820001 -23.880318)
			(xy 69.240652 -23.880318) (xy 69.244723 -23.824696) (xy 69.256849 -23.770259) (xy 69.276772 -23.718168)
			(xy 69.304068 -23.669533) (xy 69.338154 -23.62539) (xy 69.378303 -23.586681) (xy 69.423661 -23.55423)
			(xy 69.473261 -23.528729) (xy 69.526045 -23.510722) (xy 69.580888 -23.500592) (xy 69.636622 -23.498555)
			(xy 69.692059 -23.504655) (xy 69.746016 -23.518761) (xy 69.797345 -23.540573) (xy 69.844951 -23.569627)
			(xy 69.887819 -23.605302) (xy 69.925036 -23.646839) (xy 69.955809 -23.693352) (xy 69.979481 -23.743849)
			(xy 69.995549 -23.797256) (xy 70.003669 -23.852432) (xy 70.004178 -23.880318) (xy 70.256652 -23.880318)
			(xy 70.260723 -23.824696) (xy 70.272849 -23.770259) (xy 70.292772 -23.718168) (xy 70.320068 -23.669533)
			(xy 70.354154 -23.62539) (xy 70.394303 -23.586681) (xy 70.439661 -23.55423) (xy 70.489261 -23.528729)
			(xy 70.542045 -23.510722) (xy 70.596888 -23.500592) (xy 70.652622 -23.498555) (xy 70.708059 -23.504655)
			(xy 70.762016 -23.518761) (xy 70.813345 -23.540573) (xy 70.860951 -23.569627) (xy 70.903819 -23.605302)
			(xy 70.941036 -23.646839) (xy 70.971809 -23.693352) (xy 70.995481 -23.743849) (xy 71.011549 -23.797256)
			(xy 71.019669 -23.852432) (xy 71.020178 -23.880318) (xy 71.272652 -23.880318) (xy 71.276723 -23.824696)
			(xy 71.288849 -23.770259) (xy 71.308772 -23.718168) (xy 71.336068 -23.669533) (xy 71.370154 -23.62539)
			(xy 71.410303 -23.586681) (xy 71.455661 -23.55423) (xy 71.505261 -23.528729) (xy 71.558045 -23.510722)
			(xy 71.612888 -23.500592) (xy 71.668622 -23.498555) (xy 71.724059 -23.504655) (xy 71.778016 -23.518761)
			(xy 71.829345 -23.540573) (xy 71.876951 -23.569627) (xy 71.919819 -23.605302) (xy 71.957036 -23.646839)
			(xy 71.987809 -23.693352) (xy 72.011481 -23.743849) (xy 72.027549 -23.797256) (xy 72.035669 -23.852432)
			(xy 72.036178 -23.880318) (xy 72.290938 -23.880318) (xy 72.295009 -23.824696) (xy 72.307135 -23.770259)
			(xy 72.327058 -23.718168) (xy 72.354354 -23.669533) (xy 72.38844 -23.62539) (xy 72.428589 -23.586681)
			(xy 72.473947 -23.55423) (xy 72.523547 -23.528729) (xy 72.576331 -23.510722) (xy 72.631174 -23.500592)
			(xy 72.686908 -23.498555) (xy 72.742345 -23.504655) (xy 72.796302 -23.518761) (xy 72.847631 -23.540573)
			(xy 72.895237 -23.569627) (xy 72.938105 -23.605302) (xy 72.975322 -23.646839) (xy 73.006095 -23.693352)
			(xy 73.029767 -23.743849) (xy 73.045835 -23.797256) (xy 73.053955 -23.852432) (xy 73.054464 -23.880318)
			(xy 73.053955 -23.908204) (xy 73.045835 -23.96338) (xy 73.029767 -24.016787) (xy 73.006095 -24.067284)
			(xy 72.975322 -24.113797) (xy 72.938105 -24.155334) (xy 72.895237 -24.191009) (xy 72.847631 -24.220063)
			(xy 72.796302 -24.241875) (xy 72.742345 -24.255981) (xy 72.686908 -24.262081) (xy 72.631174 -24.260044)
			(xy 72.576331 -24.249914) (xy 72.523547 -24.231907) (xy 72.473947 -24.206406) (xy 72.428589 -24.173955)
			(xy 72.38844 -24.135246) (xy 72.354354 -24.091103) (xy 72.327058 -24.042468) (xy 72.307135 -23.990377)
			(xy 72.295009 -23.93594) (xy 72.290938 -23.880318) (xy 72.036178 -23.880318) (xy 72.035669 -23.908204)
			(xy 72.027549 -23.96338) (xy 72.011481 -24.016787) (xy 71.987809 -24.067284) (xy 71.957036 -24.113797)
			(xy 71.919819 -24.155334) (xy 71.876951 -24.191009) (xy 71.829345 -24.220063) (xy 71.778016 -24.241875)
			(xy 71.724059 -24.255981) (xy 71.668622 -24.262081) (xy 71.612888 -24.260044) (xy 71.558045 -24.249914)
			(xy 71.505261 -24.231907) (xy 71.455661 -24.206406) (xy 71.410303 -24.173955) (xy 71.370154 -24.135246)
			(xy 71.336068 -24.091103) (xy 71.308772 -24.042468) (xy 71.288849 -23.990377) (xy 71.276723 -23.93594)
			(xy 71.272652 -23.880318) (xy 71.020178 -23.880318) (xy 71.019669 -23.908204) (xy 71.011549 -23.96338)
			(xy 70.995481 -24.016787) (xy 70.971809 -24.067284) (xy 70.941036 -24.113797) (xy 70.903819 -24.155334)
			(xy 70.860951 -24.191009) (xy 70.813345 -24.220063) (xy 70.762016 -24.241875) (xy 70.708059 -24.255981)
			(xy 70.652622 -24.262081) (xy 70.596888 -24.260044) (xy 70.542045 -24.249914) (xy 70.489261 -24.231907)
			(xy 70.439661 -24.206406) (xy 70.394303 -24.173955) (xy 70.354154 -24.135246) (xy 70.320068 -24.091103)
			(xy 70.292772 -24.042468) (xy 70.272849 -23.990377) (xy 70.260723 -23.93594) (xy 70.256652 -23.880318)
			(xy 70.004178 -23.880318) (xy 70.003669 -23.908204) (xy 69.995549 -23.96338) (xy 69.979481 -24.016787)
			(xy 69.955809 -24.067284) (xy 69.925036 -24.113797) (xy 69.887819 -24.155334) (xy 69.844951 -24.191009)
			(xy 69.797345 -24.220063) (xy 69.746016 -24.241875) (xy 69.692059 -24.255981) (xy 69.636622 -24.262081)
			(xy 69.580888 -24.260044) (xy 69.526045 -24.249914) (xy 69.473261 -24.231907) (xy 69.423661 -24.206406)
			(xy 69.378303 -24.173955) (xy 69.338154 -24.135246) (xy 69.304068 -24.091103) (xy 69.276772 -24.042468)
			(xy 69.256849 -23.990377) (xy 69.244723 -23.93594) (xy 69.240652 -23.880318) (xy 68.820001 -23.880318)
			(xy 68.810954 -23.892108) (xy 68.768574 -23.934488) (xy 68.721024 -23.970975) (xy 68.669118 -24.000942)
			(xy 68.613745 -24.023878) (xy 68.555852 -24.039391) (xy 68.49643 -24.047214) (xy 68.436494 -24.047214)
			(xy 68.377072 -24.039391) (xy 68.319179 -24.023878) (xy 68.263806 -24.000942) (xy 68.2119 -23.970975)
			(xy 68.16435 -23.934488) (xy 68.12197 -23.892108) (xy 68.085483 -23.844558) (xy 68.055516 -23.792652)
			(xy 68.03258 -23.737279) (xy 68.017067 -23.679386) (xy 68.009244 -23.619964) (xy 64.82663 -23.619964)
			(xy 64.820178 -23.664845) (xy 64.804823 -23.71714) (xy 64.782181 -23.766717) (xy 64.752715 -23.812567)
			(xy 64.717024 -23.853758) (xy 64.675833 -23.889449) (xy 64.629983 -23.918915) (xy 64.580406 -23.941557)
			(xy 64.528111 -23.956912) (xy 64.474163 -23.964668) (xy 64.419661 -23.964668) (xy 64.365713 -23.956912)
			(xy 64.313418 -23.941557) (xy 64.263841 -23.918915) (xy 64.217991 -23.889449) (xy 64.1768 -23.853758)
			(xy 64.141109 -23.812567) (xy 64.111643 -23.766717) (xy 64.089001 -23.71714) (xy 64.073646 -23.664845)
			(xy 64.06589 -23.610897) (xy 64.065404 -23.583646) (xy 64.067182 -23.548086) (xy 64.068452 -23.53437)
			(xy 64.05753 -23.51024) (xy 63.964566 -23.44293) (xy 63.93815 -23.439882) (xy 63.925704 -23.44547)
			(xy 63.896949 -23.457294) (xy 63.837042 -23.473928) (xy 63.775435 -23.482305) (xy 63.744348 -23.482808)
			(xy 63.714375 -23.48239) (xy 63.654941 -23.474572) (xy 63.597037 -23.459063) (xy 63.541652 -23.436128)
			(xy 63.489735 -23.40616) (xy 63.442173 -23.369671) (xy 63.399781 -23.327287) (xy 63.363285 -23.279732)
			(xy 63.333308 -23.22782) (xy 63.310363 -23.172439) (xy 63.294844 -23.114537) (xy 63.287015 -23.055105)
			(xy 63.287011 -22.995159) (xy 61.543946 -22.995159) (xy 61.543946 -24.189944) (xy 63.29883 -24.189944)
			(xy 63.302901 -24.134322) (xy 63.315027 -24.079885) (xy 63.33495 -24.027794) (xy 63.362246 -23.979159)
			(xy 63.396332 -23.935016) (xy 63.436481 -23.896307) (xy 63.481839 -23.863856) (xy 63.531439 -23.838355)
			(xy 63.584223 -23.820348) (xy 63.639066 -23.810218) (xy 63.6948 -23.808181) (xy 63.750237 -23.814281)
			(xy 63.804194 -23.828387) (xy 63.855523 -23.850199) (xy 63.903129 -23.879253) (xy 63.945997 -23.914928)
			(xy 63.983214 -23.956465) (xy 64.013987 -24.002978) (xy 64.037659 -24.053475) (xy 64.053727 -24.106882)
			(xy 64.061847 -24.162058) (xy 64.062356 -24.189944) (xy 65.821812 -24.189944) (xy 65.825883 -24.134322)
			(xy 65.838009 -24.079885) (xy 65.857932 -24.027794) (xy 65.885228 -23.979159) (xy 65.919314 -23.935016)
			(xy 65.959463 -23.896307) (xy 66.004821 -23.863856) (xy 66.054421 -23.838355) (xy 66.107205 -23.820348)
			(xy 66.162048 -23.810218) (xy 66.217782 -23.808181) (xy 66.273219 -23.814281) (xy 66.327176 -23.828387)
			(xy 66.378505 -23.850199) (xy 66.426111 -23.879253) (xy 66.468979 -23.914928) (xy 66.506196 -23.956465)
			(xy 66.536969 -24.002978) (xy 66.560641 -24.053475) (xy 66.576709 -24.106882) (xy 66.584829 -24.162058)
			(xy 66.585338 -24.189944) (xy 66.584829 -24.21783) (xy 66.576709 -24.273006) (xy 66.560641 -24.326413)
			(xy 66.536969 -24.37691) (xy 66.506196 -24.423423) (xy 66.468979 -24.46496) (xy 66.426111 -24.500635)
			(xy 66.378505 -24.529689) (xy 66.327176 -24.551501) (xy 66.273219 -24.565607) (xy 66.217782 -24.571707)
			(xy 66.162048 -24.56967) (xy 66.107205 -24.55954) (xy 66.054421 -24.541533) (xy 66.004821 -24.516032)
			(xy 65.959463 -24.483581) (xy 65.919314 -24.444872) (xy 65.885228 -24.400729) (xy 65.857932 -24.352094)
			(xy 65.838009 -24.300003) (xy 65.825883 -24.245566) (xy 65.821812 -24.189944) (xy 64.062356 -24.189944)
			(xy 64.061847 -24.21783) (xy 64.053727 -24.273006) (xy 64.037659 -24.326413) (xy 64.013987 -24.37691)
			(xy 63.983214 -24.423423) (xy 63.945997 -24.46496) (xy 63.903129 -24.500635) (xy 63.855523 -24.529689)
			(xy 63.804194 -24.551501) (xy 63.750237 -24.565607) (xy 63.6948 -24.571707) (xy 63.639066 -24.56967)
			(xy 63.584223 -24.55954) (xy 63.531439 -24.541533) (xy 63.481839 -24.516032) (xy 63.436481 -24.483581)
			(xy 63.396332 -24.444872) (xy 63.362246 -24.400729) (xy 63.33495 -24.352094) (xy 63.315027 -24.300003)
			(xy 63.302901 -24.245566) (xy 63.29883 -24.189944) (xy 61.543946 -24.189944) (xy 61.543946 -25.390094)
			(xy 65.733422 -25.390094) (xy 65.733912 -25.360126) (xy 65.741735 -25.300704) (xy 65.757248 -25.242811)
			(xy 65.780184 -25.187438) (xy 65.810151 -25.135532) (xy 65.846638 -25.087982) (xy 65.889018 -25.045602)
			(xy 65.936568 -25.009115) (xy 65.988474 -24.979148) (xy 66.043847 -24.956212) (xy 66.10174 -24.940699)
			(xy 66.161162 -24.932876) (xy 66.221098 -24.932876) (xy 66.28052 -24.940699) (xy 66.338413 -24.956212)
			(xy 66.393786 -24.979148) (xy 66.445692 -25.009115) (xy 66.493242 -25.045602) (xy 66.535622 -25.087982)
			(xy 66.572109 -25.135532) (xy 66.602076 -25.187438) (xy 66.625012 -25.242811) (xy 66.640525 -25.300704)
			(xy 66.648348 -25.360126) (xy 66.648838 -25.390094) (xy 66.64839 -25.418878) (xy 66.641173 -25.475991)
			(xy 66.62685 -25.531749) (xy 66.605649 -25.585271) (xy 66.577904 -25.635712) (xy 66.544054 -25.682275)
			(xy 66.504631 -25.724227) (xy 66.482722 -25.7429) (xy 66.47434 -25.749758) (xy 66.464688 -25.769316)
			(xy 66.461386 -25.867106) (xy 66.469514 -25.887172) (xy 66.477642 -25.894792) (xy 66.49604 -25.912871)
			(xy 66.528278 -25.953137) (xy 66.554802 -25.997376) (xy 66.57513 -26.044783) (xy 66.588891 -26.094495)
			(xy 66.595835 -26.145607) (xy 66.59626 -26.171398) (xy 66.595774 -26.198649) (xy 66.588018 -26.252597)
			(xy 66.572663 -26.304892) (xy 66.550021 -26.354469) (xy 66.520555 -26.400319) (xy 66.484864 -26.44151)
			(xy 66.443673 -26.477201) (xy 66.397823 -26.506667) (xy 66.348246 -26.529309) (xy 66.295951 -26.544664)
			(xy 66.242003 -26.55242) (xy 66.187501 -26.55242) (xy 66.133553 -26.544664) (xy 66.081258 -26.529309)
			(xy 66.031681 -26.506667) (xy 65.985831 -26.477201) (xy 65.94464 -26.44151) (xy 65.908949 -26.400319)
			(xy 65.879483 -26.354469) (xy 65.856841 -26.304892) (xy 65.841486 -26.252597) (xy 65.83373 -26.198649)
			(xy 65.833244 -26.171398) (xy 65.833749 -26.142754) (xy 65.842348 -26.086115) (xy 65.859322 -26.031398)
			(xy 65.884288 -25.979836) (xy 65.916686 -25.932588) (xy 65.93586 -25.911302) (xy 65.943226 -25.903174)
			(xy 65.950084 -25.8826) (xy 65.94094 -25.785064) (xy 65.930272 -25.766268) (xy 65.921382 -25.759918)
			(xy 65.896852 -25.741344) (xy 65.852454 -25.698749) (xy 65.81416 -25.650591) (xy 65.78266 -25.59774)
			(xy 65.758521 -25.541145) (xy 65.742179 -25.481829) (xy 65.733927 -25.420857) (xy 65.733422 -25.390094)
			(xy 61.543946 -25.390094) (xy 61.543946 -25.501854) (xy 61.544962 -25.512014) (xy 61.547756 -25.526492)
			(xy 61.55182 -25.53589) (xy 61.61024 -25.593802) (xy 61.617652 -25.60048) (xy 61.636088 -25.608047)
			(xy 61.646054 -25.608534) (xy 61.648848 -25.608534) (xy 61.676094 -25.609023) (xy 61.730031 -25.616785)
			(xy 61.782314 -25.632142) (xy 61.831879 -25.654784) (xy 61.877719 -25.684248) (xy 61.918899 -25.719935)
			(xy 61.954581 -25.76112) (xy 61.984039 -25.806963) (xy 62.006675 -25.856531) (xy 62.022026 -25.908816)
			(xy 62.02978 -25.962754) (xy 62.02978 -25.990042) (xy 63.29883 -25.990042) (xy 63.302901 -25.93442)
			(xy 63.315027 -25.879983) (xy 63.33495 -25.827892) (xy 63.362246 -25.779257) (xy 63.396332 -25.735114)
			(xy 63.436481 -25.696405) (xy 63.481839 -25.663954) (xy 63.531439 -25.638453) (xy 63.584223 -25.620446)
			(xy 63.639066 -25.610316) (xy 63.6948 -25.608279) (xy 63.750237 -25.614379) (xy 63.804194 -25.628485)
			(xy 63.855523 -25.650297) (xy 63.903129 -25.679351) (xy 63.945997 -25.715026) (xy 63.983214 -25.756563)
			(xy 64.013987 -25.803076) (xy 64.037659 -25.853573) (xy 64.053727 -25.90698) (xy 64.061847 -25.962156)
			(xy 64.062356 -25.990042) (xy 64.061847 -26.017928) (xy 64.053727 -26.073104) (xy 64.037659 -26.126511)
			(xy 64.013987 -26.177008) (xy 63.983214 -26.223521) (xy 63.945997 -26.265058) (xy 63.903129 -26.300733)
			(xy 63.855523 -26.329787) (xy 63.804194 -26.351599) (xy 63.750237 -26.365705) (xy 63.6948 -26.371805)
			(xy 63.639066 -26.369768) (xy 63.584223 -26.359638) (xy 63.531439 -26.341631) (xy 63.481839 -26.31613)
			(xy 63.436481 -26.283679) (xy 63.396332 -26.24497) (xy 63.362246 -26.200827) (xy 63.33495 -26.152192)
			(xy 63.315027 -26.100101) (xy 63.302901 -26.045664) (xy 63.29883 -25.990042) (xy 62.02978 -25.990042)
			(xy 62.02978 -26.017246) (xy 62.022026 -26.071184) (xy 62.006675 -26.123469) (xy 61.984039 -26.173037)
			(xy 61.954581 -26.21888) (xy 61.918899 -26.260065) (xy 61.877719 -26.295752) (xy 61.831879 -26.325216)
			(xy 61.782314 -26.347858) (xy 61.73003 -26.363215) (xy 61.676094 -26.370977) (xy 61.648848 -26.37155)
			(xy 61.646054 -26.37155) (xy 61.636091 -26.372034) (xy 61.617666 -26.379622) (xy 61.61024 -26.386282)
			(xy 61.558932 -26.437082) (xy 61.552095 -26.444483) (xy 61.544385 -26.463082) (xy 61.543946 -26.47315)
			(xy 61.543946 -27.301952) (xy 61.544962 -27.312112) (xy 61.547756 -27.32659) (xy 61.55182 -27.335988)
			(xy 61.61024 -27.3939) (xy 61.617652 -27.400578) (xy 61.636088 -27.408145) (xy 61.646054 -27.408632)
			(xy 61.648848 -27.408632) (xy 61.676094 -27.409121) (xy 61.730031 -27.416883) (xy 61.782314 -27.43224)
			(xy 61.83188 -27.454882) (xy 61.87772 -27.484346) (xy 61.9189 -27.520034) (xy 61.954583 -27.561219)
			(xy 61.984041 -27.607062) (xy 62.006676 -27.656631) (xy 62.022028 -27.708916) (xy 62.029782 -27.762854)
			(xy 62.029782 -27.79014) (xy 63.362838 -27.79014) (xy 63.366909 -27.734518) (xy 63.379035 -27.680081)
			(xy 63.398958 -27.62799) (xy 63.426254 -27.579355) (xy 63.46034 -27.535212) (xy 63.500489 -27.496503)
			(xy 63.545847 -27.464052) (xy 63.595447 -27.438551) (xy 63.648231 -27.420544) (xy 63.703074 -27.410414)
			(xy 63.758808 -27.408377) (xy 63.814245 -27.414477) (xy 63.868202 -27.428583) (xy 63.919531 -27.450395)
			(xy 63.967137 -27.479449) (xy 64.010005 -27.515124) (xy 64.047222 -27.556661) (xy 64.077995 -27.603174)
			(xy 64.101667 -27.653671) (xy 64.117735 -27.707078) (xy 64.125855 -27.762254) (xy 64.126364 -27.79014)
			(xy 65.86677 -27.79014) (xy 65.870841 -27.734518) (xy 65.882967 -27.680081) (xy 65.90289 -27.62799)
			(xy 65.930186 -27.579355) (xy 65.964272 -27.535212) (xy 66.004421 -27.496503) (xy 66.049779 -27.464052)
			(xy 66.099379 -27.438551) (xy 66.152163 -27.420544) (xy 66.207006 -27.410414) (xy 66.26274 -27.408377)
			(xy 66.318177 -27.414477) (xy 66.372134 -27.428583) (xy 66.423463 -27.450395) (xy 66.471069 -27.479449)
			(xy 66.513937 -27.515124) (xy 66.551154 -27.556661) (xy 66.581927 -27.603174) (xy 66.605599 -27.653671)
			(xy 66.621667 -27.707078) (xy 66.629787 -27.762254) (xy 66.630296 -27.79014) (xy 66.629799 -27.817348)
			(xy 67.899818 -27.817348) (xy 67.899818 -27.762852) (xy 67.907574 -27.708911) (xy 67.922926 -27.656623)
			(xy 67.945564 -27.607052) (xy 67.975026 -27.561207) (xy 68.010713 -27.520021) (xy 68.051897 -27.484334)
			(xy 68.097741 -27.45487) (xy 68.147312 -27.432231) (xy 68.199599 -27.416876) (xy 68.25354 -27.409119)
			(xy 68.280788 -27.408632) (xy 68.306095 -27.409035) (xy 68.356267 -27.415705) (xy 68.405119 -27.428942)
			(xy 68.428616 -27.43835) (xy 68.436627 -27.441362) (xy 68.453694 -27.442459) (xy 68.470172 -27.437877)
			(xy 68.477384 -27.43327) (xy 68.502784 -27.41549) (xy 68.50967 -27.410216) (xy 68.519745 -27.396112)
			(xy 68.524543 -27.379457) (xy 68.524374 -27.370786) (xy 68.523612 -27.342846) (xy 68.523612 -26.479246)
			(xy 68.52412 -26.456894) (xy 68.524628 -26.444448) (xy 68.514214 -26.421842) (xy 68.429124 -26.355548)
			(xy 68.40474 -26.350976) (xy 68.392802 -26.354786) (xy 68.365464 -26.362623) (xy 68.309223 -26.371044)
			(xy 68.280788 -26.37155) (xy 68.25354 -26.370979) (xy 68.1996 -26.363222) (xy 68.147312 -26.347868)
			(xy 68.097742 -26.325228) (xy 68.051898 -26.295765) (xy 68.010714 -26.260077) (xy 67.975028 -26.218892)
			(xy 67.945566 -26.173047) (xy 67.922928 -26.123476) (xy 67.907575 -26.071188) (xy 67.89982 -26.017248)
			(xy 67.89982 -25.962752) (xy 67.907575 -25.908812) (xy 67.922928 -25.856524) (xy 67.945566 -25.806953)
			(xy 67.975028 -25.761108) (xy 68.010714 -25.719923) (xy 68.051898 -25.684235) (xy 68.097742 -25.654772)
			(xy 68.147312 -25.632132) (xy 68.1996 -25.616778) (xy 68.25354 -25.609021) (xy 68.280788 -25.608534)
			(xy 68.30974 -25.609088) (xy 68.36698 -25.617823) (xy 68.422243 -25.635108) (xy 68.474259 -25.660548)
			(xy 68.521831 -25.693558) (xy 68.563868 -25.733378) (xy 68.599404 -25.779095) (xy 68.627622 -25.829657)
			(xy 68.628517 -25.832054) (xy 70.188328 -25.832054) (xy 70.188806 -25.805451) (xy 70.196181 -25.752758)
			(xy 70.210809 -25.701603) (xy 70.232406 -25.652978) (xy 70.260554 -25.607827) (xy 70.294704 -25.567027)
			(xy 70.334195 -25.531371) (xy 70.355968 -25.516078) (xy 70.367447 -25.507741) (xy 70.385656 -25.486)
			(xy 70.397177 -25.460086) (xy 70.401119 -25.432002) (xy 70.397178 -25.403918) (xy 70.385659 -25.378004)
			(xy 70.367451 -25.356262) (xy 70.355968 -25.34793) (xy 70.334209 -25.332619) (xy 70.294728 -25.296957)
			(xy 70.260583 -25.256156) (xy 70.232436 -25.211009) (xy 70.210832 -25.16239) (xy 70.196189 -25.111242)
			(xy 70.188793 -25.058555) (xy 70.188328 -25.031954) (xy 70.188814 -25.004703) (xy 70.19657 -24.950755)
			(xy 70.211925 -24.89846) (xy 70.234567 -24.848883) (xy 70.264033 -24.803033) (xy 70.299724 -24.761842)
			(xy 70.340915 -24.726151) (xy 70.386765 -24.696685) (xy 70.436342 -24.674043) (xy 70.488637 -24.658688)
			(xy 70.542585 -24.650932) (xy 70.597087 -24.650932) (xy 70.651035 -24.658688) (xy 70.70333 -24.674043)
			(xy 70.752907 -24.696685) (xy 70.798757 -24.726151) (xy 70.839948 -24.761842) (xy 70.863149 -24.788618)
			(xy 72.793334 -24.788618) (xy 72.793334 -24.728682) (xy 72.801157 -24.66926) (xy 72.81667 -24.611367)
			(xy 72.839606 -24.555994) (xy 72.869573 -24.504088) (xy 72.90606 -24.456538) (xy 72.94844 -24.414158)
			(xy 72.99599 -24.377671) (xy 73.047896 -24.347704) (xy 73.103269 -24.324768) (xy 73.161162 -24.309255)
			(xy 73.220584 -24.301432) (xy 73.28052 -24.301432) (xy 73.339942 -24.309255) (xy 73.397835 -24.324768)
			(xy 73.453208 -24.347704) (xy 73.505114 -24.377671) (xy 73.552664 -24.414158) (xy 73.595044 -24.456538)
			(xy 73.631531 -24.504088) (xy 73.661498 -24.555994) (xy 73.684434 -24.611367) (xy 73.699947 -24.66926)
			(xy 73.70777 -24.728682) (xy 73.70826 -24.75865) (xy 73.70777 -24.788618) (xy 73.699947 -24.84804)
			(xy 73.684434 -24.905933) (xy 73.661498 -24.961306) (xy 73.631531 -25.013212) (xy 73.595044 -25.060762)
			(xy 73.552664 -25.103142) (xy 73.505114 -25.139629) (xy 73.453208 -25.169596) (xy 73.397835 -25.192532)
			(xy 73.339942 -25.208045) (xy 73.28052 -25.215868) (xy 73.220584 -25.215868) (xy 73.161162 -25.208045)
			(xy 73.103269 -25.192532) (xy 73.047896 -25.169596) (xy 72.99599 -25.139629) (xy 72.94844 -25.103142)
			(xy 72.90606 -25.060762) (xy 72.869573 -25.013212) (xy 72.839606 -24.961306) (xy 72.81667 -24.905933)
			(xy 72.801157 -24.84804) (xy 72.793334 -24.788618) (xy 70.863149 -24.788618) (xy 70.875639 -24.803033)
			(xy 70.905105 -24.848883) (xy 70.927747 -24.89846) (xy 70.943102 -24.950755) (xy 70.950858 -25.004703)
			(xy 70.951344 -25.031954) (xy 70.950885 -25.058558) (xy 70.943508 -25.111252) (xy 70.928877 -25.162408)
			(xy 70.907277 -25.211034) (xy 70.879127 -25.256185) (xy 70.844973 -25.296983) (xy 70.805479 -25.332638)
			(xy 70.783704 -25.34793) (xy 70.77222 -25.356259) (xy 70.754015 -25.378004) (xy 70.742498 -25.403919)
			(xy 70.738558 -25.432002) (xy 70.742499 -25.460086) (xy 70.754018 -25.486) (xy 70.772223 -25.507744)
			(xy 70.783704 -25.516078) (xy 70.80546 -25.531392) (xy 70.844942 -25.567053) (xy 70.879088 -25.607853)
			(xy 70.907237 -25.652999) (xy 70.928841 -25.701618) (xy 70.943484 -25.752766) (xy 70.95088 -25.805453)
			(xy 70.951344 -25.832054) (xy 70.950858 -25.859305) (xy 70.943102 -25.913253) (xy 70.927747 -25.965548)
			(xy 70.905105 -26.015125) (xy 70.875639 -26.060975) (xy 70.839948 -26.102166) (xy 70.798757 -26.137857)
			(xy 70.752907 -26.167323) (xy 70.70333 -26.189965) (xy 70.651035 -26.20532) (xy 70.597087 -26.213076)
			(xy 70.542585 -26.213076) (xy 70.488637 -26.20532) (xy 70.436342 -26.189965) (xy 70.386765 -26.167323)
			(xy 70.340915 -26.137857) (xy 70.299724 -26.102166) (xy 70.264033 -26.060975) (xy 70.234567 -26.015125)
			(xy 70.211925 -25.965548) (xy 70.19657 -25.913253) (xy 70.188814 -25.859305) (xy 70.188328 -25.832054)
			(xy 68.628517 -25.832054) (xy 68.647873 -25.883903) (xy 68.659693 -25.940587) (xy 68.661788 -25.969468)
			(xy 68.662296 -25.981914) (xy 68.674996 -26.00325) (xy 68.76669 -26.060654) (xy 68.791328 -26.062432)
			(xy 68.802758 -26.057606) (xy 68.831112 -26.046128) (xy 68.890112 -26.029976) (xy 68.950735 -26.021809)
			(xy 68.98132 -26.021284) (xy 69.0113 -26.021743) (xy 69.070746 -26.029574) (xy 69.12866 -26.0451)
			(xy 69.184052 -26.068055) (xy 69.235972 -26.098046) (xy 69.283532 -26.134558) (xy 69.325917 -26.176969)
			(xy 69.362402 -26.22455) (xy 69.392363 -26.276487) (xy 69.415285 -26.331892) (xy 69.423039 -26.360882)
			(xy 71.089518 -26.360882) (xy 71.093589 -26.30526) (xy 71.105715 -26.250823) (xy 71.125638 -26.198732)
			(xy 71.152934 -26.150097) (xy 71.18702 -26.105954) (xy 71.227169 -26.067245) (xy 71.272527 -26.034794)
			(xy 71.322127 -26.009293) (xy 71.374911 -25.991286) (xy 71.429754 -25.981156) (xy 71.485488 -25.979119)
			(xy 71.540925 -25.985219) (xy 71.594882 -25.999325) (xy 71.646211 -26.021137) (xy 71.693817 -26.050191)
			(xy 71.736685 -26.085866) (xy 71.773902 -26.127403) (xy 71.804675 -26.173916) (xy 71.828347 -26.224413)
			(xy 71.844415 -26.27782) (xy 71.852535 -26.332996) (xy 71.853044 -26.360882) (xy 72.105518 -26.360882)
			(xy 72.109589 -26.30526) (xy 72.121715 -26.250823) (xy 72.141638 -26.198732) (xy 72.168934 -26.150097)
			(xy 72.20302 -26.105954) (xy 72.243169 -26.067245) (xy 72.288527 -26.034794) (xy 72.338127 -26.009293)
			(xy 72.390911 -25.991286) (xy 72.445754 -25.981156) (xy 72.501488 -25.979119) (xy 72.556925 -25.985219)
			(xy 72.610882 -25.999325) (xy 72.662211 -26.021137) (xy 72.709817 -26.050191) (xy 72.752685 -26.085866)
			(xy 72.789902 -26.127403) (xy 72.820675 -26.173916) (xy 72.844347 -26.224413) (xy 72.860415 -26.27782)
			(xy 72.868535 -26.332996) (xy 72.869044 -26.360882) (xy 72.868535 -26.388768) (xy 72.860415 -26.443944)
			(xy 72.844347 -26.497351) (xy 72.820675 -26.547848) (xy 72.789902 -26.594361) (xy 72.752685 -26.635898)
			(xy 72.709817 -26.671573) (xy 72.662211 -26.700627) (xy 72.610882 -26.722439) (xy 72.556925 -26.736545)
			(xy 72.501488 -26.742645) (xy 72.445754 -26.740608) (xy 72.390911 -26.730478) (xy 72.338127 -26.712471)
			(xy 72.288527 -26.68697) (xy 72.243169 -26.654519) (xy 72.20302 -26.61581) (xy 72.168934 -26.571667)
			(xy 72.141638 -26.523032) (xy 72.121715 -26.470941) (xy 72.109589 -26.416504) (xy 72.105518 -26.360882)
			(xy 71.853044 -26.360882) (xy 71.852535 -26.388768) (xy 71.844415 -26.443944) (xy 71.828347 -26.497351)
			(xy 71.804675 -26.547848) (xy 71.773902 -26.594361) (xy 71.736685 -26.635898) (xy 71.693817 -26.671573)
			(xy 71.646211 -26.700627) (xy 71.594882 -26.722439) (xy 71.540925 -26.736545) (xy 71.485488 -26.742645)
			(xy 71.429754 -26.740608) (xy 71.374911 -26.730478) (xy 71.322127 -26.712471) (xy 71.272527 -26.68697)
			(xy 71.227169 -26.654519) (xy 71.18702 -26.61581) (xy 71.152934 -26.571667) (xy 71.125638 -26.523032)
			(xy 71.105715 -26.470941) (xy 71.093589 -26.416504) (xy 71.089518 -26.360882) (xy 69.423039 -26.360882)
			(xy 69.430778 -26.389816) (xy 69.438574 -26.449266) (xy 69.439028 -26.479246) (xy 69.439028 -26.971244)
			(xy 72.851008 -26.971244) (xy 72.855079 -26.915622) (xy 72.867205 -26.861185) (xy 72.887128 -26.809094)
			(xy 72.914424 -26.760459) (xy 72.94851 -26.716316) (xy 72.988659 -26.677607) (xy 73.034017 -26.645156)
			(xy 73.083617 -26.619655) (xy 73.136401 -26.601648) (xy 73.191244 -26.591518) (xy 73.246978 -26.589481)
			(xy 73.302415 -26.595581) (xy 73.356372 -26.609687) (xy 73.407701 -26.631499) (xy 73.455307 -26.660553)
			(xy 73.498175 -26.696228) (xy 73.535392 -26.737765) (xy 73.566165 -26.784278) (xy 73.589837 -26.834775)
			(xy 73.605905 -26.888182) (xy 73.614025 -26.943358) (xy 73.614534 -26.971244) (xy 73.614025 -26.99913)
			(xy 73.605905 -27.054306) (xy 73.589837 -27.107713) (xy 73.566165 -27.15821) (xy 73.535392 -27.204723)
			(xy 73.498175 -27.24626) (xy 73.455307 -27.281935) (xy 73.407701 -27.310989) (xy 73.356372 -27.332801)
			(xy 73.302415 -27.346907) (xy 73.246978 -27.353007) (xy 73.191244 -27.35097) (xy 73.136401 -27.34084)
			(xy 73.083617 -27.322833) (xy 73.034017 -27.297332) (xy 72.988659 -27.264881) (xy 72.94851 -27.226172)
			(xy 72.914424 -27.182029) (xy 72.887128 -27.133394) (xy 72.867205 -27.081303) (xy 72.855079 -27.026866)
			(xy 72.851008 -26.971244) (xy 69.439028 -26.971244) (xy 69.439028 -27.342846) (xy 69.438616 -27.372822)
			(xy 69.430787 -27.432261) (xy 69.41527 -27.490171) (xy 69.39233 -27.545561) (xy 69.362358 -27.597484)
			(xy 69.325868 -27.645053) (xy 69.283484 -27.687453) (xy 69.235929 -27.723962) (xy 69.184017 -27.753953)
			(xy 69.128636 -27.776914) (xy 69.070732 -27.792453) (xy 69.011296 -27.800304) (xy 68.98132 -27.800808)
			(xy 68.950184 -27.800263) (xy 68.888488 -27.791804) (xy 68.828503 -27.77508) (xy 68.79971 -27.763216)
			(xy 68.788534 -27.75839) (xy 68.764912 -27.75966) (xy 68.673726 -27.810968) (xy 68.660264 -27.830526)
			(xy 68.65874 -27.842464) (xy 68.654596 -27.869507) (xy 68.639412 -27.92207) (xy 68.616877 -27.971927)
			(xy 68.587454 -28.018054) (xy 68.551745 -28.059507) (xy 68.510483 -28.095435) (xy 68.464513 -28.125104)
			(xy 68.414778 -28.147904) (xy 68.362296 -28.163368) (xy 68.308144 -28.171179) (xy 68.280788 -28.171648)
			(xy 68.25354 -28.171081) (xy 68.199599 -28.163324) (xy 68.147312 -28.147969) (xy 68.097741 -28.12533)
			(xy 68.051897 -28.095866) (xy 68.010713 -28.060179) (xy 67.975026 -28.018993) (xy 67.945564 -27.973148)
			(xy 67.922926 -27.923577) (xy 67.907574 -27.871289) (xy 67.899818 -27.817348) (xy 66.629799 -27.817348)
			(xy 66.629787 -27.818026) (xy 66.621667 -27.873202) (xy 66.605599 -27.926609) (xy 66.581927 -27.977106)
			(xy 66.551154 -28.023619) (xy 66.513937 -28.065156) (xy 66.471069 -28.100831) (xy 66.423463 -28.129885)
			(xy 66.372134 -28.151697) (xy 66.318177 -28.165803) (xy 66.26274 -28.171903) (xy 66.207006 -28.169866)
			(xy 66.152163 -28.159736) (xy 66.099379 -28.141729) (xy 66.049779 -28.116228) (xy 66.004421 -28.083777)
			(xy 65.964272 -28.045068) (xy 65.930186 -28.000925) (xy 65.90289 -27.95229) (xy 65.882967 -27.900199)
			(xy 65.870841 -27.845762) (xy 65.86677 -27.79014) (xy 64.126364 -27.79014) (xy 64.125855 -27.818026)
			(xy 64.117735 -27.873202) (xy 64.101667 -27.926609) (xy 64.077995 -27.977106) (xy 64.047222 -28.023619)
			(xy 64.010005 -28.065156) (xy 63.967137 -28.100831) (xy 63.919531 -28.129885) (xy 63.868202 -28.151697)
			(xy 63.814245 -28.165803) (xy 63.758808 -28.171903) (xy 63.703074 -28.169866) (xy 63.648231 -28.159736)
			(xy 63.595447 -28.141729) (xy 63.545847 -28.116228) (xy 63.500489 -28.083777) (xy 63.46034 -28.045068)
			(xy 63.426254 -28.000925) (xy 63.398958 -27.95229) (xy 63.379035 -27.900199) (xy 63.366909 -27.845762)
			(xy 63.362838 -27.79014) (xy 62.029782 -27.79014) (xy 62.029782 -27.817346) (xy 62.022028 -27.871284)
			(xy 62.006676 -27.923569) (xy 61.984041 -27.973138) (xy 61.954583 -28.018981) (xy 61.9189 -28.060166)
			(xy 61.87772 -28.095854) (xy 61.83188 -28.125318) (xy 61.782314 -28.14796) (xy 61.730031 -28.163317)
			(xy 61.676094 -28.171079) (xy 61.648848 -28.171648) (xy 61.646054 -28.171648) (xy 61.636091 -28.172132)
			(xy 61.617666 -28.17972) (xy 61.61024 -28.18638) (xy 61.558932 -28.23718) (xy 61.552095 -28.244581)
			(xy 61.544384 -28.26318) (xy 61.543946 -28.273248) (xy 61.543946 -29.101796) (xy 61.544962 -29.111956)
			(xy 61.547756 -29.126434) (xy 61.55182 -29.135832) (xy 61.61024 -29.193744) (xy 61.617654 -29.200417)
			(xy 61.636089 -29.207978) (xy 61.646054 -29.208476) (xy 61.648848 -29.208476) (xy 61.676098 -29.208965)
			(xy 61.730043 -29.216727) (xy 61.782334 -29.232087) (xy 61.831907 -29.254732) (xy 61.877754 -29.284201)
			(xy 61.91894 -29.319894) (xy 61.954628 -29.361085) (xy 61.984091 -29.406935) (xy 62.006729 -29.456511)
			(xy 62.022083 -29.508804) (xy 62.029838 -29.56275) (xy 62.029838 -29.589984) (xy 63.362838 -29.589984)
			(xy 63.366909 -29.534362) (xy 63.379035 -29.479925) (xy 63.398958 -29.427834) (xy 63.426254 -29.379199)
			(xy 63.46034 -29.335056) (xy 63.500489 -29.296347) (xy 63.545847 -29.263896) (xy 63.595447 -29.238395)
			(xy 63.648231 -29.220388) (xy 63.703074 -29.210258) (xy 63.758808 -29.208221) (xy 63.814245 -29.214321)
			(xy 63.868202 -29.228427) (xy 63.919531 -29.250239) (xy 63.967137 -29.279293) (xy 64.010005 -29.314968)
			(xy 64.047222 -29.356505) (xy 64.077995 -29.403018) (xy 64.101667 -29.453515) (xy 64.117735 -29.506922)
			(xy 64.125855 -29.562098) (xy 64.126364 -29.589984) (xy 65.86677 -29.589984) (xy 65.870841 -29.534362)
			(xy 65.882967 -29.479925) (xy 65.90289 -29.427834) (xy 65.930186 -29.379199) (xy 65.964272 -29.335056)
			(xy 66.004421 -29.296347) (xy 66.049779 -29.263896) (xy 66.099379 -29.238395) (xy 66.152163 -29.220388)
			(xy 66.207006 -29.210258) (xy 66.26274 -29.208221) (xy 66.318177 -29.214321) (xy 66.372134 -29.228427)
			(xy 66.423463 -29.250239) (xy 66.471069 -29.279293) (xy 66.513937 -29.314968) (xy 66.551154 -29.356505)
			(xy 66.581927 -29.403018) (xy 66.605599 -29.453515) (xy 66.621667 -29.506922) (xy 66.629787 -29.562098)
			(xy 66.630296 -29.589984) (xy 67.89877 -29.589984) (xy 67.902841 -29.534362) (xy 67.914967 -29.479925)
			(xy 67.93489 -29.427834) (xy 67.962186 -29.379199) (xy 67.996272 -29.335056) (xy 68.036421 -29.296347)
			(xy 68.081779 -29.263896) (xy 68.131379 -29.238395) (xy 68.184163 -29.220388) (xy 68.239006 -29.210258)
			(xy 68.29474 -29.208221) (xy 68.350177 -29.214321) (xy 68.404134 -29.228427) (xy 68.455463 -29.250239)
			(xy 68.503069 -29.279293) (xy 68.545937 -29.314968) (xy 68.567608 -29.339154) (xy 70.290132 -29.339154)
			(xy 70.290132 -29.284646) (xy 70.297889 -29.230694) (xy 70.313245 -29.178394) (xy 70.335887 -29.128812)
			(xy 70.365356 -29.082957) (xy 70.401049 -29.041762) (xy 70.442243 -29.006066) (xy 70.488096 -28.976596)
			(xy 70.537677 -28.953951) (xy 70.589976 -28.938593) (xy 70.643928 -28.930833) (xy 70.671182 -28.930346)
			(xy 70.685975 -28.930481) (xy 70.715473 -28.93277) (xy 70.73011 -28.934918) (xy 70.741032 -28.936696)
			(xy 70.762368 -28.9306) (xy 70.829678 -28.873196) (xy 70.837659 -28.865616) (xy 70.846733 -28.845586)
			(xy 70.847204 -28.834588) (xy 70.847204 -28.530296) (xy 70.8467 -28.519307) (xy 70.837624 -28.499295)
			(xy 70.829678 -28.491688) (xy 70.762368 -28.434284) (xy 70.741032 -28.428188) (xy 70.73011 -28.429966)
			(xy 70.715471 -28.4321) (xy 70.685975 -28.434393) (xy 70.671182 -28.434538) (xy 70.643934 -28.433991)
			(xy 70.589992 -28.426233) (xy 70.537704 -28.410877) (xy 70.488133 -28.388237) (xy 70.442288 -28.358772)
			(xy 70.401104 -28.323084) (xy 70.365417 -28.281897) (xy 70.335955 -28.236051) (xy 70.313317 -28.186479)
			(xy 70.297964 -28.13419) (xy 70.290208 -28.080248) (xy 70.290208 -28.025752) (xy 70.297964 -27.97181)
			(xy 70.313317 -27.919521) (xy 70.335955 -27.869949) (xy 70.365417 -27.824103) (xy 70.401104 -27.782916)
			(xy 70.442288 -27.747228) (xy 70.488133 -27.717763) (xy 70.537704 -27.695123) (xy 70.589992 -27.679767)
			(xy 70.643934 -27.672009) (xy 70.671182 -27.671522) (xy 70.697108 -27.671959) (xy 70.748486 -27.678963)
			(xy 70.798441 -27.692859) (xy 70.846056 -27.71339) (xy 70.890453 -27.740178) (xy 70.930814 -27.77273)
			(xy 70.966396 -27.810447) (xy 70.981824 -27.831288) (xy 70.987546 -27.838635) (xy 71.003062 -27.848911)
			(xy 71.01205 -27.851354) (xy 71.042276 -27.858212) (xy 71.051551 -27.859977) (xy 71.070216 -27.857225)
			(xy 71.078598 -27.852878) (xy 71.104575 -27.838585) (xy 71.159427 -27.816074) (xy 71.216729 -27.800847)
			(xy 71.27552 -27.79316) (xy 71.305166 -27.79268) (xy 71.334809 -27.793181) (xy 71.393591 -27.800901)
			(xy 71.450889 -27.816127) (xy 71.505749 -27.838604) (xy 71.531734 -27.852878) (xy 71.540157 -27.857102)
			(xy 71.558778 -27.859849) (xy 71.568056 -27.858212) (xy 71.598282 -27.851354) (xy 71.607283 -27.848952)
			(xy 71.622785 -27.838641) (xy 71.628508 -27.831288) (xy 71.643903 -27.810419) (xy 71.679477 -27.772684)
			(xy 71.719838 -27.74012) (xy 71.764241 -27.713327) (xy 71.811865 -27.692799) (xy 71.861832 -27.678916)
			(xy 71.91322 -27.671934) (xy 71.93915 -27.671522) (xy 71.966407 -27.671922) (xy 72.020368 -27.679673)
			(xy 72.072676 -27.695026) (xy 72.122266 -27.717668) (xy 72.168129 -27.747137) (xy 72.209331 -27.782833)
			(xy 72.245033 -27.82403) (xy 72.274508 -27.86989) (xy 72.297156 -27.919477) (xy 72.312516 -27.971783)
			(xy 72.320275 -28.025743) (xy 72.320275 -28.080257) (xy 72.312516 -28.134217) (xy 72.297156 -28.186523)
			(xy 72.274508 -28.23611) (xy 72.245033 -28.28197) (xy 72.209331 -28.323167) (xy 72.168129 -28.358863)
			(xy 72.122266 -28.388332) (xy 72.072676 -28.410974) (xy 72.020368 -28.426327) (xy 71.966407 -28.434078)
			(xy 71.93915 -28.434538) (xy 71.924357 -28.434399) (xy 71.894859 -28.432113) (xy 71.880222 -28.429966)
			(xy 71.8693 -28.428188) (xy 71.847964 -28.434284) (xy 71.780654 -28.491688) (xy 71.772686 -28.499279)
			(xy 71.763603 -28.5193) (xy 71.763128 -28.530296) (xy 71.763128 -28.834588) (xy 71.763631 -28.845577)
			(xy 71.772707 -28.86559) (xy 71.780654 -28.873196) (xy 71.847964 -28.9306) (xy 71.8693 -28.936696)
			(xy 71.880222 -28.934918) (xy 71.89486 -28.93278) (xy 71.924357 -28.93049) (xy 71.93915 -28.930346)
			(xy 71.966402 -28.930898) (xy 72.020352 -28.938648) (xy 72.072649 -28.953998) (xy 72.12223 -28.976635)
			(xy 72.168084 -29.006098) (xy 72.209277 -29.041787) (xy 72.244972 -29.082976) (xy 72.274441 -29.128826)
			(xy 72.297085 -29.178404) (xy 72.312441 -29.230699) (xy 72.320199 -29.284648) (xy 72.320199 -29.339152)
			(xy 72.312441 -29.393101) (xy 72.297085 -29.445396) (xy 72.274441 -29.494974) (xy 72.244972 -29.540824)
			(xy 72.209277 -29.582013) (xy 72.168084 -29.617702) (xy 72.12223 -29.647165) (xy 72.072649 -29.669802)
			(xy 72.020352 -29.685152) (xy 71.966402 -29.692902) (xy 71.93915 -29.693362) (xy 71.913224 -29.692908)
			(xy 71.861847 -29.685907) (xy 71.811892 -29.672015) (xy 71.764277 -29.651488) (xy 71.71988 -29.624702)
			(xy 71.679518 -29.592151) (xy 71.643936 -29.554436) (xy 71.628508 -29.533596) (xy 71.622758 -29.526273)
			(xy 71.607263 -29.515981) (xy 71.598282 -29.51353) (xy 71.568056 -29.506672) (xy 71.558779 -29.504926)
			(xy 71.540116 -29.507666) (xy 71.531734 -29.512006) (xy 71.50575 -29.526285) (xy 71.450901 -29.5488)
			(xy 71.3936 -29.564031) (xy 71.334811 -29.571722) (xy 71.305166 -29.572204) (xy 71.275524 -29.571692)
			(xy 71.216742 -29.563975) (xy 71.159444 -29.548753) (xy 71.104583 -29.526278) (xy 71.078598 -29.512006)
			(xy 71.07019 -29.507748) (xy 71.051556 -29.505022) (xy 71.042276 -29.506672) (xy 71.01205 -29.51353)
			(xy 71.003055 -29.515951) (xy 70.987551 -29.526249) (xy 70.981824 -29.533596) (xy 70.966405 -29.554447)
			(xy 70.930835 -29.592182) (xy 70.890478 -29.624749) (xy 70.84608 -29.651544) (xy 70.79846 -29.672075)
			(xy 70.748496 -29.685961) (xy 70.697111 -29.692947) (xy 70.671182 -29.693362) (xy 70.643928 -29.692967)
			(xy 70.589976 -29.685207) (xy 70.537677 -29.669849) (xy 70.488096 -29.647204) (xy 70.442243 -29.617734)
			(xy 70.401049 -29.582038) (xy 70.365356 -29.540843) (xy 70.335887 -29.494988) (xy 70.313245 -29.445406)
			(xy 70.297889 -29.393106) (xy 70.290132 -29.339154) (xy 68.567608 -29.339154) (xy 68.583154 -29.356505)
			(xy 68.613927 -29.403018) (xy 68.637599 -29.453515) (xy 68.653667 -29.506922) (xy 68.661787 -29.562098)
			(xy 68.662296 -29.589984) (xy 68.661787 -29.61787) (xy 68.653667 -29.673046) (xy 68.637599 -29.726453)
			(xy 68.613927 -29.77695) (xy 68.583154 -29.823463) (xy 68.545937 -29.865) (xy 68.503069 -29.900675)
			(xy 68.455463 -29.929729) (xy 68.404134 -29.951541) (xy 68.350177 -29.965647) (xy 68.29474 -29.971747)
			(xy 68.239006 -29.96971) (xy 68.184163 -29.95958) (xy 68.131379 -29.941573) (xy 68.081779 -29.916072)
			(xy 68.036421 -29.883621) (xy 67.996272 -29.844912) (xy 67.962186 -29.800769) (xy 67.93489 -29.752134)
			(xy 67.914967 -29.700043) (xy 67.902841 -29.645606) (xy 67.89877 -29.589984) (xy 66.630296 -29.589984)
			(xy 66.629787 -29.61787) (xy 66.621667 -29.673046) (xy 66.605599 -29.726453) (xy 66.581927 -29.77695)
			(xy 66.551154 -29.823463) (xy 66.513937 -29.865) (xy 66.471069 -29.900675) (xy 66.423463 -29.929729)
			(xy 66.372134 -29.951541) (xy 66.318177 -29.965647) (xy 66.26274 -29.971747) (xy 66.207006 -29.96971)
			(xy 66.152163 -29.95958) (xy 66.099379 -29.941573) (xy 66.049779 -29.916072) (xy 66.004421 -29.883621)
			(xy 65.964272 -29.844912) (xy 65.930186 -29.800769) (xy 65.90289 -29.752134) (xy 65.882967 -29.700043)
			(xy 65.870841 -29.645606) (xy 65.86677 -29.589984) (xy 64.126364 -29.589984) (xy 64.125855 -29.61787)
			(xy 64.117735 -29.673046) (xy 64.101667 -29.726453) (xy 64.077995 -29.77695) (xy 64.047222 -29.823463)
			(xy 64.010005 -29.865) (xy 63.967137 -29.900675) (xy 63.919531 -29.929729) (xy 63.868202 -29.951541)
			(xy 63.814245 -29.965647) (xy 63.758808 -29.971747) (xy 63.703074 -29.96971) (xy 63.648231 -29.95958)
			(xy 63.595447 -29.941573) (xy 63.545847 -29.916072) (xy 63.500489 -29.883621) (xy 63.46034 -29.844912)
			(xy 63.426254 -29.800769) (xy 63.398958 -29.752134) (xy 63.379035 -29.700043) (xy 63.366909 -29.645606)
			(xy 63.362838 -29.589984) (xy 62.029838 -29.589984) (xy 62.029838 -29.61725) (xy 62.022083 -29.671196)
			(xy 62.006729 -29.723489) (xy 61.984091 -29.773065) (xy 61.954628 -29.818915) (xy 61.91894 -29.860106)
			(xy 61.877754 -29.895799) (xy 61.831907 -29.925268) (xy 61.782334 -29.947913) (xy 61.730043 -29.963273)
			(xy 61.676098 -29.971035) (xy 61.648848 -29.971492) (xy 61.646054 -29.971492) (xy 61.63609 -29.971975)
			(xy 61.61766 -29.979556) (xy 61.61024 -29.986224) (xy 61.558932 -30.037024) (xy 61.552086 -30.044422)
			(xy 61.544355 -30.063021) (xy 61.543946 -30.073092) (xy 61.543946 -30.901894) (xy 61.544962 -30.912054)
			(xy 61.547756 -30.926532) (xy 61.55182 -30.93593) (xy 61.61024 -30.993842) (xy 61.617654 -31.000515)
			(xy 61.636089 -31.008077) (xy 61.646054 -31.008574) (xy 61.648848 -31.008574) (xy 61.676098 -31.009063)
			(xy 61.730043 -31.016826) (xy 61.782335 -31.032186) (xy 61.831908 -31.05483) (xy 61.877755 -31.084299)
			(xy 61.918941 -31.119993) (xy 61.954629 -31.161184) (xy 61.984093 -31.207034) (xy 62.006731 -31.25661)
			(xy 62.022085 -31.308904) (xy 62.02984 -31.36285) (xy 62.02984 -31.41735) (xy 62.022085 -31.471296)
			(xy 62.006731 -31.52359) (xy 61.984093 -31.573166) (xy 61.954629 -31.619016) (xy 61.934452 -31.642304)
			(xy 63.406526 -31.642304) (xy 63.410597 -31.586682) (xy 63.422723 -31.532245) (xy 63.442646 -31.480154)
			(xy 63.469942 -31.431519) (xy 63.504028 -31.387376) (xy 63.544177 -31.348667) (xy 63.589535 -31.316216)
			(xy 63.639135 -31.290715) (xy 63.691919 -31.272708) (xy 63.746762 -31.262578) (xy 63.802496 -31.260541)
			(xy 63.857933 -31.266641) (xy 63.91189 -31.280747) (xy 63.963219 -31.302559) (xy 64.010825 -31.331613)
			(xy 64.053693 -31.367288) (xy 64.074116 -31.390082) (xy 65.86677 -31.390082) (xy 65.870841 -31.33446)
			(xy 65.882967 -31.280023) (xy 65.90289 -31.227932) (xy 65.930186 -31.179297) (xy 65.964272 -31.135154)
			(xy 66.004421 -31.096445) (xy 66.049779 -31.063994) (xy 66.099379 -31.038493) (xy 66.152163 -31.020486)
			(xy 66.207006 -31.010356) (xy 66.26274 -31.008319) (xy 66.318177 -31.014419) (xy 66.372134 -31.028525)
			(xy 66.423463 -31.050337) (xy 66.471069 -31.079391) (xy 66.513937 -31.115066) (xy 66.551154 -31.156603)
			(xy 66.581927 -31.203116) (xy 66.605599 -31.253613) (xy 66.621667 -31.30702) (xy 66.629787 -31.362196)
			(xy 66.630296 -31.390082) (xy 67.89877 -31.390082) (xy 67.902841 -31.33446) (xy 67.914967 -31.280023)
			(xy 67.93489 -31.227932) (xy 67.962186 -31.179297) (xy 67.996272 -31.135154) (xy 68.036421 -31.096445)
			(xy 68.081779 -31.063994) (xy 68.131379 -31.038493) (xy 68.184163 -31.020486) (xy 68.239006 -31.010356)
			(xy 68.29474 -31.008319) (xy 68.350177 -31.014419) (xy 68.404134 -31.028525) (xy 68.455463 -31.050337)
			(xy 68.503069 -31.079391) (xy 68.545937 -31.115066) (xy 68.583154 -31.156603) (xy 68.613927 -31.203116)
			(xy 68.637599 -31.253613) (xy 68.653667 -31.30702) (xy 68.661787 -31.362196) (xy 68.662296 -31.390082)
			(xy 68.661787 -31.417968) (xy 68.653667 -31.473144) (xy 68.637599 -31.526551) (xy 68.613927 -31.577048)
			(xy 68.583154 -31.623561) (xy 68.545937 -31.665098) (xy 68.527728 -31.680252) (xy 70.29015 -31.680252)
			(xy 70.29015 -31.625748) (xy 70.297906 -31.571797) (xy 70.313262 -31.5195) (xy 70.335903 -31.469921)
			(xy 70.36537 -31.424068) (xy 70.401062 -31.382875) (xy 70.442253 -31.347181) (xy 70.488105 -31.317712)
			(xy 70.537683 -31.295068) (xy 70.58998 -31.27971) (xy 70.64393 -31.271951) (xy 70.671182 -31.271464)
			(xy 70.697109 -31.271884) (xy 70.748488 -31.278889) (xy 70.798445 -31.292786) (xy 70.84606 -31.313319)
			(xy 70.890457 -31.340111) (xy 70.930817 -31.372666) (xy 70.966398 -31.410387) (xy 70.981824 -31.43123)
			(xy 70.987557 -31.438567) (xy 71.003065 -31.44885) (xy 71.01205 -31.451296) (xy 71.042276 -31.458154)
			(xy 71.051551 -31.459914) (xy 71.070216 -31.457165) (xy 71.078598 -31.45282) (xy 71.104591 -31.438579)
			(xy 71.159459 -31.416163) (xy 71.216757 -31.401003) (xy 71.275531 -31.39335) (xy 71.305166 -31.392876)
			(xy 71.334804 -31.393331) (xy 71.393586 -31.400953) (xy 71.450889 -31.416112) (xy 71.505751 -31.438555)
			(xy 71.531734 -31.45282) (xy 71.540158 -31.457042) (xy 71.558779 -31.459792) (xy 71.568056 -31.458154)
			(xy 71.598282 -31.451296) (xy 71.607279 -31.44888) (xy 71.622781 -31.438578) (xy 71.628508 -31.43123)
			(xy 71.643886 -31.410348) (xy 71.679465 -31.372617) (xy 71.71983 -31.340055) (xy 71.764235 -31.313264)
			(xy 71.811862 -31.292739) (xy 71.86183 -31.278858) (xy 71.913219 -31.271876) (xy 71.93915 -31.271464)
			(xy 71.966403 -31.27198) (xy 72.020356 -31.27973) (xy 72.072656 -31.295081) (xy 72.122238 -31.317719)
			(xy 72.168094 -31.347184) (xy 72.20929 -31.382875) (xy 72.244986 -31.424066) (xy 72.274457 -31.469918)
			(xy 72.297101 -31.519498) (xy 72.312459 -31.571796) (xy 72.320217 -31.625747) (xy 72.320217 -31.680253)
			(xy 72.312459 -31.734204) (xy 72.297101 -31.786502) (xy 72.274457 -31.836082) (xy 72.244986 -31.881934)
			(xy 72.20929 -31.923125) (xy 72.168094 -31.958816) (xy 72.122238 -31.988281) (xy 72.072656 -32.010919)
			(xy 72.020356 -32.02627) (xy 71.966403 -32.03402) (xy 71.93915 -32.03448) (xy 71.924357 -32.034341)
			(xy 71.894859 -32.032054) (xy 71.880222 -32.029908) (xy 71.8693 -32.02813) (xy 71.847964 -32.034226)
			(xy 71.780654 -32.09163) (xy 71.772712 -32.099244) (xy 71.763615 -32.119248) (xy 71.763128 -32.130238)
			(xy 71.763128 -32.43453) (xy 71.763608 -32.445522) (xy 71.7727 -32.465535) (xy 71.780654 -32.473138)
			(xy 71.847964 -32.530542) (xy 71.8693 -32.536638) (xy 71.880222 -32.53486) (xy 71.89486 -32.532722)
			(xy 71.924357 -32.530432) (xy 71.93915 -32.530288) (xy 71.966405 -32.530756) (xy 72.020361 -32.538507)
			(xy 72.072664 -32.553859) (xy 72.12225 -32.576498) (xy 72.168109 -32.605964) (xy 72.209307 -32.641658)
			(xy 72.245006 -32.682851) (xy 72.274478 -32.728706) (xy 72.297124 -32.778289) (xy 72.312482 -32.83059)
			(xy 72.320241 -32.884545) (xy 72.320241 -32.939055) (xy 72.312482 -32.99301) (xy 72.297124 -33.045311)
			(xy 72.274478 -33.094894) (xy 72.245006 -33.140749) (xy 72.209307 -33.181942) (xy 72.168109 -33.217636)
			(xy 72.12225 -33.247102) (xy 72.072664 -33.269741) (xy 72.020361 -33.285093) (xy 71.966405 -33.292844)
			(xy 71.93915 -33.293304) (xy 71.913225 -33.292832) (xy 71.86185 -33.285833) (xy 71.811895 -33.271943)
			(xy 71.764281 -33.251417) (xy 71.719884 -33.224634) (xy 71.679522 -33.192088) (xy 71.643937 -33.154376)
			(xy 71.628508 -33.133538) (xy 71.62277 -33.126205) (xy 71.607266 -33.11592) (xy 71.598282 -33.113472)
			(xy 71.568056 -33.106614) (xy 71.55878 -33.104863) (xy 71.540116 -33.107605) (xy 71.531734 -33.111948)
			(xy 71.505733 -33.126174) (xy 71.450868 -33.148594) (xy 71.393572 -33.163759) (xy 71.3348 -33.171416)
			(xy 71.305166 -33.171892) (xy 71.275529 -33.171428) (xy 71.216746 -33.163809) (xy 71.159443 -33.148652)
			(xy 71.104581 -33.126212) (xy 71.078598 -33.111948) (xy 71.07019 -33.107691) (xy 71.051556 -33.104964)
			(xy 71.042276 -33.106614) (xy 71.01205 -33.113472) (xy 71.003061 -33.115911) (xy 70.987555 -33.126197)
			(xy 70.981824 -33.133538) (xy 70.966417 -33.154398) (xy 70.930844 -33.192131) (xy 70.890485 -33.224696)
			(xy 70.846084 -33.25149) (xy 70.798462 -33.272019) (xy 70.748497 -33.285904) (xy 70.697112 -33.29289)
			(xy 70.671182 -33.293304) (xy 70.643931 -33.292825) (xy 70.589985 -33.285066) (xy 70.537692 -33.269709)
			(xy 70.488116 -33.247067) (xy 70.442268 -33.2176) (xy 70.401079 -33.181908) (xy 70.365389 -33.140718)
			(xy 70.335924 -33.094868) (xy 70.313284 -33.045291) (xy 70.29793 -32.992997) (xy 70.290174 -32.939051)
			(xy 70.290174 -32.884549) (xy 70.29793 -32.830603) (xy 70.313284 -32.778309) (xy 70.335924 -32.728732)
			(xy 70.365389 -32.682882) (xy 70.401079 -32.641692) (xy 70.442268 -32.606) (xy 70.488116 -32.576533)
			(xy 70.537692 -32.553891) (xy 70.589985 -32.538534) (xy 70.643931 -32.530775) (xy 70.671182 -32.530288)
			(xy 70.685975 -32.530424) (xy 70.715473 -32.532713) (xy 70.73011 -32.53486) (xy 70.741032 -32.536638)
			(xy 70.762368 -32.530542) (xy 70.829678 -32.473138) (xy 70.83764 -32.465542) (xy 70.846725 -32.445524)
			(xy 70.847204 -32.43453) (xy 70.847204 -32.130238) (xy 70.846732 -32.119245) (xy 70.837633 -32.099233)
			(xy 70.829678 -32.09163) (xy 70.762368 -32.034226) (xy 70.741032 -32.02813) (xy 70.73011 -32.029908)
			(xy 70.715471 -32.032043) (xy 70.685975 -32.034335) (xy 70.671182 -32.03448) (xy 70.64393 -32.034049)
			(xy 70.58998 -32.02629) (xy 70.537683 -32.010932) (xy 70.488105 -31.988288) (xy 70.442253 -31.958819)
			(xy 70.401062 -31.923125) (xy 70.36537 -31.881932) (xy 70.335903 -31.836079) (xy 70.313262 -31.7865)
			(xy 70.297906 -31.734203) (xy 70.29015 -31.680252) (xy 68.527728 -31.680252) (xy 68.503069 -31.700773)
			(xy 68.455463 -31.729827) (xy 68.404134 -31.751639) (xy 68.350177 -31.765745) (xy 68.29474 -31.771845)
			(xy 68.239006 -31.769808) (xy 68.184163 -31.759678) (xy 68.131379 -31.741671) (xy 68.081779 -31.71617)
			(xy 68.036421 -31.683719) (xy 67.996272 -31.64501) (xy 67.962186 -31.600867) (xy 67.93489 -31.552232)
			(xy 67.914967 -31.500141) (xy 67.902841 -31.445704) (xy 67.89877 -31.390082) (xy 66.630296 -31.390082)
			(xy 66.629787 -31.417968) (xy 66.621667 -31.473144) (xy 66.605599 -31.526551) (xy 66.581927 -31.577048)
			(xy 66.551154 -31.623561) (xy 66.513937 -31.665098) (xy 66.471069 -31.700773) (xy 66.423463 -31.729827)
			(xy 66.372134 -31.751639) (xy 66.318177 -31.765745) (xy 66.26274 -31.771845) (xy 66.207006 -31.769808)
			(xy 66.152163 -31.759678) (xy 66.099379 -31.741671) (xy 66.049779 -31.71617) (xy 66.004421 -31.683719)
			(xy 65.964272 -31.64501) (xy 65.930186 -31.600867) (xy 65.90289 -31.552232) (xy 65.882967 -31.500141)
			(xy 65.870841 -31.445704) (xy 65.86677 -31.390082) (xy 64.074116 -31.390082) (xy 64.09091 -31.408825)
			(xy 64.121683 -31.455338) (xy 64.145355 -31.505835) (xy 64.161423 -31.559242) (xy 64.169543 -31.614418)
			(xy 64.170052 -31.642304) (xy 64.169543 -31.67019) (xy 64.161423 -31.725366) (xy 64.145355 -31.778773)
			(xy 64.121683 -31.82927) (xy 64.09091 -31.875783) (xy 64.053693 -31.91732) (xy 64.010825 -31.952995)
			(xy 63.963219 -31.982049) (xy 63.91189 -32.003861) (xy 63.857933 -32.017967) (xy 63.802496 -32.024067)
			(xy 63.746762 -32.02203) (xy 63.691919 -32.0119) (xy 63.639135 -31.993893) (xy 63.589535 -31.968392)
			(xy 63.544177 -31.935941) (xy 63.504028 -31.897232) (xy 63.469942 -31.853089) (xy 63.442646 -31.804454)
			(xy 63.422723 -31.752363) (xy 63.410597 -31.697926) (xy 63.406526 -31.642304) (xy 61.934452 -31.642304)
			(xy 61.918941 -31.660207) (xy 61.877755 -31.695901) (xy 61.831908 -31.72537) (xy 61.782335 -31.748014)
			(xy 61.730043 -31.763374) (xy 61.676098 -31.771137) (xy 61.648848 -31.77159) (xy 61.646054 -31.77159)
			(xy 61.63609 -31.772072) (xy 61.61766 -31.779654) (xy 61.61024 -31.786322) (xy 61.558932 -31.837122)
			(xy 61.552085 -31.84452) (xy 61.544354 -31.863119) (xy 61.543946 -31.87319) (xy 61.543946 -32.701992)
			(xy 61.544962 -32.712152) (xy 61.547756 -32.72663) (xy 61.55182 -32.736028) (xy 61.61024 -32.79394)
			(xy 61.617654 -32.800614) (xy 61.636089 -32.808175) (xy 61.646054 -32.808672) (xy 61.648848 -32.808672)
			(xy 61.676098 -32.809161) (xy 61.730044 -32.816924) (xy 61.782336 -32.832284) (xy 61.831909 -32.854929)
			(xy 61.877756 -32.884398) (xy 61.918943 -32.920091) (xy 61.954631 -32.961282) (xy 61.984094 -33.007133)
			(xy 62.006733 -33.056709) (xy 62.022087 -33.109003) (xy 62.029842 -33.16295) (xy 62.029842 -33.19018)
			(xy 63.673988 -33.19018) (xy 63.678059 -33.134558) (xy 63.690185 -33.080121) (xy 63.710108 -33.02803)
			(xy 63.737404 -32.979395) (xy 63.77149 -32.935252) (xy 63.811639 -32.896543) (xy 63.856997 -32.864092)
			(xy 63.906597 -32.838591) (xy 63.959381 -32.820584) (xy 64.014224 -32.810454) (xy 64.069958 -32.808417)
			(xy 64.125395 -32.814517) (xy 64.179352 -32.828623) (xy 64.230681 -32.850435) (xy 64.278287 -32.879489)
			(xy 64.321155 -32.915164) (xy 64.358372 -32.956701) (xy 64.389145 -33.003214) (xy 64.412817 -33.053711)
			(xy 64.428885 -33.107118) (xy 64.437005 -33.162294) (xy 64.437514 -33.19018) (xy 65.86677 -33.19018)
			(xy 65.870841 -33.134558) (xy 65.882967 -33.080121) (xy 65.90289 -33.02803) (xy 65.930186 -32.979395)
			(xy 65.964272 -32.935252) (xy 66.004421 -32.896543) (xy 66.049779 -32.864092) (xy 66.099379 -32.838591)
			(xy 66.152163 -32.820584) (xy 66.207006 -32.810454) (xy 66.26274 -32.808417) (xy 66.318177 -32.814517)
			(xy 66.372134 -32.828623) (xy 66.423463 -32.850435) (xy 66.471069 -32.879489) (xy 66.513937 -32.915164)
			(xy 66.551154 -32.956701) (xy 66.581927 -33.003214) (xy 66.605599 -33.053711) (xy 66.621667 -33.107118)
			(xy 66.629787 -33.162294) (xy 66.630296 -33.19018) (xy 67.89877 -33.19018) (xy 67.902841 -33.134558)
			(xy 67.914967 -33.080121) (xy 67.93489 -33.02803) (xy 67.962186 -32.979395) (xy 67.996272 -32.935252)
			(xy 68.036421 -32.896543) (xy 68.081779 -32.864092) (xy 68.131379 -32.838591) (xy 68.184163 -32.820584)
			(xy 68.239006 -32.810454) (xy 68.29474 -32.808417) (xy 68.350177 -32.814517) (xy 68.404134 -32.828623)
			(xy 68.455463 -32.850435) (xy 68.503069 -32.879489) (xy 68.545937 -32.915164) (xy 68.583154 -32.956701)
			(xy 68.613927 -33.003214) (xy 68.637599 -33.053711) (xy 68.653667 -33.107118) (xy 68.661787 -33.162294)
			(xy 68.662296 -33.19018) (xy 68.661787 -33.218066) (xy 68.653667 -33.273242) (xy 68.637599 -33.326649)
			(xy 68.613927 -33.377146) (xy 68.583154 -33.423659) (xy 68.545937 -33.465196) (xy 68.503069 -33.500871)
			(xy 68.455463 -33.529925) (xy 68.404134 -33.551737) (xy 68.350177 -33.565843) (xy 68.29474 -33.571943)
			(xy 68.239006 -33.569906) (xy 68.184163 -33.559776) (xy 68.131379 -33.541769) (xy 68.081779 -33.516268)
			(xy 68.036421 -33.483817) (xy 67.996272 -33.445108) (xy 67.962186 -33.400965) (xy 67.93489 -33.35233)
			(xy 67.914967 -33.300239) (xy 67.902841 -33.245802) (xy 67.89877 -33.19018) (xy 66.630296 -33.19018)
			(xy 66.629787 -33.218066) (xy 66.621667 -33.273242) (xy 66.605599 -33.326649) (xy 66.581927 -33.377146)
			(xy 66.551154 -33.423659) (xy 66.513937 -33.465196) (xy 66.471069 -33.500871) (xy 66.423463 -33.529925)
			(xy 66.372134 -33.551737) (xy 66.318177 -33.565843) (xy 66.26274 -33.571943) (xy 66.207006 -33.569906)
			(xy 66.152163 -33.559776) (xy 66.099379 -33.541769) (xy 66.049779 -33.516268) (xy 66.004421 -33.483817)
			(xy 65.964272 -33.445108) (xy 65.930186 -33.400965) (xy 65.90289 -33.35233) (xy 65.882967 -33.300239)
			(xy 65.870841 -33.245802) (xy 65.86677 -33.19018) (xy 64.437514 -33.19018) (xy 64.437005 -33.218066)
			(xy 64.428885 -33.273242) (xy 64.412817 -33.326649) (xy 64.389145 -33.377146) (xy 64.358372 -33.423659)
			(xy 64.321155 -33.465196) (xy 64.278287 -33.500871) (xy 64.230681 -33.529925) (xy 64.179352 -33.551737)
			(xy 64.125395 -33.565843) (xy 64.069958 -33.571943) (xy 64.014224 -33.569906) (xy 63.959381 -33.559776)
			(xy 63.906597 -33.541769) (xy 63.856997 -33.516268) (xy 63.811639 -33.483817) (xy 63.77149 -33.445108)
			(xy 63.737404 -33.400965) (xy 63.710108 -33.35233) (xy 63.690185 -33.300239) (xy 63.678059 -33.245802)
			(xy 63.673988 -33.19018) (xy 62.029842 -33.19018) (xy 62.029842 -33.21745) (xy 62.022087 -33.271397)
			(xy 62.006733 -33.32369) (xy 61.984094 -33.373267) (xy 61.954631 -33.419118) (xy 61.918943 -33.460309)
			(xy 61.877756 -33.496002) (xy 61.831909 -33.525471) (xy 61.782336 -33.548116) (xy 61.730044 -33.563476)
			(xy 61.676098 -33.571239) (xy 61.648848 -33.571688) (xy 61.646054 -33.571688) (xy 61.63609 -33.57217)
			(xy 61.617659 -33.579752) (xy 61.61024 -33.58642) (xy 61.558932 -33.63722) (xy 61.552085 -33.644618)
			(xy 61.544353 -33.663216) (xy 61.543946 -33.673288) (xy 61.543946 -34.501836) (xy 61.544962 -34.511996)
			(xy 61.547756 -34.526474) (xy 61.55182 -34.535872) (xy 61.61024 -34.593784) (xy 61.617651 -34.600464)
			(xy 61.636087 -34.608034) (xy 61.646054 -34.608516) (xy 61.648848 -34.608516) (xy 61.676095 -34.609005)
			(xy 61.730034 -34.616767) (xy 61.78232 -34.632125) (xy 61.831888 -34.654768) (xy 61.877729 -34.684233)
			(xy 61.918911 -34.719923) (xy 61.954595 -34.761109) (xy 61.984055 -34.806954) (xy 62.006691 -34.856525)
			(xy 62.022043 -34.908813) (xy 62.029798 -34.962753) (xy 62.029798 -34.990024) (xy 63.672718 -34.990024)
			(xy 63.676789 -34.934402) (xy 63.688915 -34.879965) (xy 63.708838 -34.827874) (xy 63.736134 -34.779239)
			(xy 63.77022 -34.735096) (xy 63.810369 -34.696387) (xy 63.855727 -34.663936) (xy 63.905327 -34.638435)
			(xy 63.958111 -34.620428) (xy 64.012954 -34.610298) (xy 64.068688 -34.608261) (xy 64.124125 -34.614361)
			(xy 64.178082 -34.628467) (xy 64.229411 -34.650279) (xy 64.277017 -34.679333) (xy 64.319885 -34.715008)
			(xy 64.357102 -34.756545) (xy 64.387875 -34.803058) (xy 64.411547 -34.853555) (xy 64.427615 -34.906962)
			(xy 64.435735 -34.962138) (xy 64.436244 -34.990024) (xy 65.000884 -34.990024) (xy 65.004955 -34.934402)
			(xy 65.017081 -34.879965) (xy 65.037004 -34.827874) (xy 65.0643 -34.779239) (xy 65.098386 -34.735096)
			(xy 65.138535 -34.696387) (xy 65.183893 -34.663936) (xy 65.233493 -34.638435) (xy 65.286277 -34.620428)
			(xy 65.34112 -34.610298) (xy 65.396854 -34.608261) (xy 65.452291 -34.614361) (xy 65.506248 -34.628467)
			(xy 65.557577 -34.650279) (xy 65.605183 -34.679333) (xy 65.648051 -34.715008) (xy 65.685268 -34.756545)
			(xy 65.716041 -34.803058) (xy 65.739713 -34.853555) (xy 65.755781 -34.906962) (xy 65.763901 -34.962138)
			(xy 65.76441 -34.990024) (xy 67.89877 -34.990024) (xy 67.902841 -34.934402) (xy 67.914967 -34.879965)
			(xy 67.93489 -34.827874) (xy 67.962186 -34.779239) (xy 67.996272 -34.735096) (xy 68.036421 -34.696387)
			(xy 68.081779 -34.663936) (xy 68.131379 -34.638435) (xy 68.184163 -34.620428) (xy 68.239006 -34.610298)
			(xy 68.29474 -34.608261) (xy 68.350177 -34.614361) (xy 68.404134 -34.628467) (xy 68.455463 -34.650279)
			(xy 68.503069 -34.679333) (xy 68.545937 -34.715008) (xy 68.583154 -34.756545) (xy 68.613927 -34.803058)
			(xy 68.637599 -34.853555) (xy 68.653667 -34.906962) (xy 68.661787 -34.962138) (xy 68.662296 -34.990024)
			(xy 68.661787 -35.01791) (xy 68.653667 -35.073086) (xy 68.637599 -35.126493) (xy 68.613927 -35.17699)
			(xy 68.583154 -35.223503) (xy 68.545937 -35.26504) (xy 68.503069 -35.300715) (xy 68.455463 -35.329769)
			(xy 68.404134 -35.351581) (xy 68.350177 -35.365687) (xy 68.29474 -35.371787) (xy 68.239006 -35.36975)
			(xy 68.184163 -35.35962) (xy 68.131379 -35.341613) (xy 68.081779 -35.316112) (xy 68.036421 -35.283661)
			(xy 67.996272 -35.244952) (xy 67.962186 -35.200809) (xy 67.93489 -35.152174) (xy 67.914967 -35.100083)
			(xy 67.902841 -35.045646) (xy 67.89877 -34.990024) (xy 65.76441 -34.990024) (xy 65.763901 -35.01791)
			(xy 65.755781 -35.073086) (xy 65.739713 -35.126493) (xy 65.716041 -35.17699) (xy 65.685268 -35.223503)
			(xy 65.648051 -35.26504) (xy 65.605183 -35.300715) (xy 65.557577 -35.329769) (xy 65.506248 -35.351581)
			(xy 65.452291 -35.365687) (xy 65.396854 -35.371787) (xy 65.34112 -35.36975) (xy 65.286277 -35.35962)
			(xy 65.233493 -35.341613) (xy 65.183893 -35.316112) (xy 65.138535 -35.283661) (xy 65.098386 -35.244952)
			(xy 65.0643 -35.200809) (xy 65.037004 -35.152174) (xy 65.017081 -35.100083) (xy 65.004955 -35.045646)
			(xy 65.000884 -34.990024) (xy 64.436244 -34.990024) (xy 64.435735 -35.01791) (xy 64.427615 -35.073086)
			(xy 64.411547 -35.126493) (xy 64.387875 -35.17699) (xy 64.357102 -35.223503) (xy 64.319885 -35.26504)
			(xy 64.277017 -35.300715) (xy 64.229411 -35.329769) (xy 64.178082 -35.351581) (xy 64.124125 -35.365687)
			(xy 64.068688 -35.371787) (xy 64.012954 -35.36975) (xy 63.958111 -35.35962) (xy 63.905327 -35.341613)
			(xy 63.855727 -35.316112) (xy 63.810369 -35.283661) (xy 63.77022 -35.244952) (xy 63.736134 -35.200809)
			(xy 63.708838 -35.152174) (xy 63.688915 -35.100083) (xy 63.676789 -35.045646) (xy 63.672718 -34.990024)
			(xy 62.029798 -34.990024) (xy 62.029798 -35.017247) (xy 62.022043 -35.071187) (xy 62.006691 -35.123475)
			(xy 61.984055 -35.173046) (xy 61.954595 -35.218891) (xy 61.918911 -35.260077) (xy 61.877729 -35.295767)
			(xy 61.831888 -35.325232) (xy 61.78232 -35.347875) (xy 61.730034 -35.363233) (xy 61.676095 -35.370995)
			(xy 61.648848 -35.371532) (xy 61.646054 -35.371532) (xy 61.636091 -35.372015) (xy 61.617664 -35.379601)
			(xy 61.61024 -35.386264) (xy 61.558932 -35.437064) (xy 61.552092 -35.444464) (xy 61.544376 -35.463063)
			(xy 61.543946 -35.473132) (xy 61.543946 -38.193438) (xy 63.098171 -38.193438) (xy 63.098171 -38.106562)
			(xy 63.106187 -38.020058) (xy 63.12215 -37.934662) (xy 63.145925 -37.851103) (xy 63.177308 -37.770095)
			(xy 63.216032 -37.692327) (xy 63.261767 -37.618465) (xy 63.314121 -37.549137) (xy 63.372649 -37.484936)
			(xy 63.436851 -37.42641) (xy 63.50618 -37.374056) (xy 63.580043 -37.328323) (xy 63.657811 -37.289601)
			(xy 63.73882 -37.258219) (xy 63.822379 -37.234446) (xy 63.907776 -37.218484) (xy 63.99428 -37.21047)
			(xy 64.037718 -37.209984) (xy 64.115696 -37.209984) (xy 64.125719 -37.209577) (xy 64.144239 -37.201905)
			(xy 64.158412 -37.187729) (xy 64.166079 -37.169207) (xy 64.166496 -37.159184) (xy 64.166496 -37.151564)
			(xy 64.162178 -37.137594) (xy 64.158114 -37.131244) (xy 64.134195 -37.094009) (xy 64.092494 -37.015944)
			(xy 64.058109 -36.93439) (xy 64.031331 -36.850033) (xy 64.012382 -36.76358) (xy 64.001422 -36.675755)
			(xy 63.998544 -36.587297) (xy 64.003771 -36.498946) (xy 64.017059 -36.411443) (xy 64.038297 -36.325524)
			(xy 64.067306 -36.241908) (xy 64.103844 -36.161296) (xy 64.147605 -36.084366) (xy 64.198219 -36.011762)
			(xy 64.255265 -35.944093) (xy 64.318262 -35.881927) (xy 64.386682 -35.825786) (xy 64.459952 -35.776139)
			(xy 64.537457 -35.733405) (xy 64.618546 -35.69794) (xy 64.70254 -35.670044) (xy 64.788734 -35.649948)
			(xy 64.876405 -35.637824) (xy 64.964818 -35.633771) (xy 65.053231 -35.637824) (xy 65.140902 -35.649948)
			(xy 65.227096 -35.670044) (xy 65.31109 -35.69794) (xy 65.392179 -35.733405) (xy 65.469684 -35.776139)
			(xy 65.542954 -35.825786) (xy 65.60505 -35.876738) (xy 70.717154 -35.876738) (xy 70.721225 -35.821116)
			(xy 70.733351 -35.766679) (xy 70.753274 -35.714588) (xy 70.78057 -35.665953) (xy 70.814656 -35.62181)
			(xy 70.854805 -35.583101) (xy 70.900163 -35.55065) (xy 70.949763 -35.525149) (xy 71.002547 -35.507142)
			(xy 71.05739 -35.497012) (xy 71.113124 -35.494975) (xy 71.168561 -35.501075) (xy 71.222518 -35.515181)
			(xy 71.273847 -35.536993) (xy 71.321453 -35.566047) (xy 71.364321 -35.601722) (xy 71.401538 -35.643259)
			(xy 71.432311 -35.689772) (xy 71.455983 -35.740269) (xy 71.472051 -35.793676) (xy 71.480171 -35.848852)
			(xy 71.48068 -35.876738) (xy 71.480171 -35.904624) (xy 71.472051 -35.9598) (xy 71.455983 -36.013207)
			(xy 71.432311 -36.063704) (xy 71.401538 -36.110217) (xy 71.364321 -36.151754) (xy 71.321453 -36.187429)
			(xy 71.273847 -36.216483) (xy 71.222518 -36.238295) (xy 71.168561 -36.252401) (xy 71.113124 -36.258501)
			(xy 71.05739 -36.256464) (xy 71.002547 -36.246334) (xy 70.949763 -36.228327) (xy 70.900163 -36.202826)
			(xy 70.854805 -36.170375) (xy 70.814656 -36.131666) (xy 70.78057 -36.087523) (xy 70.753274 -36.038888)
			(xy 70.733351 -35.986797) (xy 70.721225 -35.93236) (xy 70.717154 -35.876738) (xy 65.60505 -35.876738)
			(xy 65.611374 -35.881927) (xy 65.674371 -35.944093) (xy 65.731417 -36.011762) (xy 65.782031 -36.084366)
			(xy 65.825792 -36.161296) (xy 65.86233 -36.241908) (xy 65.891339 -36.325524) (xy 65.912577 -36.411443)
			(xy 65.925865 -36.498946) (xy 65.92829 -36.539928) (xy 72.538572 -36.539928) (xy 72.538572 -36.479992)
			(xy 72.546395 -36.42057) (xy 72.561908 -36.362677) (xy 72.584844 -36.307304) (xy 72.614811 -36.255398)
			(xy 72.651298 -36.207848) (xy 72.693678 -36.165468) (xy 72.741228 -36.128981) (xy 72.793134 -36.099014)
			(xy 72.848507 -36.076078) (xy 72.9064 -36.060565) (xy 72.965822 -36.052742) (xy 73.025758 -36.052742)
			(xy 73.08518 -36.060565) (xy 73.143073 -36.076078) (xy 73.198446 -36.099014) (xy 73.250352 -36.128981)
			(xy 73.297902 -36.165468) (xy 73.340282 -36.207848) (xy 73.376769 -36.255398) (xy 73.406736 -36.307304)
			(xy 73.429672 -36.362677) (xy 73.445185 -36.42057) (xy 73.453008 -36.479992) (xy 73.453498 -36.50996)
			(xy 73.453008 -36.539928) (xy 73.445185 -36.59935) (xy 73.429672 -36.657243) (xy 73.406736 -36.712616)
			(xy 73.376769 -36.764522) (xy 73.340282 -36.812072) (xy 73.297902 -36.854452) (xy 73.250352 -36.890939)
			(xy 73.198446 -36.920906) (xy 73.143073 -36.943842) (xy 73.08518 -36.959355) (xy 73.025758 -36.967178)
			(xy 72.965822 -36.967178) (xy 72.9064 -36.959355) (xy 72.848507 -36.943842) (xy 72.793134 -36.920906)
			(xy 72.741228 -36.890939) (xy 72.693678 -36.854452) (xy 72.651298 -36.812072) (xy 72.614811 -36.764522)
			(xy 72.584844 -36.712616) (xy 72.561908 -36.657243) (xy 72.546395 -36.59935) (xy 72.538572 -36.539928)
			(xy 65.92829 -36.539928) (xy 65.931092 -36.587297) (xy 65.928214 -36.675755) (xy 65.917254 -36.76358)
			(xy 65.898305 -36.850033) (xy 65.871527 -36.93439) (xy 65.837142 -37.015944) (xy 65.795441 -37.094009)
			(xy 65.771522 -37.131244) (xy 65.76314 -37.143944) (xy 65.76314 -37.159184) (xy 65.763533 -37.169209)
			(xy 65.771206 -37.187734) (xy 65.785387 -37.201908) (xy 65.803915 -37.209571) (xy 65.81394 -37.209984)
			(xy 65.891918 -37.209984) (xy 65.935357 -37.21041) (xy 66.021865 -37.218428) (xy 66.107264 -37.234394)
			(xy 66.190826 -37.25817) (xy 66.271838 -37.289556) (xy 66.349608 -37.328282) (xy 66.423473 -37.374019)
			(xy 66.492803 -37.426376) (xy 66.546316 -37.47516) (xy 69.759066 -37.47516) (xy 69.763137 -37.419538)
			(xy 69.775263 -37.365101) (xy 69.795186 -37.31301) (xy 69.822482 -37.264375) (xy 69.856568 -37.220232)
			(xy 69.896717 -37.181523) (xy 69.942075 -37.149072) (xy 69.991675 -37.123571) (xy 70.044459 -37.105564)
			(xy 70.099302 -37.095434) (xy 70.155036 -37.093397) (xy 70.210473 -37.099497) (xy 70.26443 -37.113603)
			(xy 70.315759 -37.135415) (xy 70.363365 -37.164469) (xy 70.406233 -37.200144) (xy 70.44345 -37.241681)
			(xy 70.474223 -37.288194) (xy 70.497895 -37.338691) (xy 70.513963 -37.392098) (xy 70.522083 -37.447274)
			(xy 70.522592 -37.47516) (xy 70.522083 -37.503046) (xy 70.513963 -37.558222) (xy 70.497895 -37.611629)
			(xy 70.474223 -37.662126) (xy 70.454243 -37.692326) (xy 71.873092 -37.692326) (xy 71.873092 -37.63239)
			(xy 71.880915 -37.572968) (xy 71.896428 -37.515075) (xy 71.919364 -37.459702) (xy 71.949331 -37.407796)
			(xy 71.985818 -37.360246) (xy 72.028198 -37.317866) (xy 72.075748 -37.281379) (xy 72.127654 -37.251412)
			(xy 72.183027 -37.228476) (xy 72.24092 -37.212963) (xy 72.300342 -37.20514) (xy 72.360278 -37.20514)
			(xy 72.4197 -37.212963) (xy 72.477593 -37.228476) (xy 72.532966 -37.251412) (xy 72.584872 -37.281379)
			(xy 72.632422 -37.317866) (xy 72.674802 -37.360246) (xy 72.711289 -37.407796) (xy 72.741256 -37.459702)
			(xy 72.764192 -37.515075) (xy 72.779705 -37.572968) (xy 72.787528 -37.63239) (xy 72.788018 -37.662358)
			(xy 72.787528 -37.692326) (xy 72.779705 -37.751748) (xy 72.764192 -37.809641) (xy 72.741256 -37.865014)
			(xy 72.711289 -37.91692) (xy 72.674802 -37.96447) (xy 72.632422 -38.00685) (xy 72.584872 -38.043337)
			(xy 72.532966 -38.073304) (xy 72.477593 -38.09624) (xy 72.4197 -38.111753) (xy 72.360278 -38.119576)
			(xy 72.300342 -38.119576) (xy 72.24092 -38.111753) (xy 72.183027 -38.09624) (xy 72.127654 -38.073304)
			(xy 72.075748 -38.043337) (xy 72.028198 -38.00685) (xy 71.985818 -37.96447) (xy 71.949331 -37.91692)
			(xy 71.919364 -37.865014) (xy 71.896428 -37.809641) (xy 71.880915 -37.751748) (xy 71.873092 -37.692326)
			(xy 70.454243 -37.692326) (xy 70.44345 -37.708639) (xy 70.406233 -37.750176) (xy 70.363365 -37.785851)
			(xy 70.315759 -37.814905) (xy 70.26443 -37.836717) (xy 70.210473 -37.850823) (xy 70.155036 -37.856923)
			(xy 70.099302 -37.854886) (xy 70.044459 -37.844756) (xy 69.991675 -37.826749) (xy 69.942075 -37.801248)
			(xy 69.896717 -37.768797) (xy 69.856568 -37.730088) (xy 69.822482 -37.685945) (xy 69.795186 -37.63731)
			(xy 69.775263 -37.585219) (xy 69.763137 -37.530782) (xy 69.759066 -37.47516) (xy 66.546316 -37.47516)
			(xy 66.557007 -37.484906) (xy 66.615536 -37.549111) (xy 66.667892 -37.618442) (xy 66.713627 -37.692308)
			(xy 66.752352 -37.770079) (xy 66.783735 -37.851091) (xy 66.807511 -37.934653) (xy 66.823474 -38.020053)
			(xy 66.83149 -38.106561) (xy 66.83149 -38.193439) (xy 66.823474 -38.279947) (xy 66.807511 -38.365347)
			(xy 66.783735 -38.448909) (xy 66.767368 -38.49116) (xy 69.759066 -38.49116) (xy 69.763137 -38.435538)
			(xy 69.775263 -38.381101) (xy 69.795186 -38.32901) (xy 69.822482 -38.280375) (xy 69.856568 -38.236232)
			(xy 69.896717 -38.197523) (xy 69.942075 -38.165072) (xy 69.991675 -38.139571) (xy 70.044459 -38.121564)
			(xy 70.099302 -38.111434) (xy 70.155036 -38.109397) (xy 70.210473 -38.115497) (xy 70.26443 -38.129603)
			(xy 70.315759 -38.151415) (xy 70.363365 -38.180469) (xy 70.406233 -38.216144) (xy 70.44345 -38.257681)
			(xy 70.474223 -38.304194) (xy 70.497895 -38.354691) (xy 70.513963 -38.408098) (xy 70.522083 -38.463274)
			(xy 70.522592 -38.49116) (xy 70.522083 -38.519046) (xy 70.513963 -38.574222) (xy 70.497895 -38.627629)
			(xy 70.474223 -38.678126) (xy 70.458945 -38.701218) (xy 73.437494 -38.701218) (xy 73.441565 -38.645596)
			(xy 73.453691 -38.591159) (xy 73.473614 -38.539068) (xy 73.50091 -38.490433) (xy 73.534996 -38.44629)
			(xy 73.575145 -38.407581) (xy 73.620503 -38.37513) (xy 73.670103 -38.349629) (xy 73.722887 -38.331622)
			(xy 73.77773 -38.321492) (xy 73.833464 -38.319455) (xy 73.888901 -38.325555) (xy 73.942858 -38.339661)
			(xy 73.994187 -38.361473) (xy 74.041793 -38.390527) (xy 74.084661 -38.426202) (xy 74.121878 -38.467739)
			(xy 74.152651 -38.514252) (xy 74.176323 -38.564749) (xy 74.192391 -38.618156) (xy 74.200511 -38.673332)
			(xy 74.20102 -38.701218) (xy 74.200511 -38.729104) (xy 74.192391 -38.78428) (xy 74.176323 -38.837687)
			(xy 74.152651 -38.888184) (xy 74.121878 -38.934697) (xy 74.084661 -38.976234) (xy 74.041793 -39.011909)
			(xy 73.994187 -39.040963) (xy 73.942858 -39.062775) (xy 73.888901 -39.076881) (xy 73.833464 -39.082981)
			(xy 73.77773 -39.080944) (xy 73.722887 -39.070814) (xy 73.670103 -39.052807) (xy 73.620503 -39.027306)
			(xy 73.575145 -38.994855) (xy 73.534996 -38.956146) (xy 73.50091 -38.912003) (xy 73.473614 -38.863368)
			(xy 73.453691 -38.811277) (xy 73.441565 -38.75684) (xy 73.437494 -38.701218) (xy 70.458945 -38.701218)
			(xy 70.44345 -38.724639) (xy 70.406233 -38.766176) (xy 70.363365 -38.801851) (xy 70.315759 -38.830905)
			(xy 70.26443 -38.852717) (xy 70.210473 -38.866823) (xy 70.155036 -38.872923) (xy 70.099302 -38.870886)
			(xy 70.044459 -38.860756) (xy 69.991675 -38.842749) (xy 69.942075 -38.817248) (xy 69.896717 -38.784797)
			(xy 69.856568 -38.746088) (xy 69.822482 -38.701945) (xy 69.795186 -38.65331) (xy 69.775263 -38.601219)
			(xy 69.763137 -38.546782) (xy 69.759066 -38.49116) (xy 66.767368 -38.49116) (xy 66.752352 -38.529921)
			(xy 66.713627 -38.607692) (xy 66.667892 -38.681558) (xy 66.615536 -38.750889) (xy 66.557007 -38.815094)
			(xy 66.492803 -38.873624) (xy 66.423473 -38.925981) (xy 66.349608 -38.971718) (xy 66.271838 -39.010444)
			(xy 66.190826 -39.04183) (xy 66.107264 -39.065606) (xy 66.021865 -39.081572) (xy 65.935357 -39.08959)
			(xy 65.891918 -39.090092) (xy 64.037718 -39.090092) (xy 63.99428 -39.08953) (xy 63.907776 -39.081516)
			(xy 63.822379 -39.065554) (xy 63.73882 -39.041781) (xy 63.657811 -39.010399) (xy 63.580043 -38.971677)
			(xy 63.50618 -38.925944) (xy 63.436851 -38.87359) (xy 63.372649 -38.815064) (xy 63.314121 -38.750863)
			(xy 63.261767 -38.681535) (xy 63.216032 -38.607673) (xy 63.177308 -38.529905) (xy 63.145925 -38.448897)
			(xy 63.12215 -38.365338) (xy 63.106187 -38.279942) (xy 63.098171 -38.193438) (xy 61.543946 -38.193438)
			(xy 61.543946 -42.849038) (xy 72.891902 -42.849038) (xy 72.895973 -42.793416) (xy 72.908099 -42.738979)
			(xy 72.928022 -42.686888) (xy 72.955318 -42.638253) (xy 72.989404 -42.59411) (xy 73.029553 -42.555401)
			(xy 73.074911 -42.52295) (xy 73.124511 -42.497449) (xy 73.177295 -42.479442) (xy 73.232138 -42.469312)
			(xy 73.287872 -42.467275) (xy 73.343309 -42.473375) (xy 73.397266 -42.487481) (xy 73.448595 -42.509293)
			(xy 73.496201 -42.538347) (xy 73.539069 -42.574022) (xy 73.576286 -42.615559) (xy 73.607059 -42.662072)
			(xy 73.630731 -42.712569) (xy 73.646799 -42.765976) (xy 73.654919 -42.821152) (xy 73.655428 -42.849038)
			(xy 73.654919 -42.876924) (xy 73.646799 -42.9321) (xy 73.630731 -42.985507) (xy 73.607059 -43.036004)
			(xy 73.576286 -43.082517) (xy 73.539069 -43.124054) (xy 73.496201 -43.159729) (xy 73.448595 -43.188783)
			(xy 73.397266 -43.210595) (xy 73.343309 -43.224701) (xy 73.287872 -43.230801) (xy 73.232138 -43.228764)
			(xy 73.177295 -43.218634) (xy 73.124511 -43.200627) (xy 73.074911 -43.175126) (xy 73.029553 -43.142675)
			(xy 72.989404 -43.103966) (xy 72.955318 -43.059823) (xy 72.928022 -43.011188) (xy 72.908099 -42.959097)
			(xy 72.895973 -42.90466) (xy 72.891902 -42.849038) (xy 61.543946 -42.849038) (xy 61.543946 -43.719242)
			(xy 61.544409 -43.729118) (xy 61.551853 -43.747415) (xy 61.558424 -43.754802) (xy 61.558678 -43.755056)
			(xy 62.036706 -44.233084) (xy 62.037214 -44.233592) (xy 62.044595 -44.240176) (xy 62.062893 -44.247635)
			(xy 62.072774 -44.24807)
		)
		(stroke
			(width 0)
			(type solid)
		)
		(fill yes)
		(layer "B.Cu")
		(net "P12V_SSD2")
	)
	(gr_poly
		(pts
			(xy 280.077418 -44.45381) (xy 280.087295 -44.45335) (xy 280.105595 -44.445908) (xy 280.112978 -44.439332)
			(xy 280.113232 -44.439078) (xy 280.67254 -43.87977) (xy 280.673048 -43.879262) (xy 280.679633 -43.871882)
			(xy 280.68709 -43.853583) (xy 280.687526 -43.843702) (xy 280.687526 -37.58946) (xy 280.687099 -37.580069)
			(xy 280.680359 -37.562538) (xy 280.667788 -37.548583) (xy 280.659586 -37.543994) (xy 280.578814 -37.5031)
			(xy 280.570208 -37.499259) (xy 280.551467 -37.497425) (xy 280.533317 -37.502442) (xy 280.525474 -37.507672)
			(xy 280.500679 -37.525306) (xy 280.446664 -37.553307) (xy 280.388889 -37.572378) (xy 280.328819 -37.582036)
			(xy 280.298398 -37.582602) (xy 280.271147 -37.582116) (xy 280.217201 -37.574359) (xy 280.164907 -37.559004)
			(xy 280.115331 -37.536364) (xy 280.069481 -37.506898) (xy 280.028292 -37.471207) (xy 279.992601 -37.430017)
			(xy 279.963136 -37.384168) (xy 279.940495 -37.334591) (xy 279.92514 -37.282297) (xy 279.917384 -37.228351)
			(xy 279.917384 -37.173849) (xy 279.92514 -37.119903) (xy 279.940495 -37.067609) (xy 279.963136 -37.018032)
			(xy 279.992601 -36.972183) (xy 280.028292 -36.930993) (xy 280.069481 -36.895302) (xy 280.115331 -36.865836)
			(xy 280.164907 -36.843196) (xy 280.217201 -36.827841) (xy 280.271147 -36.820084) (xy 280.298398 -36.819586)
			(xy 280.328818 -36.820178) (xy 280.388886 -36.82983) (xy 280.446663 -36.848891) (xy 280.500683 -36.876878)
			(xy 280.525474 -36.894516) (xy 280.533251 -36.899891) (xy 280.551445 -36.904975) (xy 280.57024 -36.903069)
			(xy 280.578814 -36.899088) (xy 280.659586 -36.858194) (xy 280.667819 -36.853639) (xy 280.68043 -36.839695)
			(xy 280.687141 -36.822131) (xy 280.687526 -36.812728) (xy 280.687526 -35.109658) (xy 280.668984 -35.083496)
			(xy 280.653744 -35.078162) (xy 280.62747 -35.068321) (xy 280.577906 -35.042034) (xy 280.532723 -35.008774)
			(xy 280.492895 -34.96926) (xy 280.47569 -34.947098) (xy 280.470356 -34.939986) (xy 280.448258 -34.925254)
			(xy 280.444306 -34.922823) (xy 280.435746 -34.919246) (xy 280.43124 -34.918142) (xy 280.401014 -34.911284)
			(xy 280.382218 -34.914078) (xy 280.373836 -34.91865) (xy 280.355455 -34.928878) (xy 280.317168 -34.946307)
			(xy 280.297382 -34.953448) (xy 280.273182 -34.961492) (xy 280.223448 -34.972788) (xy 280.172768 -34.978491)
			(xy 280.147268 -34.978848) (xy 280.121768 -34.978485) (xy 280.071088 -34.972788) (xy 280.021355 -34.961491)
			(xy 279.997154 -34.953448) (xy 279.97737 -34.946302) (xy 279.939083 -34.928875) (xy 279.9207 -34.91865)
			(xy 279.912318 -34.914078) (xy 279.893522 -34.911284) (xy 279.863296 -34.918142) (xy 279.858775 -34.919202)
			(xy 279.850204 -34.922774) (xy 279.846278 -34.925254) (xy 279.823926 -34.94024) (xy 279.818846 -34.947352)
			(xy 279.800695 -34.970652) (xy 279.758416 -35.011889) (xy 279.710284 -35.046115) (xy 279.65745 -35.07251)
			(xy 279.601178 -35.090444) (xy 279.542815 -35.099486) (xy 279.513284 -35.100006) (xy 279.502362 -35.100006)
			(xy 279.502108 -35.099752) (xy 279.475396 -35.098512) (xy 279.422688 -35.089483) (xy 279.371758 -35.073184)
			(xy 279.323601 -35.049935) (xy 279.279162 -35.020191) (xy 279.239311 -34.984534) (xy 279.204827 -34.943663)
			(xy 279.176387 -34.898377) (xy 279.154548 -34.849565) (xy 279.139737 -34.798183) (xy 279.132244 -34.745235)
			(xy 279.131776 -34.718498) (xy 279.132262 -34.691246) (xy 279.140019 -34.637298) (xy 279.155374 -34.585003)
			(xy 279.178015 -34.535425) (xy 279.207481 -34.489573) (xy 279.243172 -34.448382) (xy 279.284362 -34.412689)
			(xy 279.330212 -34.383221) (xy 279.379789 -34.360579) (xy 279.432084 -34.345222) (xy 279.486032 -34.337463)
			(xy 279.513284 -34.33699) (xy 279.528077 -34.337135) (xy 279.557573 -34.339428) (xy 279.572212 -34.341562)
			(xy 279.583134 -34.34334) (xy 279.60447 -34.337244) (xy 279.671526 -34.280094) (xy 279.679669 -34.272507)
			(xy 279.689039 -34.252348) (xy 279.68956 -34.241232) (xy 279.68956 -33.93694) (xy 279.688993 -33.925834)
			(xy 279.679634 -33.90569) (xy 279.671526 -33.898078) (xy 279.60447 -33.840928) (xy 279.583134 -33.834832)
			(xy 279.572212 -33.83661) (xy 279.557386 -33.838782) (xy 279.527506 -33.84107) (xy 279.512522 -33.841182)
			(xy 279.512268 -33.841182) (xy 279.485066 -33.840625) (xy 279.431231 -33.83275) (xy 279.379062 -33.817305)
			(xy 279.329616 -33.794605) (xy 279.283897 -33.76511) (xy 279.242832 -33.729419) (xy 279.207255 -33.688255)
			(xy 279.177887 -33.642455) (xy 279.155324 -33.592946) (xy 279.140024 -33.540734) (xy 279.132298 -33.486878)
			(xy 279.131776 -33.459674) (xy 279.132264 -33.432424) (xy 279.140023 -33.378478) (xy 279.15538 -33.326185)
			(xy 279.178023 -33.27661) (xy 279.207489 -33.230762) (xy 279.243181 -33.189574) (xy 279.28437 -33.153883)
			(xy 279.330219 -33.124418) (xy 279.379795 -33.101777) (xy 279.432088 -33.086421) (xy 279.486034 -33.078663)
			(xy 279.513284 -33.078166) (xy 279.513538 -33.078166) (xy 279.543045 -33.078719) (xy 279.601354 -33.087807)
			(xy 279.65757 -33.10576) (xy 279.710354 -33.13215) (xy 279.758448 -33.166349) (xy 279.800706 -33.207542)
			(xy 279.818846 -33.23082) (xy 279.823926 -33.237932) (xy 279.846278 -33.252918) (xy 279.85023 -33.255347)
			(xy 279.858791 -33.25892) (xy 279.863296 -33.26003) (xy 279.893522 -33.266888) (xy 279.912318 -33.264094)
			(xy 279.9207 -33.259522) (xy 279.939082 -33.249296) (xy 279.97737 -33.231871) (xy 279.997154 -33.224724)
			(xy 280.021355 -33.216682) (xy 280.071089 -33.205391) (xy 280.121769 -33.199692) (xy 280.147268 -33.199324)
			(xy 280.172767 -33.199689) (xy 280.223447 -33.205389) (xy 280.273178 -33.21669) (xy 280.297382 -33.224724)
			(xy 280.317165 -33.231871) (xy 280.355452 -33.2493) (xy 280.373836 -33.259522) (xy 280.382218 -33.264094)
			(xy 280.401014 -33.266888) (xy 280.43124 -33.26003) (xy 280.43576 -33.258967) (xy 280.444326 -33.255388)
			(xy 280.448258 -33.252918) (xy 280.470356 -33.238186) (xy 280.47569 -33.231074) (xy 280.492893 -33.208912)
			(xy 280.532722 -33.1694) (xy 280.577909 -33.136148) (xy 280.627479 -33.109874) (xy 280.653744 -33.10001)
			(xy 280.668984 -33.094676) (xy 280.687526 -33.068514) (xy 280.687526 -31.509462) (xy 280.668984 -31.4833)
			(xy 280.653744 -31.477966) (xy 280.62747 -31.468125) (xy 280.577905 -31.441838) (xy 280.532722 -31.408579)
			(xy 280.492894 -31.369064) (xy 280.47569 -31.346902) (xy 280.470356 -31.33979) (xy 280.448258 -31.325058)
			(xy 280.444306 -31.322627) (xy 280.435746 -31.31905) (xy 280.43124 -31.317946) (xy 280.401014 -31.311088)
			(xy 280.382218 -31.313882) (xy 280.373836 -31.318454) (xy 280.355455 -31.328681) (xy 280.317168 -31.346111)
			(xy 280.297382 -31.353252) (xy 280.273182 -31.361296) (xy 280.223448 -31.372591) (xy 280.172768 -31.378295)
			(xy 280.147268 -31.378652) (xy 280.121768 -31.378289) (xy 280.071088 -31.372592) (xy 280.021355 -31.361295)
			(xy 279.997154 -31.353252) (xy 279.97737 -31.346106) (xy 279.939083 -31.328679) (xy 279.9207 -31.318454)
			(xy 279.912318 -31.313882) (xy 279.893522 -31.311088) (xy 279.863296 -31.317946) (xy 279.858775 -31.319006)
			(xy 279.850204 -31.322578) (xy 279.846278 -31.325058) (xy 279.823926 -31.340044) (xy 279.818846 -31.347156)
			(xy 279.800695 -31.370455) (xy 279.758415 -31.411693) (xy 279.710283 -31.445918) (xy 279.65745 -31.472313)
			(xy 279.601178 -31.490246) (xy 279.542815 -31.499289) (xy 279.513284 -31.49981) (xy 279.502362 -31.49981)
			(xy 279.502108 -31.499556) (xy 279.475395 -31.498316) (xy 279.422688 -31.489287) (xy 279.371757 -31.472988)
			(xy 279.323601 -31.449739) (xy 279.279161 -31.419995) (xy 279.239309 -31.384338) (xy 279.204825 -31.343467)
			(xy 279.176385 -31.298182) (xy 279.154545 -31.24937) (xy 279.139734 -31.197987) (xy 279.13224 -31.145039)
			(xy 279.131776 -31.118302) (xy 279.132262 -31.09105) (xy 279.140018 -31.037101) (xy 279.155373 -30.984806)
			(xy 279.178013 -30.935227) (xy 279.207479 -30.889375) (xy 279.243171 -30.848183) (xy 279.284361 -30.81249)
			(xy 279.330211 -30.783022) (xy 279.379789 -30.760379) (xy 279.432084 -30.745022) (xy 279.486032 -30.737263)
			(xy 279.513284 -30.736794) (xy 279.528077 -30.736939) (xy 279.557573 -30.739232) (xy 279.572212 -30.741366)
			(xy 279.583134 -30.743144) (xy 279.60447 -30.737048) (xy 279.671526 -30.679898) (xy 279.679669 -30.672311)
			(xy 279.689041 -30.652152) (xy 279.68956 -30.641036) (xy 279.68956 -30.336744) (xy 279.688994 -30.325638)
			(xy 279.679636 -30.305492) (xy 279.671526 -30.297882) (xy 279.60447 -30.240732) (xy 279.583134 -30.234636)
			(xy 279.572212 -30.236414) (xy 279.557386 -30.238586) (xy 279.527506 -30.240874) (xy 279.512522 -30.240986)
			(xy 279.512268 -30.240986) (xy 279.485066 -30.240429) (xy 279.431231 -30.232554) (xy 279.379061 -30.217109)
			(xy 279.329615 -30.194409) (xy 279.283896 -30.164915) (xy 279.24283 -30.129223) (xy 279.207253 -30.08806)
			(xy 279.177884 -30.042259) (xy 279.155321 -29.99275) (xy 279.140021 -29.940538) (xy 279.132294 -29.886682)
			(xy 279.131776 -29.859478) (xy 279.132263 -29.832227) (xy 279.140022 -29.778281) (xy 279.155379 -29.725988)
			(xy 279.178021 -29.676413) (xy 279.207488 -29.630564) (xy 279.243179 -29.589375) (xy 279.284369 -29.553684)
			(xy 279.330218 -29.524218) (xy 279.379794 -29.501577) (xy 279.432087 -29.486221) (xy 279.486033 -29.478463)
			(xy 279.513284 -29.47797) (xy 279.513538 -29.47797) (xy 279.543045 -29.478523) (xy 279.601354 -29.487611)
			(xy 279.65757 -29.505564) (xy 279.710354 -29.531954) (xy 279.758447 -29.566154) (xy 279.800705 -29.607347)
			(xy 279.818846 -29.630624) (xy 279.823926 -29.637736) (xy 279.846278 -29.652722) (xy 279.85023 -29.655151)
			(xy 279.858791 -29.658724) (xy 279.863296 -29.659834) (xy 279.893522 -29.666692) (xy 279.912318 -29.663898)
			(xy 279.9207 -29.659326) (xy 279.939082 -29.6491) (xy 279.97737 -29.631674) (xy 279.997154 -29.624528)
			(xy 280.021355 -29.616486) (xy 280.071089 -29.605195) (xy 280.121769 -29.599496) (xy 280.147268 -29.599128)
			(xy 280.172767 -29.599493) (xy 280.223447 -29.605194) (xy 280.273178 -29.616494) (xy 280.297382 -29.624528)
			(xy 280.317165 -29.631675) (xy 280.355452 -29.649104) (xy 280.373836 -29.659326) (xy 280.382218 -29.663898)
			(xy 280.401014 -29.666692) (xy 280.43124 -29.659834) (xy 280.43576 -29.658771) (xy 280.444326 -29.655192)
			(xy 280.448258 -29.652722) (xy 280.470356 -29.63799) (xy 280.47569 -29.630878) (xy 280.492893 -29.608715)
			(xy 280.532722 -29.569203) (xy 280.577908 -29.535951) (xy 280.627478 -29.509677) (xy 280.653744 -29.499814)
			(xy 280.668984 -29.49448) (xy 280.687526 -29.468318) (xy 280.687526 -19.837908) (xy 280.687317 -19.831327)
			(xy 280.683973 -19.818597) (xy 280.680922 -19.812762) (xy 280.665682 -19.786346) (xy 280.657554 -19.77771)
			(xy 280.65222 -19.774154) (xy 280.630421 -19.759651) (xy 280.590636 -19.725614) (xy 280.555876 -19.686458)
			(xy 280.540968 -19.664934) (xy 280.540714 -19.66468) (xy 280.540714 -19.664426) (xy 280.534428 -19.656125)
			(xy 280.516868 -19.644971) (xy 280.506678 -19.642836) (xy 280.433272 -19.631152) (xy 280.422907 -19.62997)
			(xy 280.4027 -19.635074) (xy 280.394156 -19.641058) (xy 280.373999 -19.656166) (xy 280.330467 -19.681518)
			(xy 280.283981 -19.700927) (xy 280.235347 -19.714058) (xy 280.18541 -19.720683) (xy 280.160222 -19.721068)
			(xy 280.152602 -19.721068) (xy 280.125709 -19.72007) (xy 280.072588 -19.711446) (xy 280.021207 -19.695441)
			(xy 279.972585 -19.672374) (xy 279.927689 -19.642701) (xy 279.887409 -19.607012) (xy 279.852545 -19.566017)
			(xy 279.823789 -19.520527) (xy 279.801712 -19.471448) (xy 279.786753 -19.419753) (xy 279.779209 -19.366468)
			(xy 279.778714 -19.33956) (xy 279.779252 -19.310645) (xy 279.787989 -19.25348) (xy 279.805256 -19.198289)
			(xy 279.830657 -19.146337) (xy 279.86361 -19.098815) (xy 279.903361 -19.056813) (xy 279.948996 -19.021294)
			(xy 279.999471 -18.993072) (xy 280.026364 -18.982436) (xy 280.038556 -18.977864) (xy 280.05532 -18.958306)
			(xy 280.076148 -18.862294) (xy 280.078034 -18.850613) (xy 280.07222 -18.827703) (xy 280.064972 -18.818352)
			(xy 280.063702 -18.816828) (xy 279.867868 -18.620994) (xy 279.860756 -18.613628) (xy 279.84196 -18.606008)
			(xy 268.129258 -18.606008) (xy 268.119191 -18.606439) (xy 268.100599 -18.614165) (xy 268.09319 -18.620994)
			(xy 267.758926 -18.955258) (xy 267.75156 -18.96237) (xy 267.74394 -18.981166) (xy 267.74394 -21.738336)
			(xy 269.616682 -21.738336) (xy 269.617172 -21.709596) (xy 269.625803 -21.652767) (xy 269.642862 -21.597876)
			(xy 269.667961 -21.546165) (xy 269.700532 -21.498804) (xy 269.719806 -21.477478) (xy 269.72641 -21.470366)
			(xy 269.733522 -21.45284) (xy 269.733522 -21.363432) (xy 269.72641 -21.345906) (xy 269.719806 -21.338794)
			(xy 269.700572 -21.317436) (xy 269.668007 -21.270078) (xy 269.642914 -21.218371) (xy 269.625863 -21.163486)
			(xy 269.617237 -21.106663) (xy 269.617233 -21.049189) (xy 269.625851 -20.992366) (xy 269.642895 -20.937477)
			(xy 269.66798 -20.885767) (xy 269.700539 -20.838405) (xy 269.719806 -20.817078) (xy 269.72641 -20.809966)
			(xy 269.733522 -20.79244) (xy 269.733522 -20.703032) (xy 269.72641 -20.685506) (xy 269.719806 -20.678394)
			(xy 269.700572 -20.657036) (xy 269.668007 -20.609678) (xy 269.642914 -20.557971) (xy 269.625863 -20.503086)
			(xy 269.617237 -20.446263) (xy 269.617233 -20.388789) (xy 269.625851 -20.331966) (xy 269.642895 -20.277077)
			(xy 269.66798 -20.225367) (xy 269.700539 -20.178005) (xy 269.719806 -20.156678) (xy 269.72641 -20.149566)
			(xy 269.733522 -20.13204) (xy 269.733522 -20.042632) (xy 269.72641 -20.025106) (xy 269.719806 -20.017994)
			(xy 269.700572 -19.996636) (xy 269.668007 -19.949278) (xy 269.642914 -19.897571) (xy 269.625863 -19.842686)
			(xy 269.617237 -19.785863) (xy 269.617233 -19.728389) (xy 269.625851 -19.671566) (xy 269.642895 -19.616677)
			(xy 269.66798 -19.564967) (xy 269.700539 -19.517605) (xy 269.719806 -19.496278) (xy 269.72641 -19.489166)
			(xy 269.733522 -19.47164) (xy 269.733522 -19.382232) (xy 269.72641 -19.364706) (xy 269.719806 -19.357594)
			(xy 269.700564 -19.336242) (xy 269.667991 -19.288888) (xy 269.642892 -19.237183) (xy 269.625835 -19.182297)
			(xy 269.617206 -19.125473) (xy 269.616682 -19.096736) (xy 269.617168 -19.069485) (xy 269.624924 -19.015537)
			(xy 269.640279 -18.963242) (xy 269.662921 -18.913665) (xy 269.692387 -18.867815) (xy 269.728078 -18.826624)
			(xy 269.769269 -18.790933) (xy 269.815119 -18.761467) (xy 269.864696 -18.738825) (xy 269.916991 -18.72347)
			(xy 269.970939 -18.715714) (xy 270.025441 -18.715714) (xy 270.079389 -18.72347) (xy 270.131684 -18.738825)
			(xy 270.181261 -18.761467) (xy 270.227111 -18.790933) (xy 270.268302 -18.826624) (xy 270.303993 -18.867815)
			(xy 270.333459 -18.913665) (xy 270.356101 -18.963242) (xy 270.371456 -19.015537) (xy 270.379212 -19.069485)
			(xy 270.379698 -19.096736) (xy 270.379197 -19.125476) (xy 270.370569 -19.182304) (xy 270.353513 -19.237195)
			(xy 270.328417 -19.288907) (xy 270.295847 -19.336268) (xy 270.276574 -19.357594) (xy 270.26997 -19.364706)
			(xy 270.262858 -19.382232) (xy 270.262858 -19.47164) (xy 270.26997 -19.489166) (xy 270.276574 -19.496278)
			(xy 270.295881 -19.517574) (xy 270.328445 -19.564941) (xy 270.353535 -19.616658) (xy 270.370582 -19.671554)
			(xy 270.379201 -19.728385) (xy 270.379197 -19.785867) (xy 270.37057 -19.842697) (xy 270.353515 -19.897591)
			(xy 270.328418 -19.949304) (xy 270.295848 -19.996667) (xy 270.276574 -20.017994) (xy 270.26997 -20.025106)
			(xy 270.262858 -20.042632) (xy 270.262858 -20.13204) (xy 270.26997 -20.149566) (xy 270.276574 -20.156678)
			(xy 270.295881 -20.177974) (xy 270.328445 -20.225341) (xy 270.353535 -20.277058) (xy 270.370582 -20.331954)
			(xy 270.374162 -20.35556) (xy 279.778204 -20.35556) (xy 279.782275 -20.299938) (xy 279.794401 -20.245501)
			(xy 279.814324 -20.19341) (xy 279.84162 -20.144775) (xy 279.875706 -20.100632) (xy 279.915855 -20.061923)
			(xy 279.961213 -20.029472) (xy 280.010813 -20.003971) (xy 280.063597 -19.985964) (xy 280.11844 -19.975834)
			(xy 280.174174 -19.973797) (xy 280.229611 -19.979897) (xy 280.283568 -19.994003) (xy 280.334897 -20.015815)
			(xy 280.382503 -20.044869) (xy 280.425371 -20.080544) (xy 280.462588 -20.122081) (xy 280.493361 -20.168594)
			(xy 280.517033 -20.219091) (xy 280.533101 -20.272498) (xy 280.541221 -20.327674) (xy 280.54173 -20.35556)
			(xy 280.541221 -20.383446) (xy 280.533101 -20.438622) (xy 280.517033 -20.492029) (xy 280.493361 -20.542526)
			(xy 280.462588 -20.589039) (xy 280.425371 -20.630576) (xy 280.382503 -20.666251) (xy 280.334897 -20.695305)
			(xy 280.283568 -20.717117) (xy 280.229611 -20.731223) (xy 280.174174 -20.737323) (xy 280.11844 -20.735286)
			(xy 280.063597 -20.725156) (xy 280.010813 -20.707149) (xy 279.961213 -20.681648) (xy 279.915855 -20.649197)
			(xy 279.875706 -20.610488) (xy 279.84162 -20.566345) (xy 279.814324 -20.51771) (xy 279.794401 -20.465619)
			(xy 279.782275 -20.411182) (xy 279.778204 -20.35556) (xy 270.374162 -20.35556) (xy 270.379201 -20.388785)
			(xy 270.379197 -20.446267) (xy 270.37057 -20.503097) (xy 270.353515 -20.557991) (xy 270.328418 -20.609704)
			(xy 270.295848 -20.657067) (xy 270.276574 -20.678394) (xy 270.26997 -20.685506) (xy 270.262858 -20.703032)
			(xy 270.262858 -20.79244) (xy 270.26997 -20.809966) (xy 270.276574 -20.817078) (xy 270.295881 -20.838374)
			(xy 270.328445 -20.885741) (xy 270.353535 -20.937458) (xy 270.370582 -20.992354) (xy 270.379201 -21.049185)
			(xy 270.379197 -21.106667) (xy 270.37057 -21.163497) (xy 270.353515 -21.218391) (xy 270.328418 -21.270104)
			(xy 270.295848 -21.317467) (xy 270.276574 -21.338794) (xy 270.26997 -21.345906) (xy 270.262858 -21.363432)
			(xy 270.262858 -21.37156) (xy 279.778204 -21.37156) (xy 279.782275 -21.315938) (xy 279.794401 -21.261501)
			(xy 279.814324 -21.20941) (xy 279.84162 -21.160775) (xy 279.875706 -21.116632) (xy 279.915855 -21.077923)
			(xy 279.961213 -21.045472) (xy 280.010813 -21.019971) (xy 280.063597 -21.001964) (xy 280.11844 -20.991834)
			(xy 280.174174 -20.989797) (xy 280.229611 -20.995897) (xy 280.283568 -21.010003) (xy 280.334897 -21.031815)
			(xy 280.382503 -21.060869) (xy 280.425371 -21.096544) (xy 280.462588 -21.138081) (xy 280.493361 -21.184594)
			(xy 280.517033 -21.235091) (xy 280.533101 -21.288498) (xy 280.541221 -21.343674) (xy 280.54173 -21.37156)
			(xy 280.541221 -21.399446) (xy 280.533101 -21.454622) (xy 280.517033 -21.508029) (xy 280.493361 -21.558526)
			(xy 280.462588 -21.605039) (xy 280.425371 -21.646576) (xy 280.382503 -21.682251) (xy 280.334897 -21.711305)
			(xy 280.283568 -21.733117) (xy 280.229611 -21.747223) (xy 280.174174 -21.753323) (xy 280.11844 -21.751286)
			(xy 280.063597 -21.741156) (xy 280.010813 -21.723149) (xy 279.961213 -21.697648) (xy 279.915855 -21.665197)
			(xy 279.875706 -21.626488) (xy 279.84162 -21.582345) (xy 279.814324 -21.53371) (xy 279.794401 -21.481619)
			(xy 279.782275 -21.427182) (xy 279.778204 -21.37156) (xy 270.262858 -21.37156) (xy 270.262858 -21.45284)
			(xy 270.26997 -21.470366) (xy 270.276574 -21.477478) (xy 270.295864 -21.498789) (xy 270.328427 -21.546155)
			(xy 270.353516 -21.597871) (xy 270.370562 -21.652765) (xy 270.37918 -21.709596) (xy 270.379698 -21.738336)
			(xy 270.379212 -21.765587) (xy 270.371456 -21.819535) (xy 270.356101 -21.87183) (xy 270.333459 -21.921407)
			(xy 270.303993 -21.967257) (xy 270.268302 -22.008448) (xy 270.227111 -22.044139) (xy 270.181261 -22.073605)
			(xy 270.131684 -22.096247) (xy 270.079389 -22.111602) (xy 270.025441 -22.119358) (xy 269.970939 -22.119358)
			(xy 269.916991 -22.111602) (xy 269.864696 -22.096247) (xy 269.815119 -22.073605) (xy 269.769269 -22.044139)
			(xy 269.728078 -22.008448) (xy 269.692387 -21.967257) (xy 269.662921 -21.921407) (xy 269.640279 -21.87183)
			(xy 269.624924 -21.819535) (xy 269.617168 -21.765587) (xy 269.616682 -21.738336) (xy 267.74394 -21.738336)
			(xy 267.74394 -22.995156) (xy 269.487017 -22.995156) (xy 269.494838 -22.935723) (xy 269.51035 -22.87782)
			(xy 269.533287 -22.822437) (xy 269.563256 -22.770522) (xy 269.599746 -22.722963) (xy 269.642131 -22.680574)
			(xy 269.689687 -22.64408) (xy 269.7416 -22.614105) (xy 269.79698 -22.591163) (xy 269.854882 -22.575646)
			(xy 269.914314 -22.56782) (xy 269.974258 -22.567818) (xy 270.03369 -22.575641) (xy 270.091593 -22.591154)
			(xy 270.146975 -22.614093) (xy 270.198889 -22.644064) (xy 270.246447 -22.680555) (xy 270.288835 -22.722942)
			(xy 270.325328 -22.770499) (xy 270.355301 -22.822412) (xy 270.378241 -22.877794) (xy 270.393756 -22.935696)
			(xy 270.401581 -22.995128) (xy 270.40205 -23.0251) (xy 270.401827 -23.045661) (xy 270.398138 -23.086618)
			(xy 270.394684 -23.106888) (xy 270.392144 -23.120604) (xy 270.401034 -23.145496) (xy 270.487648 -23.22068)
			(xy 270.513556 -23.226014) (xy 270.526764 -23.221696) (xy 270.555968 -23.212614) (xy 270.616329 -23.202786)
			(xy 270.646906 -23.202138) (xy 270.665833 -23.202407) (xy 270.703495 -23.206219) (xy 270.72209 -23.209758)
			(xy 270.73479 -23.212044) (xy 270.758412 -23.205186) (xy 270.836898 -23.128986) (xy 270.844518 -23.105618)
			(xy 270.842486 -23.092918) (xy 270.839426 -23.073888) (xy 270.836115 -23.035483) (xy 270.835882 -23.01621)
			(xy 270.83635 -22.98624) (xy 270.844173 -22.926813) (xy 270.859685 -22.868915) (xy 270.882622 -22.813537)
			(xy 270.912592 -22.761627) (xy 270.94908 -22.714073) (xy 270.991463 -22.671689) (xy 271.039016 -22.635199)
			(xy 271.090925 -22.605228) (xy 271.146302 -22.58229) (xy 271.2042 -22.566776) (xy 271.263627 -22.558951)
			(xy 271.323567 -22.558951) (xy 271.382994 -22.566774) (xy 271.440891 -22.582288) (xy 271.496269 -22.605225)
			(xy 271.548178 -22.635195) (xy 271.595732 -22.671684) (xy 271.638116 -22.714068) (xy 271.674605 -22.761622)
			(xy 271.704575 -22.813531) (xy 271.727512 -22.868909) (xy 271.743026 -22.926806) (xy 271.750849 -22.986233)
			(xy 271.750849 -23.046173) (xy 271.743024 -23.1056) (xy 271.72751 -23.163498) (xy 271.704572 -23.218875)
			(xy 271.674601 -23.270784) (xy 271.638111 -23.318337) (xy 271.595727 -23.36072) (xy 271.548173 -23.397208)
			(xy 271.496263 -23.427178) (xy 271.440885 -23.450115) (xy 271.382987 -23.465627) (xy 271.32356 -23.47345)
			(xy 271.29359 -23.473918) (xy 271.259345 -23.473323) (xy 271.191619 -23.463112) (xy 271.158716 -23.453598)
			(xy 271.146524 -23.449788) (xy 271.122394 -23.45436) (xy 271.036542 -23.522178) (xy 271.026636 -23.544784)
			(xy 271.027652 -23.557738) (xy 271.028414 -23.583646) (xy 271.027928 -23.610897) (xy 271.026624 -23.619964)
			(xy 274.209238 -23.619964) (xy 274.209238 -23.560028) (xy 274.217061 -23.500606) (xy 274.232574 -23.442713)
			(xy 274.25551 -23.38734) (xy 274.285477 -23.335434) (xy 274.321964 -23.287884) (xy 274.364344 -23.245504)
			(xy 274.411894 -23.209017) (xy 274.4638 -23.17905) (xy 274.519173 -23.156114) (xy 274.577066 -23.140601)
			(xy 274.636488 -23.132778) (xy 274.696424 -23.132778) (xy 274.755846 -23.140601) (xy 274.813739 -23.156114)
			(xy 274.869112 -23.17905) (xy 274.921018 -23.209017) (xy 274.968568 -23.245504) (xy 275.010948 -23.287884)
			(xy 275.047435 -23.335434) (xy 275.077402 -23.38734) (xy 275.100338 -23.442713) (xy 275.115851 -23.500606)
			(xy 275.123674 -23.560028) (xy 275.124164 -23.589996) (xy 275.123674 -23.619964) (xy 275.115851 -23.679386)
			(xy 275.100338 -23.737279) (xy 275.077402 -23.792652) (xy 275.047435 -23.844558) (xy 275.019995 -23.880318)
			(xy 275.440646 -23.880318) (xy 275.444717 -23.824696) (xy 275.456843 -23.770259) (xy 275.476766 -23.718168)
			(xy 275.504062 -23.669533) (xy 275.538148 -23.62539) (xy 275.578297 -23.586681) (xy 275.623655 -23.55423)
			(xy 275.673255 -23.528729) (xy 275.726039 -23.510722) (xy 275.780882 -23.500592) (xy 275.836616 -23.498555)
			(xy 275.892053 -23.504655) (xy 275.94601 -23.518761) (xy 275.997339 -23.540573) (xy 276.044945 -23.569627)
			(xy 276.087813 -23.605302) (xy 276.12503 -23.646839) (xy 276.155803 -23.693352) (xy 276.179475 -23.743849)
			(xy 276.195543 -23.797256) (xy 276.203663 -23.852432) (xy 276.204172 -23.880318) (xy 276.456646 -23.880318)
			(xy 276.460717 -23.824696) (xy 276.472843 -23.770259) (xy 276.492766 -23.718168) (xy 276.520062 -23.669533)
			(xy 276.554148 -23.62539) (xy 276.594297 -23.586681) (xy 276.639655 -23.55423) (xy 276.689255 -23.528729)
			(xy 276.742039 -23.510722) (xy 276.796882 -23.500592) (xy 276.852616 -23.498555) (xy 276.908053 -23.504655)
			(xy 276.96201 -23.518761) (xy 277.013339 -23.540573) (xy 277.060945 -23.569627) (xy 277.103813 -23.605302)
			(xy 277.14103 -23.646839) (xy 277.171803 -23.693352) (xy 277.195475 -23.743849) (xy 277.211543 -23.797256)
			(xy 277.219663 -23.852432) (xy 277.220172 -23.880318) (xy 277.472646 -23.880318) (xy 277.476717 -23.824696)
			(xy 277.488843 -23.770259) (xy 277.508766 -23.718168) (xy 277.536062 -23.669533) (xy 277.570148 -23.62539)
			(xy 277.610297 -23.586681) (xy 277.655655 -23.55423) (xy 277.705255 -23.528729) (xy 277.758039 -23.510722)
			(xy 277.812882 -23.500592) (xy 277.868616 -23.498555) (xy 277.924053 -23.504655) (xy 277.97801 -23.518761)
			(xy 278.029339 -23.540573) (xy 278.076945 -23.569627) (xy 278.119813 -23.605302) (xy 278.15703 -23.646839)
			(xy 278.187803 -23.693352) (xy 278.211475 -23.743849) (xy 278.227543 -23.797256) (xy 278.235663 -23.852432)
			(xy 278.236172 -23.880318) (xy 278.490932 -23.880318) (xy 278.495003 -23.824696) (xy 278.507129 -23.770259)
			(xy 278.527052 -23.718168) (xy 278.554348 -23.669533) (xy 278.588434 -23.62539) (xy 278.628583 -23.586681)
			(xy 278.673941 -23.55423) (xy 278.723541 -23.528729) (xy 278.776325 -23.510722) (xy 278.831168 -23.500592)
			(xy 278.886902 -23.498555) (xy 278.942339 -23.504655) (xy 278.996296 -23.518761) (xy 279.047625 -23.540573)
			(xy 279.095231 -23.569627) (xy 279.138099 -23.605302) (xy 279.175316 -23.646839) (xy 279.206089 -23.693352)
			(xy 279.229761 -23.743849) (xy 279.245829 -23.797256) (xy 279.253949 -23.852432) (xy 279.254458 -23.880318)
			(xy 279.253949 -23.908204) (xy 279.245829 -23.96338) (xy 279.229761 -24.016787) (xy 279.206089 -24.067284)
			(xy 279.175316 -24.113797) (xy 279.138099 -24.155334) (xy 279.095231 -24.191009) (xy 279.047625 -24.220063)
			(xy 278.996296 -24.241875) (xy 278.942339 -24.255981) (xy 278.886902 -24.262081) (xy 278.831168 -24.260044)
			(xy 278.776325 -24.249914) (xy 278.723541 -24.231907) (xy 278.673941 -24.206406) (xy 278.628583 -24.173955)
			(xy 278.588434 -24.135246) (xy 278.554348 -24.091103) (xy 278.527052 -24.042468) (xy 278.507129 -23.990377)
			(xy 278.495003 -23.93594) (xy 278.490932 -23.880318) (xy 278.236172 -23.880318) (xy 278.235663 -23.908204)
			(xy 278.227543 -23.96338) (xy 278.211475 -24.016787) (xy 278.187803 -24.067284) (xy 278.15703 -24.113797)
			(xy 278.119813 -24.155334) (xy 278.076945 -24.191009) (xy 278.029339 -24.220063) (xy 277.97801 -24.241875)
			(xy 277.924053 -24.255981) (xy 277.868616 -24.262081) (xy 277.812882 -24.260044) (xy 277.758039 -24.249914)
			(xy 277.705255 -24.231907) (xy 277.655655 -24.206406) (xy 277.610297 -24.173955) (xy 277.570148 -24.135246)
			(xy 277.536062 -24.091103) (xy 277.508766 -24.042468) (xy 277.488843 -23.990377) (xy 277.476717 -23.93594)
			(xy 277.472646 -23.880318) (xy 277.220172 -23.880318) (xy 277.219663 -23.908204) (xy 277.211543 -23.96338)
			(xy 277.195475 -24.016787) (xy 277.171803 -24.067284) (xy 277.14103 -24.113797) (xy 277.103813 -24.155334)
			(xy 277.060945 -24.191009) (xy 277.013339 -24.220063) (xy 276.96201 -24.241875) (xy 276.908053 -24.255981)
			(xy 276.852616 -24.262081) (xy 276.796882 -24.260044) (xy 276.742039 -24.249914) (xy 276.689255 -24.231907)
			(xy 276.639655 -24.206406) (xy 276.594297 -24.173955) (xy 276.554148 -24.135246) (xy 276.520062 -24.091103)
			(xy 276.492766 -24.042468) (xy 276.472843 -23.990377) (xy 276.460717 -23.93594) (xy 276.456646 -23.880318)
			(xy 276.204172 -23.880318) (xy 276.203663 -23.908204) (xy 276.195543 -23.96338) (xy 276.179475 -24.016787)
			(xy 276.155803 -24.067284) (xy 276.12503 -24.113797) (xy 276.087813 -24.155334) (xy 276.044945 -24.191009)
			(xy 275.997339 -24.220063) (xy 275.94601 -24.241875) (xy 275.892053 -24.255981) (xy 275.836616 -24.262081)
			(xy 275.780882 -24.260044) (xy 275.726039 -24.249914) (xy 275.673255 -24.231907) (xy 275.623655 -24.206406)
			(xy 275.578297 -24.173955) (xy 275.538148 -24.135246) (xy 275.504062 -24.091103) (xy 275.476766 -24.042468)
			(xy 275.456843 -23.990377) (xy 275.444717 -23.93594) (xy 275.440646 -23.880318) (xy 275.019995 -23.880318)
			(xy 275.010948 -23.892108) (xy 274.968568 -23.934488) (xy 274.921018 -23.970975) (xy 274.869112 -24.000942)
			(xy 274.813739 -24.023878) (xy 274.755846 -24.039391) (xy 274.696424 -24.047214) (xy 274.636488 -24.047214)
			(xy 274.577066 -24.039391) (xy 274.519173 -24.023878) (xy 274.4638 -24.000942) (xy 274.411894 -23.970975)
			(xy 274.364344 -23.934488) (xy 274.321964 -23.892108) (xy 274.285477 -23.844558) (xy 274.25551 -23.792652)
			(xy 274.232574 -23.737279) (xy 274.217061 -23.679386) (xy 274.209238 -23.619964) (xy 271.026624 -23.619964)
			(xy 271.020172 -23.664845) (xy 271.004817 -23.71714) (xy 270.982175 -23.766717) (xy 270.952709 -23.812567)
			(xy 270.917018 -23.853758) (xy 270.875827 -23.889449) (xy 270.829977 -23.918915) (xy 270.7804 -23.941557)
			(xy 270.728105 -23.956912) (xy 270.674157 -23.964668) (xy 270.619655 -23.964668) (xy 270.565707 -23.956912)
			(xy 270.513412 -23.941557) (xy 270.463835 -23.918915) (xy 270.417985 -23.889449) (xy 270.376794 -23.853758)
			(xy 270.341103 -23.812567) (xy 270.311637 -23.766717) (xy 270.288995 -23.71714) (xy 270.27364 -23.664845)
			(xy 270.265884 -23.610897) (xy 270.265398 -23.583646) (xy 270.267176 -23.548086) (xy 270.268446 -23.53437)
			(xy 270.257524 -23.51024) (xy 270.16456 -23.44293) (xy 270.138144 -23.439882) (xy 270.125698 -23.44547)
			(xy 270.096944 -23.457296) (xy 270.037036 -23.473929) (xy 269.975429 -23.482306) (xy 269.944342 -23.482808)
			(xy 269.91437 -23.482384) (xy 269.854937 -23.474564) (xy 269.797034 -23.459055) (xy 269.74165 -23.436119)
			(xy 269.689734 -23.406151) (xy 269.642174 -23.369663) (xy 269.599783 -23.327279) (xy 269.563288 -23.279724)
			(xy 269.533312 -23.227813) (xy 269.510368 -23.172433) (xy 269.494849 -23.114532) (xy 269.487021 -23.0551)
			(xy 269.487017 -22.995156) (xy 267.74394 -22.995156) (xy 267.74394 -24.189944) (xy 269.498824 -24.189944)
			(xy 269.502895 -24.134322) (xy 269.515021 -24.079885) (xy 269.534944 -24.027794) (xy 269.56224 -23.979159)
			(xy 269.596326 -23.935016) (xy 269.636475 -23.896307) (xy 269.681833 -23.863856) (xy 269.731433 -23.838355)
			(xy 269.784217 -23.820348) (xy 269.83906 -23.810218) (xy 269.894794 -23.808181) (xy 269.950231 -23.814281)
			(xy 270.004188 -23.828387) (xy 270.055517 -23.850199) (xy 270.103123 -23.879253) (xy 270.145991 -23.914928)
			(xy 270.183208 -23.956465) (xy 270.213981 -24.002978) (xy 270.237653 -24.053475) (xy 270.253721 -24.106882)
			(xy 270.261841 -24.162058) (xy 270.26235 -24.189944) (xy 272.021806 -24.189944) (xy 272.025877 -24.134322)
			(xy 272.038003 -24.079885) (xy 272.057926 -24.027794) (xy 272.085222 -23.979159) (xy 272.119308 -23.935016)
			(xy 272.159457 -23.896307) (xy 272.204815 -23.863856) (xy 272.254415 -23.838355) (xy 272.307199 -23.820348)
			(xy 272.362042 -23.810218) (xy 272.417776 -23.808181) (xy 272.473213 -23.814281) (xy 272.52717 -23.828387)
			(xy 272.578499 -23.850199) (xy 272.626105 -23.879253) (xy 272.668973 -23.914928) (xy 272.70619 -23.956465)
			(xy 272.736963 -24.002978) (xy 272.760635 -24.053475) (xy 272.776703 -24.106882) (xy 272.784823 -24.162058)
			(xy 272.785332 -24.189944) (xy 272.784823 -24.21783) (xy 272.776703 -24.273006) (xy 272.760635 -24.326413)
			(xy 272.736963 -24.37691) (xy 272.70619 -24.423423) (xy 272.668973 -24.46496) (xy 272.626105 -24.500635)
			(xy 272.578499 -24.529689) (xy 272.52717 -24.551501) (xy 272.473213 -24.565607) (xy 272.417776 -24.571707)
			(xy 272.362042 -24.56967) (xy 272.307199 -24.55954) (xy 272.254415 -24.541533) (xy 272.204815 -24.516032)
			(xy 272.159457 -24.483581) (xy 272.119308 -24.444872) (xy 272.085222 -24.400729) (xy 272.057926 -24.352094)
			(xy 272.038003 -24.300003) (xy 272.025877 -24.245566) (xy 272.021806 -24.189944) (xy 270.26235 -24.189944)
			(xy 270.261841 -24.21783) (xy 270.253721 -24.273006) (xy 270.237653 -24.326413) (xy 270.213981 -24.37691)
			(xy 270.183208 -24.423423) (xy 270.145991 -24.46496) (xy 270.103123 -24.500635) (xy 270.055517 -24.529689)
			(xy 270.004188 -24.551501) (xy 269.950231 -24.565607) (xy 269.894794 -24.571707) (xy 269.83906 -24.56967)
			(xy 269.784217 -24.55954) (xy 269.731433 -24.541533) (xy 269.681833 -24.516032) (xy 269.636475 -24.483581)
			(xy 269.596326 -24.444872) (xy 269.56224 -24.400729) (xy 269.534944 -24.352094) (xy 269.515021 -24.300003)
			(xy 269.502895 -24.245566) (xy 269.498824 -24.189944) (xy 267.74394 -24.189944) (xy 267.74394 -25.390094)
			(xy 271.933416 -25.390094) (xy 271.933906 -25.360126) (xy 271.941729 -25.300704) (xy 271.957242 -25.242811)
			(xy 271.980178 -25.187438) (xy 272.010145 -25.135532) (xy 272.046632 -25.087982) (xy 272.089012 -25.045602)
			(xy 272.136562 -25.009115) (xy 272.188468 -24.979148) (xy 272.243841 -24.956212) (xy 272.301734 -24.940699)
			(xy 272.361156 -24.932876) (xy 272.421092 -24.932876) (xy 272.480514 -24.940699) (xy 272.538407 -24.956212)
			(xy 272.59378 -24.979148) (xy 272.645686 -25.009115) (xy 272.693236 -25.045602) (xy 272.735616 -25.087982)
			(xy 272.772103 -25.135532) (xy 272.80207 -25.187438) (xy 272.825006 -25.242811) (xy 272.840519 -25.300704)
			(xy 272.848342 -25.360126) (xy 272.848832 -25.390094) (xy 272.848387 -25.418878) (xy 272.841169 -25.475992)
			(xy 272.826846 -25.53175) (xy 272.805645 -25.585271) (xy 272.777899 -25.635712) (xy 272.744048 -25.682276)
			(xy 272.704626 -25.724227) (xy 272.682716 -25.7429) (xy 272.674334 -25.749758) (xy 272.664682 -25.769316)
			(xy 272.66138 -25.867106) (xy 272.669508 -25.887172) (xy 272.677636 -25.894792) (xy 272.696032 -25.912872)
			(xy 272.728271 -25.953138) (xy 272.754796 -25.997377) (xy 272.775124 -26.044784) (xy 272.788885 -26.094496)
			(xy 272.795829 -26.145607) (xy 272.796254 -26.171398) (xy 272.795768 -26.198649) (xy 272.788012 -26.252597)
			(xy 272.772657 -26.304892) (xy 272.750015 -26.354469) (xy 272.720549 -26.400319) (xy 272.684858 -26.44151)
			(xy 272.643667 -26.477201) (xy 272.597817 -26.506667) (xy 272.54824 -26.529309) (xy 272.495945 -26.544664)
			(xy 272.441997 -26.55242) (xy 272.387495 -26.55242) (xy 272.333547 -26.544664) (xy 272.281252 -26.529309)
			(xy 272.231675 -26.506667) (xy 272.185825 -26.477201) (xy 272.144634 -26.44151) (xy 272.108943 -26.400319)
			(xy 272.079477 -26.354469) (xy 272.056835 -26.304892) (xy 272.04148 -26.252597) (xy 272.033724 -26.198649)
			(xy 272.033238 -26.171398) (xy 272.033745 -26.142754) (xy 272.042344 -26.086115) (xy 272.059317 -26.031399)
			(xy 272.084283 -25.979837) (xy 272.11668 -25.932589) (xy 272.135854 -25.911302) (xy 272.14322 -25.903174)
			(xy 272.150078 -25.8826) (xy 272.140934 -25.785064) (xy 272.130266 -25.766268) (xy 272.121376 -25.759918)
			(xy 272.096845 -25.741346) (xy 272.052447 -25.69875) (xy 272.014153 -25.650592) (xy 271.982653 -25.59774)
			(xy 271.958515 -25.541146) (xy 271.942173 -25.481829) (xy 271.933921 -25.420857) (xy 271.933416 -25.390094)
			(xy 267.74394 -25.390094) (xy 267.74394 -25.506934) (xy 267.744371 -25.517001) (xy 267.752098 -25.535592)
			(xy 267.758926 -25.543002) (xy 267.810234 -25.593802) (xy 267.817646 -25.60048) (xy 267.836082 -25.60805)
			(xy 267.846048 -25.608534) (xy 267.848842 -25.608534) (xy 267.876088 -25.609023) (xy 267.930025 -25.616784)
			(xy 267.982309 -25.632141) (xy 268.031876 -25.654782) (xy 268.077716 -25.684246) (xy 268.118896 -25.719933)
			(xy 268.154579 -25.761118) (xy 268.184039 -25.806961) (xy 268.206674 -25.85653) (xy 268.222025 -25.908816)
			(xy 268.22978 -25.962754) (xy 268.22978 -25.990042) (xy 269.498824 -25.990042) (xy 269.502895 -25.93442)
			(xy 269.515021 -25.879983) (xy 269.534944 -25.827892) (xy 269.56224 -25.779257) (xy 269.596326 -25.735114)
			(xy 269.636475 -25.696405) (xy 269.681833 -25.663954) (xy 269.731433 -25.638453) (xy 269.784217 -25.620446)
			(xy 269.83906 -25.610316) (xy 269.894794 -25.608279) (xy 269.950231 -25.614379) (xy 270.004188 -25.628485)
			(xy 270.055517 -25.650297) (xy 270.103123 -25.679351) (xy 270.145991 -25.715026) (xy 270.183208 -25.756563)
			(xy 270.213981 -25.803076) (xy 270.237653 -25.853573) (xy 270.253721 -25.90698) (xy 270.261841 -25.962156)
			(xy 270.26235 -25.990042) (xy 270.261841 -26.017928) (xy 270.253721 -26.073104) (xy 270.237653 -26.126511)
			(xy 270.213981 -26.177008) (xy 270.183208 -26.223521) (xy 270.145991 -26.265058) (xy 270.103123 -26.300733)
			(xy 270.055517 -26.329787) (xy 270.004188 -26.351599) (xy 269.950231 -26.365705) (xy 269.894794 -26.371805)
			(xy 269.83906 -26.369768) (xy 269.784217 -26.359638) (xy 269.731433 -26.341631) (xy 269.681833 -26.31613)
			(xy 269.636475 -26.283679) (xy 269.596326 -26.24497) (xy 269.56224 -26.200827) (xy 269.534944 -26.152192)
			(xy 269.515021 -26.100101) (xy 269.502895 -26.045664) (xy 269.498824 -25.990042) (xy 268.22978 -25.990042)
			(xy 268.22978 -26.017246) (xy 268.222025 -26.071184) (xy 268.206674 -26.12347) (xy 268.184039 -26.173039)
			(xy 268.154579 -26.218882) (xy 268.118896 -26.260067) (xy 268.077716 -26.295754) (xy 268.031876 -26.325218)
			(xy 267.982309 -26.347859) (xy 267.930025 -26.363216) (xy 267.876088 -26.370977) (xy 267.848842 -26.37155)
			(xy 267.846048 -26.37155) (xy 267.836086 -26.372035) (xy 267.817662 -26.379625) (xy 267.810234 -26.386282)
			(xy 267.758926 -26.437082) (xy 267.75209 -26.444484) (xy 267.744381 -26.463082) (xy 267.74394 -26.47315)
			(xy 267.74394 -27.307032) (xy 267.74437 -27.317099) (xy 267.752097 -27.335691) (xy 267.758926 -27.3431)
			(xy 267.810234 -27.3939) (xy 267.817645 -27.400579) (xy 267.836082 -27.408148) (xy 267.846048 -27.408632)
			(xy 267.848842 -27.408632) (xy 267.876088 -27.409121) (xy 267.930026 -27.416882) (xy 267.98231 -27.432239)
			(xy 268.031877 -27.45488) (xy 268.077717 -27.484344) (xy 268.118898 -27.520032) (xy 268.154581 -27.561217)
			(xy 268.18404 -27.60706) (xy 268.206676 -27.656629) (xy 268.222027 -27.708915) (xy 268.229782 -27.762854)
			(xy 268.229782 -27.79014) (xy 269.562832 -27.79014) (xy 269.566903 -27.734518) (xy 269.579029 -27.680081)
			(xy 269.598952 -27.62799) (xy 269.626248 -27.579355) (xy 269.660334 -27.535212) (xy 269.700483 -27.496503)
			(xy 269.745841 -27.464052) (xy 269.795441 -27.438551) (xy 269.848225 -27.420544) (xy 269.903068 -27.410414)
			(xy 269.958802 -27.408377) (xy 270.014239 -27.414477) (xy 270.068196 -27.428583) (xy 270.119525 -27.450395)
			(xy 270.167131 -27.479449) (xy 270.209999 -27.515124) (xy 270.247216 -27.556661) (xy 270.277989 -27.603174)
			(xy 270.301661 -27.653671) (xy 270.317729 -27.707078) (xy 270.325849 -27.762254) (xy 270.326358 -27.79014)
			(xy 272.066764 -27.79014) (xy 272.070835 -27.734518) (xy 272.082961 -27.680081) (xy 272.102884 -27.62799)
			(xy 272.13018 -27.579355) (xy 272.164266 -27.535212) (xy 272.204415 -27.496503) (xy 272.249773 -27.464052)
			(xy 272.299373 -27.438551) (xy 272.352157 -27.420544) (xy 272.407 -27.410414) (xy 272.462734 -27.408377)
			(xy 272.518171 -27.414477) (xy 272.572128 -27.428583) (xy 272.623457 -27.450395) (xy 272.671063 -27.479449)
			(xy 272.713931 -27.515124) (xy 272.751148 -27.556661) (xy 272.781921 -27.603174) (xy 272.805593 -27.653671)
			(xy 272.821661 -27.707078) (xy 272.829781 -27.762254) (xy 272.83029 -27.79014) (xy 272.829793 -27.817348)
			(xy 274.099818 -27.817348) (xy 274.099818 -27.762852) (xy 274.107573 -27.708912) (xy 274.122926 -27.656624)
			(xy 274.145563 -27.607053) (xy 274.175025 -27.561209) (xy 274.210711 -27.520023) (xy 274.251894 -27.484336)
			(xy 274.297738 -27.454872) (xy 274.347307 -27.432232) (xy 274.399594 -27.416877) (xy 274.453534 -27.409119)
			(xy 274.480782 -27.408632) (xy 274.506089 -27.409037) (xy 274.556261 -27.415706) (xy 274.605113 -27.428942)
			(xy 274.62861 -27.43835) (xy 274.636622 -27.441357) (xy 274.653689 -27.442456) (xy 274.670166 -27.437876)
			(xy 274.677378 -27.43327) (xy 274.702778 -27.41549) (xy 274.709663 -27.410214) (xy 274.719738 -27.396112)
			(xy 274.724537 -27.379457) (xy 274.724368 -27.370786) (xy 274.723352 -27.342846) (xy 274.723352 -26.479246)
			(xy 274.724114 -26.456894) (xy 274.724622 -26.444448) (xy 274.714208 -26.421842) (xy 274.629118 -26.355548)
			(xy 274.604734 -26.350976) (xy 274.592796 -26.354786) (xy 274.565458 -26.362624) (xy 274.509217 -26.371044)
			(xy 274.480782 -26.37155) (xy 274.453535 -26.370979) (xy 274.399595 -26.363221) (xy 274.347308 -26.347866)
			(xy 274.297739 -26.325226) (xy 274.251896 -26.295763) (xy 274.210712 -26.260075) (xy 274.175026 -26.21889)
			(xy 274.145565 -26.173046) (xy 274.122928 -26.123475) (xy 274.107575 -26.071188) (xy 274.09982 -26.017247)
			(xy 274.09982 -25.962753) (xy 274.107575 -25.908812) (xy 274.122928 -25.856525) (xy 274.145565 -25.806954)
			(xy 274.175026 -25.76111) (xy 274.210712 -25.719925) (xy 274.251896 -25.684237) (xy 274.297739 -25.654774)
			(xy 274.347308 -25.632134) (xy 274.399595 -25.616779) (xy 274.453535 -25.609021) (xy 274.480782 -25.608534)
			(xy 274.509734 -25.609094) (xy 274.566974 -25.617828) (xy 274.622237 -25.635113) (xy 274.674252 -25.660552)
			(xy 274.721825 -25.693561) (xy 274.763862 -25.73338) (xy 274.799397 -25.779096) (xy 274.827615 -25.829658)
			(xy 274.82851 -25.832054) (xy 276.388322 -25.832054) (xy 276.388802 -25.805451) (xy 276.396177 -25.752759)
			(xy 276.410805 -25.701603) (xy 276.432402 -25.652978) (xy 276.460549 -25.607827) (xy 276.494699 -25.567028)
			(xy 276.534189 -25.531371) (xy 276.555962 -25.516078) (xy 276.567442 -25.507741) (xy 276.585652 -25.486)
			(xy 276.597174 -25.460087) (xy 276.601116 -25.432002) (xy 276.597175 -25.403918) (xy 276.585654 -25.378004)
			(xy 276.567445 -25.356262) (xy 276.555962 -25.34793) (xy 276.534202 -25.332621) (xy 276.494721 -25.296958)
			(xy 276.460577 -25.256157) (xy 276.43243 -25.21101) (xy 276.410826 -25.16239) (xy 276.396183 -25.111242)
			(xy 276.388787 -25.058555) (xy 276.388322 -25.031954) (xy 276.388808 -25.004703) (xy 276.396564 -24.950755)
			(xy 276.411919 -24.89846) (xy 276.434561 -24.848883) (xy 276.464027 -24.803033) (xy 276.499718 -24.761842)
			(xy 276.540909 -24.726151) (xy 276.586759 -24.696685) (xy 276.636336 -24.674043) (xy 276.688631 -24.658688)
			(xy 276.742579 -24.650932) (xy 276.797081 -24.650932) (xy 276.851029 -24.658688) (xy 276.903324 -24.674043)
			(xy 276.952901 -24.696685) (xy 276.998751 -24.726151) (xy 277.039942 -24.761842) (xy 277.063143 -24.788618)
			(xy 278.993328 -24.788618) (xy 278.993328 -24.728682) (xy 279.001151 -24.66926) (xy 279.016664 -24.611367)
			(xy 279.0396 -24.555994) (xy 279.069567 -24.504088) (xy 279.106054 -24.456538) (xy 279.148434 -24.414158)
			(xy 279.195984 -24.377671) (xy 279.24789 -24.347704) (xy 279.303263 -24.324768) (xy 279.361156 -24.309255)
			(xy 279.420578 -24.301432) (xy 279.480514 -24.301432) (xy 279.539936 -24.309255) (xy 279.597829 -24.324768)
			(xy 279.653202 -24.347704) (xy 279.705108 -24.377671) (xy 279.752658 -24.414158) (xy 279.795038 -24.456538)
			(xy 279.831525 -24.504088) (xy 279.861492 -24.555994) (xy 279.884428 -24.611367) (xy 279.899941 -24.66926)
			(xy 279.907764 -24.728682) (xy 279.908254 -24.75865) (xy 279.907764 -24.788618) (xy 279.899941 -24.84804)
			(xy 279.884428 -24.905933) (xy 279.861492 -24.961306) (xy 279.831525 -25.013212) (xy 279.795038 -25.060762)
			(xy 279.752658 -25.103142) (xy 279.705108 -25.139629) (xy 279.653202 -25.169596) (xy 279.597829 -25.192532)
			(xy 279.539936 -25.208045) (xy 279.480514 -25.215868) (xy 279.420578 -25.215868) (xy 279.361156 -25.208045)
			(xy 279.303263 -25.192532) (xy 279.24789 -25.169596) (xy 279.195984 -25.139629) (xy 279.148434 -25.103142)
			(xy 279.106054 -25.060762) (xy 279.069567 -25.013212) (xy 279.0396 -24.961306) (xy 279.016664 -24.905933)
			(xy 279.001151 -24.84804) (xy 278.993328 -24.788618) (xy 277.063143 -24.788618) (xy 277.075633 -24.803033)
			(xy 277.105099 -24.848883) (xy 277.127741 -24.89846) (xy 277.143096 -24.950755) (xy 277.150852 -25.004703)
			(xy 277.151338 -25.031954) (xy 277.150881 -25.058558) (xy 277.143505 -25.111252) (xy 277.128874 -25.162409)
			(xy 277.107273 -25.211035) (xy 277.079122 -25.256185) (xy 277.044968 -25.296984) (xy 277.005473 -25.332638)
			(xy 276.983698 -25.34793) (xy 276.972214 -25.35626) (xy 276.954011 -25.378004) (xy 276.942495 -25.403919)
			(xy 276.938555 -25.432002) (xy 276.942496 -25.460085) (xy 276.954013 -25.485999) (xy 276.972218 -25.507743)
			(xy 276.983698 -25.516078) (xy 277.005475 -25.531363) (xy 277.044953 -25.567032) (xy 277.079094 -25.607838)
			(xy 277.107238 -25.65299) (xy 277.128839 -25.701612) (xy 277.143479 -25.752763) (xy 277.150874 -25.805452)
			(xy 277.151338 -25.832054) (xy 277.150852 -25.859305) (xy 277.143096 -25.913253) (xy 277.127741 -25.965548)
			(xy 277.105099 -26.015125) (xy 277.075633 -26.060975) (xy 277.039942 -26.102166) (xy 276.998751 -26.137857)
			(xy 276.952901 -26.167323) (xy 276.903324 -26.189965) (xy 276.851029 -26.20532) (xy 276.797081 -26.213076)
			(xy 276.742579 -26.213076) (xy 276.688631 -26.20532) (xy 276.636336 -26.189965) (xy 276.586759 -26.167323)
			(xy 276.540909 -26.137857) (xy 276.499718 -26.102166) (xy 276.464027 -26.060975) (xy 276.434561 -26.015125)
			(xy 276.411919 -25.965548) (xy 276.396564 -25.913253) (xy 276.388808 -25.859305) (xy 276.388322 -25.832054)
			(xy 274.82851 -25.832054) (xy 274.847867 -25.883904) (xy 274.859687 -25.940588) (xy 274.861782 -25.969468)
			(xy 274.86229 -25.981914) (xy 274.87499 -26.00325) (xy 274.966684 -26.060654) (xy 274.991322 -26.062432)
			(xy 275.002752 -26.057606) (xy 275.031107 -26.04613) (xy 275.090106 -26.029977) (xy 275.150729 -26.021809)
			(xy 275.181314 -26.021284) (xy 275.211302 -26.021694) (xy 275.270764 -26.029525) (xy 275.328696 -26.04505)
			(xy 275.384105 -26.068004) (xy 275.436044 -26.097995) (xy 275.483624 -26.134509) (xy 275.526031 -26.176921)
			(xy 275.562538 -26.224506) (xy 275.592522 -26.276449) (xy 275.615469 -26.331861) (xy 275.623242 -26.360882)
			(xy 277.289512 -26.360882) (xy 277.293583 -26.30526) (xy 277.305709 -26.250823) (xy 277.325632 -26.198732)
			(xy 277.352928 -26.150097) (xy 277.387014 -26.105954) (xy 277.427163 -26.067245) (xy 277.472521 -26.034794)
			(xy 277.522121 -26.009293) (xy 277.574905 -25.991286) (xy 277.629748 -25.981156) (xy 277.685482 -25.979119)
			(xy 277.740919 -25.985219) (xy 277.794876 -25.999325) (xy 277.846205 -26.021137) (xy 277.893811 -26.050191)
			(xy 277.936679 -26.085866) (xy 277.973896 -26.127403) (xy 278.004669 -26.173916) (xy 278.028341 -26.224413)
			(xy 278.044409 -26.27782) (xy 278.052529 -26.332996) (xy 278.053038 -26.360882) (xy 278.305512 -26.360882)
			(xy 278.309583 -26.30526) (xy 278.321709 -26.250823) (xy 278.341632 -26.198732) (xy 278.368928 -26.150097)
			(xy 278.403014 -26.105954) (xy 278.443163 -26.067245) (xy 278.488521 -26.034794) (xy 278.538121 -26.009293)
			(xy 278.590905 -25.991286) (xy 278.645748 -25.981156) (xy 278.701482 -25.979119) (xy 278.756919 -25.985219)
			(xy 278.810876 -25.999325) (xy 278.862205 -26.021137) (xy 278.909811 -26.050191) (xy 278.952679 -26.085866)
			(xy 278.989896 -26.127403) (xy 279.020669 -26.173916) (xy 279.044341 -26.224413) (xy 279.060409 -26.27782)
			(xy 279.068529 -26.332996) (xy 279.069038 -26.360882) (xy 279.068529 -26.388768) (xy 279.060409 -26.443944)
			(xy 279.044341 -26.497351) (xy 279.020669 -26.547848) (xy 278.989896 -26.594361) (xy 278.952679 -26.635898)
			(xy 278.909811 -26.671573) (xy 278.862205 -26.700627) (xy 278.810876 -26.722439) (xy 278.756919 -26.736545)
			(xy 278.701482 -26.742645) (xy 278.645748 -26.740608) (xy 278.590905 -26.730478) (xy 278.538121 -26.712471)
			(xy 278.488521 -26.68697) (xy 278.443163 -26.654519) (xy 278.403014 -26.61581) (xy 278.368928 -26.571667)
			(xy 278.341632 -26.523032) (xy 278.321709 -26.470941) (xy 278.309583 -26.416504) (xy 278.305512 -26.360882)
			(xy 278.053038 -26.360882) (xy 278.052529 -26.388768) (xy 278.044409 -26.443944) (xy 278.028341 -26.497351)
			(xy 278.004669 -26.547848) (xy 277.973896 -26.594361) (xy 277.936679 -26.635898) (xy 277.893811 -26.671573)
			(xy 277.846205 -26.700627) (xy 277.794876 -26.722439) (xy 277.740919 -26.736545) (xy 277.685482 -26.742645)
			(xy 277.629748 -26.740608) (xy 277.574905 -26.730478) (xy 277.522121 -26.712471) (xy 277.472521 -26.68697)
			(xy 277.427163 -26.654519) (xy 277.387014 -26.61581) (xy 277.352928 -26.571667) (xy 277.325632 -26.523032)
			(xy 277.305709 -26.470941) (xy 277.293583 -26.416504) (xy 277.289512 -26.360882) (xy 275.623242 -26.360882)
			(xy 275.630987 -26.389795) (xy 275.63881 -26.449258) (xy 275.639276 -26.479246) (xy 275.639276 -26.971244)
			(xy 279.051002 -26.971244) (xy 279.055073 -26.915622) (xy 279.067199 -26.861185) (xy 279.087122 -26.809094)
			(xy 279.114418 -26.760459) (xy 279.148504 -26.716316) (xy 279.188653 -26.677607) (xy 279.234011 -26.645156)
			(xy 279.283611 -26.619655) (xy 279.336395 -26.601648) (xy 279.391238 -26.591518) (xy 279.446972 -26.589481)
			(xy 279.502409 -26.595581) (xy 279.556366 -26.609687) (xy 279.607695 -26.631499) (xy 279.655301 -26.660553)
			(xy 279.698169 -26.696228) (xy 279.735386 -26.737765) (xy 279.766159 -26.784278) (xy 279.789831 -26.834775)
			(xy 279.805899 -26.888182) (xy 279.814019 -26.943358) (xy 279.814528 -26.971244) (xy 279.814019 -26.99913)
			(xy 279.805899 -27.054306) (xy 279.789831 -27.107713) (xy 279.766159 -27.15821) (xy 279.735386 -27.204723)
			(xy 279.698169 -27.24626) (xy 279.655301 -27.281935) (xy 279.607695 -27.310989) (xy 279.556366 -27.332801)
			(xy 279.502409 -27.346907) (xy 279.446972 -27.353007) (xy 279.391238 -27.35097) (xy 279.336395 -27.34084)
			(xy 279.283611 -27.322833) (xy 279.234011 -27.297332) (xy 279.188653 -27.264881) (xy 279.148504 -27.226172)
			(xy 279.114418 -27.182029) (xy 279.087122 -27.133394) (xy 279.067199 -27.081303) (xy 279.055073 -27.026866)
			(xy 279.051002 -26.971244) (xy 275.639276 -26.971244) (xy 275.639276 -27.342846) (xy 275.638815 -27.372831)
			(xy 275.630982 -27.432287) (xy 275.615456 -27.490212) (xy 275.592503 -27.545615) (xy 275.562515 -27.597548)
			(xy 275.526006 -27.645124) (xy 275.4836 -27.687527) (xy 275.436022 -27.724033) (xy 275.384086 -27.754017)
			(xy 275.328681 -27.776967) (xy 275.270755 -27.792488) (xy 275.211299 -27.800317) (xy 275.181314 -27.800808)
			(xy 275.150178 -27.800265) (xy 275.088482 -27.791805) (xy 275.028496 -27.77508) (xy 274.999704 -27.763216)
			(xy 274.988528 -27.75839) (xy 274.964906 -27.75966) (xy 274.87372 -27.810968) (xy 274.860258 -27.830526)
			(xy 274.858734 -27.842464) (xy 274.8545 -27.869491) (xy 274.839321 -27.922047) (xy 274.816793 -27.971897)
			(xy 274.787379 -28.018021) (xy 274.75168 -28.059472) (xy 274.710429 -28.095401) (xy 274.664471 -28.125072)
			(xy 274.614747 -28.147878) (xy 274.562276 -28.16335) (xy 274.508134 -28.171173) (xy 274.480782 -28.171648)
			(xy 274.453534 -28.171081) (xy 274.399594 -28.163323) (xy 274.347307 -28.147968) (xy 274.297738 -28.125328)
			(xy 274.251894 -28.095864) (xy 274.210711 -28.060177) (xy 274.175025 -28.018991) (xy 274.145563 -27.973147)
			(xy 274.122926 -27.923576) (xy 274.107573 -27.871288) (xy 274.099818 -27.817348) (xy 272.829793 -27.817348)
			(xy 272.829781 -27.818026) (xy 272.821661 -27.873202) (xy 272.805593 -27.926609) (xy 272.781921 -27.977106)
			(xy 272.751148 -28.023619) (xy 272.713931 -28.065156) (xy 272.671063 -28.100831) (xy 272.623457 -28.129885)
			(xy 272.572128 -28.151697) (xy 272.518171 -28.165803) (xy 272.462734 -28.171903) (xy 272.407 -28.169866)
			(xy 272.352157 -28.159736) (xy 272.299373 -28.141729) (xy 272.249773 -28.116228) (xy 272.204415 -28.083777)
			(xy 272.164266 -28.045068) (xy 272.13018 -28.000925) (xy 272.102884 -27.95229) (xy 272.082961 -27.900199)
			(xy 272.070835 -27.845762) (xy 272.066764 -27.79014) (xy 270.326358 -27.79014) (xy 270.325849 -27.818026)
			(xy 270.317729 -27.873202) (xy 270.301661 -27.926609) (xy 270.277989 -27.977106) (xy 270.247216 -28.023619)
			(xy 270.209999 -28.065156) (xy 270.167131 -28.100831) (xy 270.119525 -28.129885) (xy 270.068196 -28.151697)
			(xy 270.014239 -28.165803) (xy 269.958802 -28.171903) (xy 269.903068 -28.169866) (xy 269.848225 -28.159736)
			(xy 269.795441 -28.141729) (xy 269.745841 -28.116228) (xy 269.700483 -28.083777) (xy 269.660334 -28.045068)
			(xy 269.626248 -28.000925) (xy 269.598952 -27.95229) (xy 269.579029 -27.900199) (xy 269.566903 -27.845762)
			(xy 269.562832 -27.79014) (xy 268.229782 -27.79014) (xy 268.229782 -27.817346) (xy 268.222027 -27.871285)
			(xy 268.206676 -27.923571) (xy 268.18404 -27.97314) (xy 268.154581 -28.018983) (xy 268.118898 -28.060168)
			(xy 268.077717 -28.095856) (xy 268.031877 -28.12532) (xy 267.98231 -28.147961) (xy 267.930026 -28.163318)
			(xy 267.876088 -28.171079) (xy 267.848842 -28.171648) (xy 267.846048 -28.171648) (xy 267.836086 -28.172133)
			(xy 267.817662 -28.179722) (xy 267.810234 -28.18638) (xy 267.758926 -28.23718) (xy 267.752089 -28.244582)
			(xy 267.74438 -28.26318) (xy 267.74394 -28.273248) (xy 267.74394 -29.106876) (xy 267.744378 -29.116939)
			(xy 267.752117 -29.13552) (xy 267.758926 -29.142944) (xy 267.810234 -29.193744) (xy 267.817647 -29.200418)
			(xy 267.836083 -29.207981) (xy 267.846048 -29.208476) (xy 267.848842 -29.208476) (xy 267.876092 -29.208965)
			(xy 267.930038 -29.216726) (xy 267.98233 -29.232086) (xy 268.031904 -29.25473) (xy 268.077751 -29.284199)
			(xy 268.118938 -29.319892) (xy 268.154626 -29.361083) (xy 268.18409 -29.406933) (xy 268.206729 -29.45651)
			(xy 268.222083 -29.508803) (xy 268.229838 -29.56275) (xy 268.229838 -29.589984) (xy 269.562832 -29.589984)
			(xy 269.566903 -29.534362) (xy 269.579029 -29.479925) (xy 269.598952 -29.427834) (xy 269.626248 -29.379199)
			(xy 269.660334 -29.335056) (xy 269.700483 -29.296347) (xy 269.745841 -29.263896) (xy 269.795441 -29.238395)
			(xy 269.848225 -29.220388) (xy 269.903068 -29.210258) (xy 269.958802 -29.208221) (xy 270.014239 -29.214321)
			(xy 270.068196 -29.228427) (xy 270.119525 -29.250239) (xy 270.167131 -29.279293) (xy 270.209999 -29.314968)
			(xy 270.247216 -29.356505) (xy 270.277989 -29.403018) (xy 270.301661 -29.453515) (xy 270.317729 -29.506922)
			(xy 270.325849 -29.562098) (xy 270.326358 -29.589984) (xy 272.066764 -29.589984) (xy 272.070835 -29.534362)
			(xy 272.082961 -29.479925) (xy 272.102884 -29.427834) (xy 272.13018 -29.379199) (xy 272.164266 -29.335056)
			(xy 272.204415 -29.296347) (xy 272.249773 -29.263896) (xy 272.299373 -29.238395) (xy 272.352157 -29.220388)
			(xy 272.407 -29.210258) (xy 272.462734 -29.208221) (xy 272.518171 -29.214321) (xy 272.572128 -29.228427)
			(xy 272.623457 -29.250239) (xy 272.671063 -29.279293) (xy 272.713931 -29.314968) (xy 272.751148 -29.356505)
			(xy 272.781921 -29.403018) (xy 272.805593 -29.453515) (xy 272.821661 -29.506922) (xy 272.829781 -29.562098)
			(xy 272.83029 -29.589984) (xy 274.098764 -29.589984) (xy 274.102835 -29.534362) (xy 274.114961 -29.479925)
			(xy 274.134884 -29.427834) (xy 274.16218 -29.379199) (xy 274.196266 -29.335056) (xy 274.236415 -29.296347)
			(xy 274.281773 -29.263896) (xy 274.331373 -29.238395) (xy 274.384157 -29.220388) (xy 274.439 -29.210258)
			(xy 274.494734 -29.208221) (xy 274.550171 -29.214321) (xy 274.604128 -29.228427) (xy 274.655457 -29.250239)
			(xy 274.703063 -29.279293) (xy 274.745931 -29.314968) (xy 274.767601 -29.339153) (xy 276.490132 -29.339153)
			(xy 276.490132 -29.284647) (xy 276.497889 -29.230694) (xy 276.513244 -29.178395) (xy 276.535887 -29.128814)
			(xy 276.565354 -29.082959) (xy 276.601047 -29.041764) (xy 276.64224 -29.006069) (xy 276.688093 -28.976598)
			(xy 276.737673 -28.953953) (xy 276.789971 -28.938594) (xy 276.843923 -28.930834) (xy 276.871176 -28.930346)
			(xy 276.885969 -28.930482) (xy 276.915467 -28.93277) (xy 276.930104 -28.934918) (xy 276.941026 -28.936696)
			(xy 276.962362 -28.9306) (xy 277.029672 -28.873196) (xy 277.037706 -28.865635) (xy 277.046916 -28.845609)
			(xy 277.047452 -28.834588) (xy 277.047452 -28.530296) (xy 277.046932 -28.519275) (xy 277.037702 -28.499257)
			(xy 277.029672 -28.491688) (xy 276.962362 -28.434284) (xy 276.941026 -28.428188) (xy 276.930104 -28.429966)
			(xy 276.915465 -28.432101) (xy 276.885969 -28.434393) (xy 276.871176 -28.434538) (xy 276.843928 -28.43399)
			(xy 276.789987 -28.426231) (xy 276.7377 -28.410876) (xy 276.688129 -28.388235) (xy 276.642286 -28.35877)
			(xy 276.601101 -28.323082) (xy 276.565415 -28.281895) (xy 276.535954 -28.23605) (xy 276.513316 -28.186478)
			(xy 276.497963 -28.134189) (xy 276.490208 -28.080248) (xy 276.490208 -28.025752) (xy 276.497963 -27.971811)
			(xy 276.513316 -27.919522) (xy 276.535954 -27.86995) (xy 276.565415 -27.824105) (xy 276.601101 -27.782918)
			(xy 276.642286 -27.74723) (xy 276.688129 -27.717765) (xy 276.7377 -27.695124) (xy 276.789987 -27.679769)
			(xy 276.843928 -27.67201) (xy 276.871176 -27.671522) (xy 276.897102 -27.671964) (xy 276.948479 -27.678967)
			(xy 276.998435 -27.692862) (xy 277.04605 -27.713392) (xy 277.090446 -27.740179) (xy 277.130808 -27.772731)
			(xy 277.16639 -27.810447) (xy 277.181818 -27.831288) (xy 277.187542 -27.838633) (xy 277.203057 -27.84891)
			(xy 277.212044 -27.851354) (xy 277.24227 -27.858212) (xy 277.251545 -27.859974) (xy 277.27021 -27.857224)
			(xy 277.278592 -27.852878) (xy 277.30457 -27.838587) (xy 277.359421 -27.816076) (xy 277.416724 -27.800848)
			(xy 277.475515 -27.793161) (xy 277.50516 -27.79268) (xy 277.534803 -27.793183) (xy 277.593584 -27.800903)
			(xy 277.650883 -27.816128) (xy 277.705743 -27.838605) (xy 277.731728 -27.852878) (xy 277.740152 -27.857099)
			(xy 277.758773 -27.859848) (xy 277.76805 -27.858212) (xy 277.798276 -27.851354) (xy 277.807277 -27.848949)
			(xy 277.822778 -27.83864) (xy 277.828502 -27.831288) (xy 277.843901 -27.810422) (xy 277.879475 -27.772687)
			(xy 277.919835 -27.740123) (xy 277.964237 -27.713329) (xy 278.01186 -27.692801) (xy 278.061827 -27.678918)
			(xy 278.113214 -27.671935) (xy 278.139144 -27.671522) (xy 278.166395 -27.671951) (xy 278.220343 -27.679713)
			(xy 278.272636 -27.695073) (xy 278.322212 -27.717719) (xy 278.36806 -27.747188) (xy 278.409248 -27.782883)
			(xy 278.444938 -27.824075) (xy 278.474402 -27.869927) (xy 278.497042 -27.919505) (xy 278.512396 -27.971801)
			(xy 278.520152 -28.025749) (xy 278.520152 -28.080251) (xy 278.512396 -28.134199) (xy 278.497042 -28.186495)
			(xy 278.474402 -28.236073) (xy 278.444938 -28.281925) (xy 278.409248 -28.323117) (xy 278.36806 -28.358812)
			(xy 278.322212 -28.388281) (xy 278.272636 -28.410927) (xy 278.220343 -28.426287) (xy 278.166395 -28.434049)
			(xy 278.139144 -28.434538) (xy 278.124351 -28.4344) (xy 278.094853 -28.432113) (xy 278.080216 -28.429966)
			(xy 278.069294 -28.428188) (xy 278.047958 -28.434284) (xy 277.980648 -28.491688) (xy 277.972624 -28.499259)
			(xy 277.963408 -28.519277) (xy 277.962868 -28.530296) (xy 277.962868 -28.834588) (xy 277.963423 -28.845605)
			(xy 277.972631 -28.865621) (xy 277.980648 -28.873196) (xy 278.047958 -28.9306) (xy 278.069294 -28.936696)
			(xy 278.080216 -28.934918) (xy 278.094854 -28.932781) (xy 278.124351 -28.93049) (xy 278.139144 -28.930346)
			(xy 278.16639 -28.930927) (xy 278.220326 -28.938688) (xy 278.272609 -28.954045) (xy 278.322175 -28.976686)
			(xy 278.368014 -29.00615) (xy 278.409194 -29.041837) (xy 278.444877 -29.083021) (xy 278.474335 -29.128864)
			(xy 278.496971 -29.178432) (xy 278.512322 -29.230717) (xy 278.520076 -29.284654) (xy 278.520076 -29.339146)
			(xy 278.512322 -29.393083) (xy 278.496971 -29.445368) (xy 278.474335 -29.494936) (xy 278.444877 -29.540779)
			(xy 278.409194 -29.581963) (xy 278.368014 -29.61765) (xy 278.322175 -29.647114) (xy 278.272609 -29.669755)
			(xy 278.220326 -29.685112) (xy 278.16639 -29.692873) (xy 278.139144 -29.693362) (xy 278.113218 -29.692912)
			(xy 278.061841 -29.685911) (xy 278.011885 -29.672018) (xy 277.96427 -29.65149) (xy 277.919873 -29.624703)
			(xy 277.879512 -29.592152) (xy 277.84393 -29.554436) (xy 277.828502 -29.533596) (xy 277.822755 -29.526271)
			(xy 277.807258 -29.515981) (xy 277.798276 -29.51353) (xy 277.76805 -29.506672) (xy 277.758774 -29.504923)
			(xy 277.74011 -29.507664) (xy 277.731728 -29.512006) (xy 277.705745 -29.526288) (xy 277.650896 -29.548802)
			(xy 277.593595 -29.564032) (xy 277.534805 -29.571722) (xy 277.50516 -29.572204) (xy 277.475518 -29.571694)
			(xy 277.416736 -29.563977) (xy 277.359438 -29.548754) (xy 277.304577 -29.526279) (xy 277.278592 -29.512006)
			(xy 277.270186 -29.507745) (xy 277.25155 -29.505021) (xy 277.24227 -29.506672) (xy 277.212044 -29.51353)
			(xy 277.203048 -29.515948) (xy 277.187544 -29.526248) (xy 277.181818 -29.533596) (xy 277.166403 -29.554449)
			(xy 277.130832 -29.592185) (xy 277.090475 -29.624751) (xy 277.046076 -29.651547) (xy 276.998455 -29.672077)
			(xy 276.948491 -29.685962) (xy 276.897105 -29.692948) (xy 276.871176 -29.693362) (xy 276.843923 -29.692966)
			(xy 276.789971 -29.685206) (xy 276.737673 -29.669847) (xy 276.688093 -29.647202) (xy 276.64224 -29.617731)
			(xy 276.601047 -29.582036) (xy 276.565354 -29.540841) (xy 276.535887 -29.494986) (xy 276.513244 -29.445405)
			(xy 276.497889 -29.393106) (xy 276.490132 -29.339153) (xy 274.767601 -29.339153) (xy 274.783148 -29.356505)
			(xy 274.813921 -29.403018) (xy 274.837593 -29.453515) (xy 274.853661 -29.506922) (xy 274.861781 -29.562098)
			(xy 274.86229 -29.589984) (xy 274.861781 -29.61787) (xy 274.853661 -29.673046) (xy 274.837593 -29.726453)
			(xy 274.813921 -29.77695) (xy 274.783148 -29.823463) (xy 274.745931 -29.865) (xy 274.703063 -29.900675)
			(xy 274.655457 -29.929729) (xy 274.604128 -29.951541) (xy 274.550171 -29.965647) (xy 274.494734 -29.971747)
			(xy 274.439 -29.96971) (xy 274.384157 -29.95958) (xy 274.331373 -29.941573) (xy 274.281773 -29.916072)
			(xy 274.236415 -29.883621) (xy 274.196266 -29.844912) (xy 274.16218 -29.800769) (xy 274.134884 -29.752134)
			(xy 274.114961 -29.700043) (xy 274.102835 -29.645606) (xy 274.098764 -29.589984) (xy 272.83029 -29.589984)
			(xy 272.829781 -29.61787) (xy 272.821661 -29.673046) (xy 272.805593 -29.726453) (xy 272.781921 -29.77695)
			(xy 272.751148 -29.823463) (xy 272.713931 -29.865) (xy 272.671063 -29.900675) (xy 272.623457 -29.929729)
			(xy 272.572128 -29.951541) (xy 272.518171 -29.965647) (xy 272.462734 -29.971747) (xy 272.407 -29.96971)
			(xy 272.352157 -29.95958) (xy 272.299373 -29.941573) (xy 272.249773 -29.916072) (xy 272.204415 -29.883621)
			(xy 272.164266 -29.844912) (xy 272.13018 -29.800769) (xy 272.102884 -29.752134) (xy 272.082961 -29.700043)
			(xy 272.070835 -29.645606) (xy 272.066764 -29.589984) (xy 270.326358 -29.589984) (xy 270.325849 -29.61787)
			(xy 270.317729 -29.673046) (xy 270.301661 -29.726453) (xy 270.277989 -29.77695) (xy 270.247216 -29.823463)
			(xy 270.209999 -29.865) (xy 270.167131 -29.900675) (xy 270.119525 -29.929729) (xy 270.068196 -29.951541)
			(xy 270.014239 -29.965647) (xy 269.958802 -29.971747) (xy 269.903068 -29.96971) (xy 269.848225 -29.95958)
			(xy 269.795441 -29.941573) (xy 269.745841 -29.916072) (xy 269.700483 -29.883621) (xy 269.660334 -29.844912)
			(xy 269.626248 -29.800769) (xy 269.598952 -29.752134) (xy 269.579029 -29.700043) (xy 269.566903 -29.645606)
			(xy 269.562832 -29.589984) (xy 268.229838 -29.589984) (xy 268.229838 -29.61725) (xy 268.222083 -29.671197)
			(xy 268.206729 -29.72349) (xy 268.18409 -29.773067) (xy 268.154626 -29.818917) (xy 268.118938 -29.860108)
			(xy 268.077751 -29.895801) (xy 268.031904 -29.92527) (xy 267.98233 -29.947914) (xy 267.930038 -29.963274)
			(xy 267.876092 -29.971035) (xy 267.848842 -29.971492) (xy 267.846048 -29.971492) (xy 267.836085 -29.971976)
			(xy 267.817656 -29.979559) (xy 267.810234 -29.986224) (xy 267.758926 -30.037024) (xy 267.75208 -30.044423)
			(xy 267.744351 -30.063021) (xy 267.74394 -30.073092) (xy 267.74394 -30.906974) (xy 267.744378 -30.917037)
			(xy 267.752116 -30.935618) (xy 267.758926 -30.943042) (xy 267.810234 -30.993842) (xy 267.817647 -31.000516)
			(xy 267.836083 -31.00808) (xy 267.846048 -31.008574) (xy 267.848842 -31.008574) (xy 267.876093 -31.009063)
			(xy 267.930038 -31.016824) (xy 267.98233 -31.032184) (xy 268.031905 -31.054829) (xy 268.077752 -31.084297)
			(xy 268.118939 -31.119991) (xy 268.154628 -31.161182) (xy 268.184092 -31.207032) (xy 268.206731 -31.256609)
			(xy 268.222085 -31.308903) (xy 268.22984 -31.362849) (xy 268.22984 -31.417351) (xy 268.222085 -31.471297)
			(xy 268.206731 -31.523591) (xy 268.184092 -31.573168) (xy 268.154628 -31.619018) (xy 268.134452 -31.642304)
			(xy 269.60652 -31.642304) (xy 269.610591 -31.586682) (xy 269.622717 -31.532245) (xy 269.64264 -31.480154)
			(xy 269.669936 -31.431519) (xy 269.704022 -31.387376) (xy 269.744171 -31.348667) (xy 269.789529 -31.316216)
			(xy 269.839129 -31.290715) (xy 269.891913 -31.272708) (xy 269.946756 -31.262578) (xy 270.00249 -31.260541)
			(xy 270.057927 -31.266641) (xy 270.111884 -31.280747) (xy 270.163213 -31.302559) (xy 270.210819 -31.331613)
			(xy 270.253687 -31.367288) (xy 270.27411 -31.390082) (xy 272.066764 -31.390082) (xy 272.070835 -31.33446)
			(xy 272.082961 -31.280023) (xy 272.102884 -31.227932) (xy 272.13018 -31.179297) (xy 272.164266 -31.135154)
			(xy 272.204415 -31.096445) (xy 272.249773 -31.063994) (xy 272.299373 -31.038493) (xy 272.352157 -31.020486)
			(xy 272.407 -31.010356) (xy 272.462734 -31.008319) (xy 272.518171 -31.014419) (xy 272.572128 -31.028525)
			(xy 272.623457 -31.050337) (xy 272.671063 -31.079391) (xy 272.713931 -31.115066) (xy 272.751148 -31.156603)
			(xy 272.781921 -31.203116) (xy 272.805593 -31.253613) (xy 272.821661 -31.30702) (xy 272.829781 -31.362196)
			(xy 272.83029 -31.390082) (xy 274.098764 -31.390082) (xy 274.102835 -31.33446) (xy 274.114961 -31.280023)
			(xy 274.134884 -31.227932) (xy 274.16218 -31.179297) (xy 274.196266 -31.135154) (xy 274.236415 -31.096445)
			(xy 274.281773 -31.063994) (xy 274.331373 -31.038493) (xy 274.384157 -31.020486) (xy 274.439 -31.010356)
			(xy 274.494734 -31.008319) (xy 274.550171 -31.014419) (xy 274.604128 -31.028525) (xy 274.655457 -31.050337)
			(xy 274.703063 -31.079391) (xy 274.745931 -31.115066) (xy 274.783148 -31.156603) (xy 274.813921 -31.203116)
			(xy 274.837593 -31.253613) (xy 274.853661 -31.30702) (xy 274.861781 -31.362196) (xy 274.86229 -31.390082)
			(xy 274.861781 -31.417968) (xy 274.853661 -31.473144) (xy 274.837593 -31.526551) (xy 274.813921 -31.577048)
			(xy 274.783148 -31.623561) (xy 274.745931 -31.665098) (xy 274.727722 -31.680252) (xy 276.49015 -31.680252)
			(xy 276.49015 -31.625748) (xy 276.497906 -31.571798) (xy 276.513261 -31.519502) (xy 276.535902 -31.469922)
			(xy 276.565369 -31.42407) (xy 276.60106 -31.382877) (xy 276.64225 -31.347183) (xy 276.688101 -31.317714)
			(xy 276.737679 -31.29507) (xy 276.789975 -31.279711) (xy 276.843924 -31.271951) (xy 276.871176 -31.271464)
			(xy 276.897103 -31.271888) (xy 276.948481 -31.278892) (xy 276.998438 -31.292789) (xy 277.046054 -31.313321)
			(xy 277.09045 -31.340112) (xy 277.130811 -31.372667) (xy 277.166391 -31.410387) (xy 277.181818 -31.43123)
			(xy 277.187553 -31.438565) (xy 277.203059 -31.448849) (xy 277.212044 -31.451296) (xy 277.24227 -31.458154)
			(xy 277.251545 -31.459911) (xy 277.27021 -31.457164) (xy 277.278592 -31.45282) (xy 277.304587 -31.438582)
			(xy 277.359454 -31.416165) (xy 277.416752 -31.401004) (xy 277.475525 -31.39335) (xy 277.50516 -31.392876)
			(xy 277.534798 -31.393333) (xy 277.59358 -31.400955) (xy 277.650883 -31.416114) (xy 277.705745 -31.438555)
			(xy 277.731728 -31.45282) (xy 277.740153 -31.457039) (xy 277.758773 -31.459791) (xy 277.76805 -31.458154)
			(xy 277.798276 -31.451296) (xy 277.807272 -31.448878) (xy 277.822775 -31.438578) (xy 277.828502 -31.43123)
			(xy 277.843884 -31.410351) (xy 277.879462 -31.372619) (xy 277.919826 -31.340058) (xy 277.964231 -31.313267)
			(xy 278.011857 -31.292741) (xy 278.061825 -31.278859) (xy 278.113213 -31.271877) (xy 278.139144 -31.271464)
			(xy 278.166391 -31.272009) (xy 278.22033 -31.27977) (xy 278.272616 -31.295128) (xy 278.322184 -31.31777)
			(xy 278.368025 -31.347235) (xy 278.409207 -31.382924) (xy 278.444891 -31.42411) (xy 278.474351 -31.469955)
			(xy 278.496987 -31.519526) (xy 278.512339 -31.571813) (xy 278.520094 -31.625753) (xy 278.520094 -31.680247)
			(xy 278.512339 -31.734187) (xy 278.496987 -31.786474) (xy 278.474351 -31.836045) (xy 278.444891 -31.88189)
			(xy 278.409207 -31.923076) (xy 278.368025 -31.958765) (xy 278.322184 -31.98823) (xy 278.272616 -32.010872)
			(xy 278.22033 -32.02623) (xy 278.166391 -32.033991) (xy 278.139144 -32.03448) (xy 278.124351 -32.034342)
			(xy 278.094853 -32.032055) (xy 278.080216 -32.029908) (xy 278.069294 -32.02813) (xy 278.047958 -32.034226)
			(xy 277.980648 -32.09163) (xy 277.972605 -32.099184) (xy 277.9634 -32.119215) (xy 277.962868 -32.130238)
			(xy 277.962868 -32.43453) (xy 277.963399 -32.445549) (xy 277.972624 -32.465565) (xy 277.980648 -32.473138)
			(xy 278.047958 -32.530542) (xy 278.069294 -32.536638) (xy 278.080216 -32.53486) (xy 278.094854 -32.532722)
			(xy 278.124351 -32.530432) (xy 278.139144 -32.530288) (xy 278.166393 -32.530785) (xy 278.220335 -32.538546)
			(xy 278.272624 -32.553905) (xy 278.322195 -32.576548) (xy 278.36804 -32.606016) (xy 278.409224 -32.641707)
			(xy 278.444911 -32.682895) (xy 278.474373 -32.728743) (xy 278.49701 -32.778317) (xy 278.512363 -32.830608)
			(xy 278.520118 -32.884551) (xy 278.520118 -32.939049) (xy 278.512363 -32.992992) (xy 278.49701 -33.045283)
			(xy 278.474373 -33.094857) (xy 278.444911 -33.140705) (xy 278.409224 -33.181893) (xy 278.36804 -33.217584)
			(xy 278.322195 -33.247052) (xy 278.272624 -33.269695) (xy 278.220335 -33.285054) (xy 278.166393 -33.292815)
			(xy 278.139144 -33.293304) (xy 278.113219 -33.292837) (xy 278.061843 -33.285837) (xy 278.011889 -33.271945)
			(xy 277.964274 -33.251419) (xy 277.919877 -33.224636) (xy 277.879515 -33.192089) (xy 277.843931 -33.154376)
			(xy 277.828502 -33.133538) (xy 277.822766 -33.126203) (xy 277.80726 -33.11592) (xy 277.798276 -33.113472)
			(xy 277.76805 -33.106614) (xy 277.758774 -33.10486) (xy 277.74011 -33.107604) (xy 277.731728 -33.111948)
			(xy 277.705728 -33.126176) (xy 277.650863 -33.148596) (xy 277.593567 -33.16376) (xy 277.534794 -33.171416)
			(xy 277.50516 -33.171892) (xy 277.475523 -33.17143) (xy 277.41674 -33.163811) (xy 277.359437 -33.148653)
			(xy 277.304575 -33.126212) (xy 277.278592 -33.111948) (xy 277.270185 -33.107688) (xy 277.25155 -33.104963)
			(xy 277.24227 -33.106614) (xy 277.212044 -33.113472) (xy 277.203054 -33.115909) (xy 277.187549 -33.126196)
			(xy 277.181818 -33.133538) (xy 277.166415 -33.154401) (xy 277.130841 -33.192134) (xy 277.090481 -33.224698)
			(xy 277.04608 -33.251492) (xy 276.998457 -33.27202) (xy 276.948492 -33.285905) (xy 276.897106 -33.29289)
			(xy 276.871176 -33.293304) (xy 276.843926 -33.292825) (xy 276.78998 -33.285065) (xy 276.737687 -33.269708)
			(xy 276.688113 -33.247065) (xy 276.642265 -33.217598) (xy 276.601077 -33.181906) (xy 276.565388 -33.140716)
			(xy 276.535923 -33.094866) (xy 276.513284 -33.04529) (xy 276.49793 -32.992997) (xy 276.490174 -32.93905)
			(xy 276.490174 -32.88455) (xy 276.49793 -32.830603) (xy 276.513284 -32.77831) (xy 276.535923 -32.728734)
			(xy 276.565388 -32.682884) (xy 276.601077 -32.641694) (xy 276.642265 -32.606002) (xy 276.688113 -32.576535)
			(xy 276.737687 -32.553892) (xy 276.78998 -32.538535) (xy 276.843926 -32.530775) (xy 276.871176 -32.530288)
			(xy 276.885969 -32.530425) (xy 276.915467 -32.532713) (xy 276.930104 -32.53486) (xy 276.941026 -32.536638)
			(xy 276.962362 -32.530542) (xy 277.029672 -32.473138) (xy 277.037687 -32.46556) (xy 277.046907 -32.445547)
			(xy 277.047452 -32.43453) (xy 277.047452 -32.130238) (xy 277.046908 -32.119219) (xy 277.037695 -32.099202)
			(xy 277.029672 -32.09163) (xy 276.962362 -32.034226) (xy 276.941026 -32.02813) (xy 276.930104 -32.029908)
			(xy 276.915465 -32.032043) (xy 276.885969 -32.034335) (xy 276.871176 -32.03448) (xy 276.843924 -32.034049)
			(xy 276.789975 -32.026289) (xy 276.737679 -32.01093) (xy 276.688101 -31.988286) (xy 276.64225 -31.958817)
			(xy 276.60106 -31.923123) (xy 276.565369 -31.88193) (xy 276.535902 -31.836078) (xy 276.513261 -31.786498)
			(xy 276.497906 -31.734202) (xy 276.49015 -31.680252) (xy 274.727722 -31.680252) (xy 274.703063 -31.700773)
			(xy 274.655457 -31.729827) (xy 274.604128 -31.751639) (xy 274.550171 -31.765745) (xy 274.494734 -31.771845)
			(xy 274.439 -31.769808) (xy 274.384157 -31.759678) (xy 274.331373 -31.741671) (xy 274.281773 -31.71617)
			(xy 274.236415 -31.683719) (xy 274.196266 -31.64501) (xy 274.16218 -31.600867) (xy 274.134884 -31.552232)
			(xy 274.114961 -31.500141) (xy 274.102835 -31.445704) (xy 274.098764 -31.390082) (xy 272.83029 -31.390082)
			(xy 272.829781 -31.417968) (xy 272.821661 -31.473144) (xy 272.805593 -31.526551) (xy 272.781921 -31.577048)
			(xy 272.751148 -31.623561) (xy 272.713931 -31.665098) (xy 272.671063 -31.700773) (xy 272.623457 -31.729827)
			(xy 272.572128 -31.751639) (xy 272.518171 -31.765745) (xy 272.462734 -31.771845) (xy 272.407 -31.769808)
			(xy 272.352157 -31.759678) (xy 272.299373 -31.741671) (xy 272.249773 -31.71617) (xy 272.204415 -31.683719)
			(xy 272.164266 -31.64501) (xy 272.13018 -31.600867) (xy 272.102884 -31.552232) (xy 272.082961 -31.500141)
			(xy 272.070835 -31.445704) (xy 272.066764 -31.390082) (xy 270.27411 -31.390082) (xy 270.290904 -31.408825)
			(xy 270.321677 -31.455338) (xy 270.345349 -31.505835) (xy 270.361417 -31.559242) (xy 270.369537 -31.614418)
			(xy 270.370046 -31.642304) (xy 270.369537 -31.67019) (xy 270.361417 -31.725366) (xy 270.345349 -31.778773)
			(xy 270.321677 -31.82927) (xy 270.290904 -31.875783) (xy 270.253687 -31.91732) (xy 270.210819 -31.952995)
			(xy 270.163213 -31.982049) (xy 270.111884 -32.003861) (xy 270.057927 -32.017967) (xy 270.00249 -32.024067)
			(xy 269.946756 -32.02203) (xy 269.891913 -32.0119) (xy 269.839129 -31.993893) (xy 269.789529 -31.968392)
			(xy 269.744171 -31.935941) (xy 269.704022 -31.897232) (xy 269.669936 -31.853089) (xy 269.64264 -31.804454)
			(xy 269.622717 -31.752363) (xy 269.610591 -31.697926) (xy 269.60652 -31.642304) (xy 268.134452 -31.642304)
			(xy 268.118939 -31.660209) (xy 268.077752 -31.695903) (xy 268.031905 -31.725371) (xy 267.98233 -31.748016)
			(xy 267.930038 -31.763376) (xy 267.876093 -31.771137) (xy 267.848842 -31.77159) (xy 267.846048 -31.77159)
			(xy 267.836084 -31.772074) (xy 267.817656 -31.779656) (xy 267.810234 -31.786322) (xy 267.758926 -31.837122)
			(xy 267.75208 -31.84452) (xy 267.74435 -31.863119) (xy 267.74394 -31.87319) (xy 267.74394 -32.707072)
			(xy 267.744378 -32.717135) (xy 267.752115 -32.735717) (xy 267.758926 -32.74314) (xy 267.810234 -32.79394)
			(xy 267.817647 -32.800615) (xy 267.836083 -32.808178) (xy 267.846048 -32.808672) (xy 267.848842 -32.808672)
			(xy 267.876093 -32.809161) (xy 267.930039 -32.816922) (xy 267.982331 -32.832282) (xy 268.031906 -32.854927)
			(xy 268.077753 -32.884396) (xy 268.118941 -32.920089) (xy 268.154629 -32.96128) (xy 268.184093 -33.007131)
			(xy 268.206733 -33.056708) (xy 268.222086 -33.109002) (xy 268.229842 -33.162949) (xy 268.229842 -33.19018)
			(xy 269.873982 -33.19018) (xy 269.878053 -33.134558) (xy 269.890179 -33.080121) (xy 269.910102 -33.02803)
			(xy 269.937398 -32.979395) (xy 269.971484 -32.935252) (xy 270.011633 -32.896543) (xy 270.056991 -32.864092)
			(xy 270.106591 -32.838591) (xy 270.159375 -32.820584) (xy 270.214218 -32.810454) (xy 270.269952 -32.808417)
			(xy 270.325389 -32.814517) (xy 270.379346 -32.828623) (xy 270.430675 -32.850435) (xy 270.478281 -32.879489)
			(xy 270.521149 -32.915164) (xy 270.558366 -32.956701) (xy 270.589139 -33.003214) (xy 270.612811 -33.053711)
			(xy 270.628879 -33.107118) (xy 270.636999 -33.162294) (xy 270.637508 -33.19018) (xy 272.066764 -33.19018)
			(xy 272.070835 -33.134558) (xy 272.082961 -33.080121) (xy 272.102884 -33.02803) (xy 272.13018 -32.979395)
			(xy 272.164266 -32.935252) (xy 272.204415 -32.896543) (xy 272.249773 -32.864092) (xy 272.299373 -32.838591)
			(xy 272.352157 -32.820584) (xy 272.407 -32.810454) (xy 272.462734 -32.808417) (xy 272.518171 -32.814517)
			(xy 272.572128 -32.828623) (xy 272.623457 -32.850435) (xy 272.671063 -32.879489) (xy 272.713931 -32.915164)
			(xy 272.751148 -32.956701) (xy 272.781921 -33.003214) (xy 272.805593 -33.053711) (xy 272.821661 -33.107118)
			(xy 272.829781 -33.162294) (xy 272.83029 -33.19018) (xy 274.098764 -33.19018) (xy 274.102835 -33.134558)
			(xy 274.114961 -33.080121) (xy 274.134884 -33.02803) (xy 274.16218 -32.979395) (xy 274.196266 -32.935252)
			(xy 274.236415 -32.896543) (xy 274.281773 -32.864092) (xy 274.331373 -32.838591) (xy 274.384157 -32.820584)
			(xy 274.439 -32.810454) (xy 274.494734 -32.808417) (xy 274.550171 -32.814517) (xy 274.604128 -32.828623)
			(xy 274.655457 -32.850435) (xy 274.703063 -32.879489) (xy 274.745931 -32.915164) (xy 274.783148 -32.956701)
			(xy 274.813921 -33.003214) (xy 274.837593 -33.053711) (xy 274.853661 -33.107118) (xy 274.861781 -33.162294)
			(xy 274.86229 -33.19018) (xy 274.861781 -33.218066) (xy 274.853661 -33.273242) (xy 274.837593 -33.326649)
			(xy 274.813921 -33.377146) (xy 274.783148 -33.423659) (xy 274.745931 -33.465196) (xy 274.703063 -33.500871)
			(xy 274.655457 -33.529925) (xy 274.604128 -33.551737) (xy 274.550171 -33.565843) (xy 274.494734 -33.571943)
			(xy 274.439 -33.569906) (xy 274.384157 -33.559776) (xy 274.331373 -33.541769) (xy 274.281773 -33.516268)
			(xy 274.236415 -33.483817) (xy 274.196266 -33.445108) (xy 274.16218 -33.400965) (xy 274.134884 -33.35233)
			(xy 274.114961 -33.300239) (xy 274.102835 -33.245802) (xy 274.098764 -33.19018) (xy 272.83029 -33.19018)
			(xy 272.829781 -33.218066) (xy 272.821661 -33.273242) (xy 272.805593 -33.326649) (xy 272.781921 -33.377146)
			(xy 272.751148 -33.423659) (xy 272.713931 -33.465196) (xy 272.671063 -33.500871) (xy 272.623457 -33.529925)
			(xy 272.572128 -33.551737) (xy 272.518171 -33.565843) (xy 272.462734 -33.571943) (xy 272.407 -33.569906)
			(xy 272.352157 -33.559776) (xy 272.299373 -33.541769) (xy 272.249773 -33.516268) (xy 272.204415 -33.483817)
			(xy 272.164266 -33.445108) (xy 272.13018 -33.400965) (xy 272.102884 -33.35233) (xy 272.082961 -33.300239)
			(xy 272.070835 -33.245802) (xy 272.066764 -33.19018) (xy 270.637508 -33.19018) (xy 270.636999 -33.218066)
			(xy 270.628879 -33.273242) (xy 270.612811 -33.326649) (xy 270.589139 -33.377146) (xy 270.558366 -33.423659)
			(xy 270.521149 -33.465196) (xy 270.478281 -33.500871) (xy 270.430675 -33.529925) (xy 270.379346 -33.551737)
			(xy 270.325389 -33.565843) (xy 270.269952 -33.571943) (xy 270.214218 -33.569906) (xy 270.159375 -33.559776)
			(xy 270.106591 -33.541769) (xy 270.056991 -33.516268) (xy 270.011633 -33.483817) (xy 269.971484 -33.445108)
			(xy 269.937398 -33.400965) (xy 269.910102 -33.35233) (xy 269.890179 -33.300239) (xy 269.878053 -33.245802)
			(xy 269.873982 -33.19018) (xy 268.229842 -33.19018) (xy 268.229842 -33.217451) (xy 268.222086 -33.271398)
			(xy 268.206733 -33.323692) (xy 268.184093 -33.373269) (xy 268.154629 -33.41912) (xy 268.118941 -33.460311)
			(xy 268.077753 -33.496004) (xy 268.031906 -33.525473) (xy 267.982331 -33.548118) (xy 267.930039 -33.563478)
			(xy 267.876093 -33.571239) (xy 267.848842 -33.571688) (xy 267.846048 -33.571688) (xy 267.836084 -33.572172)
			(xy 267.817655 -33.579754) (xy 267.810234 -33.58642) (xy 267.758926 -33.63722) (xy 267.75208 -33.644618)
			(xy 267.744349 -33.663217) (xy 267.74394 -33.673288) (xy 267.74394 -34.506916) (xy 267.744367 -34.516984)
			(xy 267.75209 -34.53558) (xy 267.758926 -34.542984) (xy 267.810234 -34.593784) (xy 267.817645 -34.600465)
			(xy 267.836081 -34.608037) (xy 267.846048 -34.608516) (xy 267.848842 -34.608516) (xy 267.87609 -34.609005)
			(xy 267.930029 -34.616766) (xy 267.982316 -34.632124) (xy 268.031884 -34.654766) (xy 268.077727 -34.684231)
			(xy 268.118909 -34.719921) (xy 268.154594 -34.761107) (xy 268.184054 -34.806953) (xy 268.206691 -34.856524)
			(xy 268.222043 -34.908812) (xy 268.229798 -34.962752) (xy 268.229798 -34.990024) (xy 269.872712 -34.990024)
			(xy 269.876783 -34.934402) (xy 269.888909 -34.879965) (xy 269.908832 -34.827874) (xy 269.936128 -34.779239)
			(xy 269.970214 -34.735096) (xy 270.010363 -34.696387) (xy 270.055721 -34.663936) (xy 270.105321 -34.638435)
			(xy 270.158105 -34.620428) (xy 270.212948 -34.610298) (xy 270.268682 -34.608261) (xy 270.324119 -34.614361)
			(xy 270.378076 -34.628467) (xy 270.429405 -34.650279) (xy 270.477011 -34.679333) (xy 270.519879 -34.715008)
			(xy 270.557096 -34.756545) (xy 270.587869 -34.803058) (xy 270.611541 -34.853555) (xy 270.627609 -34.906962)
			(xy 270.635729 -34.962138) (xy 270.636238 -34.990024) (xy 271.200878 -34.990024) (xy 271.204949 -34.934402)
			(xy 271.217075 -34.879965) (xy 271.236998 -34.827874) (xy 271.264294 -34.779239) (xy 271.29838 -34.735096)
			(xy 271.338529 -34.696387) (xy 271.383887 -34.663936) (xy 271.433487 -34.638435) (xy 271.486271 -34.620428)
			(xy 271.541114 -34.610298) (xy 271.596848 -34.608261) (xy 271.652285 -34.614361) (xy 271.706242 -34.628467)
			(xy 271.757571 -34.650279) (xy 271.805177 -34.679333) (xy 271.848045 -34.715008) (xy 271.885262 -34.756545)
			(xy 271.916035 -34.803058) (xy 271.939707 -34.853555) (xy 271.955775 -34.906962) (xy 271.963895 -34.962138)
			(xy 271.964404 -34.990024) (xy 274.098764 -34.990024) (xy 274.102835 -34.934402) (xy 274.114961 -34.879965)
			(xy 274.134884 -34.827874) (xy 274.16218 -34.779239) (xy 274.196266 -34.735096) (xy 274.236415 -34.696387)
			(xy 274.281773 -34.663936) (xy 274.331373 -34.638435) (xy 274.384157 -34.620428) (xy 274.439 -34.610298)
			(xy 274.494734 -34.608261) (xy 274.550171 -34.614361) (xy 274.604128 -34.628467) (xy 274.655457 -34.650279)
			(xy 274.703063 -34.679333) (xy 274.745931 -34.715008) (xy 274.783148 -34.756545) (xy 274.813921 -34.803058)
			(xy 274.837593 -34.853555) (xy 274.853661 -34.906962) (xy 274.861781 -34.962138) (xy 274.86229 -34.990024)
			(xy 274.861781 -35.01791) (xy 274.853661 -35.073086) (xy 274.837593 -35.126493) (xy 274.813921 -35.17699)
			(xy 274.783148 -35.223503) (xy 274.745931 -35.26504) (xy 274.703063 -35.300715) (xy 274.655457 -35.329769)
			(xy 274.604128 -35.351581) (xy 274.550171 -35.365687) (xy 274.494734 -35.371787) (xy 274.439 -35.36975)
			(xy 274.384157 -35.35962) (xy 274.331373 -35.341613) (xy 274.281773 -35.316112) (xy 274.236415 -35.283661)
			(xy 274.196266 -35.244952) (xy 274.16218 -35.200809) (xy 274.134884 -35.152174) (xy 274.114961 -35.100083)
			(xy 274.102835 -35.045646) (xy 274.098764 -34.990024) (xy 271.964404 -34.990024) (xy 271.963895 -35.01791)
			(xy 271.955775 -35.073086) (xy 271.939707 -35.126493) (xy 271.916035 -35.17699) (xy 271.885262 -35.223503)
			(xy 271.848045 -35.26504) (xy 271.805177 -35.300715) (xy 271.757571 -35.329769) (xy 271.706242 -35.351581)
			(xy 271.652285 -35.365687) (xy 271.596848 -35.371787) (xy 271.541114 -35.36975) (xy 271.486271 -35.35962)
			(xy 271.433487 -35.341613) (xy 271.383887 -35.316112) (xy 271.338529 -35.283661) (xy 271.29838 -35.244952)
			(xy 271.264294 -35.200809) (xy 271.236998 -35.152174) (xy 271.217075 -35.100083) (xy 271.204949 -35.045646)
			(xy 271.200878 -34.990024) (xy 270.636238 -34.990024) (xy 270.635729 -35.01791) (xy 270.627609 -35.073086)
			(xy 270.611541 -35.126493) (xy 270.587869 -35.17699) (xy 270.557096 -35.223503) (xy 270.519879 -35.26504)
			(xy 270.477011 -35.300715) (xy 270.429405 -35.329769) (xy 270.378076 -35.351581) (xy 270.324119 -35.365687)
			(xy 270.268682 -35.371787) (xy 270.212948 -35.36975) (xy 270.158105 -35.35962) (xy 270.105321 -35.341613)
			(xy 270.055721 -35.316112) (xy 270.010363 -35.283661) (xy 269.970214 -35.244952) (xy 269.936128 -35.200809)
			(xy 269.908832 -35.152174) (xy 269.888909 -35.100083) (xy 269.876783 -35.045646) (xy 269.872712 -34.990024)
			(xy 268.229798 -34.990024) (xy 268.229798 -35.017248) (xy 268.222043 -35.071188) (xy 268.206691 -35.123476)
			(xy 268.184054 -35.173047) (xy 268.154594 -35.218893) (xy 268.118909 -35.260079) (xy 268.077727 -35.295769)
			(xy 268.031884 -35.325234) (xy 267.982316 -35.347876) (xy 267.930029 -35.363234) (xy 267.87609 -35.370995)
			(xy 267.848842 -35.371532) (xy 267.846048 -35.371532) (xy 267.836085 -35.372016) (xy 267.81766 -35.379604)
			(xy 267.810234 -35.386264) (xy 267.758926 -35.437064) (xy 267.752087 -35.444465) (xy 267.744372 -35.463063)
			(xy 267.74394 -35.473132) (xy 267.74394 -38.193437) (xy 269.298171 -38.193437) (xy 269.298171 -38.106563)
			(xy 269.306186 -38.020058) (xy 269.32215 -37.934663) (xy 269.345924 -37.851104) (xy 269.377307 -37.770096)
			(xy 269.416031 -37.692329) (xy 269.461765 -37.618467) (xy 269.514119 -37.549139) (xy 269.572647 -37.484938)
			(xy 269.636849 -37.426412) (xy 269.706177 -37.374058) (xy 269.78004 -37.328325) (xy 269.857807 -37.289603)
			(xy 269.938816 -37.258221) (xy 270.022374 -37.234447) (xy 270.10777 -37.218485) (xy 270.194275 -37.21047)
			(xy 270.237712 -37.209984) (xy 270.31569 -37.209984) (xy 270.325713 -37.209572) (xy 270.344232 -37.201902)
			(xy 270.358406 -37.187727) (xy 270.366073 -37.169207) (xy 270.36649 -37.159184) (xy 270.36649 -37.151564)
			(xy 270.362172 -37.137594) (xy 270.358108 -37.131244) (xy 270.334668 -37.094792) (xy 270.293672 -37.018429)
			(xy 270.259684 -36.938701) (xy 270.232976 -36.856247) (xy 270.213763 -36.771733) (xy 270.202201 -36.685836)
			(xy 270.198381 -36.59925) (xy 270.202335 -36.512669) (xy 270.214031 -36.426791) (xy 270.233375 -36.342306)
			(xy 270.260211 -36.259894) (xy 270.294323 -36.180218) (xy 270.335437 -36.103919) (xy 270.383223 -36.031611)
			(xy 270.437295 -35.963876) (xy 270.497218 -35.901258) (xy 270.562512 -35.844261) (xy 270.632649 -35.793344)
			(xy 270.707067 -35.748916) (xy 270.785166 -35.711334) (xy 270.866319 -35.680902) (xy 270.949872 -35.657863)
			(xy 271.035153 -35.642404) (xy 271.121476 -35.634648) (xy 271.164812 -35.634168) (xy 271.165066 -35.634168)
			(xy 271.208398 -35.634594) (xy 271.294713 -35.642372) (xy 271.379984 -35.657851) (xy 271.463526 -35.680906)
			(xy 271.544666 -35.711353) (xy 271.622753 -35.748945) (xy 271.697158 -35.793381) (xy 271.767284 -35.844304)
			(xy 271.804431 -35.876738) (xy 276.917148 -35.876738) (xy 276.921219 -35.821116) (xy 276.933345 -35.766679)
			(xy 276.953268 -35.714588) (xy 276.980564 -35.665953) (xy 277.01465 -35.62181) (xy 277.054799 -35.583101)
			(xy 277.100157 -35.55065) (xy 277.149757 -35.525149) (xy 277.202541 -35.507142) (xy 277.257384 -35.497012)
			(xy 277.313118 -35.494975) (xy 277.368555 -35.501075) (xy 277.422512 -35.515181) (xy 277.473841 -35.536993)
			(xy 277.521447 -35.566047) (xy 277.564315 -35.601722) (xy 277.601532 -35.643259) (xy 277.632305 -35.689772)
			(xy 277.655977 -35.740269) (xy 277.672045 -35.793676) (xy 277.680165 -35.848852) (xy 277.680674 -35.876738)
			(xy 277.680165 -35.904624) (xy 277.672045 -35.9598) (xy 277.655977 -36.013207) (xy 277.632305 -36.063704)
			(xy 277.601532 -36.110217) (xy 277.564315 -36.151754) (xy 277.521447 -36.187429) (xy 277.473841 -36.216483)
			(xy 277.422512 -36.238295) (xy 277.368555 -36.252401) (xy 277.313118 -36.258501) (xy 277.257384 -36.256464)
			(xy 277.202541 -36.246334) (xy 277.149757 -36.228327) (xy 277.100157 -36.202826) (xy 277.054799 -36.170375)
			(xy 277.01465 -36.131666) (xy 276.980564 -36.087523) (xy 276.953268 -36.038888) (xy 276.933345 -35.986797)
			(xy 276.921219 -35.93236) (xy 276.917148 -35.876738) (xy 271.804431 -35.876738) (xy 271.832566 -35.901304)
			(xy 271.89248 -35.963922) (xy 271.946543 -36.031656) (xy 271.994322 -36.103961) (xy 272.035431 -36.180255)
			(xy 272.069541 -36.259925) (xy 272.096377 -36.34233) (xy 272.115723 -36.426807) (xy 272.127424 -36.512678)
			(xy 272.128671 -36.539928) (xy 278.738566 -36.539928) (xy 278.738566 -36.479992) (xy 278.746389 -36.42057)
			(xy 278.761902 -36.362677) (xy 278.784838 -36.307304) (xy 278.814805 -36.255398) (xy 278.851292 -36.207848)
			(xy 278.893672 -36.165468) (xy 278.941222 -36.128981) (xy 278.993128 -36.099014) (xy 279.048501 -36.076078)
			(xy 279.106394 -36.060565) (xy 279.165816 -36.052742) (xy 279.225752 -36.052742) (xy 279.285174 -36.060565)
			(xy 279.343067 -36.076078) (xy 279.39844 -36.099014) (xy 279.450346 -36.128981) (xy 279.497896 -36.165468)
			(xy 279.540276 -36.207848) (xy 279.576763 -36.255398) (xy 279.60673 -36.307304) (xy 279.629666 -36.362677)
			(xy 279.645179 -36.42057) (xy 279.653002 -36.479992) (xy 279.653492 -36.50996) (xy 279.653002 -36.539928)
			(xy 279.645179 -36.59935) (xy 279.629666 -36.657243) (xy 279.60673 -36.712616) (xy 279.576763 -36.764522)
			(xy 279.540276 -36.812072) (xy 279.497896 -36.854452) (xy 279.450346 -36.890939) (xy 279.39844 -36.920906)
			(xy 279.343067 -36.943842) (xy 279.285174 -36.959355) (xy 279.225752 -36.967178) (xy 279.165816 -36.967178)
			(xy 279.106394 -36.959355) (xy 279.048501 -36.943842) (xy 278.993128 -36.920906) (xy 278.941222 -36.890939)
			(xy 278.893672 -36.854452) (xy 278.851292 -36.812072) (xy 278.814805 -36.764522) (xy 278.784838 -36.712616)
			(xy 278.761902 -36.657243) (xy 278.746389 -36.59935) (xy 278.738566 -36.539928) (xy 272.128671 -36.539928)
			(xy 272.131385 -36.599252) (xy 272.127575 -36.685833) (xy 272.116025 -36.771724) (xy 272.096827 -36.856236)
			(xy 272.070136 -36.938688) (xy 272.036166 -37.018417) (xy 271.995191 -37.094783) (xy 271.97177 -37.131244)
			(xy 271.963388 -37.143944) (xy 271.963388 -37.159184) (xy 271.963832 -37.169203) (xy 271.971495 -37.187717)
			(xy 271.985659 -37.20189) (xy 272.004169 -37.209562) (xy 272.014188 -37.209984) (xy 272.091912 -37.209984)
			(xy 272.135352 -37.21041) (xy 272.22186 -37.218427) (xy 272.307259 -37.234392) (xy 272.390822 -37.258169)
			(xy 272.471834 -37.289554) (xy 272.549604 -37.32828) (xy 272.62347 -37.374017) (xy 272.692801 -37.426373)
			(xy 272.746317 -37.47516) (xy 275.95906 -37.47516) (xy 275.963131 -37.419538) (xy 275.975257 -37.365101)
			(xy 275.99518 -37.31301) (xy 276.022476 -37.264375) (xy 276.056562 -37.220232) (xy 276.096711 -37.181523)
			(xy 276.142069 -37.149072) (xy 276.191669 -37.123571) (xy 276.244453 -37.105564) (xy 276.299296 -37.095434)
			(xy 276.35503 -37.093397) (xy 276.410467 -37.099497) (xy 276.464424 -37.113603) (xy 276.515753 -37.135415)
			(xy 276.563359 -37.164469) (xy 276.606227 -37.200144) (xy 276.643444 -37.241681) (xy 276.674217 -37.288194)
			(xy 276.697889 -37.338691) (xy 276.713957 -37.392098) (xy 276.722077 -37.447274) (xy 276.722586 -37.47516)
			(xy 276.722077 -37.503046) (xy 276.713957 -37.558222) (xy 276.697889 -37.611629) (xy 276.674217 -37.662126)
			(xy 276.654237 -37.692326) (xy 278.073086 -37.692326) (xy 278.073086 -37.63239) (xy 278.080909 -37.572968)
			(xy 278.096422 -37.515075) (xy 278.119358 -37.459702) (xy 278.149325 -37.407796) (xy 278.185812 -37.360246)
			(xy 278.228192 -37.317866) (xy 278.275742 -37.281379) (xy 278.327648 -37.251412) (xy 278.383021 -37.228476)
			(xy 278.440914 -37.212963) (xy 278.500336 -37.20514) (xy 278.560272 -37.20514) (xy 278.619694 -37.212963)
			(xy 278.677587 -37.228476) (xy 278.73296 -37.251412) (xy 278.784866 -37.281379) (xy 278.832416 -37.317866)
			(xy 278.874796 -37.360246) (xy 278.911283 -37.407796) (xy 278.94125 -37.459702) (xy 278.964186 -37.515075)
			(xy 278.979699 -37.572968) (xy 278.987522 -37.63239) (xy 278.988012 -37.662358) (xy 278.987522 -37.692326)
			(xy 278.979699 -37.751748) (xy 278.964186 -37.809641) (xy 278.94125 -37.865014) (xy 278.911283 -37.91692)
			(xy 278.874796 -37.96447) (xy 278.832416 -38.00685) (xy 278.784866 -38.043337) (xy 278.73296 -38.073304)
			(xy 278.677587 -38.09624) (xy 278.619694 -38.111753) (xy 278.560272 -38.119576) (xy 278.500336 -38.119576)
			(xy 278.440914 -38.111753) (xy 278.383021 -38.09624) (xy 278.327648 -38.073304) (xy 278.275742 -38.043337)
			(xy 278.228192 -38.00685) (xy 278.185812 -37.96447) (xy 278.149325 -37.91692) (xy 278.119358 -37.865014)
			(xy 278.096422 -37.809641) (xy 278.080909 -37.751748) (xy 278.073086 -37.692326) (xy 276.654237 -37.692326)
			(xy 276.643444 -37.708639) (xy 276.606227 -37.750176) (xy 276.563359 -37.785851) (xy 276.515753 -37.814905)
			(xy 276.464424 -37.836717) (xy 276.410467 -37.850823) (xy 276.35503 -37.856923) (xy 276.299296 -37.854886)
			(xy 276.244453 -37.844756) (xy 276.191669 -37.826749) (xy 276.142069 -37.801248) (xy 276.096711 -37.768797)
			(xy 276.056562 -37.730088) (xy 276.022476 -37.685945) (xy 275.99518 -37.63731) (xy 275.975257 -37.585219)
			(xy 275.963131 -37.530782) (xy 275.95906 -37.47516) (xy 272.746317 -37.47516) (xy 272.757005 -37.484904)
			(xy 272.815534 -37.549109) (xy 272.86789 -37.61844) (xy 272.913626 -37.692306) (xy 272.952351 -37.770077)
			(xy 272.983735 -37.85109) (xy 273.00751 -37.934652) (xy 273.023474 -38.020052) (xy 273.03149 -38.10656)
			(xy 273.03149 -38.19344) (xy 273.023474 -38.279948) (xy 273.00751 -38.365348) (xy 272.983735 -38.44891)
			(xy 272.967368 -38.49116) (xy 275.95906 -38.49116) (xy 275.963131 -38.435538) (xy 275.975257 -38.381101)
			(xy 275.99518 -38.32901) (xy 276.022476 -38.280375) (xy 276.056562 -38.236232) (xy 276.096711 -38.197523)
			(xy 276.142069 -38.165072) (xy 276.191669 -38.139571) (xy 276.244453 -38.121564) (xy 276.299296 -38.111434)
			(xy 276.35503 -38.109397) (xy 276.410467 -38.115497) (xy 276.464424 -38.129603) (xy 276.515753 -38.151415)
			(xy 276.563359 -38.180469) (xy 276.606227 -38.216144) (xy 276.643444 -38.257681) (xy 276.674217 -38.304194)
			(xy 276.697889 -38.354691) (xy 276.713957 -38.408098) (xy 276.722077 -38.463274) (xy 276.722586 -38.49116)
			(xy 276.722077 -38.519046) (xy 276.713957 -38.574222) (xy 276.697889 -38.627629) (xy 276.674217 -38.678126)
			(xy 276.658939 -38.701218) (xy 279.637488 -38.701218) (xy 279.641559 -38.645596) (xy 279.653685 -38.591159)
			(xy 279.673608 -38.539068) (xy 279.700904 -38.490433) (xy 279.73499 -38.44629) (xy 279.775139 -38.407581)
			(xy 279.820497 -38.37513) (xy 279.870097 -38.349629) (xy 279.922881 -38.331622) (xy 279.977724 -38.321492)
			(xy 280.033458 -38.319455) (xy 280.088895 -38.325555) (xy 280.142852 -38.339661) (xy 280.194181 -38.361473)
			(xy 280.241787 -38.390527) (xy 280.284655 -38.426202) (xy 280.321872 -38.467739) (xy 280.352645 -38.514252)
			(xy 280.376317 -38.564749) (xy 280.392385 -38.618156) (xy 280.400505 -38.673332) (xy 280.401014 -38.701218)
			(xy 280.400505 -38.729104) (xy 280.392385 -38.78428) (xy 280.376317 -38.837687) (xy 280.352645 -38.888184)
			(xy 280.321872 -38.934697) (xy 280.284655 -38.976234) (xy 280.241787 -39.011909) (xy 280.194181 -39.040963)
			(xy 280.142852 -39.062775) (xy 280.088895 -39.076881) (xy 280.033458 -39.082981) (xy 279.977724 -39.080944)
			(xy 279.922881 -39.070814) (xy 279.870097 -39.052807) (xy 279.820497 -39.027306) (xy 279.775139 -38.994855)
			(xy 279.73499 -38.956146) (xy 279.700904 -38.912003) (xy 279.673608 -38.863368) (xy 279.653685 -38.811277)
			(xy 279.641559 -38.75684) (xy 279.637488 -38.701218) (xy 276.658939 -38.701218) (xy 276.643444 -38.724639)
			(xy 276.606227 -38.766176) (xy 276.563359 -38.801851) (xy 276.515753 -38.830905) (xy 276.464424 -38.852717)
			(xy 276.410467 -38.866823) (xy 276.35503 -38.872923) (xy 276.299296 -38.870886) (xy 276.244453 -38.860756)
			(xy 276.191669 -38.842749) (xy 276.142069 -38.817248) (xy 276.096711 -38.784797) (xy 276.056562 -38.746088)
			(xy 276.022476 -38.701945) (xy 275.99518 -38.65331) (xy 275.975257 -38.601219) (xy 275.963131 -38.546782)
			(xy 275.95906 -38.49116) (xy 272.967368 -38.49116) (xy 272.952351 -38.529923) (xy 272.913626 -38.607694)
			(xy 272.86789 -38.68156) (xy 272.815534 -38.750891) (xy 272.757005 -38.815096) (xy 272.692801 -38.873627)
			(xy 272.62347 -38.925983) (xy 272.549604 -38.97172) (xy 272.471834 -39.010446) (xy 272.390822 -39.041831)
			(xy 272.307259 -39.065608) (xy 272.22186 -39.081573) (xy 272.135352 -39.08959) (xy 272.091912 -39.090092)
			(xy 270.237712 -39.090092) (xy 270.194275 -39.08953) (xy 270.10777 -39.081515) (xy 270.022374 -39.065553)
			(xy 269.938816 -39.041779) (xy 269.857807 -39.010397) (xy 269.78004 -38.971675) (xy 269.706177 -38.925942)
			(xy 269.636849 -38.873588) (xy 269.572647 -38.815062) (xy 269.514119 -38.750861) (xy 269.461765 -38.681533)
			(xy 269.416031 -38.607671) (xy 269.377307 -38.529904) (xy 269.345924 -38.448896) (xy 269.32215 -38.365337)
			(xy 269.306186 -38.279942) (xy 269.298171 -38.193437) (xy 267.74394 -38.193437) (xy 267.74394 -42.849038)
			(xy 279.091896 -42.849038) (xy 279.095967 -42.793416) (xy 279.108093 -42.738979) (xy 279.128016 -42.686888)
			(xy 279.155312 -42.638253) (xy 279.189398 -42.59411) (xy 279.229547 -42.555401) (xy 279.274905 -42.52295)
			(xy 279.324505 -42.497449) (xy 279.377289 -42.479442) (xy 279.432132 -42.469312) (xy 279.487866 -42.467275)
			(xy 279.543303 -42.473375) (xy 279.59726 -42.487481) (xy 279.648589 -42.509293) (xy 279.696195 -42.538347)
			(xy 279.739063 -42.574022) (xy 279.77628 -42.615559) (xy 279.807053 -42.662072) (xy 279.830725 -42.712569)
			(xy 279.846793 -42.765976) (xy 279.854913 -42.821152) (xy 279.855422 -42.849038) (xy 279.854913 -42.876924)
			(xy 279.846793 -42.9321) (xy 279.830725 -42.985507) (xy 279.807053 -43.036004) (xy 279.77628 -43.082517)
			(xy 279.739063 -43.124054) (xy 279.696195 -43.159729) (xy 279.648589 -43.188783) (xy 279.59726 -43.210595)
			(xy 279.543303 -43.224701) (xy 279.487866 -43.230801) (xy 279.432132 -43.228764) (xy 279.377289 -43.218634)
			(xy 279.324505 -43.200627) (xy 279.274905 -43.175126) (xy 279.229547 -43.142675) (xy 279.189398 -43.103966)
			(xy 279.155312 -43.059823) (xy 279.128016 -43.011188) (xy 279.108093 -42.959097) (xy 279.095967 -42.90466)
			(xy 279.091896 -42.849038) (xy 267.74394 -42.849038) (xy 267.74394 -43.766228) (xy 278.337754 -43.766228)
			(xy 278.337754 -43.706292) (xy 278.345577 -43.64687) (xy 278.36109 -43.588977) (xy 278.384026 -43.533604)
			(xy 278.413993 -43.481698) (xy 278.45048 -43.434148) (xy 278.49286 -43.391768) (xy 278.54041 -43.355281)
			(xy 278.592316 -43.325314) (xy 278.647689 -43.302378) (xy 278.705582 -43.286865) (xy 278.765004 -43.279042)
			(xy 278.82494 -43.279042) (xy 278.884362 -43.286865) (xy 278.942255 -43.302378) (xy 278.997628 -43.325314)
			(xy 279.049534 -43.355281) (xy 279.097084 -43.391768) (xy 279.139464 -43.434148) (xy 279.175951 -43.481698)
			(xy 279.205918 -43.533604) (xy 279.228854 -43.588977) (xy 279.244367 -43.64687) (xy 279.25219 -43.706292)
			(xy 279.25268 -43.73626) (xy 279.25219 -43.766228) (xy 279.244367 -43.82565) (xy 279.228854 -43.883543)
			(xy 279.205918 -43.938916) (xy 279.175951 -43.990822) (xy 279.139464 -44.038372) (xy 279.097084 -44.080752)
			(xy 279.049534 -44.117239) (xy 278.997628 -44.147206) (xy 278.942255 -44.170142) (xy 278.884362 -44.185655)
			(xy 278.82494 -44.193478) (xy 278.765004 -44.193478) (xy 278.705582 -44.185655) (xy 278.647689 -44.170142)
			(xy 278.592316 -44.147206) (xy 278.54041 -44.117239) (xy 278.49286 -44.080752) (xy 278.45048 -44.038372)
			(xy 278.413993 -43.990822) (xy 278.384026 -43.938916) (xy 278.36109 -43.883543) (xy 278.345577 -43.82565)
			(xy 278.337754 -43.766228) (xy 267.74394 -43.766228) (xy 267.74394 -43.924982) (xy 267.74441 -43.934855)
			(xy 267.751863 -43.953143) (xy 267.758418 -43.960542) (xy 267.758672 -43.960796) (xy 268.2367 -44.438824)
			(xy 268.237208 -44.439332) (xy 268.244586 -44.445923) (xy 268.262885 -44.453393) (xy 268.272768 -44.45381)
		)
		(stroke
			(width 0)
			(type solid)
		)
		(fill yes)
		(layer "B.Cu")
		(net "P12V_SSD9")
	)
	(gr_poly
		(pts
			(xy 368.514884 -44.24807) (xy 368.525058 -44.247619) (xy 368.543804 -44.239705) (xy 368.557991 -44.225119)
			(xy 368.562128 -44.215812) (xy 368.602514 -44.112942) (xy 368.595656 -44.082716) (xy 368.583972 -44.072048)
			(xy 368.561282 -44.0503) (xy 368.521472 -44.001665) (xy 368.488686 -43.948043) (xy 368.46354 -43.890442)
			(xy 368.446506 -43.829944) (xy 368.437904 -43.767685) (xy 368.437414 -43.73626) (xy 368.437904 -43.706292)
			(xy 368.445727 -43.64687) (xy 368.46124 -43.588977) (xy 368.484176 -43.533604) (xy 368.514143 -43.481698)
			(xy 368.55063 -43.434148) (xy 368.59301 -43.391768) (xy 368.64056 -43.355281) (xy 368.692466 -43.325314)
			(xy 368.747839 -43.302378) (xy 368.805732 -43.286865) (xy 368.865154 -43.279042) (xy 368.92509 -43.279042)
			(xy 368.984512 -43.286865) (xy 369.042405 -43.302378) (xy 369.097778 -43.325314) (xy 369.149684 -43.355281)
			(xy 369.197234 -43.391768) (xy 369.239614 -43.434148) (xy 369.276101 -43.481698) (xy 369.306068 -43.533604)
			(xy 369.329004 -43.588977) (xy 369.344517 -43.64687) (xy 369.35234 -43.706292) (xy 369.35283 -43.73626)
			(xy 369.352749 -43.748987) (xy 369.351353 -43.774401) (xy 369.350036 -43.78706) (xy 369.35029 -43.78706)
			(xy 369.346081 -43.819423) (xy 369.329674 -43.882589) (xy 369.30446 -43.942783) (xy 369.270951 -43.998784)
			(xy 369.229825 -44.049457) (xy 369.206272 -44.072048) (xy 369.194842 -44.08297) (xy 369.18773 -44.113196)
			(xy 369.228116 -44.215812) (xy 369.232252 -44.225119) (xy 369.24645 -44.239696) (xy 369.265187 -44.247633)
			(xy 369.27536 -44.24807) (xy 370.177568 -44.24807) (xy 370.187441 -44.2476) (xy 370.205724 -44.240141)
			(xy 370.213128 -44.233592) (xy 370.213382 -44.233338) (xy 370.77269 -43.67403) (xy 370.773198 -43.673522)
			(xy 370.779782 -43.666142) (xy 370.787232 -43.647842) (xy 370.787676 -43.637962) (xy 370.787676 -37.58946)
			(xy 370.787248 -37.580071) (xy 370.780504 -37.562545) (xy 370.767927 -37.548601) (xy 370.759736 -37.543994)
			(xy 370.678964 -37.5031) (xy 370.670356 -37.49925) (xy 370.651607 -37.497399) (xy 370.633444 -37.502404)
			(xy 370.625624 -37.507672) (xy 370.600828 -37.525303) (xy 370.546812 -37.553297) (xy 370.489036 -37.57236)
			(xy 370.428968 -37.58201) (xy 370.398548 -37.582602) (xy 370.371293 -37.582142) (xy 370.317338 -37.574391)
			(xy 370.265035 -37.559039) (xy 370.21545 -37.5364) (xy 370.169591 -37.506933) (xy 370.128394 -37.47124)
			(xy 370.092695 -37.430047) (xy 370.063223 -37.384192) (xy 370.040578 -37.33461) (xy 370.02522 -37.282309)
			(xy 370.017461 -37.228355) (xy 370.017461 -37.173845) (xy 370.02522 -37.119891) (xy 370.040578 -37.06759)
			(xy 370.063223 -37.018008) (xy 370.092695 -36.972153) (xy 370.128394 -36.93096) (xy 370.169591 -36.895267)
			(xy 370.21545 -36.8658) (xy 370.265035 -36.843161) (xy 370.317338 -36.827809) (xy 370.371293 -36.820058)
			(xy 370.398548 -36.819586) (xy 370.428966 -36.820182) (xy 370.489032 -36.829841) (xy 370.546803 -36.848908)
			(xy 370.600818 -36.8769) (xy 370.625624 -36.894516) (xy 370.633402 -36.899881) (xy 370.65159 -36.904948)
			(xy 370.670374 -36.903027) (xy 370.678964 -36.899088) (xy 370.759736 -36.858194) (xy 370.767975 -36.853644)
			(xy 370.780599 -36.839702) (xy 370.787317 -36.822134) (xy 370.787676 -36.812728) (xy 370.787676 -35.109658)
			(xy 370.769134 -35.083496) (xy 370.753894 -35.078162) (xy 370.727622 -35.068318) (xy 370.678062 -35.042026)
			(xy 370.632884 -35.008763) (xy 370.593061 -34.969246) (xy 370.57584 -34.947098) (xy 370.570506 -34.939986)
			(xy 370.548408 -34.925254) (xy 370.544458 -34.922819) (xy 370.5359 -34.919234) (xy 370.53139 -34.918142)
			(xy 370.501164 -34.911284) (xy 370.482368 -34.914078) (xy 370.473986 -34.91865) (xy 370.455604 -34.928876)
			(xy 370.417316 -34.946301) (xy 370.397532 -34.953448) (xy 370.373331 -34.96149) (xy 370.323597 -34.97278)
			(xy 370.272917 -34.978477) (xy 370.247418 -34.978848) (xy 370.221918 -34.978488) (xy 370.171236 -34.972796)
			(xy 370.121501 -34.961504) (xy 370.097304 -34.953448) (xy 370.077519 -34.946304) (xy 370.03923 -34.92888)
			(xy 370.02085 -34.91865) (xy 370.012468 -34.914078) (xy 369.993672 -34.911284) (xy 369.963446 -34.918142)
			(xy 369.958926 -34.919206) (xy 369.95036 -34.922785) (xy 369.946428 -34.925254) (xy 369.924076 -34.94024)
			(xy 369.918996 -34.947352) (xy 369.900846 -34.970654) (xy 369.858568 -35.011898) (xy 369.810437 -35.04613)
			(xy 369.757604 -35.072532) (xy 369.701331 -35.090472) (xy 369.642966 -35.099522) (xy 369.613434 -35.100006)
			(xy 369.602512 -35.100006) (xy 369.602258 -35.099752) (xy 369.575543 -35.098515) (xy 369.522831 -35.089492)
			(xy 369.471894 -35.073197) (xy 369.423732 -35.049951) (xy 369.379286 -35.020208) (xy 369.339429 -34.984551)
			(xy 369.30494 -34.943678) (xy 369.276496 -34.898391) (xy 369.254653 -34.849576) (xy 369.23984 -34.798189)
			(xy 369.232346 -34.745237) (xy 369.231926 -34.718498) (xy 369.232389 -34.691246) (xy 369.240147 -34.637297)
			(xy 369.255503 -34.585002) (xy 369.278147 -34.535424) (xy 369.307615 -34.489573) (xy 369.343309 -34.448384)
			(xy 369.384502 -34.412694) (xy 369.430355 -34.383229) (xy 369.479935 -34.360591) (xy 369.532232 -34.345239)
			(xy 369.586182 -34.337487) (xy 369.613434 -34.33699) (xy 369.628227 -34.337133) (xy 369.657724 -34.339422)
			(xy 369.672362 -34.341562) (xy 369.683284 -34.34334) (xy 369.70462 -34.337244) (xy 369.780312 -34.272728)
			(xy 369.789456 -34.252662) (xy 369.789456 -33.93694) (xy 369.789456 -33.92551) (xy 369.780312 -33.905444)
			(xy 369.70462 -33.840928) (xy 369.683284 -33.834832) (xy 369.672362 -33.83661) (xy 369.657536 -33.838784)
			(xy 369.627656 -33.841075) (xy 369.612672 -33.841182) (xy 369.612418 -33.841182) (xy 369.585213 -33.840629)
			(xy 369.531373 -33.832759) (xy 369.479198 -33.817319) (xy 369.429746 -33.794621) (xy 369.38402 -33.765128)
			(xy 369.34295 -33.729437) (xy 369.307367 -33.688272) (xy 369.277994 -33.642469) (xy 369.255428 -33.592957)
			(xy 369.240126 -33.540741) (xy 369.232398 -33.48688) (xy 369.231926 -33.459674) (xy 369.232391 -33.432423)
			(xy 369.240151 -33.378477) (xy 369.25551 -33.326184) (xy 369.278154 -33.276609) (xy 369.307624 -33.230762)
			(xy 369.343318 -33.189575) (xy 369.38451 -33.153888) (xy 369.430362 -33.124426) (xy 369.47994 -33.101789)
			(xy 369.532236 -33.086439) (xy 369.586183 -33.078687) (xy 369.613434 -33.078166) (xy 369.613688 -33.078166)
			(xy 369.643193 -33.078723) (xy 369.701498 -33.087817) (xy 369.757709 -33.105775) (xy 369.810487 -33.13217)
			(xy 369.858575 -33.166371) (xy 369.900827 -33.207566) (xy 369.918996 -33.23082) (xy 369.924076 -33.237932)
			(xy 369.946428 -33.252918) (xy 369.950379 -33.255351) (xy 369.958938 -33.258932) (xy 369.963446 -33.26003)
			(xy 369.993672 -33.266888) (xy 370.012468 -33.264094) (xy 370.02085 -33.259522) (xy 370.039231 -33.249295)
			(xy 370.077518 -33.231865) (xy 370.097304 -33.224724) (xy 370.121504 -33.216679) (xy 370.171238 -33.205383)
			(xy 370.221918 -33.199679) (xy 370.247418 -33.199324) (xy 370.272918 -33.199686) (xy 370.323599 -33.205381)
			(xy 370.373332 -33.216677) (xy 370.397532 -33.224724) (xy 370.417316 -33.231869) (xy 370.455605 -33.249295)
			(xy 370.473986 -33.259522) (xy 370.482368 -33.264094) (xy 370.501164 -33.266888) (xy 370.53139 -33.26003)
			(xy 370.535908 -33.258963) (xy 370.54447 -33.255376) (xy 370.548408 -33.252918) (xy 370.570506 -33.238186)
			(xy 370.57584 -33.231074) (xy 370.593042 -33.20891) (xy 370.632868 -33.169393) (xy 370.678053 -33.136136)
			(xy 370.727621 -33.109855) (xy 370.753894 -33.10001) (xy 370.769134 -33.094676) (xy 370.787676 -33.068514)
			(xy 370.787676 -31.509462) (xy 370.769134 -31.4833) (xy 370.753894 -31.477966) (xy 370.727622 -31.468122)
			(xy 370.678062 -31.44183) (xy 370.632884 -31.408568) (xy 370.593061 -31.369051) (xy 370.57584 -31.346902)
			(xy 370.570506 -31.33979) (xy 370.548408 -31.325058) (xy 370.544458 -31.322623) (xy 370.5359 -31.319038)
			(xy 370.53139 -31.317946) (xy 370.501164 -31.311088) (xy 370.482368 -31.313882) (xy 370.473986 -31.318454)
			(xy 370.455604 -31.32868) (xy 370.417316 -31.346105) (xy 370.397532 -31.353252) (xy 370.373331 -31.361294)
			(xy 370.323597 -31.372583) (xy 370.272917 -31.378281) (xy 370.247418 -31.378652) (xy 370.221918 -31.378292)
			(xy 370.171236 -31.3726) (xy 370.121501 -31.361308) (xy 370.097304 -31.353252) (xy 370.077519 -31.346108)
			(xy 370.03923 -31.328684) (xy 370.02085 -31.318454) (xy 370.012468 -31.313882) (xy 369.993672 -31.311088)
			(xy 369.963446 -31.317946) (xy 369.958926 -31.31901) (xy 369.950361 -31.32259) (xy 369.946428 -31.325058)
			(xy 369.924076 -31.340044) (xy 369.918996 -31.347156) (xy 369.900846 -31.370458) (xy 369.858568 -31.411701)
			(xy 369.810437 -31.445933) (xy 369.757603 -31.472334) (xy 369.701331 -31.490275) (xy 369.642966 -31.499325)
			(xy 369.613434 -31.49981) (xy 369.602512 -31.49981) (xy 369.602258 -31.499556) (xy 369.575543 -31.498319)
			(xy 369.52283 -31.489296) (xy 369.471894 -31.473001) (xy 369.423731 -31.449755) (xy 369.379285 -31.420012)
			(xy 369.339428 -31.384355) (xy 369.304939 -31.343483) (xy 369.276494 -31.298195) (xy 369.254651 -31.24938)
			(xy 369.239836 -31.197993) (xy 369.232342 -31.145042) (xy 369.231926 -31.118302) (xy 369.232389 -31.09105)
			(xy 369.240146 -31.037101) (xy 369.255502 -30.984804) (xy 369.278145 -30.935226) (xy 369.307614 -30.889375)
			(xy 369.343308 -30.848185) (xy 369.384501 -30.812494) (xy 369.430354 -30.78303) (xy 369.479934 -30.760391)
			(xy 369.532232 -30.745039) (xy 369.586182 -30.737287) (xy 369.613434 -30.736794) (xy 369.628227 -30.736937)
			(xy 369.657724 -30.739226) (xy 369.672362 -30.741366) (xy 369.683284 -30.743144) (xy 369.70462 -30.737048)
			(xy 369.780312 -30.672532) (xy 369.789456 -30.652466) (xy 369.789456 -30.336744) (xy 369.789456 -30.325314)
			(xy 369.780312 -30.305248) (xy 369.70462 -30.240732) (xy 369.683284 -30.234636) (xy 369.672362 -30.236414)
			(xy 369.657536 -30.238588) (xy 369.627656 -30.240879) (xy 369.612672 -30.240986) (xy 369.612418 -30.240986)
			(xy 369.585213 -30.240433) (xy 369.531373 -30.232563) (xy 369.479197 -30.217123) (xy 369.429745 -30.194426)
			(xy 369.384019 -30.164932) (xy 369.342948 -30.129241) (xy 369.307365 -30.088076) (xy 369.277992 -30.042273)
			(xy 369.255425 -29.992761) (xy 369.240123 -29.940545) (xy 369.232394 -29.886684) (xy 369.231926 -29.859478)
			(xy 369.232391 -29.832227) (xy 369.240151 -29.77828) (xy 369.255509 -29.725987) (xy 369.278153 -29.676412)
			(xy 369.307622 -29.630564) (xy 369.343316 -29.589377) (xy 369.384509 -29.553689) (xy 369.430361 -29.524226)
			(xy 369.47994 -29.501589) (xy 369.532235 -29.486239) (xy 369.586183 -29.478487) (xy 369.613434 -29.47797)
			(xy 369.613688 -29.47797) (xy 369.643193 -29.478527) (xy 369.701498 -29.487621) (xy 369.757709 -29.50558)
			(xy 369.810487 -29.531974) (xy 369.858574 -29.566176) (xy 369.900826 -29.607371) (xy 369.918996 -29.630624)
			(xy 369.924076 -29.637736) (xy 369.946428 -29.652722) (xy 369.950379 -29.655155) (xy 369.958938 -29.658736)
			(xy 369.963446 -29.659834) (xy 369.993672 -29.666692) (xy 370.012468 -29.663898) (xy 370.02085 -29.659326)
			(xy 370.039231 -29.649098) (xy 370.077518 -29.631669) (xy 370.097304 -29.624528) (xy 370.121504 -29.616483)
			(xy 370.171238 -29.605187) (xy 370.221918 -29.599483) (xy 370.247418 -29.599128) (xy 370.272918 -29.59949)
			(xy 370.323599 -29.605185) (xy 370.373332 -29.616481) (xy 370.397532 -29.624528) (xy 370.417316 -29.631673)
			(xy 370.455605 -29.649099) (xy 370.473986 -29.659326) (xy 370.482368 -29.663898) (xy 370.501164 -29.666692)
			(xy 370.53139 -29.659834) (xy 370.535908 -29.658767) (xy 370.54447 -29.655181) (xy 370.548408 -29.652722)
			(xy 370.570506 -29.63799) (xy 370.57584 -29.630878) (xy 370.593042 -29.608713) (xy 370.632868 -29.569196)
			(xy 370.678053 -29.535939) (xy 370.727621 -29.509658) (xy 370.753894 -29.499814) (xy 370.769134 -29.49448)
			(xy 370.787676 -29.468318) (xy 370.787676 -19.837908) (xy 370.787467 -19.831327) (xy 370.784126 -19.818595)
			(xy 370.781072 -19.812762) (xy 370.765832 -19.786346) (xy 370.757704 -19.77771) (xy 370.75237 -19.774154)
			(xy 370.730569 -19.759653) (xy 370.69078 -19.725619) (xy 370.656016 -19.686466) (xy 370.641118 -19.664934)
			(xy 370.640864 -19.66468) (xy 370.640864 -19.664426) (xy 370.634575 -19.656132) (xy 370.617012 -19.644994)
			(xy 370.606828 -19.642836) (xy 370.533422 -19.631152) (xy 370.52306 -19.62998) (xy 370.502866 -19.6351)
			(xy 370.494306 -19.641058) (xy 370.474148 -19.656164) (xy 370.430615 -19.681509) (xy 370.384129 -19.700913)
			(xy 370.335495 -19.714037) (xy 370.285559 -19.720655) (xy 370.260372 -19.721068) (xy 370.252752 -19.721068)
			(xy 370.225856 -19.720073) (xy 370.17273 -19.711455) (xy 370.121343 -19.695455) (xy 370.072716 -19.67239)
			(xy 370.027813 -19.642718) (xy 369.987527 -19.60703) (xy 369.952658 -19.566032) (xy 369.923897 -19.520541)
			(xy 369.901817 -19.471458) (xy 369.886855 -19.419759) (xy 369.87931 -19.36647) (xy 369.878864 -19.33956)
			(xy 369.879352 -19.31231) (xy 369.887113 -19.258365) (xy 369.902472 -19.206073) (xy 369.925115 -19.156499)
			(xy 369.954582 -19.110652) (xy 369.990273 -19.069464) (xy 370.031462 -19.033775) (xy 370.07731 -19.004309)
			(xy 370.126885 -18.981668) (xy 370.179177 -18.966311) (xy 370.233122 -18.958552) (xy 370.260372 -18.958052)
			(xy 370.264436 -18.958052) (xy 370.279676 -18.958306) (xy 370.305838 -18.941288) (xy 370.348256 -18.840196)
			(xy 370.351807 -18.830751) (xy 370.351916 -18.81059) (xy 370.344199 -18.791964) (xy 370.337334 -18.78457)
			(xy 369.968018 -18.415254) (xy 369.960906 -18.407888) (xy 369.94211 -18.400268) (xy 358.229408 -18.400268)
			(xy 358.219336 -18.400689) (xy 358.200727 -18.408398) (xy 358.19334 -18.415254) (xy 357.859076 -18.749518)
			(xy 357.85171 -18.75663) (xy 357.84409 -18.775426) (xy 357.84409 -21.738336) (xy 359.716832 -21.738336)
			(xy 359.717335 -21.709597) (xy 359.725965 -21.652769) (xy 359.743021 -21.597879) (xy 359.768117 -21.546168)
			(xy 359.800685 -21.498805) (xy 359.819956 -21.477478) (xy 359.82656 -21.470366) (xy 359.833672 -21.45284)
			(xy 359.833672 -21.363432) (xy 359.82656 -21.345906) (xy 359.819956 -21.338794) (xy 359.800719 -21.317437)
			(xy 359.76815 -21.270081) (xy 359.743055 -21.218374) (xy 359.726 -21.163488) (xy 359.717374 -21.106664)
			(xy 359.71737 -21.049189) (xy 359.725989 -20.992364) (xy 359.743035 -20.937475) (xy 359.768124 -20.885765)
			(xy 359.800686 -20.838404) (xy 359.819956 -20.817078) (xy 359.82656 -20.809966) (xy 359.833672 -20.79244)
			(xy 359.833672 -20.703032) (xy 359.82656 -20.685506) (xy 359.819956 -20.678394) (xy 359.800719 -20.657037)
			(xy 359.76815 -20.609681) (xy 359.743055 -20.557974) (xy 359.726 -20.503088) (xy 359.717374 -20.446264)
			(xy 359.71737 -20.388789) (xy 359.725989 -20.331964) (xy 359.743035 -20.277075) (xy 359.768124 -20.225365)
			(xy 359.800686 -20.178004) (xy 359.819956 -20.156678) (xy 359.82656 -20.149566) (xy 359.833672 -20.13204)
			(xy 359.833672 -20.042632) (xy 359.82656 -20.025106) (xy 359.819956 -20.017994) (xy 359.800719 -19.996637)
			(xy 359.76815 -19.949281) (xy 359.743055 -19.897574) (xy 359.726 -19.842688) (xy 359.717374 -19.785864)
			(xy 359.71737 -19.728389) (xy 359.725989 -19.671564) (xy 359.743035 -19.616675) (xy 359.768124 -19.564965)
			(xy 359.800686 -19.517604) (xy 359.819956 -19.496278) (xy 359.82656 -19.489166) (xy 359.833672 -19.47164)
			(xy 359.833672 -19.382232) (xy 359.82656 -19.364706) (xy 359.819956 -19.357594) (xy 359.800705 -19.33625)
			(xy 359.768136 -19.288893) (xy 359.743039 -19.237185) (xy 359.725984 -19.182298) (xy 359.717356 -19.125474)
			(xy 359.716832 -19.096736) (xy 359.717318 -19.069485) (xy 359.725074 -19.015537) (xy 359.740429 -18.963242)
			(xy 359.763071 -18.913665) (xy 359.792537 -18.867815) (xy 359.828228 -18.826624) (xy 359.869419 -18.790933)
			(xy 359.915269 -18.761467) (xy 359.964846 -18.738825) (xy 360.017141 -18.72347) (xy 360.071089 -18.715714)
			(xy 360.125591 -18.715714) (xy 360.179539 -18.72347) (xy 360.231834 -18.738825) (xy 360.281411 -18.761467)
			(xy 360.327261 -18.790933) (xy 360.368452 -18.826624) (xy 360.404143 -18.867815) (xy 360.433609 -18.913665)
			(xy 360.456251 -18.963242) (xy 360.471606 -19.015537) (xy 360.479362 -19.069485) (xy 360.479848 -19.096736)
			(xy 360.479333 -19.125475) (xy 360.470707 -19.182302) (xy 360.453654 -19.237193) (xy 360.42856 -19.288904)
			(xy 360.395995 -19.336267) (xy 360.376724 -19.357594) (xy 360.37012 -19.364706) (xy 360.363008 -19.382232)
			(xy 360.363008 -19.47164) (xy 360.37012 -19.489166) (xy 360.376724 -19.496278) (xy 360.396028 -19.517575)
			(xy 360.428588 -19.564944) (xy 360.453675 -19.616661) (xy 360.47072 -19.671556) (xy 360.479338 -19.728386)
			(xy 360.479334 -19.785866) (xy 360.470708 -19.842696) (xy 360.453655 -19.897588) (xy 360.428562 -19.949302)
			(xy 360.395995 -19.996666) (xy 360.376724 -20.017994) (xy 360.37012 -20.025106) (xy 360.363008 -20.042632)
			(xy 360.363008 -20.13204) (xy 360.37012 -20.149566) (xy 360.376724 -20.156678) (xy 360.396028 -20.177975)
			(xy 360.428588 -20.225344) (xy 360.453675 -20.277061) (xy 360.47072 -20.331956) (xy 360.474299 -20.35556)
			(xy 369.878354 -20.35556) (xy 369.882425 -20.299938) (xy 369.894551 -20.245501) (xy 369.914474 -20.19341)
			(xy 369.94177 -20.144775) (xy 369.975856 -20.100632) (xy 370.016005 -20.061923) (xy 370.061363 -20.029472)
			(xy 370.110963 -20.003971) (xy 370.163747 -19.985964) (xy 370.21859 -19.975834) (xy 370.274324 -19.973797)
			(xy 370.329761 -19.979897) (xy 370.383718 -19.994003) (xy 370.435047 -20.015815) (xy 370.482653 -20.044869)
			(xy 370.525521 -20.080544) (xy 370.562738 -20.122081) (xy 370.593511 -20.168594) (xy 370.617183 -20.219091)
			(xy 370.633251 -20.272498) (xy 370.641371 -20.327674) (xy 370.64188 -20.35556) (xy 370.641371 -20.383446)
			(xy 370.633251 -20.438622) (xy 370.617183 -20.492029) (xy 370.593511 -20.542526) (xy 370.562738 -20.589039)
			(xy 370.525521 -20.630576) (xy 370.482653 -20.666251) (xy 370.435047 -20.695305) (xy 370.383718 -20.717117)
			(xy 370.329761 -20.731223) (xy 370.274324 -20.737323) (xy 370.21859 -20.735286) (xy 370.163747 -20.725156)
			(xy 370.110963 -20.707149) (xy 370.061363 -20.681648) (xy 370.016005 -20.649197) (xy 369.975856 -20.610488)
			(xy 369.94177 -20.566345) (xy 369.914474 -20.51771) (xy 369.894551 -20.465619) (xy 369.882425 -20.411182)
			(xy 369.878354 -20.35556) (xy 360.474299 -20.35556) (xy 360.479338 -20.388786) (xy 360.479334 -20.446266)
			(xy 360.470708 -20.503096) (xy 360.453655 -20.557988) (xy 360.428562 -20.609702) (xy 360.395995 -20.657066)
			(xy 360.376724 -20.678394) (xy 360.37012 -20.685506) (xy 360.363008 -20.703032) (xy 360.363008 -20.79244)
			(xy 360.37012 -20.809966) (xy 360.376724 -20.817078) (xy 360.396028 -20.838375) (xy 360.428588 -20.885744)
			(xy 360.453675 -20.937461) (xy 360.47072 -20.992356) (xy 360.479338 -21.049186) (xy 360.479334 -21.106666)
			(xy 360.470708 -21.163496) (xy 360.453655 -21.218388) (xy 360.428562 -21.270102) (xy 360.395995 -21.317466)
			(xy 360.376724 -21.338794) (xy 360.37012 -21.345906) (xy 360.363008 -21.363432) (xy 360.363008 -21.37156)
			(xy 369.878354 -21.37156) (xy 369.882425 -21.315938) (xy 369.894551 -21.261501) (xy 369.914474 -21.20941)
			(xy 369.94177 -21.160775) (xy 369.975856 -21.116632) (xy 370.016005 -21.077923) (xy 370.061363 -21.045472)
			(xy 370.110963 -21.019971) (xy 370.163747 -21.001964) (xy 370.21859 -20.991834) (xy 370.274324 -20.989797)
			(xy 370.329761 -20.995897) (xy 370.383718 -21.010003) (xy 370.435047 -21.031815) (xy 370.482653 -21.060869)
			(xy 370.525521 -21.096544) (xy 370.562738 -21.138081) (xy 370.593511 -21.184594) (xy 370.617183 -21.235091)
			(xy 370.633251 -21.288498) (xy 370.641371 -21.343674) (xy 370.64188 -21.37156) (xy 370.641371 -21.399446)
			(xy 370.633251 -21.454622) (xy 370.617183 -21.508029) (xy 370.593511 -21.558526) (xy 370.562738 -21.605039)
			(xy 370.525521 -21.646576) (xy 370.482653 -21.682251) (xy 370.435047 -21.711305) (xy 370.383718 -21.733117)
			(xy 370.329761 -21.747223) (xy 370.274324 -21.753323) (xy 370.21859 -21.751286) (xy 370.163747 -21.741156)
			(xy 370.110963 -21.723149) (xy 370.061363 -21.697648) (xy 370.016005 -21.665197) (xy 369.975856 -21.626488)
			(xy 369.94177 -21.582345) (xy 369.914474 -21.53371) (xy 369.894551 -21.481619) (xy 369.882425 -21.427182)
			(xy 369.878354 -21.37156) (xy 360.363008 -21.37156) (xy 360.363008 -21.45284) (xy 360.37012 -21.470366)
			(xy 360.376724 -21.477478) (xy 360.396006 -21.498796) (xy 360.428572 -21.54616) (xy 360.453663 -21.597874)
			(xy 360.470711 -21.652767) (xy 360.47933 -21.709596) (xy 360.479848 -21.738336) (xy 360.479362 -21.765587)
			(xy 360.471606 -21.819535) (xy 360.456251 -21.87183) (xy 360.433609 -21.921407) (xy 360.404143 -21.967257)
			(xy 360.368452 -22.008448) (xy 360.327261 -22.044139) (xy 360.281411 -22.073605) (xy 360.231834 -22.096247)
			(xy 360.179539 -22.111602) (xy 360.125591 -22.119358) (xy 360.071089 -22.119358) (xy 360.017141 -22.111602)
			(xy 359.964846 -22.096247) (xy 359.915269 -22.073605) (xy 359.869419 -22.044139) (xy 359.828228 -22.008448)
			(xy 359.792537 -21.967257) (xy 359.763071 -21.921407) (xy 359.740429 -21.87183) (xy 359.725074 -21.819535)
			(xy 359.717318 -21.765587) (xy 359.716832 -21.738336) (xy 357.84409 -21.738336) (xy 357.84409 -23.055062)
			(xy 359.58729 -23.055062) (xy 359.58729 -22.995128) (xy 359.595114 -22.935706) (xy 359.610627 -22.877815)
			(xy 359.633563 -22.822443) (xy 359.663531 -22.770539) (xy 359.700016 -22.722991) (xy 359.742397 -22.680611)
			(xy 359.789946 -22.644126) (xy 359.84185 -22.614159) (xy 359.897222 -22.591224) (xy 359.955114 -22.575712)
			(xy 360.014536 -22.56789) (xy 360.07447 -22.56789) (xy 360.133891 -22.575713) (xy 360.191783 -22.591226)
			(xy 360.247154 -22.614162) (xy 360.299059 -22.644129) (xy 360.346607 -22.680615) (xy 360.388987 -22.722995)
			(xy 360.425472 -22.770544) (xy 360.455439 -22.822448) (xy 360.478375 -22.87782) (xy 360.493887 -22.935712)
			(xy 360.50171 -22.995133) (xy 360.5022 -23.0251) (xy 360.501976 -23.045661) (xy 360.498287 -23.086618)
			(xy 360.494834 -23.106888) (xy 360.492294 -23.120604) (xy 360.501184 -23.145496) (xy 360.587798 -23.22068)
			(xy 360.613706 -23.226014) (xy 360.626914 -23.221696) (xy 360.656115 -23.212603) (xy 360.716478 -23.202782)
			(xy 360.747056 -23.202138) (xy 360.765983 -23.2024) (xy 360.803645 -23.206217) (xy 360.82224 -23.209758)
			(xy 360.83494 -23.212044) (xy 360.858562 -23.205186) (xy 360.937048 -23.128986) (xy 360.944668 -23.105618)
			(xy 360.942636 -23.092918) (xy 360.939576 -23.073888) (xy 360.936265 -23.035483) (xy 360.936032 -23.01621)
			(xy 360.936471 -22.986242) (xy 360.944293 -22.926819) (xy 360.959804 -22.868925) (xy 360.982739 -22.813551)
			(xy 361.012705 -22.761644) (xy 361.049191 -22.714093) (xy 361.09157 -22.67171) (xy 361.139119 -22.635222)
			(xy 361.191024 -22.605252) (xy 361.246397 -22.582314) (xy 361.304289 -22.566799) (xy 361.363712 -22.558973)
			(xy 361.423648 -22.558971) (xy 361.483071 -22.566791) (xy 361.540966 -22.582301) (xy 361.59634 -22.605235)
			(xy 361.648248 -22.6352) (xy 361.6958 -22.671684) (xy 361.738183 -22.714063) (xy 361.774672 -22.761611)
			(xy 361.804643 -22.813515) (xy 361.827583 -22.868887) (xy 361.843099 -22.92678) (xy 361.850926 -22.986202)
			(xy 361.85093 -23.046138) (xy 361.843111 -23.105561) (xy 361.827602 -23.163456) (xy 361.80467 -23.218831)
			(xy 361.774706 -23.270739) (xy 361.738223 -23.318292) (xy 361.695845 -23.360676) (xy 361.648297 -23.397167)
			(xy 361.596394 -23.427139) (xy 361.541022 -23.45008) (xy 361.48313 -23.465597) (xy 361.423708 -23.473425)
			(xy 361.39374 -23.473918) (xy 361.359495 -23.473312) (xy 361.291769 -23.463109) (xy 361.258866 -23.453598)
			(xy 361.246674 -23.449788) (xy 361.222544 -23.45436) (xy 361.136692 -23.522178) (xy 361.126786 -23.544784)
			(xy 361.127802 -23.557738) (xy 361.128564 -23.583646) (xy 361.128078 -23.610897) (xy 361.126774 -23.619964)
			(xy 364.309388 -23.619964) (xy 364.309388 -23.560028) (xy 364.317211 -23.500606) (xy 364.332724 -23.442713)
			(xy 364.35566 -23.38734) (xy 364.385627 -23.335434) (xy 364.422114 -23.287884) (xy 364.464494 -23.245504)
			(xy 364.512044 -23.209017) (xy 364.56395 -23.17905) (xy 364.619323 -23.156114) (xy 364.677216 -23.140601)
			(xy 364.736638 -23.132778) (xy 364.796574 -23.132778) (xy 364.855996 -23.140601) (xy 364.913889 -23.156114)
			(xy 364.969262 -23.17905) (xy 365.021168 -23.209017) (xy 365.068718 -23.245504) (xy 365.111098 -23.287884)
			(xy 365.147585 -23.335434) (xy 365.177552 -23.38734) (xy 365.200488 -23.442713) (xy 365.216001 -23.500606)
			(xy 365.223824 -23.560028) (xy 365.224314 -23.589996) (xy 365.223824 -23.619964) (xy 365.216001 -23.679386)
			(xy 365.200488 -23.737279) (xy 365.177552 -23.792652) (xy 365.147585 -23.844558) (xy 365.120145 -23.880318)
			(xy 365.540796 -23.880318) (xy 365.544867 -23.824696) (xy 365.556993 -23.770259) (xy 365.576916 -23.718168)
			(xy 365.604212 -23.669533) (xy 365.638298 -23.62539) (xy 365.678447 -23.586681) (xy 365.723805 -23.55423)
			(xy 365.773405 -23.528729) (xy 365.826189 -23.510722) (xy 365.881032 -23.500592) (xy 365.936766 -23.498555)
			(xy 365.992203 -23.504655) (xy 366.04616 -23.518761) (xy 366.097489 -23.540573) (xy 366.145095 -23.569627)
			(xy 366.187963 -23.605302) (xy 366.22518 -23.646839) (xy 366.255953 -23.693352) (xy 366.279625 -23.743849)
			(xy 366.295693 -23.797256) (xy 366.303813 -23.852432) (xy 366.304322 -23.880318) (xy 366.556796 -23.880318)
			(xy 366.560867 -23.824696) (xy 366.572993 -23.770259) (xy 366.592916 -23.718168) (xy 366.620212 -23.669533)
			(xy 366.654298 -23.62539) (xy 366.694447 -23.586681) (xy 366.739805 -23.55423) (xy 366.789405 -23.528729)
			(xy 366.842189 -23.510722) (xy 366.897032 -23.500592) (xy 366.952766 -23.498555) (xy 367.008203 -23.504655)
			(xy 367.06216 -23.518761) (xy 367.113489 -23.540573) (xy 367.161095 -23.569627) (xy 367.203963 -23.605302)
			(xy 367.24118 -23.646839) (xy 367.271953 -23.693352) (xy 367.295625 -23.743849) (xy 367.311693 -23.797256)
			(xy 367.319813 -23.852432) (xy 367.320322 -23.880318) (xy 367.572796 -23.880318) (xy 367.576867 -23.824696)
			(xy 367.588993 -23.770259) (xy 367.608916 -23.718168) (xy 367.636212 -23.669533) (xy 367.670298 -23.62539)
			(xy 367.710447 -23.586681) (xy 367.755805 -23.55423) (xy 367.805405 -23.528729) (xy 367.858189 -23.510722)
			(xy 367.913032 -23.500592) (xy 367.968766 -23.498555) (xy 368.024203 -23.504655) (xy 368.07816 -23.518761)
			(xy 368.129489 -23.540573) (xy 368.177095 -23.569627) (xy 368.219963 -23.605302) (xy 368.25718 -23.646839)
			(xy 368.287953 -23.693352) (xy 368.311625 -23.743849) (xy 368.327693 -23.797256) (xy 368.335813 -23.852432)
			(xy 368.336322 -23.880318) (xy 368.591082 -23.880318) (xy 368.595153 -23.824696) (xy 368.607279 -23.770259)
			(xy 368.627202 -23.718168) (xy 368.654498 -23.669533) (xy 368.688584 -23.62539) (xy 368.728733 -23.586681)
			(xy 368.774091 -23.55423) (xy 368.823691 -23.528729) (xy 368.876475 -23.510722) (xy 368.931318 -23.500592)
			(xy 368.987052 -23.498555) (xy 369.042489 -23.504655) (xy 369.096446 -23.518761) (xy 369.147775 -23.540573)
			(xy 369.195381 -23.569627) (xy 369.238249 -23.605302) (xy 369.275466 -23.646839) (xy 369.306239 -23.693352)
			(xy 369.329911 -23.743849) (xy 369.345979 -23.797256) (xy 369.354099 -23.852432) (xy 369.354608 -23.880318)
			(xy 369.354099 -23.908204) (xy 369.345979 -23.96338) (xy 369.329911 -24.016787) (xy 369.306239 -24.067284)
			(xy 369.275466 -24.113797) (xy 369.238249 -24.155334) (xy 369.195381 -24.191009) (xy 369.147775 -24.220063)
			(xy 369.096446 -24.241875) (xy 369.042489 -24.255981) (xy 368.987052 -24.262081) (xy 368.931318 -24.260044)
			(xy 368.876475 -24.249914) (xy 368.823691 -24.231907) (xy 368.774091 -24.206406) (xy 368.728733 -24.173955)
			(xy 368.688584 -24.135246) (xy 368.654498 -24.091103) (xy 368.627202 -24.042468) (xy 368.607279 -23.990377)
			(xy 368.595153 -23.93594) (xy 368.591082 -23.880318) (xy 368.336322 -23.880318) (xy 368.335813 -23.908204)
			(xy 368.327693 -23.96338) (xy 368.311625 -24.016787) (xy 368.287953 -24.067284) (xy 368.25718 -24.113797)
			(xy 368.219963 -24.155334) (xy 368.177095 -24.191009) (xy 368.129489 -24.220063) (xy 368.07816 -24.241875)
			(xy 368.024203 -24.255981) (xy 367.968766 -24.262081) (xy 367.913032 -24.260044) (xy 367.858189 -24.249914)
			(xy 367.805405 -24.231907) (xy 367.755805 -24.206406) (xy 367.710447 -24.173955) (xy 367.670298 -24.135246)
			(xy 367.636212 -24.091103) (xy 367.608916 -24.042468) (xy 367.588993 -23.990377) (xy 367.576867 -23.93594)
			(xy 367.572796 -23.880318) (xy 367.320322 -23.880318) (xy 367.319813 -23.908204) (xy 367.311693 -23.96338)
			(xy 367.295625 -24.016787) (xy 367.271953 -24.067284) (xy 367.24118 -24.113797) (xy 367.203963 -24.155334)
			(xy 367.161095 -24.191009) (xy 367.113489 -24.220063) (xy 367.06216 -24.241875) (xy 367.008203 -24.255981)
			(xy 366.952766 -24.262081) (xy 366.897032 -24.260044) (xy 366.842189 -24.249914) (xy 366.789405 -24.231907)
			(xy 366.739805 -24.206406) (xy 366.694447 -24.173955) (xy 366.654298 -24.135246) (xy 366.620212 -24.091103)
			(xy 366.592916 -24.042468) (xy 366.572993 -23.990377) (xy 366.560867 -23.93594) (xy 366.556796 -23.880318)
			(xy 366.304322 -23.880318) (xy 366.303813 -23.908204) (xy 366.295693 -23.96338) (xy 366.279625 -24.016787)
			(xy 366.255953 -24.067284) (xy 366.22518 -24.113797) (xy 366.187963 -24.155334) (xy 366.145095 -24.191009)
			(xy 366.097489 -24.220063) (xy 366.04616 -24.241875) (xy 365.992203 -24.255981) (xy 365.936766 -24.262081)
			(xy 365.881032 -24.260044) (xy 365.826189 -24.249914) (xy 365.773405 -24.231907) (xy 365.723805 -24.206406)
			(xy 365.678447 -24.173955) (xy 365.638298 -24.135246) (xy 365.604212 -24.091103) (xy 365.576916 -24.042468)
			(xy 365.556993 -23.990377) (xy 365.544867 -23.93594) (xy 365.540796 -23.880318) (xy 365.120145 -23.880318)
			(xy 365.111098 -23.892108) (xy 365.068718 -23.934488) (xy 365.021168 -23.970975) (xy 364.969262 -24.000942)
			(xy 364.913889 -24.023878) (xy 364.855996 -24.039391) (xy 364.796574 -24.047214) (xy 364.736638 -24.047214)
			(xy 364.677216 -24.039391) (xy 364.619323 -24.023878) (xy 364.56395 -24.000942) (xy 364.512044 -23.970975)
			(xy 364.464494 -23.934488) (xy 364.422114 -23.892108) (xy 364.385627 -23.844558) (xy 364.35566 -23.792652)
			(xy 364.332724 -23.737279) (xy 364.317211 -23.679386) (xy 364.309388 -23.619964) (xy 361.126774 -23.619964)
			(xy 361.120322 -23.664845) (xy 361.104967 -23.71714) (xy 361.082325 -23.766717) (xy 361.052859 -23.812567)
			(xy 361.017168 -23.853758) (xy 360.975977 -23.889449) (xy 360.930127 -23.918915) (xy 360.88055 -23.941557)
			(xy 360.828255 -23.956912) (xy 360.774307 -23.964668) (xy 360.719805 -23.964668) (xy 360.665857 -23.956912)
			(xy 360.613562 -23.941557) (xy 360.563985 -23.918915) (xy 360.518135 -23.889449) (xy 360.476944 -23.853758)
			(xy 360.441253 -23.812567) (xy 360.411787 -23.766717) (xy 360.389145 -23.71714) (xy 360.37379 -23.664845)
			(xy 360.366034 -23.610897) (xy 360.365548 -23.583646) (xy 360.367326 -23.548086) (xy 360.368596 -23.53437)
			(xy 360.357674 -23.51024) (xy 360.26471 -23.44293) (xy 360.238294 -23.439882) (xy 360.225848 -23.44547)
			(xy 360.197088 -23.457281) (xy 360.137183 -23.47392) (xy 360.075578 -23.482302) (xy 360.044492 -23.482808)
			(xy 360.014525 -23.482309) (xy 359.955104 -23.474485) (xy 359.897212 -23.458972) (xy 359.841841 -23.436036)
			(xy 359.789937 -23.406068) (xy 359.742389 -23.369582) (xy 359.700009 -23.327201) (xy 359.663525 -23.279652)
			(xy 359.633558 -23.227747) (xy 359.610623 -23.172375) (xy 359.595112 -23.114483) (xy 359.58729 -23.055062)
			(xy 357.84409 -23.055062) (xy 357.84409 -24.189944) (xy 359.598974 -24.189944) (xy 359.603045 -24.134322)
			(xy 359.615171 -24.079885) (xy 359.635094 -24.027794) (xy 359.66239 -23.979159) (xy 359.696476 -23.935016)
			(xy 359.736625 -23.896307) (xy 359.781983 -23.863856) (xy 359.831583 -23.838355) (xy 359.884367 -23.820348)
			(xy 359.93921 -23.810218) (xy 359.994944 -23.808181) (xy 360.050381 -23.814281) (xy 360.104338 -23.828387)
			(xy 360.155667 -23.850199) (xy 360.203273 -23.879253) (xy 360.246141 -23.914928) (xy 360.283358 -23.956465)
			(xy 360.314131 -24.002978) (xy 360.337803 -24.053475) (xy 360.353871 -24.106882) (xy 360.361991 -24.162058)
			(xy 360.3625 -24.189944) (xy 362.121956 -24.189944) (xy 362.126027 -24.134322) (xy 362.138153 -24.079885)
			(xy 362.158076 -24.027794) (xy 362.185372 -23.979159) (xy 362.219458 -23.935016) (xy 362.259607 -23.896307)
			(xy 362.304965 -23.863856) (xy 362.354565 -23.838355) (xy 362.407349 -23.820348) (xy 362.462192 -23.810218)
			(xy 362.517926 -23.808181) (xy 362.573363 -23.814281) (xy 362.62732 -23.828387) (xy 362.678649 -23.850199)
			(xy 362.726255 -23.879253) (xy 362.769123 -23.914928) (xy 362.80634 -23.956465) (xy 362.837113 -24.002978)
			(xy 362.860785 -24.053475) (xy 362.876853 -24.106882) (xy 362.884973 -24.162058) (xy 362.885482 -24.189944)
			(xy 362.884973 -24.21783) (xy 362.876853 -24.273006) (xy 362.860785 -24.326413) (xy 362.837113 -24.37691)
			(xy 362.80634 -24.423423) (xy 362.769123 -24.46496) (xy 362.726255 -24.500635) (xy 362.678649 -24.529689)
			(xy 362.62732 -24.551501) (xy 362.573363 -24.565607) (xy 362.517926 -24.571707) (xy 362.462192 -24.56967)
			(xy 362.407349 -24.55954) (xy 362.354565 -24.541533) (xy 362.304965 -24.516032) (xy 362.259607 -24.483581)
			(xy 362.219458 -24.444872) (xy 362.185372 -24.400729) (xy 362.158076 -24.352094) (xy 362.138153 -24.300003)
			(xy 362.126027 -24.245566) (xy 362.121956 -24.189944) (xy 360.3625 -24.189944) (xy 360.361991 -24.21783)
			(xy 360.353871 -24.273006) (xy 360.337803 -24.326413) (xy 360.314131 -24.37691) (xy 360.283358 -24.423423)
			(xy 360.246141 -24.46496) (xy 360.203273 -24.500635) (xy 360.155667 -24.529689) (xy 360.104338 -24.551501)
			(xy 360.050381 -24.565607) (xy 359.994944 -24.571707) (xy 359.93921 -24.56967) (xy 359.884367 -24.55954)
			(xy 359.831583 -24.541533) (xy 359.781983 -24.516032) (xy 359.736625 -24.483581) (xy 359.696476 -24.444872)
			(xy 359.66239 -24.400729) (xy 359.635094 -24.352094) (xy 359.615171 -24.300003) (xy 359.603045 -24.245566)
			(xy 359.598974 -24.189944) (xy 357.84409 -24.189944) (xy 357.84409 -25.390094) (xy 362.033566 -25.390094)
			(xy 362.034056 -25.360126) (xy 362.041879 -25.300704) (xy 362.057392 -25.242811) (xy 362.080328 -25.187438)
			(xy 362.110295 -25.135532) (xy 362.146782 -25.087982) (xy 362.189162 -25.045602) (xy 362.236712 -25.009115)
			(xy 362.288618 -24.979148) (xy 362.343991 -24.956212) (xy 362.401884 -24.940699) (xy 362.461306 -24.932876)
			(xy 362.521242 -24.932876) (xy 362.580664 -24.940699) (xy 362.638557 -24.956212) (xy 362.69393 -24.979148)
			(xy 362.745836 -25.009115) (xy 362.793386 -25.045602) (xy 362.835766 -25.087982) (xy 362.872253 -25.135532)
			(xy 362.90222 -25.187438) (xy 362.925156 -25.242811) (xy 362.940669 -25.300704) (xy 362.948492 -25.360126)
			(xy 362.948982 -25.390094) (xy 362.948555 -25.418879) (xy 362.941336 -25.475994) (xy 362.927011 -25.531753)
			(xy 362.905808 -25.585275) (xy 362.878059 -25.635716) (xy 362.844204 -25.682279) (xy 362.804778 -25.724228)
			(xy 362.782866 -25.7429) (xy 362.774484 -25.749758) (xy 362.764832 -25.769316) (xy 362.76153 -25.867106)
			(xy 362.769658 -25.887172) (xy 362.777786 -25.894792) (xy 362.796192 -25.912863) (xy 362.828428 -25.953132)
			(xy 362.85495 -25.997373) (xy 362.875276 -26.044781) (xy 362.889036 -26.094494) (xy 362.895979 -26.145607)
			(xy 362.896404 -26.171398) (xy 362.895918 -26.198649) (xy 362.888162 -26.252597) (xy 362.872807 -26.304892)
			(xy 362.850165 -26.354469) (xy 362.820699 -26.400319) (xy 362.785008 -26.44151) (xy 362.743817 -26.477201)
			(xy 362.697967 -26.506667) (xy 362.64839 -26.529309) (xy 362.596095 -26.544664) (xy 362.542147 -26.55242)
			(xy 362.487645 -26.55242) (xy 362.433697 -26.544664) (xy 362.381402 -26.529309) (xy 362.331825 -26.506667)
			(xy 362.285975 -26.477201) (xy 362.244784 -26.44151) (xy 362.209093 -26.400319) (xy 362.179627 -26.354469)
			(xy 362.156985 -26.304892) (xy 362.14163 -26.252597) (xy 362.133874 -26.198649) (xy 362.133388 -26.171398)
			(xy 362.133908 -26.142755) (xy 362.142506 -26.086117) (xy 362.159477 -26.031401) (xy 362.184439 -25.979839)
			(xy 362.216833 -25.93259) (xy 362.236004 -25.911302) (xy 362.24337 -25.903174) (xy 362.250228 -25.8826)
			(xy 362.241084 -25.785064) (xy 362.230416 -25.766268) (xy 362.221526 -25.759918) (xy 362.196984 -25.74136)
			(xy 362.152589 -25.69876) (xy 362.114297 -25.650599) (xy 362.0828 -25.597745) (xy 362.058663 -25.541149)
			(xy 362.042322 -25.48183) (xy 362.034071 -25.420858) (xy 362.033566 -25.390094) (xy 357.84409 -25.390094)
			(xy 357.84409 -25.506934) (xy 357.844519 -25.517002) (xy 357.852241 -25.535598) (xy 357.859076 -25.543002)
			(xy 357.910384 -25.593802) (xy 357.917793 -25.600488) (xy 357.936229 -25.608076) (xy 357.946198 -25.608534)
			(xy 357.948992 -25.608534) (xy 357.976242 -25.608997) (xy 358.030188 -25.616752) (xy 358.082481 -25.632106)
			(xy 358.132057 -25.654745) (xy 358.177906 -25.68421) (xy 358.219095 -25.719899) (xy 358.254786 -25.761088)
			(xy 358.284251 -25.806936) (xy 358.306892 -25.856511) (xy 358.322246 -25.908804) (xy 358.330003 -25.96275)
			(xy 358.330003 -25.990042) (xy 359.598974 -25.990042) (xy 359.603045 -25.93442) (xy 359.615171 -25.879983)
			(xy 359.635094 -25.827892) (xy 359.66239 -25.779257) (xy 359.696476 -25.735114) (xy 359.736625 -25.696405)
			(xy 359.781983 -25.663954) (xy 359.831583 -25.638453) (xy 359.884367 -25.620446) (xy 359.93921 -25.610316)
			(xy 359.994944 -25.608279) (xy 360.050381 -25.614379) (xy 360.104338 -25.628485) (xy 360.155667 -25.650297)
			(xy 360.203273 -25.679351) (xy 360.246141 -25.715026) (xy 360.283358 -25.756563) (xy 360.314131 -25.803076)
			(xy 360.337803 -25.853573) (xy 360.353871 -25.90698) (xy 360.361991 -25.962156) (xy 360.3625 -25.990042)
			(xy 360.361991 -26.017928) (xy 360.353871 -26.073104) (xy 360.337803 -26.126511) (xy 360.314131 -26.177008)
			(xy 360.283358 -26.223521) (xy 360.246141 -26.265058) (xy 360.203273 -26.300733) (xy 360.155667 -26.329787)
			(xy 360.104338 -26.351599) (xy 360.050381 -26.365705) (xy 359.994944 -26.371805) (xy 359.93921 -26.369768)
			(xy 359.884367 -26.359638) (xy 359.831583 -26.341631) (xy 359.781983 -26.31613) (xy 359.736625 -26.283679)
			(xy 359.696476 -26.24497) (xy 359.66239 -26.200827) (xy 359.635094 -26.152192) (xy 359.615171 -26.100101)
			(xy 359.603045 -26.045664) (xy 359.598974 -25.990042) (xy 358.330003 -25.990042) (xy 358.330003 -26.01725)
			(xy 358.322246 -26.071196) (xy 358.306892 -26.123489) (xy 358.284251 -26.173064) (xy 358.254786 -26.218912)
			(xy 358.219095 -26.260101) (xy 358.177906 -26.29579) (xy 358.132057 -26.325255) (xy 358.082481 -26.347894)
			(xy 358.030188 -26.363248) (xy 357.976242 -26.371003) (xy 357.948992 -26.37155) (xy 357.946198 -26.37155)
			(xy 357.936232 -26.372026) (xy 357.917795 -26.379603) (xy 357.910384 -26.386282) (xy 357.859076 -26.437082)
			(xy 357.852234 -26.444481) (xy 357.844518 -26.46308) (xy 357.84409 -26.47315) (xy 357.84409 -27.307032)
			(xy 357.844518 -27.3171) (xy 357.85224 -27.335697) (xy 357.859076 -27.3431) (xy 357.910384 -27.3939)
			(xy 357.917793 -27.400587) (xy 357.936229 -27.408175) (xy 357.946198 -27.408632) (xy 357.948992 -27.408632)
			(xy 357.976242 -27.409095) (xy 358.030189 -27.41685) (xy 358.082482 -27.432204) (xy 358.132058 -27.454843)
			(xy 358.177907 -27.484308) (xy 358.219096 -27.519998) (xy 358.254787 -27.561186) (xy 358.284253 -27.607035)
			(xy 358.306894 -27.656611) (xy 358.322248 -27.708904) (xy 358.330005 -27.76285) (xy 358.330005 -27.79014)
			(xy 359.662982 -27.79014) (xy 359.667053 -27.734518) (xy 359.679179 -27.680081) (xy 359.699102 -27.62799)
			(xy 359.726398 -27.579355) (xy 359.760484 -27.535212) (xy 359.800633 -27.496503) (xy 359.845991 -27.464052)
			(xy 359.895591 -27.438551) (xy 359.948375 -27.420544) (xy 360.003218 -27.410414) (xy 360.058952 -27.408377)
			(xy 360.114389 -27.414477) (xy 360.168346 -27.428583) (xy 360.219675 -27.450395) (xy 360.267281 -27.479449)
			(xy 360.310149 -27.515124) (xy 360.347366 -27.556661) (xy 360.378139 -27.603174) (xy 360.401811 -27.653671)
			(xy 360.417879 -27.707078) (xy 360.425999 -27.762254) (xy 360.426508 -27.79014) (xy 362.166914 -27.79014)
			(xy 362.170985 -27.734518) (xy 362.183111 -27.680081) (xy 362.203034 -27.62799) (xy 362.23033 -27.579355)
			(xy 362.264416 -27.535212) (xy 362.304565 -27.496503) (xy 362.349923 -27.464052) (xy 362.399523 -27.438551)
			(xy 362.452307 -27.420544) (xy 362.50715 -27.410414) (xy 362.562884 -27.408377) (xy 362.618321 -27.414477)
			(xy 362.672278 -27.428583) (xy 362.723607 -27.450395) (xy 362.771213 -27.479449) (xy 362.814081 -27.515124)
			(xy 362.851298 -27.556661) (xy 362.882071 -27.603174) (xy 362.905743 -27.653671) (xy 362.921811 -27.707078)
			(xy 362.929931 -27.762254) (xy 362.93044 -27.79014) (xy 362.929943 -27.817351) (xy 364.199895 -27.817351)
			(xy 364.199895 -27.762849) (xy 364.207652 -27.7089) (xy 364.223008 -27.656606) (xy 364.245651 -27.607028)
			(xy 364.275119 -27.561179) (xy 364.310812 -27.519989) (xy 364.352004 -27.4843) (xy 364.397857 -27.454835)
			(xy 364.447436 -27.432197) (xy 364.499732 -27.416846) (xy 364.553681 -27.409093) (xy 364.580932 -27.408632)
			(xy 364.606239 -27.409021) (xy 364.656412 -27.415696) (xy 364.705264 -27.428939) (xy 364.72876 -27.43835)
			(xy 364.73676 -27.441396) (xy 364.753835 -27.44248) (xy 364.770317 -27.437884) (xy 364.777528 -27.43327)
			(xy 364.802928 -27.41549) (xy 364.809804 -27.410202) (xy 364.819885 -27.396107) (xy 364.824686 -27.379456)
			(xy 364.824518 -27.370786) (xy 364.823756 -27.342846) (xy 364.823756 -26.479246) (xy 364.824264 -26.456894)
			(xy 364.824772 -26.444448) (xy 364.814358 -26.421842) (xy 364.729268 -26.355548) (xy 364.704884 -26.350976)
			(xy 364.692946 -26.354786) (xy 364.665611 -26.362635) (xy 364.609367 -26.371048) (xy 364.580932 -26.37155)
			(xy 364.553681 -26.371005) (xy 364.499732 -26.363253) (xy 364.447436 -26.347901) (xy 364.397858 -26.325263)
			(xy 364.352005 -26.295799) (xy 364.310814 -26.260109) (xy 364.27512 -26.21892) (xy 364.245653 -26.173071)
			(xy 364.22301 -26.123494) (xy 364.207654 -26.071199) (xy 364.199897 -26.017251) (xy 364.199897 -25.962749)
			(xy 364.207654 -25.908801) (xy 364.22301 -25.856506) (xy 364.245653 -25.806929) (xy 364.27512 -25.76108)
			(xy 364.310814 -25.719891) (xy 364.352005 -25.684201) (xy 364.397858 -25.654737) (xy 364.447436 -25.632099)
			(xy 364.499732 -25.616747) (xy 364.553681 -25.608995) (xy 364.580932 -25.608534) (xy 364.609885 -25.609047)
			(xy 364.667127 -25.617788) (xy 364.722391 -25.63508) (xy 364.774406 -25.660525) (xy 364.821979 -25.69354)
			(xy 364.864015 -25.733364) (xy 364.89955 -25.779085) (xy 364.927767 -25.82965) (xy 364.928664 -25.832054)
			(xy 366.488472 -25.832054) (xy 366.48893 -25.80545) (xy 366.496306 -25.752756) (xy 366.510937 -25.701599)
			(xy 366.532537 -25.652973) (xy 366.560688 -25.607822) (xy 366.594842 -25.567024) (xy 366.634337 -25.53137)
			(xy 366.656112 -25.516078) (xy 366.667587 -25.507738) (xy 366.685788 -25.485995) (xy 366.697304 -25.460083)
			(xy 366.701244 -25.432002) (xy 366.697305 -25.403922) (xy 366.685791 -25.378009) (xy 366.66759 -25.356265)
			(xy 366.656112 -25.34793) (xy 366.634341 -25.332637) (xy 366.594863 -25.296969) (xy 366.560721 -25.256165)
			(xy 366.532576 -25.211015) (xy 366.510973 -25.162394) (xy 366.496333 -25.111244) (xy 366.488937 -25.058556)
			(xy 366.488472 -25.031954) (xy 366.488958 -25.004703) (xy 366.496714 -24.950755) (xy 366.512069 -24.89846)
			(xy 366.534711 -24.848883) (xy 366.564177 -24.803033) (xy 366.599868 -24.761842) (xy 366.641059 -24.726151)
			(xy 366.686909 -24.696685) (xy 366.736486 -24.674043) (xy 366.788781 -24.658688) (xy 366.842729 -24.650932)
			(xy 366.897231 -24.650932) (xy 366.951179 -24.658688) (xy 367.003474 -24.674043) (xy 367.053051 -24.696685)
			(xy 367.098901 -24.726151) (xy 367.140092 -24.761842) (xy 367.163293 -24.788618) (xy 369.093478 -24.788618)
			(xy 369.093478 -24.728682) (xy 369.101301 -24.66926) (xy 369.116814 -24.611367) (xy 369.13975 -24.555994)
			(xy 369.169717 -24.504088) (xy 369.206204 -24.456538) (xy 369.248584 -24.414158) (xy 369.296134 -24.377671)
			(xy 369.34804 -24.347704) (xy 369.403413 -24.324768) (xy 369.461306 -24.309255) (xy 369.520728 -24.301432)
			(xy 369.580664 -24.301432) (xy 369.640086 -24.309255) (xy 369.697979 -24.324768) (xy 369.753352 -24.347704)
			(xy 369.805258 -24.377671) (xy 369.852808 -24.414158) (xy 369.895188 -24.456538) (xy 369.931675 -24.504088)
			(xy 369.961642 -24.555994) (xy 369.984578 -24.611367) (xy 370.000091 -24.66926) (xy 370.007914 -24.728682)
			(xy 370.008404 -24.75865) (xy 370.007914 -24.788618) (xy 370.000091 -24.84804) (xy 369.984578 -24.905933)
			(xy 369.961642 -24.961306) (xy 369.931675 -25.013212) (xy 369.895188 -25.060762) (xy 369.852808 -25.103142)
			(xy 369.805258 -25.139629) (xy 369.753352 -25.169596) (xy 369.697979 -25.192532) (xy 369.640086 -25.208045)
			(xy 369.580664 -25.215868) (xy 369.520728 -25.215868) (xy 369.461306 -25.208045) (xy 369.403413 -25.192532)
			(xy 369.34804 -25.169596) (xy 369.296134 -25.139629) (xy 369.248584 -25.103142) (xy 369.206204 -25.060762)
			(xy 369.169717 -25.013212) (xy 369.13975 -24.961306) (xy 369.116814 -24.905933) (xy 369.101301 -24.84804)
			(xy 369.093478 -24.788618) (xy 367.163293 -24.788618) (xy 367.175783 -24.803033) (xy 367.205249 -24.848883)
			(xy 367.227891 -24.89846) (xy 367.243246 -24.950755) (xy 367.251002 -25.004703) (xy 367.251488 -25.031954)
			(xy 367.25101 -25.058557) (xy 367.243634 -25.111249) (xy 367.229005 -25.162404) (xy 367.207408 -25.211029)
			(xy 367.17926 -25.25618) (xy 367.14511 -25.29698) (xy 367.10562 -25.332637) (xy 367.083848 -25.34793)
			(xy 367.072359 -25.356257) (xy 367.054147 -25.377999) (xy 367.042625 -25.403915) (xy 367.038683 -25.432002)
			(xy 367.042626 -25.460089) (xy 367.05415 -25.486005) (xy 367.072363 -25.507746) (xy 367.083848 -25.516078)
			(xy 367.105614 -25.531379) (xy 367.145094 -25.567044) (xy 367.179238 -25.607846) (xy 367.207384 -25.652995)
			(xy 367.228987 -25.701615) (xy 367.243628 -25.752765) (xy 367.251024 -25.805452) (xy 367.251488 -25.832054)
			(xy 367.251002 -25.859305) (xy 367.243246 -25.913253) (xy 367.227891 -25.965548) (xy 367.205249 -26.015125)
			(xy 367.175783 -26.060975) (xy 367.140092 -26.102166) (xy 367.098901 -26.137857) (xy 367.053051 -26.167323)
			(xy 367.003474 -26.189965) (xy 366.951179 -26.20532) (xy 366.897231 -26.213076) (xy 366.842729 -26.213076)
			(xy 366.788781 -26.20532) (xy 366.736486 -26.189965) (xy 366.686909 -26.167323) (xy 366.641059 -26.137857)
			(xy 366.599868 -26.102166) (xy 366.564177 -26.060975) (xy 366.534711 -26.015125) (xy 366.512069 -25.965548)
			(xy 366.496714 -25.913253) (xy 366.488958 -25.859305) (xy 366.488472 -25.832054) (xy 364.928664 -25.832054)
			(xy 364.948018 -25.883899) (xy 364.959837 -25.940586) (xy 364.961932 -25.969468) (xy 364.96244 -25.981914)
			(xy 364.97514 -26.00325) (xy 365.066834 -26.060654) (xy 365.091472 -26.062432) (xy 365.102902 -26.057606)
			(xy 365.131263 -26.046145) (xy 365.190259 -26.029987) (xy 365.25088 -26.021813) (xy 365.281464 -26.021284)
			(xy 365.311442 -26.021795) (xy 365.370887 -26.02962) (xy 365.4288 -26.045139) (xy 365.484191 -26.068088)
			(xy 365.536111 -26.098073) (xy 365.583672 -26.134581) (xy 365.626058 -26.176986) (xy 365.662544 -26.224563)
			(xy 365.692505 -26.276497) (xy 365.715429 -26.331899) (xy 365.723181 -26.360882) (xy 367.389662 -26.360882)
			(xy 367.393733 -26.30526) (xy 367.405859 -26.250823) (xy 367.425782 -26.198732) (xy 367.453078 -26.150097)
			(xy 367.487164 -26.105954) (xy 367.527313 -26.067245) (xy 367.572671 -26.034794) (xy 367.622271 -26.009293)
			(xy 367.675055 -25.991286) (xy 367.729898 -25.981156) (xy 367.785632 -25.979119) (xy 367.841069 -25.985219)
			(xy 367.895026 -25.999325) (xy 367.946355 -26.021137) (xy 367.993961 -26.050191) (xy 368.036829 -26.085866)
			(xy 368.074046 -26.127403) (xy 368.104819 -26.173916) (xy 368.128491 -26.224413) (xy 368.144559 -26.27782)
			(xy 368.152679 -26.332996) (xy 368.153188 -26.360882) (xy 368.405662 -26.360882) (xy 368.409733 -26.30526)
			(xy 368.421859 -26.250823) (xy 368.441782 -26.198732) (xy 368.469078 -26.150097) (xy 368.503164 -26.105954)
			(xy 368.543313 -26.067245) (xy 368.588671 -26.034794) (xy 368.638271 -26.009293) (xy 368.691055 -25.991286)
			(xy 368.745898 -25.981156) (xy 368.801632 -25.979119) (xy 368.857069 -25.985219) (xy 368.911026 -25.999325)
			(xy 368.962355 -26.021137) (xy 369.009961 -26.050191) (xy 369.052829 -26.085866) (xy 369.090046 -26.127403)
			(xy 369.120819 -26.173916) (xy 369.144491 -26.224413) (xy 369.160559 -26.27782) (xy 369.168679 -26.332996)
			(xy 369.169188 -26.360882) (xy 369.168679 -26.388768) (xy 369.160559 -26.443944) (xy 369.144491 -26.497351)
			(xy 369.120819 -26.547848) (xy 369.090046 -26.594361) (xy 369.052829 -26.635898) (xy 369.009961 -26.671573)
			(xy 368.962355 -26.700627) (xy 368.911026 -26.722439) (xy 368.857069 -26.736545) (xy 368.801632 -26.742645)
			(xy 368.745898 -26.740608) (xy 368.691055 -26.730478) (xy 368.638271 -26.712471) (xy 368.588671 -26.68697)
			(xy 368.543313 -26.654519) (xy 368.503164 -26.61581) (xy 368.469078 -26.571667) (xy 368.441782 -26.523032)
			(xy 368.421859 -26.470941) (xy 368.409733 -26.416504) (xy 368.405662 -26.360882) (xy 368.153188 -26.360882)
			(xy 368.152679 -26.388768) (xy 368.144559 -26.443944) (xy 368.128491 -26.497351) (xy 368.104819 -26.547848)
			(xy 368.074046 -26.594361) (xy 368.036829 -26.635898) (xy 367.993961 -26.671573) (xy 367.946355 -26.700627)
			(xy 367.895026 -26.722439) (xy 367.841069 -26.736545) (xy 367.785632 -26.742645) (xy 367.729898 -26.740608)
			(xy 367.675055 -26.730478) (xy 367.622271 -26.712471) (xy 367.572671 -26.68697) (xy 367.527313 -26.654519)
			(xy 367.487164 -26.61581) (xy 367.453078 -26.571667) (xy 367.425782 -26.523032) (xy 367.405859 -26.470941)
			(xy 367.393733 -26.416504) (xy 367.389662 -26.360882) (xy 365.723181 -26.360882) (xy 365.730921 -26.38982)
			(xy 365.738718 -26.449267) (xy 365.739172 -26.479246) (xy 365.739172 -26.971244) (xy 369.151152 -26.971244)
			(xy 369.155223 -26.915622) (xy 369.167349 -26.861185) (xy 369.187272 -26.809094) (xy 369.214568 -26.760459)
			(xy 369.248654 -26.716316) (xy 369.288803 -26.677607) (xy 369.334161 -26.645156) (xy 369.383761 -26.619655)
			(xy 369.436545 -26.601648) (xy 369.491388 -26.591518) (xy 369.547122 -26.589481) (xy 369.602559 -26.595581)
			(xy 369.656516 -26.609687) (xy 369.707845 -26.631499) (xy 369.755451 -26.660553) (xy 369.798319 -26.696228)
			(xy 369.835536 -26.737765) (xy 369.866309 -26.784278) (xy 369.889981 -26.834775) (xy 369.906049 -26.888182)
			(xy 369.914169 -26.943358) (xy 369.914678 -26.971244) (xy 369.914169 -26.99913) (xy 369.906049 -27.054306)
			(xy 369.889981 -27.107713) (xy 369.866309 -27.15821) (xy 369.835536 -27.204723) (xy 369.798319 -27.24626)
			(xy 369.755451 -27.281935) (xy 369.707845 -27.310989) (xy 369.656516 -27.332801) (xy 369.602559 -27.346907)
			(xy 369.547122 -27.353007) (xy 369.491388 -27.35097) (xy 369.436545 -27.34084) (xy 369.383761 -27.322833)
			(xy 369.334161 -27.297332) (xy 369.288803 -27.264881) (xy 369.248654 -27.226172) (xy 369.214568 -27.182029)
			(xy 369.187272 -27.133394) (xy 369.167349 -27.081303) (xy 369.155223 -27.026866) (xy 369.151152 -26.971244)
			(xy 365.739172 -26.971244) (xy 365.739172 -27.342846) (xy 365.738716 -27.37282) (xy 365.730888 -27.432256)
			(xy 365.715373 -27.490162) (xy 365.692435 -27.545549) (xy 365.662468 -27.59747) (xy 365.625982 -27.645037)
			(xy 365.583602 -27.687438) (xy 365.536052 -27.723946) (xy 365.484145 -27.753939) (xy 365.428769 -27.776903)
			(xy 365.37087 -27.792446) (xy 365.311438 -27.800301) (xy 365.281464 -27.800808) (xy 365.250327 -27.800281)
			(xy 365.188631 -27.791815) (xy 365.128646 -27.775083) (xy 365.099854 -27.763216) (xy 365.088678 -27.75839)
			(xy 365.065056 -27.75966) (xy 364.97387 -27.810968) (xy 364.960408 -27.830526) (xy 364.958884 -27.842464)
			(xy 364.954698 -27.8695) (xy 364.939516 -27.922059) (xy 364.916985 -27.971913) (xy 364.887565 -28.018038)
			(xy 364.851862 -28.05949) (xy 364.810605 -28.095419) (xy 364.76464 -28.125089) (xy 364.71491 -28.147892)
			(xy 364.662434 -28.16336) (xy 364.608286 -28.171176) (xy 364.580932 -28.171648) (xy 364.553681 -28.171107)
			(xy 364.499732 -28.163354) (xy 364.447436 -28.148003) (xy 364.397857 -28.125365) (xy 364.352004 -28.0959)
			(xy 364.310812 -28.060211) (xy 364.275119 -28.019021) (xy 364.245651 -27.973172) (xy 364.223008 -27.923594)
			(xy 364.207652 -27.8713) (xy 364.199895 -27.817351) (xy 362.929943 -27.817351) (xy 362.929931 -27.818026)
			(xy 362.921811 -27.873202) (xy 362.905743 -27.926609) (xy 362.882071 -27.977106) (xy 362.851298 -28.023619)
			(xy 362.814081 -28.065156) (xy 362.771213 -28.100831) (xy 362.723607 -28.129885) (xy 362.672278 -28.151697)
			(xy 362.618321 -28.165803) (xy 362.562884 -28.171903) (xy 362.50715 -28.169866) (xy 362.452307 -28.159736)
			(xy 362.399523 -28.141729) (xy 362.349923 -28.116228) (xy 362.304565 -28.083777) (xy 362.264416 -28.045068)
			(xy 362.23033 -28.000925) (xy 362.203034 -27.95229) (xy 362.183111 -27.900199) (xy 362.170985 -27.845762)
			(xy 362.166914 -27.79014) (xy 360.426508 -27.79014) (xy 360.425999 -27.818026) (xy 360.417879 -27.873202)
			(xy 360.401811 -27.926609) (xy 360.378139 -27.977106) (xy 360.347366 -28.023619) (xy 360.310149 -28.065156)
			(xy 360.267281 -28.100831) (xy 360.219675 -28.129885) (xy 360.168346 -28.151697) (xy 360.114389 -28.165803)
			(xy 360.058952 -28.171903) (xy 360.003218 -28.169866) (xy 359.948375 -28.159736) (xy 359.895591 -28.141729)
			(xy 359.845991 -28.116228) (xy 359.800633 -28.083777) (xy 359.760484 -28.045068) (xy 359.726398 -28.000925)
			(xy 359.699102 -27.95229) (xy 359.679179 -27.900199) (xy 359.667053 -27.845762) (xy 359.662982 -27.79014)
			(xy 358.330005 -27.79014) (xy 358.330005 -27.81735) (xy 358.322248 -27.871296) (xy 358.306894 -27.923589)
			(xy 358.284253 -27.973165) (xy 358.254787 -28.019014) (xy 358.219096 -28.060202) (xy 358.177907 -28.095892)
			(xy 358.132058 -28.125357) (xy 358.082482 -28.147996) (xy 358.030189 -28.16335) (xy 357.976242 -28.171105)
			(xy 357.948992 -28.171648) (xy 357.946198 -28.171648) (xy 357.936232 -28.172124) (xy 357.917795 -28.1797)
			(xy 357.910384 -28.18638) (xy 357.859076 -28.23718) (xy 357.852234 -28.244579) (xy 357.844517 -28.263178)
			(xy 357.84409 -28.273248) (xy 357.84409 -29.106876) (xy 357.844527 -29.11694) (xy 357.852259 -29.135526)
			(xy 357.859076 -29.142944) (xy 357.910384 -29.193744) (xy 357.917795 -29.200426) (xy 357.93623 -29.208007)
			(xy 357.946198 -29.208476) (xy 357.948992 -29.208476) (xy 357.976246 -29.208938) (xy 358.030201 -29.216695)
			(xy 358.082502 -29.232051) (xy 358.132085 -29.254694) (xy 358.177941 -29.284163) (xy 358.219136 -29.319858)
			(xy 358.254832 -29.361053) (xy 358.284302 -29.406908) (xy 358.306946 -29.456491) (xy 358.322304 -29.508792)
			(xy 358.330061 -29.562746) (xy 358.330061 -29.589984) (xy 359.662982 -29.589984) (xy 359.667053 -29.534362)
			(xy 359.679179 -29.479925) (xy 359.699102 -29.427834) (xy 359.726398 -29.379199) (xy 359.760484 -29.335056)
			(xy 359.800633 -29.296347) (xy 359.845991 -29.263896) (xy 359.895591 -29.238395) (xy 359.948375 -29.220388)
			(xy 360.003218 -29.210258) (xy 360.058952 -29.208221) (xy 360.114389 -29.214321) (xy 360.168346 -29.228427)
			(xy 360.219675 -29.250239) (xy 360.267281 -29.279293) (xy 360.310149 -29.314968) (xy 360.347366 -29.356505)
			(xy 360.378139 -29.403018) (xy 360.401811 -29.453515) (xy 360.417879 -29.506922) (xy 360.425999 -29.562098)
			(xy 360.426508 -29.589984) (xy 362.166914 -29.589984) (xy 362.170985 -29.534362) (xy 362.183111 -29.479925)
			(xy 362.203034 -29.427834) (xy 362.23033 -29.379199) (xy 362.264416 -29.335056) (xy 362.304565 -29.296347)
			(xy 362.349923 -29.263896) (xy 362.399523 -29.238395) (xy 362.452307 -29.220388) (xy 362.50715 -29.210258)
			(xy 362.562884 -29.208221) (xy 362.618321 -29.214321) (xy 362.672278 -29.228427) (xy 362.723607 -29.250239)
			(xy 362.771213 -29.279293) (xy 362.814081 -29.314968) (xy 362.851298 -29.356505) (xy 362.882071 -29.403018)
			(xy 362.905743 -29.453515) (xy 362.921811 -29.506922) (xy 362.929931 -29.562098) (xy 362.93044 -29.589984)
			(xy 364.198914 -29.589984) (xy 364.202985 -29.534362) (xy 364.215111 -29.479925) (xy 364.235034 -29.427834)
			(xy 364.26233 -29.379199) (xy 364.296416 -29.335056) (xy 364.336565 -29.296347) (xy 364.381923 -29.263896)
			(xy 364.431523 -29.238395) (xy 364.484307 -29.220388) (xy 364.53915 -29.210258) (xy 364.594884 -29.208221)
			(xy 364.650321 -29.214321) (xy 364.704278 -29.228427) (xy 364.755607 -29.250239) (xy 364.803213 -29.279293)
			(xy 364.846081 -29.314968) (xy 364.867754 -29.339157) (xy 366.590209 -29.339157) (xy 366.590209 -29.284643)
			(xy 366.597968 -29.230683) (xy 366.613327 -29.178377) (xy 366.635974 -29.128789) (xy 366.665448 -29.082929)
			(xy 366.701149 -29.04173) (xy 366.74235 -29.006032) (xy 366.788212 -28.976562) (xy 366.837801 -28.953918)
			(xy 366.890108 -28.938562) (xy 366.944069 -28.930807) (xy 366.971326 -28.930346) (xy 366.986119 -28.930476)
			(xy 367.015617 -28.932769) (xy 367.030254 -28.934918) (xy 367.041176 -28.936696) (xy 367.062512 -28.9306)
			(xy 367.129822 -28.873196) (xy 367.137794 -28.865608) (xy 367.146875 -28.845585) (xy 367.147348 -28.834588)
			(xy 367.147348 -28.530296) (xy 367.14683 -28.519309) (xy 367.137762 -28.499298) (xy 367.129822 -28.491688)
			(xy 367.062512 -28.434284) (xy 367.041176 -28.428188) (xy 367.030254 -28.429966) (xy 367.015616 -28.432107)
			(xy 366.986119 -28.434395) (xy 366.971326 -28.434538) (xy 366.944074 -28.434017) (xy 366.890125 -28.426263)
			(xy 366.837828 -28.410911) (xy 366.788248 -28.388271) (xy 366.742395 -28.358806) (xy 366.701203 -28.323116)
			(xy 366.665509 -28.281925) (xy 366.636041 -28.236075) (xy 366.613399 -28.186497) (xy 366.598042 -28.134201)
			(xy 366.590285 -28.080252) (xy 366.590285 -28.025748) (xy 366.598042 -27.971799) (xy 366.613399 -27.919503)
			(xy 366.636041 -27.869925) (xy 366.665509 -27.824075) (xy 366.701203 -27.782884) (xy 366.742395 -27.747194)
			(xy 366.788248 -27.717729) (xy 366.837828 -27.695089) (xy 366.890125 -27.679737) (xy 366.944074 -27.671983)
			(xy 366.971326 -27.671522) (xy 366.997253 -27.671926) (xy 367.048632 -27.678936) (xy 367.098589 -27.692837)
			(xy 367.146203 -27.713374) (xy 367.1906 -27.740167) (xy 367.23096 -27.772724) (xy 367.266541 -27.810445)
			(xy 367.281968 -27.831288) (xy 367.287709 -27.838617) (xy 367.303212 -27.848903) (xy 367.312194 -27.851354)
			(xy 367.34242 -27.858212) (xy 367.351698 -27.859947) (xy 367.370359 -27.857215) (xy 367.378742 -27.852878)
			(xy 367.40471 -27.838568) (xy 367.459565 -27.816061) (xy 367.516871 -27.800839) (xy 367.575664 -27.793158)
			(xy 367.60531 -27.79268) (xy 367.634952 -27.793205) (xy 367.693733 -27.800918) (xy 367.751031 -27.816136)
			(xy 367.805893 -27.838607) (xy 367.831878 -27.852878) (xy 367.840291 -27.857124) (xy 367.858921 -27.859857)
			(xy 367.8682 -27.858212) (xy 367.898426 -27.851354) (xy 367.90742 -27.848929) (xy 367.922925 -27.838635)
			(xy 367.928652 -27.831288) (xy 367.944081 -27.810445) (xy 367.97965 -27.77271) (xy 368.020005 -27.740144)
			(xy 368.064401 -27.713347) (xy 368.11202 -27.692815) (xy 368.161982 -27.678927) (xy 368.213365 -27.671938)
			(xy 368.239294 -27.671522) (xy 368.266549 -27.671925) (xy 368.320505 -27.679681) (xy 368.372808 -27.695038)
			(xy 368.422393 -27.717682) (xy 368.46825 -27.747152) (xy 368.509447 -27.782849) (xy 368.545144 -27.824045)
			(xy 368.574615 -27.869902) (xy 368.59726 -27.919486) (xy 368.612617 -27.971789) (xy 368.620375 -28.025745)
			(xy 368.620375 -28.080255) (xy 368.612617 -28.134211) (xy 368.59726 -28.186514) (xy 368.574615 -28.236098)
			(xy 368.545144 -28.281955) (xy 368.509447 -28.323151) (xy 368.46825 -28.358848) (xy 368.422393 -28.388318)
			(xy 368.372808 -28.410962) (xy 368.320505 -28.426319) (xy 368.266549 -28.434075) (xy 368.239294 -28.434538)
			(xy 368.224501 -28.434406) (xy 368.195003 -28.432115) (xy 368.180366 -28.429966) (xy 368.169444 -28.428188)
			(xy 368.148108 -28.434284) (xy 368.080798 -28.491688) (xy 368.072836 -28.499285) (xy 368.063749 -28.519302)
			(xy 368.063272 -28.530296) (xy 368.063272 -28.834588) (xy 368.063793 -28.845575) (xy 368.072858 -28.865587)
			(xy 368.080798 -28.873196) (xy 368.148108 -28.9306) (xy 368.169444 -28.936696) (xy 368.180366 -28.934918)
			(xy 368.195004 -28.932775) (xy 368.224501 -28.930488) (xy 368.239294 -28.930346) (xy 368.266544 -28.930901)
			(xy 368.320489 -28.938656) (xy 368.372781 -28.95401) (xy 368.422356 -28.976649) (xy 368.468204 -29.006114)
			(xy 368.509393 -29.041803) (xy 368.545083 -29.082991) (xy 368.574548 -29.128839) (xy 368.597188 -29.178413)
			(xy 368.612543 -29.230705) (xy 368.620299 -29.28465) (xy 368.620299 -29.33915) (xy 368.612543 -29.393095)
			(xy 368.597188 -29.445387) (xy 368.574548 -29.494961) (xy 368.545083 -29.540809) (xy 368.509393 -29.581997)
			(xy 368.468204 -29.617686) (xy 368.422356 -29.647151) (xy 368.372781 -29.66979) (xy 368.320489 -29.685144)
			(xy 368.266544 -29.692899) (xy 368.239294 -29.693362) (xy 368.213367 -29.69295) (xy 368.161988 -29.685942)
			(xy 368.112032 -29.672043) (xy 368.064417 -29.651508) (xy 368.02002 -29.624716) (xy 367.97966 -29.592159)
			(xy 367.944079 -29.554439) (xy 367.928652 -29.533596) (xy 367.922887 -29.526287) (xy 367.907403 -29.515988)
			(xy 367.898426 -29.51353) (xy 367.8682 -29.506672) (xy 367.85892 -29.50495) (xy 367.840261 -29.507674)
			(xy 367.831878 -29.512006) (xy 367.805905 -29.526307) (xy 367.751052 -29.548816) (xy 367.693748 -29.564041)
			(xy 367.634956 -29.571725) (xy 367.60531 -29.572204) (xy 367.575667 -29.571716) (xy 367.516884 -29.563992)
			(xy 367.459586 -29.548763) (xy 367.404726 -29.526282) (xy 367.378742 -29.512006) (xy 367.370325 -29.507769)
			(xy 367.351699 -29.50503) (xy 367.34242 -29.506672) (xy 367.312194 -29.51353) (xy 367.303205 -29.515969)
			(xy 367.287697 -29.526253) (xy 367.281968 -29.533596) (xy 367.266522 -29.554426) (xy 367.230957 -29.592162)
			(xy 367.190605 -29.62473) (xy 367.146211 -29.651528) (xy 367.098595 -29.672062) (xy 367.048635 -29.685953)
			(xy 366.997254 -29.692945) (xy 366.971326 -29.693362) (xy 366.944069 -29.692993) (xy 366.890108 -29.685238)
			(xy 366.837801 -29.669882) (xy 366.788212 -29.647238) (xy 366.74235 -29.617768) (xy 366.701149 -29.58207)
			(xy 366.665448 -29.540871) (xy 366.635974 -29.495011) (xy 366.613327 -29.445423) (xy 366.597968 -29.393117)
			(xy 366.590209 -29.339157) (xy 364.867754 -29.339157) (xy 364.883298 -29.356505) (xy 364.914071 -29.403018)
			(xy 364.937743 -29.453515) (xy 364.953811 -29.506922) (xy 364.961931 -29.562098) (xy 364.96244 -29.589984)
			(xy 364.961931 -29.61787) (xy 364.953811 -29.673046) (xy 364.937743 -29.726453) (xy 364.914071 -29.77695)
			(xy 364.883298 -29.823463) (xy 364.846081 -29.865) (xy 364.803213 -29.900675) (xy 364.755607 -29.929729)
			(xy 364.704278 -29.951541) (xy 364.650321 -29.965647) (xy 364.594884 -29.971747) (xy 364.53915 -29.96971)
			(xy 364.484307 -29.95958) (xy 364.431523 -29.941573) (xy 364.381923 -29.916072) (xy 364.336565 -29.883621)
			(xy 364.296416 -29.844912) (xy 364.26233 -29.800769) (xy 364.235034 -29.752134) (xy 364.215111 -29.700043)
			(xy 364.202985 -29.645606) (xy 364.198914 -29.589984) (xy 362.93044 -29.589984) (xy 362.929931 -29.61787)
			(xy 362.921811 -29.673046) (xy 362.905743 -29.726453) (xy 362.882071 -29.77695) (xy 362.851298 -29.823463)
			(xy 362.814081 -29.865) (xy 362.771213 -29.900675) (xy 362.723607 -29.929729) (xy 362.672278 -29.951541)
			(xy 362.618321 -29.965647) (xy 362.562884 -29.971747) (xy 362.50715 -29.96971) (xy 362.452307 -29.95958)
			(xy 362.399523 -29.941573) (xy 362.349923 -29.916072) (xy 362.304565 -29.883621) (xy 362.264416 -29.844912)
			(xy 362.23033 -29.800769) (xy 362.203034 -29.752134) (xy 362.183111 -29.700043) (xy 362.170985 -29.645606)
			(xy 362.166914 -29.589984) (xy 360.426508 -29.589984) (xy 360.425999 -29.61787) (xy 360.417879 -29.673046)
			(xy 360.401811 -29.726453) (xy 360.378139 -29.77695) (xy 360.347366 -29.823463) (xy 360.310149 -29.865)
			(xy 360.267281 -29.900675) (xy 360.219675 -29.929729) (xy 360.168346 -29.951541) (xy 360.114389 -29.965647)
			(xy 360.058952 -29.971747) (xy 360.003218 -29.96971) (xy 359.948375 -29.95958) (xy 359.895591 -29.941573)
			(xy 359.845991 -29.916072) (xy 359.800633 -29.883621) (xy 359.760484 -29.844912) (xy 359.726398 -29.800769)
			(xy 359.699102 -29.752134) (xy 359.679179 -29.700043) (xy 359.667053 -29.645606) (xy 359.662982 -29.589984)
			(xy 358.330061 -29.589984) (xy 358.330061 -29.617254) (xy 358.322304 -29.671208) (xy 358.306946 -29.723509)
			(xy 358.284302 -29.773092) (xy 358.254832 -29.818947) (xy 358.219136 -29.860142) (xy 358.177941 -29.895837)
			(xy 358.132085 -29.925306) (xy 358.082502 -29.947949) (xy 358.030201 -29.963305) (xy 357.976246 -29.971062)
			(xy 357.948992 -29.971492) (xy 357.946198 -29.971492) (xy 357.93623 -29.971967) (xy 357.917789 -29.979537)
			(xy 357.910384 -29.986224) (xy 357.859076 -30.037024) (xy 357.852225 -30.04442) (xy 357.844487 -30.063019)
			(xy 357.84409 -30.073092) (xy 357.84409 -30.906974) (xy 357.844526 -30.917038) (xy 357.852258 -30.935624)
			(xy 357.859076 -30.943042) (xy 357.910384 -30.993842) (xy 357.917795 -31.000524) (xy 357.93623 -31.008106)
			(xy 357.946198 -31.008574) (xy 357.948992 -31.008574) (xy 357.976247 -31.009036) (xy 358.030201 -31.016793)
			(xy 358.082502 -31.032149) (xy 358.132086 -31.054792) (xy 358.177942 -31.084261) (xy 358.219138 -31.119957)
			(xy 358.254834 -31.161151) (xy 358.284304 -31.207007) (xy 358.288685 -31.2166) (xy 360.729782 -31.2166)
			(xy 360.733853 -31.160978) (xy 360.745979 -31.106541) (xy 360.765902 -31.05445) (xy 360.793198 -31.005815)
			(xy 360.827284 -30.961672) (xy 360.867433 -30.922963) (xy 360.912791 -30.890512) (xy 360.962391 -30.865011)
			(xy 361.015175 -30.847004) (xy 361.070018 -30.836874) (xy 361.125752 -30.834837) (xy 361.181189 -30.840937)
			(xy 361.235146 -30.855043) (xy 361.286475 -30.876855) (xy 361.334081 -30.905909) (xy 361.376949 -30.941584)
			(xy 361.414166 -30.983121) (xy 361.444939 -31.029634) (xy 361.468611 -31.080131) (xy 361.484679 -31.133538)
			(xy 361.492799 -31.188714) (xy 361.493308 -31.2166) (xy 361.492799 -31.244486) (xy 361.484679 -31.299662)
			(xy 361.468611 -31.353069) (xy 361.45126 -31.390082) (xy 362.166914 -31.390082) (xy 362.170985 -31.33446)
			(xy 362.183111 -31.280023) (xy 362.203034 -31.227932) (xy 362.23033 -31.179297) (xy 362.264416 -31.135154)
			(xy 362.304565 -31.096445) (xy 362.349923 -31.063994) (xy 362.399523 -31.038493) (xy 362.452307 -31.020486)
			(xy 362.50715 -31.010356) (xy 362.562884 -31.008319) (xy 362.618321 -31.014419) (xy 362.672278 -31.028525)
			(xy 362.723607 -31.050337) (xy 362.771213 -31.079391) (xy 362.814081 -31.115066) (xy 362.851298 -31.156603)
			(xy 362.882071 -31.203116) (xy 362.905743 -31.253613) (xy 362.921811 -31.30702) (xy 362.929931 -31.362196)
			(xy 362.93044 -31.390082) (xy 364.198914 -31.390082) (xy 364.202985 -31.33446) (xy 364.215111 -31.280023)
			(xy 364.235034 -31.227932) (xy 364.26233 -31.179297) (xy 364.296416 -31.135154) (xy 364.336565 -31.096445)
			(xy 364.381923 -31.063994) (xy 364.431523 -31.038493) (xy 364.484307 -31.020486) (xy 364.53915 -31.010356)
			(xy 364.594884 -31.008319) (xy 364.650321 -31.014419) (xy 364.704278 -31.028525) (xy 364.755607 -31.050337)
			(xy 364.803213 -31.079391) (xy 364.846081 -31.115066) (xy 364.883298 -31.156603) (xy 364.914071 -31.203116)
			(xy 364.937743 -31.253613) (xy 364.953811 -31.30702) (xy 364.961931 -31.362196) (xy 364.96244 -31.390082)
			(xy 364.961931 -31.417968) (xy 364.953811 -31.473144) (xy 364.937743 -31.526551) (xy 364.914071 -31.577048)
			(xy 364.883298 -31.623561) (xy 364.846081 -31.665098) (xy 364.827867 -31.680256) (xy 366.590227 -31.680256)
			(xy 366.590227 -31.625744) (xy 366.597985 -31.571787) (xy 366.613344 -31.519483) (xy 366.63599 -31.469897)
			(xy 366.665462 -31.42404) (xy 366.701162 -31.382843) (xy 366.74236 -31.347147) (xy 366.78822 -31.317677)
			(xy 366.837807 -31.295035) (xy 366.890112 -31.27968) (xy 366.94407 -31.271925) (xy 366.971326 -31.271464)
			(xy 366.997254 -31.271851) (xy 367.048634 -31.278862) (xy 367.098592 -31.292765) (xy 367.146207 -31.313303)
			(xy 367.190604 -31.3401) (xy 367.230963 -31.37266) (xy 367.266542 -31.410385) (xy 367.281968 -31.43123)
			(xy 367.287721 -31.43855) (xy 367.303214 -31.448843) (xy 367.312194 -31.451296) (xy 367.34242 -31.458154)
			(xy 367.351699 -31.459884) (xy 367.370359 -31.457154) (xy 367.378742 -31.45282) (xy 367.404726 -31.438562)
			(xy 367.459597 -31.416151) (xy 367.516898 -31.400995) (xy 367.575674 -31.393347) (xy 367.60531 -31.392876)
			(xy 367.634948 -31.393312) (xy 367.693731 -31.40094) (xy 367.751035 -31.416105) (xy 367.805896 -31.438553)
			(xy 367.831878 -31.45282) (xy 367.840292 -31.457064) (xy 367.858921 -31.4598) (xy 367.8682 -31.458154)
			(xy 367.898426 -31.451296) (xy 367.907415 -31.448857) (xy 367.922922 -31.438572) (xy 367.928652 -31.43123)
			(xy 367.944064 -31.410375) (xy 367.979638 -31.372642) (xy 368.019996 -31.340079) (xy 368.064396 -31.313285)
			(xy 368.112017 -31.292755) (xy 368.16198 -31.278868) (xy 368.213365 -31.27188) (xy 368.239294 -31.271464)
			(xy 368.266545 -31.271983) (xy 368.320493 -31.279739) (xy 368.372787 -31.295093) (xy 368.422365 -31.317733)
			(xy 368.468215 -31.347199) (xy 368.509406 -31.38289) (xy 368.545097 -31.42408) (xy 368.574564 -31.46993)
			(xy 368.597205 -31.519507) (xy 368.61256 -31.571801) (xy 368.620317 -31.625749) (xy 368.620317 -31.680251)
			(xy 368.61256 -31.734199) (xy 368.597205 -31.786493) (xy 368.574564 -31.83607) (xy 368.545097 -31.88192)
			(xy 368.509406 -31.92311) (xy 368.468215 -31.958801) (xy 368.422365 -31.988267) (xy 368.372787 -32.010907)
			(xy 368.320493 -32.026261) (xy 368.266545 -32.034017) (xy 368.239294 -32.03448) (xy 368.224501 -32.034347)
			(xy 368.195003 -32.032057) (xy 368.180366 -32.029908) (xy 368.169444 -32.02813) (xy 368.148108 -32.034226)
			(xy 368.080798 -32.09163) (xy 368.072863 -32.099251) (xy 368.06376 -32.119249) (xy 368.063272 -32.130238)
			(xy 368.063272 -32.43453) (xy 368.063769 -32.44552) (xy 368.072851 -32.465531) (xy 368.080798 -32.473138)
			(xy 368.148108 -32.530542) (xy 368.169444 -32.536638) (xy 368.180366 -32.53486) (xy 368.195004 -32.532717)
			(xy 368.224501 -32.53043) (xy 368.239294 -32.530288) (xy 368.266547 -32.530759) (xy 368.320498 -32.538515)
			(xy 368.372796 -32.55387) (xy 368.422376 -32.576512) (xy 368.46823 -32.60598) (xy 368.509423 -32.641673)
			(xy 368.545116 -32.682866) (xy 368.574585 -32.728718) (xy 368.597227 -32.778299) (xy 368.612584 -32.830596)
			(xy 368.620341 -32.884547) (xy 368.620341 -32.939053) (xy 368.612584 -32.993004) (xy 368.597227 -33.045301)
			(xy 368.574585 -33.094882) (xy 368.545116 -33.140734) (xy 368.509423 -33.181927) (xy 368.46823 -33.21762)
			(xy 368.422376 -33.247088) (xy 368.372796 -33.26973) (xy 368.320498 -33.285085) (xy 368.266547 -33.292841)
			(xy 368.239294 -33.293304) (xy 368.213368 -33.292874) (xy 368.16199 -33.285867) (xy 368.112035 -33.27197)
			(xy 368.064421 -33.251437) (xy 368.020024 -33.224648) (xy 367.979663 -33.192096) (xy 367.94408 -33.154379)
			(xy 367.928652 -33.133538) (xy 367.922899 -33.126219) (xy 367.907405 -33.115927) (xy 367.898426 -33.113472)
			(xy 367.8682 -33.106614) (xy 367.858921 -33.104886) (xy 367.84026 -33.107612) (xy 367.831878 -33.111948)
			(xy 367.805888 -33.126195) (xy 367.751019 -33.14861) (xy 367.69372 -33.163769) (xy 367.634945 -33.171419)
			(xy 367.60531 -33.171892) (xy 367.575672 -33.171452) (xy 367.516889 -33.163826) (xy 367.459585 -33.148662)
			(xy 367.404724 -33.126215) (xy 367.378742 -33.111948) (xy 367.370324 -33.107713) (xy 367.351698 -33.104972)
			(xy 367.34242 -33.106614) (xy 367.312194 -33.113472) (xy 367.303211 -33.115929) (xy 367.287702 -33.126202)
			(xy 367.281968 -33.133538) (xy 367.266534 -33.154377) (xy 367.230965 -33.192111) (xy 367.190611 -33.224677)
			(xy 367.146215 -33.251474) (xy 367.098598 -33.272006) (xy 367.048637 -33.285896) (xy 366.997254 -33.292887)
			(xy 366.971326 -33.293304) (xy 366.944072 -33.29285) (xy 366.890117 -33.285096) (xy 366.837816 -33.269742)
			(xy 366.788232 -33.247101) (xy 366.742375 -33.217634) (xy 366.701179 -33.18194) (xy 366.665482 -33.140746)
			(xy 366.636011 -33.094891) (xy 366.613367 -33.045309) (xy 366.598009 -32.993008) (xy 366.590251 -32.939054)
			(xy 366.590251 -32.884546) (xy 366.598009 -32.830592) (xy 366.613367 -32.778291) (xy 366.636011 -32.728709)
			(xy 366.665482 -32.682854) (xy 366.701179 -32.64166) (xy 366.742375 -32.605966) (xy 366.788232 -32.576499)
			(xy 366.837816 -32.553858) (xy 366.890117 -32.538504) (xy 366.944072 -32.53075) (xy 366.971326 -32.530288)
			(xy 366.986119 -32.530419) (xy 367.015617 -32.532711) (xy 367.030254 -32.53486) (xy 367.041176 -32.536638)
			(xy 367.062512 -32.530542) (xy 367.129822 -32.473138) (xy 367.137775 -32.465533) (xy 367.146867 -32.445522)
			(xy 367.147348 -32.43453) (xy 367.147348 -32.130238) (xy 367.146862 -32.119247) (xy 367.137772 -32.099236)
			(xy 367.129822 -32.09163) (xy 367.062512 -32.034226) (xy 367.041176 -32.02813) (xy 367.030254 -32.029908)
			(xy 367.015616 -32.032049) (xy 366.986119 -32.034337) (xy 366.971326 -32.03448) (xy 366.94407 -32.034075)
			(xy 366.890112 -32.02632) (xy 366.837807 -32.010965) (xy 366.78822 -31.988323) (xy 366.74236 -31.958853)
			(xy 366.701162 -31.923157) (xy 366.665462 -31.88196) (xy 366.63599 -31.836103) (xy 366.613344 -31.786517)
			(xy 366.597985 -31.734213) (xy 366.590227 -31.680256) (xy 364.827867 -31.680256) (xy 364.803213 -31.700773)
			(xy 364.755607 -31.729827) (xy 364.704278 -31.751639) (xy 364.650321 -31.765745) (xy 364.594884 -31.771845)
			(xy 364.53915 -31.769808) (xy 364.484307 -31.759678) (xy 364.431523 -31.741671) (xy 364.381923 -31.71617)
			(xy 364.336565 -31.683719) (xy 364.296416 -31.64501) (xy 364.26233 -31.600867) (xy 364.235034 -31.552232)
			(xy 364.215111 -31.500141) (xy 364.202985 -31.445704) (xy 364.198914 -31.390082) (xy 362.93044 -31.390082)
			(xy 362.929931 -31.417968) (xy 362.921811 -31.473144) (xy 362.905743 -31.526551) (xy 362.882071 -31.577048)
			(xy 362.851298 -31.623561) (xy 362.814081 -31.665098) (xy 362.771213 -31.700773) (xy 362.723607 -31.729827)
			(xy 362.672278 -31.751639) (xy 362.618321 -31.765745) (xy 362.562884 -31.771845) (xy 362.50715 -31.769808)
			(xy 362.452307 -31.759678) (xy 362.399523 -31.741671) (xy 362.349923 -31.71617) (xy 362.304565 -31.683719)
			(xy 362.264416 -31.64501) (xy 362.23033 -31.600867) (xy 362.203034 -31.552232) (xy 362.183111 -31.500141)
			(xy 362.170985 -31.445704) (xy 362.166914 -31.390082) (xy 361.45126 -31.390082) (xy 361.444939 -31.403566)
			(xy 361.414166 -31.450079) (xy 361.376949 -31.491616) (xy 361.334081 -31.527291) (xy 361.286475 -31.556345)
			(xy 361.235146 -31.578157) (xy 361.181189 -31.592263) (xy 361.125752 -31.598363) (xy 361.070018 -31.596326)
			(xy 361.015175 -31.586196) (xy 360.962391 -31.568189) (xy 360.912791 -31.542688) (xy 360.867433 -31.510237)
			(xy 360.827284 -31.471528) (xy 360.793198 -31.427385) (xy 360.765902 -31.37875) (xy 360.745979 -31.326659)
			(xy 360.733853 -31.272222) (xy 360.729782 -31.2166) (xy 358.288685 -31.2166) (xy 358.306948 -31.25659)
			(xy 358.322306 -31.308891) (xy 358.330063 -31.362845) (xy 358.330063 -31.417355) (xy 358.322306 -31.471309)
			(xy 358.306948 -31.52361) (xy 358.284304 -31.573193) (xy 358.254834 -31.619049) (xy 358.219138 -31.660243)
			(xy 358.177942 -31.695939) (xy 358.132086 -31.725408) (xy 358.082502 -31.748051) (xy 358.030201 -31.763407)
			(xy 357.976247 -31.771164) (xy 357.948992 -31.77159) (xy 357.946198 -31.77159) (xy 357.93623 -31.772064)
			(xy 357.917789 -31.779635) (xy 357.910384 -31.786322) (xy 357.859076 -31.837122) (xy 357.852225 -31.844518)
			(xy 357.844486 -31.863117) (xy 357.84409 -31.87319) (xy 357.84409 -32.707072) (xy 357.844526 -32.717137)
			(xy 357.852257 -32.735723) (xy 357.859076 -32.74314) (xy 357.910384 -32.79394) (xy 357.917795 -32.800623)
			(xy 357.93623 -32.808204) (xy 357.946198 -32.808672) (xy 357.948992 -32.808672) (xy 357.976247 -32.809134)
			(xy 358.030201 -32.816891) (xy 358.082503 -32.832247) (xy 358.132087 -32.85489) (xy 358.177943 -32.88436)
			(xy 358.219139 -32.920055) (xy 358.254836 -32.96125) (xy 358.284306 -33.007106) (xy 358.30695 -33.05669)
			(xy 358.322307 -33.108991) (xy 358.330065 -33.162945) (xy 358.330065 -33.19018) (xy 359.974132 -33.19018)
			(xy 359.978203 -33.134558) (xy 359.990329 -33.080121) (xy 360.010252 -33.02803) (xy 360.037548 -32.979395)
			(xy 360.071634 -32.935252) (xy 360.111783 -32.896543) (xy 360.157141 -32.864092) (xy 360.206741 -32.838591)
			(xy 360.259525 -32.820584) (xy 360.314368 -32.810454) (xy 360.370102 -32.808417) (xy 360.425539 -32.814517)
			(xy 360.479496 -32.828623) (xy 360.530825 -32.850435) (xy 360.578431 -32.879489) (xy 360.621299 -32.915164)
			(xy 360.658516 -32.956701) (xy 360.689289 -33.003214) (xy 360.712961 -33.053711) (xy 360.729029 -33.107118)
			(xy 360.737149 -33.162294) (xy 360.737658 -33.19018) (xy 362.166914 -33.19018) (xy 362.170985 -33.134558)
			(xy 362.183111 -33.080121) (xy 362.203034 -33.02803) (xy 362.23033 -32.979395) (xy 362.264416 -32.935252)
			(xy 362.304565 -32.896543) (xy 362.349923 -32.864092) (xy 362.399523 -32.838591) (xy 362.452307 -32.820584)
			(xy 362.50715 -32.810454) (xy 362.562884 -32.808417) (xy 362.618321 -32.814517) (xy 362.672278 -32.828623)
			(xy 362.723607 -32.850435) (xy 362.771213 -32.879489) (xy 362.814081 -32.915164) (xy 362.851298 -32.956701)
			(xy 362.882071 -33.003214) (xy 362.905743 -33.053711) (xy 362.921811 -33.107118) (xy 362.929931 -33.162294)
			(xy 362.93044 -33.19018) (xy 364.198914 -33.19018) (xy 364.202985 -33.134558) (xy 364.215111 -33.080121)
			(xy 364.235034 -33.02803) (xy 364.26233 -32.979395) (xy 364.296416 -32.935252) (xy 364.336565 -32.896543)
			(xy 364.381923 -32.864092) (xy 364.431523 -32.838591) (xy 364.484307 -32.820584) (xy 364.53915 -32.810454)
			(xy 364.594884 -32.808417) (xy 364.650321 -32.814517) (xy 364.704278 -32.828623) (xy 364.755607 -32.850435)
			(xy 364.803213 -32.879489) (xy 364.846081 -32.915164) (xy 364.883298 -32.956701) (xy 364.914071 -33.003214)
			(xy 364.937743 -33.053711) (xy 364.953811 -33.107118) (xy 364.961931 -33.162294) (xy 364.96244 -33.19018)
			(xy 364.961931 -33.218066) (xy 364.953811 -33.273242) (xy 364.937743 -33.326649) (xy 364.914071 -33.377146)
			(xy 364.883298 -33.423659) (xy 364.846081 -33.465196) (xy 364.803213 -33.500871) (xy 364.755607 -33.529925)
			(xy 364.704278 -33.551737) (xy 364.650321 -33.565843) (xy 364.594884 -33.571943) (xy 364.53915 -33.569906)
			(xy 364.484307 -33.559776) (xy 364.431523 -33.541769) (xy 364.381923 -33.516268) (xy 364.336565 -33.483817)
			(xy 364.296416 -33.445108) (xy 364.26233 -33.400965) (xy 364.235034 -33.35233) (xy 364.215111 -33.300239)
			(xy 364.202985 -33.245802) (xy 364.198914 -33.19018) (xy 362.93044 -33.19018) (xy 362.929931 -33.218066)
			(xy 362.921811 -33.273242) (xy 362.905743 -33.326649) (xy 362.882071 -33.377146) (xy 362.851298 -33.423659)
			(xy 362.814081 -33.465196) (xy 362.771213 -33.500871) (xy 362.723607 -33.529925) (xy 362.672278 -33.551737)
			(xy 362.618321 -33.565843) (xy 362.562884 -33.571943) (xy 362.50715 -33.569906) (xy 362.452307 -33.559776)
			(xy 362.399523 -33.541769) (xy 362.349923 -33.516268) (xy 362.304565 -33.483817) (xy 362.264416 -33.445108)
			(xy 362.23033 -33.400965) (xy 362.203034 -33.35233) (xy 362.183111 -33.300239) (xy 362.170985 -33.245802)
			(xy 362.166914 -33.19018) (xy 360.737658 -33.19018) (xy 360.737149 -33.218066) (xy 360.729029 -33.273242)
			(xy 360.712961 -33.326649) (xy 360.689289 -33.377146) (xy 360.658516 -33.423659) (xy 360.621299 -33.465196)
			(xy 360.578431 -33.500871) (xy 360.530825 -33.529925) (xy 360.479496 -33.551737) (xy 360.425539 -33.565843)
			(xy 360.370102 -33.571943) (xy 360.314368 -33.569906) (xy 360.259525 -33.559776) (xy 360.206741 -33.541769)
			(xy 360.157141 -33.516268) (xy 360.111783 -33.483817) (xy 360.071634 -33.445108) (xy 360.037548 -33.400965)
			(xy 360.010252 -33.35233) (xy 359.990329 -33.300239) (xy 359.978203 -33.245802) (xy 359.974132 -33.19018)
			(xy 358.330065 -33.19018) (xy 358.330065 -33.217455) (xy 358.322307 -33.271409) (xy 358.30695 -33.32371)
			(xy 358.284306 -33.373294) (xy 358.254836 -33.41915) (xy 358.219139 -33.460345) (xy 358.177943 -33.49604)
			(xy 358.132087 -33.52551) (xy 358.082503 -33.548153) (xy 358.030201 -33.563509) (xy 357.976247 -33.571266)
			(xy 357.948992 -33.571688) (xy 357.946198 -33.571688) (xy 357.93623 -33.572162) (xy 357.917788 -33.579732)
			(xy 357.910384 -33.58642) (xy 357.859076 -33.63722) (xy 357.852225 -33.644616) (xy 357.844485 -33.663215)
			(xy 357.84409 -33.673288) (xy 357.84409 -34.506916) (xy 357.844516 -34.516985) (xy 357.852233 -34.535586)
			(xy 357.859076 -34.542984) (xy 357.910384 -34.593784) (xy 357.917792 -34.600472) (xy 357.936228 -34.608063)
			(xy 357.946198 -34.608516) (xy 357.948992 -34.608516) (xy 357.976244 -34.608979) (xy 358.030192 -34.616734)
			(xy 358.082487 -34.632089) (xy 358.132065 -34.654729) (xy 358.177917 -34.684195) (xy 358.219108 -34.719887)
			(xy 358.2548 -34.761077) (xy 358.284267 -34.806928) (xy 358.306909 -34.856505) (xy 358.322264 -34.9088)
			(xy 358.330021 -34.962748) (xy 358.330021 -34.990024) (xy 359.972862 -34.990024) (xy 359.976933 -34.934402)
			(xy 359.989059 -34.879965) (xy 360.008982 -34.827874) (xy 360.036278 -34.779239) (xy 360.070364 -34.735096)
			(xy 360.110513 -34.696387) (xy 360.155871 -34.663936) (xy 360.205471 -34.638435) (xy 360.258255 -34.620428)
			(xy 360.313098 -34.610298) (xy 360.368832 -34.608261) (xy 360.424269 -34.614361) (xy 360.478226 -34.628467)
			(xy 360.529555 -34.650279) (xy 360.577161 -34.679333) (xy 360.620029 -34.715008) (xy 360.657246 -34.756545)
			(xy 360.688019 -34.803058) (xy 360.711691 -34.853555) (xy 360.727759 -34.906962) (xy 360.735879 -34.962138)
			(xy 360.736388 -34.990024) (xy 361.190792 -34.990024) (xy 361.194863 -34.934402) (xy 361.206989 -34.879965)
			(xy 361.226912 -34.827874) (xy 361.254208 -34.779239) (xy 361.288294 -34.735096) (xy 361.328443 -34.696387)
			(xy 361.373801 -34.663936) (xy 361.423401 -34.638435) (xy 361.476185 -34.620428) (xy 361.531028 -34.610298)
			(xy 361.586762 -34.608261) (xy 361.642199 -34.614361) (xy 361.696156 -34.628467) (xy 361.747485 -34.650279)
			(xy 361.795091 -34.679333) (xy 361.837959 -34.715008) (xy 361.875176 -34.756545) (xy 361.905949 -34.803058)
			(xy 361.929621 -34.853555) (xy 361.945689 -34.906962) (xy 361.953809 -34.962138) (xy 361.954318 -34.990024)
			(xy 364.198914 -34.990024) (xy 364.202985 -34.934402) (xy 364.215111 -34.879965) (xy 364.235034 -34.827874)
			(xy 364.26233 -34.779239) (xy 364.296416 -34.735096) (xy 364.336565 -34.696387) (xy 364.381923 -34.663936)
			(xy 364.431523 -34.638435) (xy 364.484307 -34.620428) (xy 364.53915 -34.610298) (xy 364.594884 -34.608261)
			(xy 364.650321 -34.614361) (xy 364.704278 -34.628467) (xy 364.755607 -34.650279) (xy 364.803213 -34.679333)
			(xy 364.846081 -34.715008) (xy 364.883298 -34.756545) (xy 364.914071 -34.803058) (xy 364.937743 -34.853555)
			(xy 364.953811 -34.906962) (xy 364.961931 -34.962138) (xy 364.96244 -34.990024) (xy 364.961931 -35.01791)
			(xy 364.953811 -35.073086) (xy 364.937743 -35.126493) (xy 364.914071 -35.17699) (xy 364.883298 -35.223503)
			(xy 364.846081 -35.26504) (xy 364.803213 -35.300715) (xy 364.755607 -35.329769) (xy 364.704278 -35.351581)
			(xy 364.650321 -35.365687) (xy 364.594884 -35.371787) (xy 364.53915 -35.36975) (xy 364.484307 -35.35962)
			(xy 364.431523 -35.341613) (xy 364.381923 -35.316112) (xy 364.336565 -35.283661) (xy 364.296416 -35.244952)
			(xy 364.26233 -35.200809) (xy 364.235034 -35.152174) (xy 364.215111 -35.100083) (xy 364.202985 -35.045646)
			(xy 364.198914 -34.990024) (xy 361.954318 -34.990024) (xy 361.953809 -35.01791) (xy 361.945689 -35.073086)
			(xy 361.929621 -35.126493) (xy 361.905949 -35.17699) (xy 361.875176 -35.223503) (xy 361.837959 -35.26504)
			(xy 361.795091 -35.300715) (xy 361.747485 -35.329769) (xy 361.696156 -35.351581) (xy 361.642199 -35.365687)
			(xy 361.586762 -35.371787) (xy 361.531028 -35.36975) (xy 361.476185 -35.35962) (xy 361.423401 -35.341613)
			(xy 361.373801 -35.316112) (xy 361.328443 -35.283661) (xy 361.288294 -35.244952) (xy 361.254208 -35.200809)
			(xy 361.226912 -35.152174) (xy 361.206989 -35.100083) (xy 361.194863 -35.045646) (xy 361.190792 -34.990024)
			(xy 360.736388 -34.990024) (xy 360.735879 -35.01791) (xy 360.727759 -35.073086) (xy 360.711691 -35.126493)
			(xy 360.688019 -35.17699) (xy 360.657246 -35.223503) (xy 360.620029 -35.26504) (xy 360.577161 -35.300715)
			(xy 360.529555 -35.329769) (xy 360.478226 -35.351581) (xy 360.424269 -35.365687) (xy 360.368832 -35.371787)
			(xy 360.313098 -35.36975) (xy 360.258255 -35.35962) (xy 360.205471 -35.341613) (xy 360.155871 -35.316112)
			(xy 360.110513 -35.283661) (xy 360.070364 -35.244952) (xy 360.036278 -35.200809) (xy 360.008982 -35.152174)
			(xy 359.989059 -35.100083) (xy 359.976933 -35.045646) (xy 359.972862 -34.990024) (xy 358.330021 -34.990024)
			(xy 358.330021 -35.017252) (xy 358.322264 -35.0712) (xy 358.306909 -35.123495) (xy 358.284267 -35.173072)
			(xy 358.2548 -35.218923) (xy 358.219108 -35.260113) (xy 358.177917 -35.295805) (xy 358.132065 -35.325271)
			(xy 358.082487 -35.347911) (xy 358.030192 -35.363266) (xy 357.976244 -35.371021) (xy 357.948992 -35.371532)
			(xy 357.946198 -35.371532) (xy 357.936231 -35.372007) (xy 357.917793 -35.379582) (xy 357.910384 -35.386264)
			(xy 357.859076 -35.437064) (xy 357.852232 -35.444462) (xy 357.844508 -35.463061) (xy 357.84409 -35.473132)
			(xy 357.84409 -38.193435) (xy 359.398386 -38.193435) (xy 359.398386 -38.106565) (xy 359.406401 -38.020065)
			(xy 359.422363 -37.934673) (xy 359.446135 -37.851119) (xy 359.477516 -37.770114) (xy 359.516236 -37.69235)
			(xy 359.561967 -37.618491) (xy 359.614317 -37.549166) (xy 359.67284 -37.484967) (xy 359.737037 -37.426441)
			(xy 359.80636 -37.374088) (xy 359.880217 -37.328355) (xy 359.957979 -37.289631) (xy 360.038983 -37.258247)
			(xy 360.122536 -37.234471) (xy 360.207927 -37.218506) (xy 360.294427 -37.210487) (xy 360.337862 -37.209984)
			(xy 360.41584 -37.209984) (xy 360.425852 -37.209544) (xy 360.444348 -37.201869) (xy 360.4585 -37.187701)
			(xy 360.466155 -37.169197) (xy 360.46664 -37.159184) (xy 360.46664 -37.151564) (xy 360.462322 -37.137594)
			(xy 360.458258 -37.131244) (xy 360.434339 -37.094009) (xy 360.392638 -37.015944) (xy 360.358253 -36.93439)
			(xy 360.331475 -36.850033) (xy 360.312526 -36.76358) (xy 360.301566 -36.675755) (xy 360.298688 -36.587297)
			(xy 360.303915 -36.498946) (xy 360.317203 -36.411443) (xy 360.338441 -36.325524) (xy 360.36745 -36.241908)
			(xy 360.403988 -36.161296) (xy 360.447749 -36.084366) (xy 360.498363 -36.011762) (xy 360.555409 -35.944093)
			(xy 360.618406 -35.881927) (xy 360.686826 -35.825786) (xy 360.760096 -35.776139) (xy 360.837601 -35.733405)
			(xy 360.91869 -35.69794) (xy 361.002684 -35.670044) (xy 361.088878 -35.649948) (xy 361.176549 -35.637824)
			(xy 361.264962 -35.633771) (xy 361.353375 -35.637824) (xy 361.441046 -35.649948) (xy 361.52724 -35.670044)
			(xy 361.611234 -35.69794) (xy 361.692323 -35.733405) (xy 361.769828 -35.776139) (xy 361.843098 -35.825786)
			(xy 361.905194 -35.876738) (xy 367.017298 -35.876738) (xy 367.021369 -35.821116) (xy 367.033495 -35.766679)
			(xy 367.053418 -35.714588) (xy 367.080714 -35.665953) (xy 367.1148 -35.62181) (xy 367.154949 -35.583101)
			(xy 367.200307 -35.55065) (xy 367.249907 -35.525149) (xy 367.302691 -35.507142) (xy 367.357534 -35.497012)
			(xy 367.413268 -35.494975) (xy 367.468705 -35.501075) (xy 367.522662 -35.515181) (xy 367.573991 -35.536993)
			(xy 367.621597 -35.566047) (xy 367.664465 -35.601722) (xy 367.701682 -35.643259) (xy 367.732455 -35.689772)
			(xy 367.756127 -35.740269) (xy 367.772195 -35.793676) (xy 367.780315 -35.848852) (xy 367.780824 -35.876738)
			(xy 367.780315 -35.904624) (xy 367.772195 -35.9598) (xy 367.756127 -36.013207) (xy 367.732455 -36.063704)
			(xy 367.701682 -36.110217) (xy 367.664465 -36.151754) (xy 367.621597 -36.187429) (xy 367.573991 -36.216483)
			(xy 367.522662 -36.238295) (xy 367.468705 -36.252401) (xy 367.413268 -36.258501) (xy 367.357534 -36.256464)
			(xy 367.302691 -36.246334) (xy 367.249907 -36.228327) (xy 367.200307 -36.202826) (xy 367.154949 -36.170375)
			(xy 367.1148 -36.131666) (xy 367.080714 -36.087523) (xy 367.053418 -36.038888) (xy 367.033495 -35.986797)
			(xy 367.021369 -35.93236) (xy 367.017298 -35.876738) (xy 361.905194 -35.876738) (xy 361.911518 -35.881927)
			(xy 361.974515 -35.944093) (xy 362.031561 -36.011762) (xy 362.082175 -36.084366) (xy 362.125936 -36.161296)
			(xy 362.162474 -36.241908) (xy 362.191483 -36.325524) (xy 362.212721 -36.411443) (xy 362.226009 -36.498946)
			(xy 362.228434 -36.539928) (xy 368.838716 -36.539928) (xy 368.838716 -36.479992) (xy 368.846539 -36.42057)
			(xy 368.862052 -36.362677) (xy 368.884988 -36.307304) (xy 368.914955 -36.255398) (xy 368.951442 -36.207848)
			(xy 368.993822 -36.165468) (xy 369.041372 -36.128981) (xy 369.093278 -36.099014) (xy 369.148651 -36.076078)
			(xy 369.206544 -36.060565) (xy 369.265966 -36.052742) (xy 369.325902 -36.052742) (xy 369.385324 -36.060565)
			(xy 369.443217 -36.076078) (xy 369.49859 -36.099014) (xy 369.550496 -36.128981) (xy 369.598046 -36.165468)
			(xy 369.640426 -36.207848) (xy 369.676913 -36.255398) (xy 369.70688 -36.307304) (xy 369.729816 -36.362677)
			(xy 369.745329 -36.42057) (xy 369.753152 -36.479992) (xy 369.753642 -36.50996) (xy 369.753152 -36.539928)
			(xy 369.745329 -36.59935) (xy 369.729816 -36.657243) (xy 369.70688 -36.712616) (xy 369.676913 -36.764522)
			(xy 369.640426 -36.812072) (xy 369.598046 -36.854452) (xy 369.550496 -36.890939) (xy 369.49859 -36.920906)
			(xy 369.443217 -36.943842) (xy 369.385324 -36.959355) (xy 369.325902 -36.967178) (xy 369.265966 -36.967178)
			(xy 369.206544 -36.959355) (xy 369.148651 -36.943842) (xy 369.093278 -36.920906) (xy 369.041372 -36.890939)
			(xy 368.993822 -36.854452) (xy 368.951442 -36.812072) (xy 368.914955 -36.764522) (xy 368.884988 -36.712616)
			(xy 368.862052 -36.657243) (xy 368.846539 -36.59935) (xy 368.838716 -36.539928) (xy 362.228434 -36.539928)
			(xy 362.231236 -36.587297) (xy 362.228358 -36.675755) (xy 362.217398 -36.76358) (xy 362.198449 -36.850033)
			(xy 362.171671 -36.93439) (xy 362.137286 -37.015944) (xy 362.095585 -37.094009) (xy 362.071666 -37.131244)
			(xy 362.063284 -37.143944) (xy 362.063284 -37.159184) (xy 362.063801 -37.169189) (xy 362.071452 -37.187677)
			(xy 362.085596 -37.20183) (xy 362.10408 -37.209493) (xy 362.114084 -37.209984) (xy 362.192062 -37.209984)
			(xy 362.235504 -37.210393) (xy 362.322017 -37.218406) (xy 362.407421 -37.234368) (xy 362.490989 -37.258142)
			(xy 362.572006 -37.289525) (xy 362.649782 -37.32825) (xy 362.723653 -37.373987) (xy 362.792989 -37.426344)
			(xy 362.84654 -37.47516) (xy 366.05921 -37.47516) (xy 366.063281 -37.419538) (xy 366.075407 -37.365101)
			(xy 366.09533 -37.31301) (xy 366.122626 -37.264375) (xy 366.156712 -37.220232) (xy 366.196861 -37.181523)
			(xy 366.242219 -37.149072) (xy 366.291819 -37.123571) (xy 366.344603 -37.105564) (xy 366.399446 -37.095434)
			(xy 366.45518 -37.093397) (xy 366.510617 -37.099497) (xy 366.564574 -37.113603) (xy 366.615903 -37.135415)
			(xy 366.663509 -37.164469) (xy 366.706377 -37.200144) (xy 366.743594 -37.241681) (xy 366.774367 -37.288194)
			(xy 366.798039 -37.338691) (xy 366.814107 -37.392098) (xy 366.822227 -37.447274) (xy 366.822736 -37.47516)
			(xy 366.822227 -37.503046) (xy 366.814107 -37.558222) (xy 366.798039 -37.611629) (xy 366.774367 -37.662126)
			(xy 366.754387 -37.692326) (xy 368.173236 -37.692326) (xy 368.173236 -37.63239) (xy 368.181059 -37.572968)
			(xy 368.196572 -37.515075) (xy 368.219508 -37.459702) (xy 368.249475 -37.407796) (xy 368.285962 -37.360246)
			(xy 368.328342 -37.317866) (xy 368.375892 -37.281379) (xy 368.427798 -37.251412) (xy 368.483171 -37.228476)
			(xy 368.541064 -37.212963) (xy 368.600486 -37.20514) (xy 368.660422 -37.20514) (xy 368.719844 -37.212963)
			(xy 368.777737 -37.228476) (xy 368.83311 -37.251412) (xy 368.885016 -37.281379) (xy 368.932566 -37.317866)
			(xy 368.974946 -37.360246) (xy 369.011433 -37.407796) (xy 369.0414 -37.459702) (xy 369.064336 -37.515075)
			(xy 369.079849 -37.572968) (xy 369.087672 -37.63239) (xy 369.088162 -37.662358) (xy 369.087672 -37.692326)
			(xy 369.079849 -37.751748) (xy 369.064336 -37.809641) (xy 369.0414 -37.865014) (xy 369.011433 -37.91692)
			(xy 368.974946 -37.96447) (xy 368.932566 -38.00685) (xy 368.885016 -38.043337) (xy 368.83311 -38.073304)
			(xy 368.777737 -38.09624) (xy 368.719844 -38.111753) (xy 368.660422 -38.119576) (xy 368.600486 -38.119576)
			(xy 368.541064 -38.111753) (xy 368.483171 -38.09624) (xy 368.427798 -38.073304) (xy 368.375892 -38.043337)
			(xy 368.328342 -38.00685) (xy 368.285962 -37.96447) (xy 368.249475 -37.91692) (xy 368.219508 -37.865014)
			(xy 368.196572 -37.809641) (xy 368.181059 -37.751748) (xy 368.173236 -37.692326) (xy 366.754387 -37.692326)
			(xy 366.743594 -37.708639) (xy 366.706377 -37.750176) (xy 366.663509 -37.785851) (xy 366.615903 -37.814905)
			(xy 366.564574 -37.836717) (xy 366.510617 -37.850823) (xy 366.45518 -37.856923) (xy 366.399446 -37.854886)
			(xy 366.344603 -37.844756) (xy 366.291819 -37.826749) (xy 366.242219 -37.801248) (xy 366.196861 -37.768797)
			(xy 366.156712 -37.730088) (xy 366.122626 -37.685945) (xy 366.09533 -37.63731) (xy 366.075407 -37.585219)
			(xy 366.063281 -37.530782) (xy 366.05921 -37.47516) (xy 362.84654 -37.47516) (xy 362.857198 -37.484876)
			(xy 362.915732 -37.549082) (xy 362.968092 -37.618416) (xy 363.013831 -37.692285) (xy 363.052559 -37.770059)
			(xy 363.083946 -37.851075) (xy 363.107723 -37.934642) (xy 363.123689 -38.020046) (xy 363.131705 -38.106558)
			(xy 363.131705 -38.193442) (xy 363.123689 -38.279954) (xy 363.107723 -38.365358) (xy 363.083946 -38.448925)
			(xy 363.067583 -38.49116) (xy 366.05921 -38.49116) (xy 366.063281 -38.435538) (xy 366.075407 -38.381101)
			(xy 366.09533 -38.32901) (xy 366.122626 -38.280375) (xy 366.156712 -38.236232) (xy 366.196861 -38.197523)
			(xy 366.242219 -38.165072) (xy 366.291819 -38.139571) (xy 366.344603 -38.121564) (xy 366.399446 -38.111434)
			(xy 366.45518 -38.109397) (xy 366.510617 -38.115497) (xy 366.564574 -38.129603) (xy 366.615903 -38.151415)
			(xy 366.663509 -38.180469) (xy 366.706377 -38.216144) (xy 366.743594 -38.257681) (xy 366.774367 -38.304194)
			(xy 366.798039 -38.354691) (xy 366.814107 -38.408098) (xy 366.822227 -38.463274) (xy 366.822736 -38.49116)
			(xy 366.822227 -38.519046) (xy 366.814107 -38.574222) (xy 366.798039 -38.627629) (xy 366.774367 -38.678126)
			(xy 366.759089 -38.701218) (xy 369.737638 -38.701218) (xy 369.741709 -38.645596) (xy 369.753835 -38.591159)
			(xy 369.773758 -38.539068) (xy 369.801054 -38.490433) (xy 369.83514 -38.44629) (xy 369.875289 -38.407581)
			(xy 369.920647 -38.37513) (xy 369.970247 -38.349629) (xy 370.023031 -38.331622) (xy 370.077874 -38.321492)
			(xy 370.133608 -38.319455) (xy 370.189045 -38.325555) (xy 370.243002 -38.339661) (xy 370.294331 -38.361473)
			(xy 370.341937 -38.390527) (xy 370.384805 -38.426202) (xy 370.422022 -38.467739) (xy 370.452795 -38.514252)
			(xy 370.476467 -38.564749) (xy 370.492535 -38.618156) (xy 370.500655 -38.673332) (xy 370.501164 -38.701218)
			(xy 370.500655 -38.729104) (xy 370.492535 -38.78428) (xy 370.476467 -38.837687) (xy 370.452795 -38.888184)
			(xy 370.422022 -38.934697) (xy 370.384805 -38.976234) (xy 370.341937 -39.011909) (xy 370.294331 -39.040963)
			(xy 370.243002 -39.062775) (xy 370.189045 -39.076881) (xy 370.133608 -39.082981) (xy 370.077874 -39.080944)
			(xy 370.023031 -39.070814) (xy 369.970247 -39.052807) (xy 369.920647 -39.027306) (xy 369.875289 -38.994855)
			(xy 369.83514 -38.956146) (xy 369.801054 -38.912003) (xy 369.773758 -38.863368) (xy 369.753835 -38.811277)
			(xy 369.741709 -38.75684) (xy 369.737638 -38.701218) (xy 366.759089 -38.701218) (xy 366.743594 -38.724639)
			(xy 366.706377 -38.766176) (xy 366.663509 -38.801851) (xy 366.615903 -38.830905) (xy 366.564574 -38.852717)
			(xy 366.510617 -38.866823) (xy 366.45518 -38.872923) (xy 366.399446 -38.870886) (xy 366.344603 -38.860756)
			(xy 366.291819 -38.842749) (xy 366.242219 -38.817248) (xy 366.196861 -38.784797) (xy 366.156712 -38.746088)
			(xy 366.122626 -38.701945) (xy 366.09533 -38.65331) (xy 366.075407 -38.601219) (xy 366.063281 -38.546782)
			(xy 366.05921 -38.49116) (xy 363.067583 -38.49116) (xy 363.052559 -38.529941) (xy 363.013831 -38.607715)
			(xy 362.968092 -38.681584) (xy 362.915732 -38.750918) (xy 362.857198 -38.815124) (xy 362.792989 -38.873656)
			(xy 362.723653 -38.926013) (xy 362.649782 -38.97175) (xy 362.572006 -39.010475) (xy 362.490989 -39.041858)
			(xy 362.407421 -39.065632) (xy 362.322017 -39.081594) (xy 362.235504 -39.089607) (xy 362.192062 -39.090092)
			(xy 360.337862 -39.090092) (xy 360.294427 -39.089513) (xy 360.207927 -39.081494) (xy 360.122536 -39.065529)
			(xy 360.038983 -39.041753) (xy 359.957979 -39.010369) (xy 359.880217 -38.971645) (xy 359.80636 -38.925912)
			(xy 359.737037 -38.873559) (xy 359.67284 -38.815033) (xy 359.614317 -38.750834) (xy 359.561967 -38.681509)
			(xy 359.516236 -38.60765) (xy 359.477516 -38.529886) (xy 359.446135 -38.448881) (xy 359.422363 -38.365327)
			(xy 359.406401 -38.279935) (xy 359.398386 -38.193435) (xy 357.84409 -38.193435) (xy 357.84409 -42.849038)
			(xy 369.192046 -42.849038) (xy 369.196117 -42.793416) (xy 369.208243 -42.738979) (xy 369.228166 -42.686888)
			(xy 369.255462 -42.638253) (xy 369.289548 -42.59411) (xy 369.329697 -42.555401) (xy 369.375055 -42.52295)
			(xy 369.424655 -42.497449) (xy 369.477439 -42.479442) (xy 369.532282 -42.469312) (xy 369.588016 -42.467275)
			(xy 369.643453 -42.473375) (xy 369.69741 -42.487481) (xy 369.748739 -42.509293) (xy 369.796345 -42.538347)
			(xy 369.839213 -42.574022) (xy 369.87643 -42.615559) (xy 369.907203 -42.662072) (xy 369.930875 -42.712569)
			(xy 369.946943 -42.765976) (xy 369.955063 -42.821152) (xy 369.955572 -42.849038) (xy 369.955063 -42.876924)
			(xy 369.946943 -42.9321) (xy 369.930875 -42.985507) (xy 369.907203 -43.036004) (xy 369.87643 -43.082517)
			(xy 369.839213 -43.124054) (xy 369.796345 -43.159729) (xy 369.748739 -43.188783) (xy 369.69741 -43.210595)
			(xy 369.643453 -43.224701) (xy 369.588016 -43.230801) (xy 369.532282 -43.228764) (xy 369.477439 -43.218634)
			(xy 369.424655 -43.200627) (xy 369.375055 -43.175126) (xy 369.329697 -43.142675) (xy 369.289548 -43.103966)
			(xy 369.255462 -43.059823) (xy 369.228166 -43.011188) (xy 369.208243 -42.959097) (xy 369.196117 -42.90466)
			(xy 369.192046 -42.849038) (xy 357.84409 -42.849038) (xy 357.84409 -43.719242) (xy 357.844554 -43.729117)
			(xy 357.852003 -43.747411) (xy 357.858568 -43.754802) (xy 357.858822 -43.755056) (xy 358.33685 -44.233084)
			(xy 358.337358 -44.233592) (xy 358.344741 -44.240169) (xy 358.36304 -44.247612) (xy 358.372918 -44.24807)
		)
		(stroke
			(width 0)
			(type solid)
		)
		(fill yes)
		(layer "B.Cu")
		(net "P12V_SSD12")
	)
	(gr_poly
		(pts
			(xy 394.514832 -44.24807) (xy 394.525012 -44.247628) (xy 394.543774 -44.239725) (xy 394.557977 -44.225139)
			(xy 394.562076 -44.215812) (xy 394.602462 -44.112942) (xy 394.595604 -44.082716) (xy 394.58392 -44.072048)
			(xy 394.561228 -44.050301) (xy 394.521414 -44.001668) (xy 394.488625 -43.948046) (xy 394.463476 -43.890445)
			(xy 394.44644 -43.829946) (xy 394.437837 -43.767686) (xy 394.437362 -43.73626) (xy 394.437852 -43.706292)
			(xy 394.445675 -43.64687) (xy 394.461188 -43.588977) (xy 394.484124 -43.533604) (xy 394.514091 -43.481698)
			(xy 394.550578 -43.434148) (xy 394.592958 -43.391768) (xy 394.640508 -43.355281) (xy 394.692414 -43.325314)
			(xy 394.747787 -43.302378) (xy 394.80568 -43.286865) (xy 394.865102 -43.279042) (xy 394.925038 -43.279042)
			(xy 394.98446 -43.286865) (xy 395.042353 -43.302378) (xy 395.097726 -43.325314) (xy 395.149632 -43.355281)
			(xy 395.197182 -43.391768) (xy 395.239562 -43.434148) (xy 395.276049 -43.481698) (xy 395.306016 -43.533604)
			(xy 395.328952 -43.588977) (xy 395.344465 -43.64687) (xy 395.352288 -43.706292) (xy 395.352778 -43.73626)
			(xy 395.352697 -43.748987) (xy 395.351301 -43.774401) (xy 395.349984 -43.78706) (xy 395.350238 -43.78706)
			(xy 395.346029 -43.819423) (xy 395.32962 -43.882587) (xy 395.304404 -43.942779) (xy 395.270892 -43.998778)
			(xy 395.229764 -44.049447) (xy 395.20622 -44.072048) (xy 395.19479 -44.08297) (xy 395.187678 -44.113196)
			(xy 395.228064 -44.215812) (xy 395.232202 -44.225113) (xy 395.246402 -44.239678) (xy 395.265138 -44.247597)
			(xy 395.275308 -44.24807) (xy 396.177516 -44.24807) (xy 396.187393 -44.24761) (xy 396.205689 -44.240164)
			(xy 396.213076 -44.233592) (xy 396.21333 -44.233338) (xy 396.772638 -43.67403) (xy 396.773146 -43.673522)
			(xy 396.779725 -43.66614) (xy 396.787167 -43.647841) (xy 396.787624 -43.637962) (xy 396.787624 -37.58946)
			(xy 396.787197 -37.580069) (xy 396.780457 -37.562538) (xy 396.767885 -37.548584) (xy 396.759684 -37.543994)
			(xy 396.678912 -37.5031) (xy 396.670306 -37.499259) (xy 396.651565 -37.497426) (xy 396.633416 -37.502444)
			(xy 396.625572 -37.507672) (xy 396.600777 -37.525306) (xy 396.546762 -37.553307) (xy 396.488987 -37.572377)
			(xy 396.428917 -37.582035) (xy 396.398496 -37.582602) (xy 396.371245 -37.582116) (xy 396.317299 -37.574359)
			(xy 396.265005 -37.559004) (xy 396.21543 -37.536363) (xy 396.16958 -37.506897) (xy 396.128391 -37.471206)
			(xy 396.092701 -37.430016) (xy 396.063235 -37.384167) (xy 396.040595 -37.334591) (xy 396.02524 -37.282297)
			(xy 396.017484 -37.228351) (xy 396.017484 -37.173849) (xy 396.02524 -37.119903) (xy 396.040595 -37.067609)
			(xy 396.063235 -37.018033) (xy 396.092701 -36.972184) (xy 396.128391 -36.930994) (xy 396.16958 -36.895303)
			(xy 396.21543 -36.865837) (xy 396.265005 -36.843196) (xy 396.317299 -36.827841) (xy 396.371245 -36.820084)
			(xy 396.398496 -36.819586) (xy 396.428916 -36.820178) (xy 396.488985 -36.82983) (xy 396.546761 -36.848891)
			(xy 396.600782 -36.876877) (xy 396.625572 -36.894516) (xy 396.633349 -36.899891) (xy 396.651544 -36.904976)
			(xy 396.670339 -36.903071) (xy 396.678912 -36.899088) (xy 396.759684 -36.858194) (xy 396.767917 -36.85364)
			(xy 396.780529 -36.839695) (xy 396.78724 -36.822131) (xy 396.787624 -36.812728) (xy 396.787624 -35.109658)
			(xy 396.769082 -35.083496) (xy 396.753842 -35.078162) (xy 396.727568 -35.06832) (xy 396.678004 -35.042033)
			(xy 396.632821 -35.008774) (xy 396.592994 -34.969259) (xy 396.575788 -34.947098) (xy 396.570454 -34.939986)
			(xy 396.548356 -34.925254) (xy 396.544404 -34.922823) (xy 396.535844 -34.919247) (xy 396.531338 -34.918142)
			(xy 396.501112 -34.911284) (xy 396.482316 -34.914078) (xy 396.473934 -34.91865) (xy 396.455553 -34.928877)
			(xy 396.417266 -34.946307) (xy 396.39748 -34.953448) (xy 396.37328 -34.961492) (xy 396.323546 -34.972787)
			(xy 396.272866 -34.97849) (xy 396.247366 -34.978848) (xy 396.221866 -34.978485) (xy 396.171186 -34.972788)
			(xy 396.121453 -34.96149) (xy 396.097252 -34.953448) (xy 396.077468 -34.946302) (xy 396.039181 -34.928874)
			(xy 396.020798 -34.91865) (xy 396.012416 -34.914078) (xy 395.99362 -34.911284) (xy 395.963394 -34.918142)
			(xy 395.958873 -34.919202) (xy 395.950302 -34.922774) (xy 395.946376 -34.925254) (xy 395.924024 -34.94024)
			(xy 395.918944 -34.947352) (xy 395.900793 -34.970651) (xy 395.858514 -35.011889) (xy 395.810381 -35.046114)
			(xy 395.757548 -35.072509) (xy 395.701276 -35.090442) (xy 395.642913 -35.099485) (xy 395.613382 -35.100006)
			(xy 395.60246 -35.100006) (xy 395.602206 -35.099752) (xy 395.575494 -35.098512) (xy 395.522787 -35.089483)
			(xy 395.471856 -35.073184) (xy 395.4237 -35.049935) (xy 395.379261 -35.02019) (xy 395.33941 -34.984533)
			(xy 395.304927 -34.943662) (xy 395.276487 -34.898377) (xy 395.254648 -34.849565) (xy 395.239837 -34.798182)
			(xy 395.232344 -34.745235) (xy 395.231874 -34.718498) (xy 395.23236 -34.691246) (xy 395.240117 -34.637298)
			(xy 395.255472 -34.585002) (xy 395.278113 -34.535424) (xy 395.307579 -34.489573) (xy 395.34327 -34.448381)
			(xy 395.38446 -34.412688) (xy 395.43031 -34.38322) (xy 395.479887 -34.360577) (xy 395.532182 -34.34522)
			(xy 395.58613 -34.337461) (xy 395.613382 -34.33699) (xy 395.628175 -34.337135) (xy 395.657671 -34.339427)
			(xy 395.67231 -34.341562) (xy 395.683232 -34.34334) (xy 395.704568 -34.337244) (xy 395.78026 -34.272728)
			(xy 395.789404 -34.252662) (xy 395.789404 -33.93694) (xy 395.789404 -33.92551) (xy 395.78026 -33.905444)
			(xy 395.704568 -33.840928) (xy 395.683232 -33.834832) (xy 395.67231 -33.83661) (xy 395.657484 -33.838782)
			(xy 395.627604 -33.841069) (xy 395.61262 -33.841182) (xy 395.612366 -33.841182) (xy 395.585164 -33.840625)
			(xy 395.531329 -33.832749) (xy 395.47916 -33.817305) (xy 395.429715 -33.794605) (xy 395.383996 -33.76511)
			(xy 395.342931 -33.729418) (xy 395.307354 -33.688255) (xy 395.277986 -33.642454) (xy 395.255424 -33.592946)
			(xy 395.240124 -33.540734) (xy 395.232398 -33.486878) (xy 395.231874 -33.459674) (xy 395.232362 -33.432423)
			(xy 395.240121 -33.378478) (xy 395.255478 -33.326185) (xy 395.278121 -33.27661) (xy 395.307587 -33.230761)
			(xy 395.343278 -33.189573) (xy 395.384468 -33.153882) (xy 395.430317 -33.124417) (xy 395.479892 -33.101775)
			(xy 395.532185 -33.086419) (xy 395.586131 -33.078661) (xy 395.613382 -33.078166) (xy 395.613636 -33.078166)
			(xy 395.643143 -33.078719) (xy 395.701452 -33.087806) (xy 395.757669 -33.105759) (xy 395.810453 -33.132149)
			(xy 395.858547 -33.166348) (xy 395.900805 -33.207541) (xy 395.918944 -33.23082) (xy 395.924024 -33.237932)
			(xy 395.946376 -33.252918) (xy 395.950328 -33.255348) (xy 395.958889 -33.258921) (xy 395.963394 -33.26003)
			(xy 395.99362 -33.266888) (xy 396.012416 -33.264094) (xy 396.020798 -33.259522) (xy 396.03918 -33.249296)
			(xy 396.077468 -33.23187) (xy 396.097252 -33.224724) (xy 396.121453 -33.216682) (xy 396.171187 -33.205391)
			(xy 396.221867 -33.199692) (xy 396.247366 -33.199324) (xy 396.272865 -33.199689) (xy 396.323545 -33.205389)
			(xy 396.373277 -33.216689) (xy 396.39748 -33.224724) (xy 396.417263 -33.231871) (xy 396.45555 -33.2493)
			(xy 396.473934 -33.259522) (xy 396.482316 -33.264094) (xy 396.501112 -33.266888) (xy 396.531338 -33.26003)
			(xy 396.535858 -33.258967) (xy 396.544424 -33.255388) (xy 396.548356 -33.252918) (xy 396.570454 -33.238186)
			(xy 396.575788 -33.231074) (xy 396.592991 -33.208911) (xy 396.63282 -33.169399) (xy 396.678007 -33.136148)
			(xy 396.727576 -33.109873) (xy 396.753842 -33.10001) (xy 396.769082 -33.094676) (xy 396.787624 -33.068514)
			(xy 396.787624 -31.509462) (xy 396.769082 -31.4833) (xy 396.753842 -31.477966) (xy 396.727568 -31.468124)
			(xy 396.678004 -31.441838) (xy 396.632821 -31.408579) (xy 396.592993 -31.369064) (xy 396.575788 -31.346902)
			(xy 396.570454 -31.33979) (xy 396.548356 -31.325058) (xy 396.544404 -31.322627) (xy 396.535844 -31.31905)
			(xy 396.531338 -31.317946) (xy 396.501112 -31.311088) (xy 396.482316 -31.313882) (xy 396.473934 -31.318454)
			(xy 396.455553 -31.328681) (xy 396.417266 -31.346111) (xy 396.39748 -31.353252) (xy 396.37328 -31.361296)
			(xy 396.323546 -31.372591) (xy 396.272866 -31.378294) (xy 396.247366 -31.378652) (xy 396.221866 -31.378289)
			(xy 396.171186 -31.372592) (xy 396.121453 -31.361294) (xy 396.097252 -31.353252) (xy 396.077468 -31.346106)
			(xy 396.039181 -31.328679) (xy 396.020798 -31.318454) (xy 396.012416 -31.313882) (xy 395.99362 -31.311088)
			(xy 395.963394 -31.317946) (xy 395.958873 -31.319006) (xy 395.950302 -31.322579) (xy 395.946376 -31.325058)
			(xy 395.924024 -31.340044) (xy 395.918944 -31.347156) (xy 395.900793 -31.370455) (xy 395.858513 -31.411692)
			(xy 395.810381 -31.445918) (xy 395.757547 -31.472312) (xy 395.701276 -31.490245) (xy 395.642913 -31.499287)
			(xy 395.613382 -31.49981) (xy 395.60246 -31.49981) (xy 395.602206 -31.499556) (xy 395.575494 -31.498316)
			(xy 395.522786 -31.489287) (xy 395.471856 -31.472988) (xy 395.423699 -31.449739) (xy 395.37926 -31.419994)
			(xy 395.339408 -31.384337) (xy 395.304925 -31.343466) (xy 395.276485 -31.298181) (xy 395.254645 -31.249369)
			(xy 395.239833 -31.197987) (xy 395.23234 -31.145039) (xy 395.231874 -31.118302) (xy 395.23236 -31.09105)
			(xy 395.240116 -31.037101) (xy 395.255471 -30.984805) (xy 395.278111 -30.935227) (xy 395.307577 -30.889375)
			(xy 395.343269 -30.848183) (xy 395.384459 -30.812489) (xy 395.430309 -30.783021) (xy 395.479886 -30.760378)
			(xy 395.532182 -30.74502) (xy 395.58613 -30.737261) (xy 395.613382 -30.736794) (xy 395.628175 -30.736939)
			(xy 395.657671 -30.739231) (xy 395.67231 -30.741366) (xy 395.683232 -30.743144) (xy 395.704568 -30.737048)
			(xy 395.78026 -30.672532) (xy 395.789404 -30.652466) (xy 395.789404 -30.336744) (xy 395.789404 -30.325314)
			(xy 395.78026 -30.305248) (xy 395.704568 -30.240732) (xy 395.683232 -30.234636) (xy 395.67231 -30.236414)
			(xy 395.657484 -30.238586) (xy 395.627604 -30.240873) (xy 395.61262 -30.240986) (xy 395.612366 -30.240986)
			(xy 395.585164 -30.240429) (xy 395.531329 -30.232553) (xy 395.47916 -30.217109) (xy 395.429714 -30.194409)
			(xy 395.383995 -30.164914) (xy 395.34293 -30.129223) (xy 395.307352 -30.088059) (xy 395.277984 -30.042258)
			(xy 395.255421 -29.99275) (xy 395.240121 -29.940538) (xy 395.232394 -29.886682) (xy 395.231874 -29.859478)
			(xy 395.232361 -29.832227) (xy 395.24012 -29.778281) (xy 395.255477 -29.725988) (xy 395.278119 -29.676412)
			(xy 395.307586 -29.630563) (xy 395.343277 -29.589374) (xy 395.384467 -29.553683) (xy 395.430316 -29.524217)
			(xy 395.479892 -29.501576) (xy 395.532185 -29.486219) (xy 395.586131 -29.478461) (xy 395.613382 -29.47797)
			(xy 395.613636 -29.47797) (xy 395.643143 -29.478523) (xy 395.701452 -29.487611) (xy 395.757669 -29.505563)
			(xy 395.810452 -29.531954) (xy 395.858546 -29.566153) (xy 395.900804 -29.607346) (xy 395.918944 -29.630624)
			(xy 395.924024 -29.637736) (xy 395.946376 -29.652722) (xy 395.950328 -29.655151) (xy 395.958889 -29.658724)
			(xy 395.963394 -29.659834) (xy 395.99362 -29.666692) (xy 396.012416 -29.663898) (xy 396.020798 -29.659326)
			(xy 396.03918 -29.6491) (xy 396.077468 -29.631674) (xy 396.097252 -29.624528) (xy 396.121453 -29.616486)
			(xy 396.171187 -29.605195) (xy 396.221867 -29.599496) (xy 396.247366 -29.599128) (xy 396.272865 -29.599493)
			(xy 396.323545 -29.605193) (xy 396.373276 -29.616494) (xy 396.39748 -29.624528) (xy 396.417263 -29.631675)
			(xy 396.45555 -29.649104) (xy 396.473934 -29.659326) (xy 396.482316 -29.663898) (xy 396.501112 -29.666692)
			(xy 396.531338 -29.659834) (xy 396.535858 -29.658771) (xy 396.544425 -29.655192) (xy 396.548356 -29.652722)
			(xy 396.570454 -29.63799) (xy 396.575788 -29.630878) (xy 396.592991 -29.608715) (xy 396.63282 -29.569203)
			(xy 396.678006 -29.535951) (xy 396.727576 -29.509676) (xy 396.753842 -29.499814) (xy 396.769082 -29.49448)
			(xy 396.787624 -29.468318) (xy 396.787624 -19.837908) (xy 396.787415 -19.831327) (xy 396.784071 -19.818597)
			(xy 396.78102 -19.812762) (xy 396.76578 -19.786346) (xy 396.757652 -19.77771) (xy 396.752318 -19.774154)
			(xy 396.730519 -19.759651) (xy 396.690734 -19.725613) (xy 396.655974 -19.686458) (xy 396.641066 -19.664934)
			(xy 396.640812 -19.66468) (xy 396.640812 -19.664426) (xy 396.634526 -19.656125) (xy 396.616966 -19.644971)
			(xy 396.606776 -19.642836) (xy 396.53337 -19.631152) (xy 396.523005 -19.62997) (xy 396.502799 -19.635075)
			(xy 396.494254 -19.641058) (xy 396.474097 -19.656166) (xy 396.430565 -19.681517) (xy 396.384079 -19.700927)
			(xy 396.335445 -19.714057) (xy 396.285508 -19.720682) (xy 396.26032 -19.721068) (xy 396.2527 -19.721068)
			(xy 396.225807 -19.72007) (xy 396.172686 -19.711446) (xy 396.121305 -19.695441) (xy 396.072684 -19.672373)
			(xy 396.027788 -19.6427) (xy 395.987508 -19.607012) (xy 395.952644 -19.566016) (xy 395.923888 -19.520527)
			(xy 395.901812 -19.471448) (xy 395.886853 -19.419753) (xy 395.879308 -19.366468) (xy 395.878812 -19.33956)
			(xy 395.879301 -19.312311) (xy 395.887062 -19.258369) (xy 395.902421 -19.20608) (xy 395.925065 -19.156509)
			(xy 395.954532 -19.110665) (xy 395.990224 -19.069482) (xy 396.031414 -19.033796) (xy 396.077262 -19.004336)
			(xy 396.126836 -18.9817) (xy 396.179128 -18.966349) (xy 396.233071 -18.958597) (xy 396.26032 -18.958052)
			(xy 396.264384 -18.958052) (xy 396.279624 -18.958306) (xy 396.305786 -18.941288) (xy 396.348204 -18.840196)
			(xy 396.351753 -18.83075) (xy 396.351861 -18.810589) (xy 396.344151 -18.79196) (xy 396.337282 -18.78457)
			(xy 395.967966 -18.415254) (xy 395.960854 -18.407888) (xy 395.942058 -18.400268) (xy 384.229356 -18.400268)
			(xy 384.219289 -18.400698) (xy 384.200693 -18.40842) (xy 384.193288 -18.415254) (xy 383.859024 -18.749518)
			(xy 383.851658 -18.75663) (xy 383.844038 -18.775426) (xy 383.844038 -21.738336) (xy 385.71678 -21.738336)
			(xy 385.71727 -21.709596) (xy 385.725902 -21.652767) (xy 385.74296 -21.597876) (xy 385.768059 -21.546165)
			(xy 385.80063 -21.498804) (xy 385.819904 -21.477478) (xy 385.826508 -21.470366) (xy 385.83362 -21.45284)
			(xy 385.83362 -21.363432) (xy 385.826508 -21.345906) (xy 385.819904 -21.338794) (xy 385.80067 -21.317436)
			(xy 385.768105 -21.270078) (xy 385.743013 -21.218371) (xy 385.725961 -21.163486) (xy 385.717336 -21.106663)
			(xy 385.717332 -21.049189) (xy 385.725949 -20.992366) (xy 385.742994 -20.937478) (xy 385.768079 -20.885767)
			(xy 385.800637 -20.838405) (xy 385.819904 -20.817078) (xy 385.826508 -20.809966) (xy 385.83362 -20.79244)
			(xy 385.83362 -20.703032) (xy 385.826508 -20.685506) (xy 385.819904 -20.678394) (xy 385.80067 -20.657036)
			(xy 385.768105 -20.609678) (xy 385.743013 -20.557971) (xy 385.725961 -20.503086) (xy 385.717336 -20.446263)
			(xy 385.717332 -20.388789) (xy 385.725949 -20.331966) (xy 385.742994 -20.277078) (xy 385.768079 -20.225367)
			(xy 385.800637 -20.178005) (xy 385.819904 -20.156678) (xy 385.826508 -20.149566) (xy 385.83362 -20.13204)
			(xy 385.83362 -20.042632) (xy 385.826508 -20.025106) (xy 385.819904 -20.017994) (xy 385.80067 -19.996636)
			(xy 385.768105 -19.949278) (xy 385.743013 -19.897571) (xy 385.725961 -19.842686) (xy 385.717336 -19.785863)
			(xy 385.717332 -19.728389) (xy 385.725949 -19.671566) (xy 385.742994 -19.616678) (xy 385.768079 -19.564967)
			(xy 385.800637 -19.517605) (xy 385.819904 -19.496278) (xy 385.826508 -19.489166) (xy 385.83362 -19.47164)
			(xy 385.83362 -19.382232) (xy 385.826508 -19.364706) (xy 385.819904 -19.357594) (xy 385.800662 -19.336242)
			(xy 385.768089 -19.288888) (xy 385.74299 -19.237183) (xy 385.725933 -19.182297) (xy 385.717304 -19.125473)
			(xy 385.71678 -19.096736) (xy 385.717266 -19.069485) (xy 385.725022 -19.015537) (xy 385.740377 -18.963242)
			(xy 385.763019 -18.913665) (xy 385.792485 -18.867815) (xy 385.828176 -18.826624) (xy 385.869367 -18.790933)
			(xy 385.915217 -18.761467) (xy 385.964794 -18.738825) (xy 386.017089 -18.72347) (xy 386.071037 -18.715714)
			(xy 386.125539 -18.715714) (xy 386.179487 -18.72347) (xy 386.231782 -18.738825) (xy 386.281359 -18.761467)
			(xy 386.327209 -18.790933) (xy 386.3684 -18.826624) (xy 386.404091 -18.867815) (xy 386.433557 -18.913665)
			(xy 386.456199 -18.963242) (xy 386.471554 -19.015537) (xy 386.47931 -19.069485) (xy 386.479796 -19.096736)
			(xy 386.479295 -19.125476) (xy 386.470667 -19.182304) (xy 386.453612 -19.237195) (xy 386.428515 -19.288907)
			(xy 386.395945 -19.336268) (xy 386.376672 -19.357594) (xy 386.370068 -19.364706) (xy 386.362956 -19.382232)
			(xy 386.362956 -19.47164) (xy 386.370068 -19.489166) (xy 386.376672 -19.496278) (xy 386.395979 -19.517574)
			(xy 386.428543 -19.564941) (xy 386.453633 -19.616658) (xy 386.470681 -19.671554) (xy 386.4793 -19.728385)
			(xy 386.479296 -19.785867) (xy 386.470669 -19.842698) (xy 386.453614 -19.897591) (xy 386.428517 -19.949304)
			(xy 386.395946 -19.996667) (xy 386.376672 -20.017994) (xy 386.370068 -20.025106) (xy 386.362956 -20.042632)
			(xy 386.362956 -20.13204) (xy 386.370068 -20.149566) (xy 386.376672 -20.156678) (xy 386.395979 -20.177974)
			(xy 386.428543 -20.225341) (xy 386.453633 -20.277058) (xy 386.470681 -20.331954) (xy 386.474261 -20.35556)
			(xy 395.878302 -20.35556) (xy 395.882373 -20.299938) (xy 395.894499 -20.245501) (xy 395.914422 -20.19341)
			(xy 395.941718 -20.144775) (xy 395.975804 -20.100632) (xy 396.015953 -20.061923) (xy 396.061311 -20.029472)
			(xy 396.110911 -20.003971) (xy 396.163695 -19.985964) (xy 396.218538 -19.975834) (xy 396.274272 -19.973797)
			(xy 396.329709 -19.979897) (xy 396.383666 -19.994003) (xy 396.434995 -20.015815) (xy 396.482601 -20.044869)
			(xy 396.525469 -20.080544) (xy 396.562686 -20.122081) (xy 396.593459 -20.168594) (xy 396.617131 -20.219091)
			(xy 396.633199 -20.272498) (xy 396.641319 -20.327674) (xy 396.641828 -20.35556) (xy 396.641319 -20.383446)
			(xy 396.633199 -20.438622) (xy 396.617131 -20.492029) (xy 396.593459 -20.542526) (xy 396.562686 -20.589039)
			(xy 396.525469 -20.630576) (xy 396.482601 -20.666251) (xy 396.434995 -20.695305) (xy 396.383666 -20.717117)
			(xy 396.329709 -20.731223) (xy 396.274272 -20.737323) (xy 396.218538 -20.735286) (xy 396.163695 -20.725156)
			(xy 396.110911 -20.707149) (xy 396.061311 -20.681648) (xy 396.015953 -20.649197) (xy 395.975804 -20.610488)
			(xy 395.941718 -20.566345) (xy 395.914422 -20.51771) (xy 395.894499 -20.465619) (xy 395.882373 -20.411182)
			(xy 395.878302 -20.35556) (xy 386.474261 -20.35556) (xy 386.4793 -20.388785) (xy 386.479296 -20.446267)
			(xy 386.470669 -20.503098) (xy 386.453614 -20.557991) (xy 386.428517 -20.609704) (xy 386.395946 -20.657067)
			(xy 386.376672 -20.678394) (xy 386.370068 -20.685506) (xy 386.362956 -20.703032) (xy 386.362956 -20.79244)
			(xy 386.370068 -20.809966) (xy 386.376672 -20.817078) (xy 386.395979 -20.838374) (xy 386.428543 -20.885741)
			(xy 386.453633 -20.937458) (xy 386.470681 -20.992354) (xy 386.4793 -21.049185) (xy 386.479296 -21.106667)
			(xy 386.470669 -21.163498) (xy 386.453614 -21.218391) (xy 386.428517 -21.270104) (xy 386.395946 -21.317467)
			(xy 386.376672 -21.338794) (xy 386.370068 -21.345906) (xy 386.362956 -21.363432) (xy 386.362956 -21.37156)
			(xy 395.878302 -21.37156) (xy 395.882373 -21.315938) (xy 395.894499 -21.261501) (xy 395.914422 -21.20941)
			(xy 395.941718 -21.160775) (xy 395.975804 -21.116632) (xy 396.015953 -21.077923) (xy 396.061311 -21.045472)
			(xy 396.110911 -21.019971) (xy 396.163695 -21.001964) (xy 396.218538 -20.991834) (xy 396.274272 -20.989797)
			(xy 396.329709 -20.995897) (xy 396.383666 -21.010003) (xy 396.434995 -21.031815) (xy 396.482601 -21.060869)
			(xy 396.525469 -21.096544) (xy 396.562686 -21.138081) (xy 396.593459 -21.184594) (xy 396.617131 -21.235091)
			(xy 396.633199 -21.288498) (xy 396.641319 -21.343674) (xy 396.641828 -21.37156) (xy 396.641319 -21.399446)
			(xy 396.633199 -21.454622) (xy 396.617131 -21.508029) (xy 396.593459 -21.558526) (xy 396.562686 -21.605039)
			(xy 396.525469 -21.646576) (xy 396.482601 -21.682251) (xy 396.434995 -21.711305) (xy 396.383666 -21.733117)
			(xy 396.329709 -21.747223) (xy 396.274272 -21.753323) (xy 396.218538 -21.751286) (xy 396.163695 -21.741156)
			(xy 396.110911 -21.723149) (xy 396.061311 -21.697648) (xy 396.015953 -21.665197) (xy 395.975804 -21.626488)
			(xy 395.941718 -21.582345) (xy 395.914422 -21.53371) (xy 395.894499 -21.481619) (xy 395.882373 -21.427182)
			(xy 395.878302 -21.37156) (xy 386.362956 -21.37156) (xy 386.362956 -21.45284) (xy 386.370068 -21.470366)
			(xy 386.376672 -21.477478) (xy 386.395961 -21.498789) (xy 386.428525 -21.546155) (xy 386.453613 -21.597871)
			(xy 386.47066 -21.652766) (xy 386.479278 -21.709596) (xy 386.479796 -21.738336) (xy 386.47931 -21.765587)
			(xy 386.471554 -21.819535) (xy 386.456199 -21.87183) (xy 386.433557 -21.921407) (xy 386.404091 -21.967257)
			(xy 386.3684 -22.008448) (xy 386.327209 -22.044139) (xy 386.281359 -22.073605) (xy 386.231782 -22.096247)
			(xy 386.179487 -22.111602) (xy 386.125539 -22.119358) (xy 386.071037 -22.119358) (xy 386.017089 -22.111602)
			(xy 385.964794 -22.096247) (xy 385.915217 -22.073605) (xy 385.869367 -22.044139) (xy 385.828176 -22.008448)
			(xy 385.792485 -21.967257) (xy 385.763019 -21.921407) (xy 385.740377 -21.87183) (xy 385.725022 -21.819535)
			(xy 385.717266 -21.765587) (xy 385.71678 -21.738336) (xy 383.844038 -21.738336) (xy 383.844038 -22.995154)
			(xy 385.587119 -22.995154) (xy 385.59494 -22.935722) (xy 385.610452 -22.87782) (xy 385.633389 -22.822437)
			(xy 385.663359 -22.770522) (xy 385.699848 -22.722964) (xy 385.742234 -22.680575) (xy 385.789789 -22.644081)
			(xy 385.841701 -22.614107) (xy 385.897082 -22.591165) (xy 385.954983 -22.575648) (xy 386.014414 -22.567822)
			(xy 386.074359 -22.56782) (xy 386.133791 -22.575643) (xy 386.191693 -22.591156) (xy 386.247075 -22.614095)
			(xy 386.298989 -22.644066) (xy 386.346546 -22.680557) (xy 386.388934 -22.722944) (xy 386.425426 -22.7705)
			(xy 386.455399 -22.822413) (xy 386.478339 -22.877795) (xy 386.493854 -22.935696) (xy 386.501679 -22.995128)
			(xy 386.502148 -23.0251) (xy 386.501925 -23.045661) (xy 386.498236 -23.086618) (xy 386.494782 -23.106888)
			(xy 386.492242 -23.120604) (xy 386.501132 -23.145496) (xy 386.587746 -23.22068) (xy 386.613654 -23.226014)
			(xy 386.626862 -23.221696) (xy 386.656066 -23.212615) (xy 386.716427 -23.202786) (xy 386.747004 -23.202138)
			(xy 386.765931 -23.202407) (xy 386.803593 -23.20622) (xy 386.822188 -23.209758) (xy 386.834888 -23.212044)
			(xy 386.85851 -23.205186) (xy 386.936996 -23.128986) (xy 386.944616 -23.105618) (xy 386.942584 -23.092918)
			(xy 386.939524 -23.073888) (xy 386.936213 -23.035483) (xy 386.93598 -23.01621) (xy 386.93645 -22.98624)
			(xy 386.944273 -22.926813) (xy 386.959785 -22.868915) (xy 386.982723 -22.813537) (xy 387.012692 -22.761627)
			(xy 387.04918 -22.714073) (xy 387.091563 -22.671688) (xy 387.139117 -22.635199) (xy 387.191026 -22.605228)
			(xy 387.246403 -22.58229) (xy 387.3043 -22.566775) (xy 387.363727 -22.558951) (xy 387.423667 -22.558951)
			(xy 387.483095 -22.566774) (xy 387.540992 -22.582288) (xy 387.596369 -22.605226) (xy 387.648279 -22.635196)
			(xy 387.695833 -22.671685) (xy 387.738216 -22.714069) (xy 387.774705 -22.761623) (xy 387.804675 -22.813532)
			(xy 387.827613 -22.86891) (xy 387.843126 -22.926807) (xy 387.850949 -22.986235) (xy 387.850949 -23.046175)
			(xy 387.843124 -23.105602) (xy 387.82761 -23.163499) (xy 387.804671 -23.218876) (xy 387.7747 -23.270785)
			(xy 387.73821 -23.318338) (xy 387.695826 -23.360721) (xy 387.648271 -23.397209) (xy 387.596361 -23.427178)
			(xy 387.540983 -23.450115) (xy 387.483085 -23.465627) (xy 387.423658 -23.47345) (xy 387.393688 -23.473918)
			(xy 387.359442 -23.473323) (xy 387.291717 -23.463113) (xy 387.258814 -23.453598) (xy 387.246622 -23.449788)
			(xy 387.222492 -23.45436) (xy 387.13664 -23.522178) (xy 387.126734 -23.544784) (xy 387.12775 -23.557738)
			(xy 387.128512 -23.583646) (xy 387.128026 -23.610897) (xy 387.126722 -23.619964) (xy 390.309336 -23.619964)
			(xy 390.309336 -23.560028) (xy 390.317159 -23.500606) (xy 390.332672 -23.442713) (xy 390.355608 -23.38734)
			(xy 390.385575 -23.335434) (xy 390.422062 -23.287884) (xy 390.464442 -23.245504) (xy 390.511992 -23.209017)
			(xy 390.563898 -23.17905) (xy 390.619271 -23.156114) (xy 390.677164 -23.140601) (xy 390.736586 -23.132778)
			(xy 390.796522 -23.132778) (xy 390.855944 -23.140601) (xy 390.913837 -23.156114) (xy 390.96921 -23.17905)
			(xy 391.021116 -23.209017) (xy 391.068666 -23.245504) (xy 391.111046 -23.287884) (xy 391.147533 -23.335434)
			(xy 391.1775 -23.38734) (xy 391.200436 -23.442713) (xy 391.215949 -23.500606) (xy 391.223772 -23.560028)
			(xy 391.224262 -23.589996) (xy 391.223772 -23.619964) (xy 391.215949 -23.679386) (xy 391.200436 -23.737279)
			(xy 391.1775 -23.792652) (xy 391.147533 -23.844558) (xy 391.120093 -23.880318) (xy 391.540744 -23.880318)
			(xy 391.544815 -23.824696) (xy 391.556941 -23.770259) (xy 391.576864 -23.718168) (xy 391.60416 -23.669533)
			(xy 391.638246 -23.62539) (xy 391.678395 -23.586681) (xy 391.723753 -23.55423) (xy 391.773353 -23.528729)
			(xy 391.826137 -23.510722) (xy 391.88098 -23.500592) (xy 391.936714 -23.498555) (xy 391.992151 -23.504655)
			(xy 392.046108 -23.518761) (xy 392.097437 -23.540573) (xy 392.145043 -23.569627) (xy 392.187911 -23.605302)
			(xy 392.225128 -23.646839) (xy 392.255901 -23.693352) (xy 392.279573 -23.743849) (xy 392.295641 -23.797256)
			(xy 392.303761 -23.852432) (xy 392.30427 -23.880318) (xy 392.556744 -23.880318) (xy 392.560815 -23.824696)
			(xy 392.572941 -23.770259) (xy 392.592864 -23.718168) (xy 392.62016 -23.669533) (xy 392.654246 -23.62539)
			(xy 392.694395 -23.586681) (xy 392.739753 -23.55423) (xy 392.789353 -23.528729) (xy 392.842137 -23.510722)
			(xy 392.89698 -23.500592) (xy 392.952714 -23.498555) (xy 393.008151 -23.504655) (xy 393.062108 -23.518761)
			(xy 393.113437 -23.540573) (xy 393.161043 -23.569627) (xy 393.203911 -23.605302) (xy 393.241128 -23.646839)
			(xy 393.271901 -23.693352) (xy 393.295573 -23.743849) (xy 393.311641 -23.797256) (xy 393.319761 -23.852432)
			(xy 393.32027 -23.880318) (xy 393.572744 -23.880318) (xy 393.576815 -23.824696) (xy 393.588941 -23.770259)
			(xy 393.608864 -23.718168) (xy 393.63616 -23.669533) (xy 393.670246 -23.62539) (xy 393.710395 -23.586681)
			(xy 393.755753 -23.55423) (xy 393.805353 -23.528729) (xy 393.858137 -23.510722) (xy 393.91298 -23.500592)
			(xy 393.968714 -23.498555) (xy 394.024151 -23.504655) (xy 394.078108 -23.518761) (xy 394.129437 -23.540573)
			(xy 394.177043 -23.569627) (xy 394.219911 -23.605302) (xy 394.257128 -23.646839) (xy 394.287901 -23.693352)
			(xy 394.311573 -23.743849) (xy 394.327641 -23.797256) (xy 394.335761 -23.852432) (xy 394.33627 -23.880318)
			(xy 394.59103 -23.880318) (xy 394.595101 -23.824696) (xy 394.607227 -23.770259) (xy 394.62715 -23.718168)
			(xy 394.654446 -23.669533) (xy 394.688532 -23.62539) (xy 394.728681 -23.586681) (xy 394.774039 -23.55423)
			(xy 394.823639 -23.528729) (xy 394.876423 -23.510722) (xy 394.931266 -23.500592) (xy 394.987 -23.498555)
			(xy 395.042437 -23.504655) (xy 395.096394 -23.518761) (xy 395.147723 -23.540573) (xy 395.195329 -23.569627)
			(xy 395.238197 -23.605302) (xy 395.275414 -23.646839) (xy 395.306187 -23.693352) (xy 395.329859 -23.743849)
			(xy 395.345927 -23.797256) (xy 395.354047 -23.852432) (xy 395.354556 -23.880318) (xy 395.354047 -23.908204)
			(xy 395.345927 -23.96338) (xy 395.329859 -24.016787) (xy 395.306187 -24.067284) (xy 395.275414 -24.113797)
			(xy 395.238197 -24.155334) (xy 395.195329 -24.191009) (xy 395.147723 -24.220063) (xy 395.096394 -24.241875)
			(xy 395.042437 -24.255981) (xy 394.987 -24.262081) (xy 394.931266 -24.260044) (xy 394.876423 -24.249914)
			(xy 394.823639 -24.231907) (xy 394.774039 -24.206406) (xy 394.728681 -24.173955) (xy 394.688532 -24.135246)
			(xy 394.654446 -24.091103) (xy 394.62715 -24.042468) (xy 394.607227 -23.990377) (xy 394.595101 -23.93594)
			(xy 394.59103 -23.880318) (xy 394.33627 -23.880318) (xy 394.335761 -23.908204) (xy 394.327641 -23.96338)
			(xy 394.311573 -24.016787) (xy 394.287901 -24.067284) (xy 394.257128 -24.113797) (xy 394.219911 -24.155334)
			(xy 394.177043 -24.191009) (xy 394.129437 -24.220063) (xy 394.078108 -24.241875) (xy 394.024151 -24.255981)
			(xy 393.968714 -24.262081) (xy 393.91298 -24.260044) (xy 393.858137 -24.249914) (xy 393.805353 -24.231907)
			(xy 393.755753 -24.206406) (xy 393.710395 -24.173955) (xy 393.670246 -24.135246) (xy 393.63616 -24.091103)
			(xy 393.608864 -24.042468) (xy 393.588941 -23.990377) (xy 393.576815 -23.93594) (xy 393.572744 -23.880318)
			(xy 393.32027 -23.880318) (xy 393.319761 -23.908204) (xy 393.311641 -23.96338) (xy 393.295573 -24.016787)
			(xy 393.271901 -24.067284) (xy 393.241128 -24.113797) (xy 393.203911 -24.155334) (xy 393.161043 -24.191009)
			(xy 393.113437 -24.220063) (xy 393.062108 -24.241875) (xy 393.008151 -24.255981) (xy 392.952714 -24.262081)
			(xy 392.89698 -24.260044) (xy 392.842137 -24.249914) (xy 392.789353 -24.231907) (xy 392.739753 -24.206406)
			(xy 392.694395 -24.173955) (xy 392.654246 -24.135246) (xy 392.62016 -24.091103) (xy 392.592864 -24.042468)
			(xy 392.572941 -23.990377) (xy 392.560815 -23.93594) (xy 392.556744 -23.880318) (xy 392.30427 -23.880318)
			(xy 392.303761 -23.908204) (xy 392.295641 -23.96338) (xy 392.279573 -24.016787) (xy 392.255901 -24.067284)
			(xy 392.225128 -24.113797) (xy 392.187911 -24.155334) (xy 392.145043 -24.191009) (xy 392.097437 -24.220063)
			(xy 392.046108 -24.241875) (xy 391.992151 -24.255981) (xy 391.936714 -24.262081) (xy 391.88098 -24.260044)
			(xy 391.826137 -24.249914) (xy 391.773353 -24.231907) (xy 391.723753 -24.206406) (xy 391.678395 -24.173955)
			(xy 391.638246 -24.135246) (xy 391.60416 -24.091103) (xy 391.576864 -24.042468) (xy 391.556941 -23.990377)
			(xy 391.544815 -23.93594) (xy 391.540744 -23.880318) (xy 391.120093 -23.880318) (xy 391.111046 -23.892108)
			(xy 391.068666 -23.934488) (xy 391.021116 -23.970975) (xy 390.96921 -24.000942) (xy 390.913837 -24.023878)
			(xy 390.855944 -24.039391) (xy 390.796522 -24.047214) (xy 390.736586 -24.047214) (xy 390.677164 -24.039391)
			(xy 390.619271 -24.023878) (xy 390.563898 -24.000942) (xy 390.511992 -23.970975) (xy 390.464442 -23.934488)
			(xy 390.422062 -23.892108) (xy 390.385575 -23.844558) (xy 390.355608 -23.792652) (xy 390.332672 -23.737279)
			(xy 390.317159 -23.679386) (xy 390.309336 -23.619964) (xy 387.126722 -23.619964) (xy 387.12027 -23.664845)
			(xy 387.104915 -23.71714) (xy 387.082273 -23.766717) (xy 387.052807 -23.812567) (xy 387.017116 -23.853758)
			(xy 386.975925 -23.889449) (xy 386.930075 -23.918915) (xy 386.880498 -23.941557) (xy 386.828203 -23.956912)
			(xy 386.774255 -23.964668) (xy 386.719753 -23.964668) (xy 386.665805 -23.956912) (xy 386.61351 -23.941557)
			(xy 386.563933 -23.918915) (xy 386.518083 -23.889449) (xy 386.476892 -23.853758) (xy 386.441201 -23.812567)
			(xy 386.411735 -23.766717) (xy 386.389093 -23.71714) (xy 386.373738 -23.664845) (xy 386.365982 -23.610897)
			(xy 386.365496 -23.583646) (xy 386.367274 -23.548086) (xy 386.368544 -23.53437) (xy 386.357622 -23.51024)
			(xy 386.264658 -23.44293) (xy 386.238242 -23.439882) (xy 386.225796 -23.44547) (xy 386.197042 -23.457297)
			(xy 386.137134 -23.47393) (xy 386.075527 -23.482306) (xy 386.04444 -23.482808) (xy 386.014468 -23.482381)
			(xy 385.955036 -23.474562) (xy 385.897132 -23.459052) (xy 385.841749 -23.436117) (xy 385.789834 -23.406149)
			(xy 385.742274 -23.36966) (xy 385.699884 -23.327276) (xy 385.663388 -23.279722) (xy 385.633413 -23.227811)
			(xy 385.610469 -23.172431) (xy 385.594951 -23.11453) (xy 385.587123 -23.055099) (xy 385.587119 -22.995154)
			(xy 383.844038 -22.995154) (xy 383.844038 -24.189944) (xy 385.598922 -24.189944) (xy 385.602993 -24.134322)
			(xy 385.615119 -24.079885) (xy 385.635042 -24.027794) (xy 385.662338 -23.979159) (xy 385.696424 -23.935016)
			(xy 385.736573 -23.896307) (xy 385.781931 -23.863856) (xy 385.831531 -23.838355) (xy 385.884315 -23.820348)
			(xy 385.939158 -23.810218) (xy 385.994892 -23.808181) (xy 386.050329 -23.814281) (xy 386.104286 -23.828387)
			(xy 386.155615 -23.850199) (xy 386.203221 -23.879253) (xy 386.246089 -23.914928) (xy 386.283306 -23.956465)
			(xy 386.314079 -24.002978) (xy 386.337751 -24.053475) (xy 386.353819 -24.106882) (xy 386.361939 -24.162058)
			(xy 386.362448 -24.189944) (xy 388.121904 -24.189944) (xy 388.125975 -24.134322) (xy 388.138101 -24.079885)
			(xy 388.158024 -24.027794) (xy 388.18532 -23.979159) (xy 388.219406 -23.935016) (xy 388.259555 -23.896307)
			(xy 388.304913 -23.863856) (xy 388.354513 -23.838355) (xy 388.407297 -23.820348) (xy 388.46214 -23.810218)
			(xy 388.517874 -23.808181) (xy 388.573311 -23.814281) (xy 388.627268 -23.828387) (xy 388.678597 -23.850199)
			(xy 388.726203 -23.879253) (xy 388.769071 -23.914928) (xy 388.806288 -23.956465) (xy 388.837061 -24.002978)
			(xy 388.860733 -24.053475) (xy 388.876801 -24.106882) (xy 388.884921 -24.162058) (xy 388.88543 -24.189944)
			(xy 388.884921 -24.21783) (xy 388.876801 -24.273006) (xy 388.860733 -24.326413) (xy 388.837061 -24.37691)
			(xy 388.806288 -24.423423) (xy 388.769071 -24.46496) (xy 388.726203 -24.500635) (xy 388.678597 -24.529689)
			(xy 388.627268 -24.551501) (xy 388.573311 -24.565607) (xy 388.517874 -24.571707) (xy 388.46214 -24.56967)
			(xy 388.407297 -24.55954) (xy 388.354513 -24.541533) (xy 388.304913 -24.516032) (xy 388.259555 -24.483581)
			(xy 388.219406 -24.444872) (xy 388.18532 -24.400729) (xy 388.158024 -24.352094) (xy 388.138101 -24.300003)
			(xy 388.125975 -24.245566) (xy 388.121904 -24.189944) (xy 386.362448 -24.189944) (xy 386.361939 -24.21783)
			(xy 386.353819 -24.273006) (xy 386.337751 -24.326413) (xy 386.314079 -24.37691) (xy 386.283306 -24.423423)
			(xy 386.246089 -24.46496) (xy 386.203221 -24.500635) (xy 386.155615 -24.529689) (xy 386.104286 -24.551501)
			(xy 386.050329 -24.565607) (xy 385.994892 -24.571707) (xy 385.939158 -24.56967) (xy 385.884315 -24.55954)
			(xy 385.831531 -24.541533) (xy 385.781931 -24.516032) (xy 385.736573 -24.483581) (xy 385.696424 -24.444872)
			(xy 385.662338 -24.400729) (xy 385.635042 -24.352094) (xy 385.615119 -24.300003) (xy 385.602993 -24.245566)
			(xy 385.598922 -24.189944) (xy 383.844038 -24.189944) (xy 383.844038 -25.390094) (xy 388.033514 -25.390094)
			(xy 388.034004 -25.360126) (xy 388.041827 -25.300704) (xy 388.05734 -25.242811) (xy 388.080276 -25.187438)
			(xy 388.110243 -25.135532) (xy 388.14673 -25.087982) (xy 388.18911 -25.045602) (xy 388.23666 -25.009115)
			(xy 388.288566 -24.979148) (xy 388.343939 -24.956212) (xy 388.401832 -24.940699) (xy 388.461254 -24.932876)
			(xy 388.52119 -24.932876) (xy 388.580612 -24.940699) (xy 388.638505 -24.956212) (xy 388.693878 -24.979148)
			(xy 388.745784 -25.009115) (xy 388.793334 -25.045602) (xy 388.835714 -25.087982) (xy 388.872201 -25.135532)
			(xy 388.902168 -25.187438) (xy 388.925104 -25.242811) (xy 388.940617 -25.300704) (xy 388.94844 -25.360126)
			(xy 388.94893 -25.390094) (xy 388.948485 -25.418878) (xy 388.941267 -25.475992) (xy 388.926945 -25.53175)
			(xy 388.905743 -25.585271) (xy 388.877998 -25.635712) (xy 388.844147 -25.682276) (xy 388.804724 -25.724227)
			(xy 388.782814 -25.7429) (xy 388.774432 -25.749758) (xy 388.76478 -25.769316) (xy 388.761478 -25.867106)
			(xy 388.769606 -25.887172) (xy 388.777734 -25.894792) (xy 388.79613 -25.912873) (xy 388.828369 -25.953138)
			(xy 388.854894 -25.997377) (xy 388.875222 -26.044784) (xy 388.888983 -26.094496) (xy 388.895927 -26.145607)
			(xy 388.896352 -26.171398) (xy 388.895866 -26.198649) (xy 388.88811 -26.252597) (xy 388.872755 -26.304892)
			(xy 388.850113 -26.354469) (xy 388.820647 -26.400319) (xy 388.784956 -26.44151) (xy 388.743765 -26.477201)
			(xy 388.697915 -26.506667) (xy 388.648338 -26.529309) (xy 388.596043 -26.544664) (xy 388.542095 -26.55242)
			(xy 388.487593 -26.55242) (xy 388.433645 -26.544664) (xy 388.38135 -26.529309) (xy 388.331773 -26.506667)
			(xy 388.285923 -26.477201) (xy 388.244732 -26.44151) (xy 388.209041 -26.400319) (xy 388.179575 -26.354469)
			(xy 388.156933 -26.304892) (xy 388.141578 -26.252597) (xy 388.133822 -26.198649) (xy 388.133336 -26.171398)
			(xy 388.133844 -26.142754) (xy 388.142442 -26.086115) (xy 388.159415 -26.031399) (xy 388.184381 -25.979837)
			(xy 388.216778 -25.932589) (xy 388.235952 -25.911302) (xy 388.243318 -25.903174) (xy 388.250176 -25.8826)
			(xy 388.241032 -25.785064) (xy 388.230364 -25.766268) (xy 388.221474 -25.759918) (xy 388.196942 -25.741347)
			(xy 388.152545 -25.698751) (xy 388.114251 -25.650593) (xy 388.082751 -25.59774) (xy 388.058613 -25.541146)
			(xy 388.042271 -25.481829) (xy 388.034019 -25.420857) (xy 388.033514 -25.390094) (xy 383.844038 -25.390094)
			(xy 383.844038 -25.506934) (xy 383.844468 -25.517001) (xy 383.852195 -25.535593) (xy 383.859024 -25.543002)
			(xy 383.910332 -25.593802) (xy 383.917743 -25.600481) (xy 383.93618 -25.608051) (xy 383.946146 -25.608534)
			(xy 383.94894 -25.608534) (xy 383.976186 -25.609023) (xy 384.030124 -25.616783) (xy 384.082408 -25.63214)
			(xy 384.131975 -25.654781) (xy 384.177815 -25.684245) (xy 384.218996 -25.719933) (xy 384.254679 -25.761117)
			(xy 384.284138 -25.806961) (xy 384.306774 -25.85653) (xy 384.322125 -25.908815) (xy 384.32988 -25.962754)
			(xy 384.32988 -25.990042) (xy 385.598922 -25.990042) (xy 385.602993 -25.93442) (xy 385.615119 -25.879983)
			(xy 385.635042 -25.827892) (xy 385.662338 -25.779257) (xy 385.696424 -25.735114) (xy 385.736573 -25.696405)
			(xy 385.781931 -25.663954) (xy 385.831531 -25.638453) (xy 385.884315 -25.620446) (xy 385.939158 -25.610316)
			(xy 385.994892 -25.608279) (xy 386.050329 -25.614379) (xy 386.104286 -25.628485) (xy 386.155615 -25.650297)
			(xy 386.203221 -25.679351) (xy 386.246089 -25.715026) (xy 386.283306 -25.756563) (xy 386.314079 -25.803076)
			(xy 386.337751 -25.853573) (xy 386.353819 -25.90698) (xy 386.361939 -25.962156) (xy 386.362448 -25.990042)
			(xy 386.361939 -26.017928) (xy 386.353819 -26.073104) (xy 386.337751 -26.126511) (xy 386.314079 -26.177008)
			(xy 386.283306 -26.223521) (xy 386.246089 -26.265058) (xy 386.203221 -26.300733) (xy 386.155615 -26.329787)
			(xy 386.104286 -26.351599) (xy 386.050329 -26.365705) (xy 385.994892 -26.371805) (xy 385.939158 -26.369768)
			(xy 385.884315 -26.359638) (xy 385.831531 -26.341631) (xy 385.781931 -26.31613) (xy 385.736573 -26.283679)
			(xy 385.696424 -26.24497) (xy 385.662338 -26.200827) (xy 385.635042 -26.152192) (xy 385.615119 -26.100101)
			(xy 385.602993 -26.045664) (xy 385.598922 -25.990042) (xy 384.32988 -25.990042) (xy 384.32988 -26.017246)
			(xy 384.322125 -26.071185) (xy 384.306774 -26.12347) (xy 384.284138 -26.173039) (xy 384.254679 -26.218883)
			(xy 384.218996 -26.260067) (xy 384.177815 -26.295755) (xy 384.131975 -26.325219) (xy 384.082408 -26.34786)
			(xy 384.030124 -26.363217) (xy 383.976186 -26.370977) (xy 383.94894 -26.37155) (xy 383.946146 -26.37155)
			(xy 383.936184 -26.372035) (xy 383.917761 -26.379625) (xy 383.910332 -26.386282) (xy 383.859024 -26.437082)
			(xy 383.852188 -26.444484) (xy 383.84448 -26.463082) (xy 383.844038 -26.47315) (xy 383.844038 -27.307032)
			(xy 383.844468 -27.317099) (xy 383.852195 -27.335691) (xy 383.859024 -27.3431) (xy 383.910332 -27.3939)
			(xy 383.917743 -27.400579) (xy 383.93618 -27.408149) (xy 383.946146 -27.408632) (xy 383.94894 -27.408632)
			(xy 383.976186 -27.409121) (xy 384.030124 -27.416881) (xy 384.082409 -27.432238) (xy 384.131976 -27.454879)
			(xy 384.177816 -27.484343) (xy 384.218997 -27.520031) (xy 384.254681 -27.561216) (xy 384.28414 -27.60706)
			(xy 384.306776 -27.656629) (xy 384.322127 -27.708915) (xy 384.329882 -27.762853) (xy 384.329882 -27.79014)
			(xy 385.66293 -27.79014) (xy 385.667001 -27.734518) (xy 385.679127 -27.680081) (xy 385.69905 -27.62799)
			(xy 385.726346 -27.579355) (xy 385.760432 -27.535212) (xy 385.800581 -27.496503) (xy 385.845939 -27.464052)
			(xy 385.895539 -27.438551) (xy 385.948323 -27.420544) (xy 386.003166 -27.410414) (xy 386.0589 -27.408377)
			(xy 386.114337 -27.414477) (xy 386.168294 -27.428583) (xy 386.219623 -27.450395) (xy 386.267229 -27.479449)
			(xy 386.310097 -27.515124) (xy 386.347314 -27.556661) (xy 386.378087 -27.603174) (xy 386.401759 -27.653671)
			(xy 386.417827 -27.707078) (xy 386.425947 -27.762254) (xy 386.426456 -27.79014) (xy 388.166862 -27.79014)
			(xy 388.170933 -27.734518) (xy 388.183059 -27.680081) (xy 388.202982 -27.62799) (xy 388.230278 -27.579355)
			(xy 388.264364 -27.535212) (xy 388.304513 -27.496503) (xy 388.349871 -27.464052) (xy 388.399471 -27.438551)
			(xy 388.452255 -27.420544) (xy 388.507098 -27.410414) (xy 388.562832 -27.408377) (xy 388.618269 -27.414477)
			(xy 388.672226 -27.428583) (xy 388.723555 -27.450395) (xy 388.771161 -27.479449) (xy 388.814029 -27.515124)
			(xy 388.851246 -27.556661) (xy 388.882019 -27.603174) (xy 388.905691 -27.653671) (xy 388.921759 -27.707078)
			(xy 388.929879 -27.762254) (xy 388.930388 -27.79014) (xy 388.929891 -27.817347) (xy 390.199918 -27.817347)
			(xy 390.199918 -27.762853) (xy 390.207673 -27.708912) (xy 390.223026 -27.656625) (xy 390.245663 -27.607054)
			(xy 390.275124 -27.561209) (xy 390.31081 -27.520024) (xy 390.351993 -27.484336) (xy 390.397836 -27.454873)
			(xy 390.447406 -27.432233) (xy 390.499693 -27.416878) (xy 390.553633 -27.40912) (xy 390.58088 -27.408632)
			(xy 390.606187 -27.409037) (xy 390.656359 -27.415706) (xy 390.705211 -27.428943) (xy 390.728708 -27.43835)
			(xy 390.736721 -27.441356) (xy 390.753787 -27.442455) (xy 390.770264 -27.437875) (xy 390.777476 -27.43327)
			(xy 390.802876 -27.41549) (xy 390.809761 -27.410214) (xy 390.819836 -27.396111) (xy 390.824635 -27.379457)
			(xy 390.824466 -27.370786) (xy 390.823704 -27.342846) (xy 390.823704 -26.479246) (xy 390.824212 -26.456894)
			(xy 390.82472 -26.444448) (xy 390.814306 -26.421842) (xy 390.729216 -26.355548) (xy 390.704832 -26.350976)
			(xy 390.692894 -26.354786) (xy 390.665556 -26.362625) (xy 390.609315 -26.371045) (xy 390.58088 -26.37155)
			(xy 390.553633 -26.370978) (xy 390.499693 -26.363221) (xy 390.447407 -26.347865) (xy 390.397837 -26.325226)
			(xy 390.351995 -26.295762) (xy 390.310811 -26.260074) (xy 390.275126 -26.218889) (xy 390.245665 -26.173045)
			(xy 390.223028 -26.123475) (xy 390.207675 -26.071187) (xy 390.19992 -26.017247) (xy 390.19992 -25.962753)
			(xy 390.207675 -25.908813) (xy 390.223028 -25.856525) (xy 390.245665 -25.806955) (xy 390.275126 -25.761111)
			(xy 390.310811 -25.719926) (xy 390.351995 -25.684238) (xy 390.397837 -25.654774) (xy 390.447407 -25.632135)
			(xy 390.499693 -25.616779) (xy 390.553633 -25.609022) (xy 390.58088 -25.608534) (xy 390.609832 -25.609096)
			(xy 390.667072 -25.617829) (xy 390.722334 -25.635114) (xy 390.77435 -25.660553) (xy 390.821922 -25.693561)
			(xy 390.86396 -25.733381) (xy 390.899495 -25.779097) (xy 390.927713 -25.829658) (xy 390.928608 -25.832054)
			(xy 392.48842 -25.832054) (xy 392.488901 -25.805451) (xy 392.496276 -25.752759) (xy 392.510904 -25.701604)
			(xy 392.532501 -25.652978) (xy 392.560648 -25.607828) (xy 392.594798 -25.567028) (xy 392.634288 -25.531371)
			(xy 392.65606 -25.516078) (xy 392.66754 -25.507741) (xy 392.685751 -25.486) (xy 392.697272 -25.460087)
			(xy 392.701215 -25.432002) (xy 392.697274 -25.403918) (xy 392.685753 -25.378003) (xy 392.667543 -25.356262)
			(xy 392.65606 -25.34793) (xy 392.634299 -25.332622) (xy 392.594819 -25.296958) (xy 392.560674 -25.256157)
			(xy 392.532527 -25.21101) (xy 392.510923 -25.162391) (xy 392.496281 -25.111242) (xy 392.488885 -25.058555)
			(xy 392.48842 -25.031954) (xy 392.488906 -25.004703) (xy 392.496662 -24.950755) (xy 392.512017 -24.89846)
			(xy 392.534659 -24.848883) (xy 392.564125 -24.803033) (xy 392.599816 -24.761842) (xy 392.641007 -24.726151)
			(xy 392.686857 -24.696685) (xy 392.736434 -24.674043) (xy 392.788729 -24.658688) (xy 392.842677 -24.650932)
			(xy 392.897179 -24.650932) (xy 392.951127 -24.658688) (xy 393.003422 -24.674043) (xy 393.052999 -24.696685)
			(xy 393.098849 -24.726151) (xy 393.14004 -24.761842) (xy 393.163241 -24.788618) (xy 395.093426 -24.788618)
			(xy 395.093426 -24.728682) (xy 395.101249 -24.66926) (xy 395.116762 -24.611367) (xy 395.139698 -24.555994)
			(xy 395.169665 -24.504088) (xy 395.206152 -24.456538) (xy 395.248532 -24.414158) (xy 395.296082 -24.377671)
			(xy 395.347988 -24.347704) (xy 395.403361 -24.324768) (xy 395.461254 -24.309255) (xy 395.520676 -24.301432)
			(xy 395.580612 -24.301432) (xy 395.640034 -24.309255) (xy 395.697927 -24.324768) (xy 395.7533 -24.347704)
			(xy 395.805206 -24.377671) (xy 395.852756 -24.414158) (xy 395.895136 -24.456538) (xy 395.931623 -24.504088)
			(xy 395.96159 -24.555994) (xy 395.984526 -24.611367) (xy 396.000039 -24.66926) (xy 396.007862 -24.728682)
			(xy 396.008352 -24.75865) (xy 396.007862 -24.788618) (xy 396.000039 -24.84804) (xy 395.984526 -24.905933)
			(xy 395.96159 -24.961306) (xy 395.931623 -25.013212) (xy 395.895136 -25.060762) (xy 395.852756 -25.103142)
			(xy 395.805206 -25.139629) (xy 395.7533 -25.169596) (xy 395.697927 -25.192532) (xy 395.640034 -25.208045)
			(xy 395.580612 -25.215868) (xy 395.520676 -25.215868) (xy 395.461254 -25.208045) (xy 395.403361 -25.192532)
			(xy 395.347988 -25.169596) (xy 395.296082 -25.139629) (xy 395.248532 -25.103142) (xy 395.206152 -25.060762)
			(xy 395.169665 -25.013212) (xy 395.139698 -24.961306) (xy 395.116762 -24.905933) (xy 395.101249 -24.84804)
			(xy 395.093426 -24.788618) (xy 393.163241 -24.788618) (xy 393.175731 -24.803033) (xy 393.205197 -24.848883)
			(xy 393.227839 -24.89846) (xy 393.243194 -24.950755) (xy 393.25095 -25.004703) (xy 393.251436 -25.031954)
			(xy 393.25098 -25.058558) (xy 393.243603 -25.111252) (xy 393.228972 -25.162409) (xy 393.207372 -25.211035)
			(xy 393.179221 -25.256185) (xy 393.145066 -25.296984) (xy 393.105571 -25.332638) (xy 393.083796 -25.34793)
			(xy 393.072312 -25.35626) (xy 393.054109 -25.378005) (xy 393.042593 -25.403919) (xy 393.038654 -25.432002)
			(xy 393.042595 -25.460085) (xy 393.054112 -25.485999) (xy 393.072316 -25.507743) (xy 393.083796 -25.516078)
			(xy 393.105573 -25.531364) (xy 393.14505 -25.567033) (xy 393.179192 -25.607838) (xy 393.207336 -25.65299)
			(xy 393.228937 -25.701612) (xy 393.243577 -25.752763) (xy 393.250972 -25.805452) (xy 393.251436 -25.832054)
			(xy 393.25095 -25.859305) (xy 393.243194 -25.913253) (xy 393.227839 -25.965548) (xy 393.205197 -26.015125)
			(xy 393.175731 -26.060975) (xy 393.14004 -26.102166) (xy 393.098849 -26.137857) (xy 393.052999 -26.167323)
			(xy 393.003422 -26.189965) (xy 392.951127 -26.20532) (xy 392.897179 -26.213076) (xy 392.842677 -26.213076)
			(xy 392.788729 -26.20532) (xy 392.736434 -26.189965) (xy 392.686857 -26.167323) (xy 392.641007 -26.137857)
			(xy 392.599816 -26.102166) (xy 392.564125 -26.060975) (xy 392.534659 -26.015125) (xy 392.512017 -25.965548)
			(xy 392.496662 -25.913253) (xy 392.488906 -25.859305) (xy 392.48842 -25.832054) (xy 390.928608 -25.832054)
			(xy 390.947965 -25.883904) (xy 390.959785 -25.940588) (xy 390.96188 -25.969468) (xy 390.962388 -25.981914)
			(xy 390.975088 -26.00325) (xy 391.066782 -26.060654) (xy 391.09142 -26.062432) (xy 391.10285 -26.057606)
			(xy 391.131205 -26.04613) (xy 391.190204 -26.029977) (xy 391.250827 -26.021809) (xy 391.281412 -26.021284)
			(xy 391.311392 -26.02175) (xy 391.370837 -26.029581) (xy 391.428751 -26.045106) (xy 391.484143 -26.06806)
			(xy 391.536063 -26.098049) (xy 391.583623 -26.134562) (xy 391.626009 -26.176971) (xy 391.662494 -26.224552)
			(xy 391.692455 -26.276489) (xy 391.715377 -26.331893) (xy 391.723131 -26.360882) (xy 393.38961 -26.360882)
			(xy 393.393681 -26.30526) (xy 393.405807 -26.250823) (xy 393.42573 -26.198732) (xy 393.453026 -26.150097)
			(xy 393.487112 -26.105954) (xy 393.527261 -26.067245) (xy 393.572619 -26.034794) (xy 393.622219 -26.009293)
			(xy 393.675003 -25.991286) (xy 393.729846 -25.981156) (xy 393.78558 -25.979119) (xy 393.841017 -25.985219)
			(xy 393.894974 -25.999325) (xy 393.946303 -26.021137) (xy 393.993909 -26.050191) (xy 394.036777 -26.085866)
			(xy 394.073994 -26.127403) (xy 394.104767 -26.173916) (xy 394.128439 -26.224413) (xy 394.144507 -26.27782)
			(xy 394.152627 -26.332996) (xy 394.153136 -26.360882) (xy 394.40561 -26.360882) (xy 394.409681 -26.30526)
			(xy 394.421807 -26.250823) (xy 394.44173 -26.198732) (xy 394.469026 -26.150097) (xy 394.503112 -26.105954)
			(xy 394.543261 -26.067245) (xy 394.588619 -26.034794) (xy 394.638219 -26.009293) (xy 394.691003 -25.991286)
			(xy 394.745846 -25.981156) (xy 394.80158 -25.979119) (xy 394.857017 -25.985219) (xy 394.910974 -25.999325)
			(xy 394.962303 -26.021137) (xy 395.009909 -26.050191) (xy 395.052777 -26.085866) (xy 395.089994 -26.127403)
			(xy 395.120767 -26.173916) (xy 395.144439 -26.224413) (xy 395.160507 -26.27782) (xy 395.168627 -26.332996)
			(xy 395.169136 -26.360882) (xy 395.168627 -26.388768) (xy 395.160507 -26.443944) (xy 395.144439 -26.497351)
			(xy 395.120767 -26.547848) (xy 395.089994 -26.594361) (xy 395.052777 -26.635898) (xy 395.009909 -26.671573)
			(xy 394.962303 -26.700627) (xy 394.910974 -26.722439) (xy 394.857017 -26.736545) (xy 394.80158 -26.742645)
			(xy 394.745846 -26.740608) (xy 394.691003 -26.730478) (xy 394.638219 -26.712471) (xy 394.588619 -26.68697)
			(xy 394.543261 -26.654519) (xy 394.503112 -26.61581) (xy 394.469026 -26.571667) (xy 394.44173 -26.523032)
			(xy 394.421807 -26.470941) (xy 394.409681 -26.416504) (xy 394.40561 -26.360882) (xy 394.153136 -26.360882)
			(xy 394.152627 -26.388768) (xy 394.144507 -26.443944) (xy 394.128439 -26.497351) (xy 394.104767 -26.547848)
			(xy 394.073994 -26.594361) (xy 394.036777 -26.635898) (xy 393.993909 -26.671573) (xy 393.946303 -26.700627)
			(xy 393.894974 -26.722439) (xy 393.841017 -26.736545) (xy 393.78558 -26.742645) (xy 393.729846 -26.740608)
			(xy 393.675003 -26.730478) (xy 393.622219 -26.712471) (xy 393.572619 -26.68697) (xy 393.527261 -26.654519)
			(xy 393.487112 -26.61581) (xy 393.453026 -26.571667) (xy 393.42573 -26.523032) (xy 393.405807 -26.470941)
			(xy 393.393681 -26.416504) (xy 393.38961 -26.360882) (xy 391.723131 -26.360882) (xy 391.73087 -26.389816)
			(xy 391.738666 -26.449266) (xy 391.73912 -26.479246) (xy 391.73912 -26.971244) (xy 395.1511 -26.971244)
			(xy 395.155171 -26.915622) (xy 395.167297 -26.861185) (xy 395.18722 -26.809094) (xy 395.214516 -26.760459)
			(xy 395.248602 -26.716316) (xy 395.288751 -26.677607) (xy 395.334109 -26.645156) (xy 395.383709 -26.619655)
			(xy 395.436493 -26.601648) (xy 395.491336 -26.591518) (xy 395.54707 -26.589481) (xy 395.602507 -26.595581)
			(xy 395.656464 -26.609687) (xy 395.707793 -26.631499) (xy 395.755399 -26.660553) (xy 395.798267 -26.696228)
			(xy 395.835484 -26.737765) (xy 395.866257 -26.784278) (xy 395.889929 -26.834775) (xy 395.905997 -26.888182)
			(xy 395.914117 -26.943358) (xy 395.914626 -26.971244) (xy 395.914117 -26.99913) (xy 395.905997 -27.054306)
			(xy 395.889929 -27.107713) (xy 395.866257 -27.15821) (xy 395.835484 -27.204723) (xy 395.798267 -27.24626)
			(xy 395.755399 -27.281935) (xy 395.707793 -27.310989) (xy 395.656464 -27.332801) (xy 395.602507 -27.346907)
			(xy 395.54707 -27.353007) (xy 395.491336 -27.35097) (xy 395.436493 -27.34084) (xy 395.383709 -27.322833)
			(xy 395.334109 -27.297332) (xy 395.288751 -27.264881) (xy 395.248602 -27.226172) (xy 395.214516 -27.182029)
			(xy 395.18722 -27.133394) (xy 395.167297 -27.081303) (xy 395.155171 -27.026866) (xy 395.1511 -26.971244)
			(xy 391.73912 -26.971244) (xy 391.73912 -27.342846) (xy 391.738716 -27.372823) (xy 391.730887 -27.432262)
			(xy 391.71537 -27.490173) (xy 391.692429 -27.545563) (xy 391.662457 -27.597486) (xy 391.625966 -27.645055)
			(xy 391.58358 -27.687456) (xy 391.536025 -27.723964) (xy 391.484112 -27.753955) (xy 391.42873 -27.776916)
			(xy 391.370825 -27.792454) (xy 391.311388 -27.800305) (xy 391.281412 -27.800808) (xy 391.250276 -27.800265)
			(xy 391.18858 -27.791805) (xy 391.128594 -27.77508) (xy 391.099802 -27.763216) (xy 391.088626 -27.75839)
			(xy 391.065004 -27.75966) (xy 390.973818 -27.810968) (xy 390.960356 -27.830526) (xy 390.958832 -27.842464)
			(xy 390.9546 -27.869491) (xy 390.93942 -27.922047) (xy 390.916893 -27.971898) (xy 390.887478 -28.018021)
			(xy 390.851779 -28.059472) (xy 390.810528 -28.095402) (xy 390.76457 -28.125073) (xy 390.714845 -28.147878)
			(xy 390.662375 -28.163351) (xy 390.608232 -28.171173) (xy 390.58088 -28.171648) (xy 390.553633 -28.17108)
			(xy 390.499693 -28.163322) (xy 390.447406 -28.147967) (xy 390.397836 -28.125327) (xy 390.351993 -28.095864)
			(xy 390.31081 -28.060176) (xy 390.275124 -28.018991) (xy 390.245663 -27.973146) (xy 390.223026 -27.923575)
			(xy 390.207673 -27.871288) (xy 390.199918 -27.817347) (xy 388.929891 -27.817347) (xy 388.929879 -27.818026)
			(xy 388.921759 -27.873202) (xy 388.905691 -27.926609) (xy 388.882019 -27.977106) (xy 388.851246 -28.023619)
			(xy 388.814029 -28.065156) (xy 388.771161 -28.100831) (xy 388.723555 -28.129885) (xy 388.672226 -28.151697)
			(xy 388.618269 -28.165803) (xy 388.562832 -28.171903) (xy 388.507098 -28.169866) (xy 388.452255 -28.159736)
			(xy 388.399471 -28.141729) (xy 388.349871 -28.116228) (xy 388.304513 -28.083777) (xy 388.264364 -28.045068)
			(xy 388.230278 -28.000925) (xy 388.202982 -27.95229) (xy 388.183059 -27.900199) (xy 388.170933 -27.845762)
			(xy 388.166862 -27.79014) (xy 386.426456 -27.79014) (xy 386.425947 -27.818026) (xy 386.417827 -27.873202)
			(xy 386.401759 -27.926609) (xy 386.378087 -27.977106) (xy 386.347314 -28.023619) (xy 386.310097 -28.065156)
			(xy 386.267229 -28.100831) (xy 386.219623 -28.129885) (xy 386.168294 -28.151697) (xy 386.114337 -28.165803)
			(xy 386.0589 -28.171903) (xy 386.003166 -28.169866) (xy 385.948323 -28.159736) (xy 385.895539 -28.141729)
			(xy 385.845939 -28.116228) (xy 385.800581 -28.083777) (xy 385.760432 -28.045068) (xy 385.726346 -28.000925)
			(xy 385.69905 -27.95229) (xy 385.679127 -27.900199) (xy 385.667001 -27.845762) (xy 385.66293 -27.79014)
			(xy 384.329882 -27.79014) (xy 384.329882 -27.817347) (xy 384.322127 -27.871285) (xy 384.306776 -27.923571)
			(xy 384.28414 -27.97314) (xy 384.254681 -28.018984) (xy 384.218997 -28.060169) (xy 384.177816 -28.095857)
			(xy 384.131976 -28.125321) (xy 384.082409 -28.147962) (xy 384.030124 -28.163319) (xy 383.976186 -28.171079)
			(xy 383.94894 -28.171648) (xy 383.946146 -28.171648) (xy 383.936184 -28.172133) (xy 383.917761 -28.179723)
			(xy 383.910332 -28.18638) (xy 383.859024 -28.23718) (xy 383.852188 -28.244582) (xy 383.844478 -28.26318)
			(xy 383.844038 -28.273248) (xy 383.844038 -29.106876) (xy 383.844476 -29.116939) (xy 383.852214 -29.13552)
			(xy 383.859024 -29.142944) (xy 383.910332 -29.193744) (xy 383.917745 -29.200418) (xy 383.936181 -29.207982)
			(xy 383.946146 -29.208476) (xy 383.94894 -29.208476) (xy 383.976191 -29.208965) (xy 384.030136 -29.216726)
			(xy 384.082428 -29.232085) (xy 384.132003 -29.25473) (xy 384.17785 -29.284198) (xy 384.219037 -29.319891)
			(xy 384.254726 -29.361082) (xy 384.28419 -29.406933) (xy 384.306829 -29.456509) (xy 384.322183 -29.508803)
			(xy 384.329938 -29.562749) (xy 384.329938 -29.589984) (xy 385.66293 -29.589984) (xy 385.667001 -29.534362)
			(xy 385.679127 -29.479925) (xy 385.69905 -29.427834) (xy 385.726346 -29.379199) (xy 385.760432 -29.335056)
			(xy 385.800581 -29.296347) (xy 385.845939 -29.263896) (xy 385.895539 -29.238395) (xy 385.948323 -29.220388)
			(xy 386.003166 -29.210258) (xy 386.0589 -29.208221) (xy 386.114337 -29.214321) (xy 386.168294 -29.228427)
			(xy 386.219623 -29.250239) (xy 386.267229 -29.279293) (xy 386.310097 -29.314968) (xy 386.347314 -29.356505)
			(xy 386.378087 -29.403018) (xy 386.401759 -29.453515) (xy 386.417827 -29.506922) (xy 386.425947 -29.562098)
			(xy 386.426456 -29.589984) (xy 388.166862 -29.589984) (xy 388.170933 -29.534362) (xy 388.183059 -29.479925)
			(xy 388.202982 -29.427834) (xy 388.230278 -29.379199) (xy 388.264364 -29.335056) (xy 388.304513 -29.296347)
			(xy 388.349871 -29.263896) (xy 388.399471 -29.238395) (xy 388.452255 -29.220388) (xy 388.507098 -29.210258)
			(xy 388.562832 -29.208221) (xy 388.618269 -29.214321) (xy 388.672226 -29.228427) (xy 388.723555 -29.250239)
			(xy 388.771161 -29.279293) (xy 388.814029 -29.314968) (xy 388.851246 -29.356505) (xy 388.882019 -29.403018)
			(xy 388.905691 -29.453515) (xy 388.921759 -29.506922) (xy 388.929879 -29.562098) (xy 388.930388 -29.589984)
			(xy 390.198862 -29.589984) (xy 390.202933 -29.534362) (xy 390.215059 -29.479925) (xy 390.234982 -29.427834)
			(xy 390.262278 -29.379199) (xy 390.296364 -29.335056) (xy 390.336513 -29.296347) (xy 390.381871 -29.263896)
			(xy 390.431471 -29.238395) (xy 390.484255 -29.220388) (xy 390.539098 -29.210258) (xy 390.594832 -29.208221)
			(xy 390.650269 -29.214321) (xy 390.704226 -29.228427) (xy 390.755555 -29.250239) (xy 390.803161 -29.279293)
			(xy 390.846029 -29.314968) (xy 390.867699 -29.339153) (xy 392.590232 -29.339153) (xy 392.590232 -29.284647)
			(xy 392.597989 -29.230695) (xy 392.613344 -29.178396) (xy 392.635986 -29.128814) (xy 392.665454 -29.08296)
			(xy 392.701147 -29.041765) (xy 392.742339 -29.006069) (xy 392.788191 -28.976599) (xy 392.837771 -28.953953)
			(xy 392.890069 -28.938594) (xy 392.944021 -28.930834) (xy 392.971274 -28.930346) (xy 392.986067 -28.930482)
			(xy 393.015565 -28.932771) (xy 393.030202 -28.934918) (xy 393.041124 -28.936696) (xy 393.06246 -28.9306)
			(xy 393.12977 -28.873196) (xy 393.13775 -28.865615) (xy 393.146825 -28.845586) (xy 393.147296 -28.834588)
			(xy 393.147296 -28.530296) (xy 393.146794 -28.519307) (xy 393.137717 -28.499294) (xy 393.12977 -28.491688)
			(xy 393.06246 -28.434284) (xy 393.041124 -28.428188) (xy 393.030202 -28.429966) (xy 393.015563 -28.432101)
			(xy 392.986067 -28.434393) (xy 392.971274 -28.434538) (xy 392.944026 -28.43399) (xy 392.890086 -28.426231)
			(xy 392.837798 -28.410875) (xy 392.788228 -28.388234) (xy 392.742385 -28.35877) (xy 392.701201 -28.323081)
			(xy 392.665515 -28.281895) (xy 392.636053 -28.236049) (xy 392.613416 -28.186478) (xy 392.598063 -28.134189)
			(xy 392.590308 -28.080248) (xy 392.590308 -28.025752) (xy 392.598063 -27.971811) (xy 392.613416 -27.919522)
			(xy 392.636053 -27.869951) (xy 392.665515 -27.824105) (xy 392.701201 -27.782919) (xy 392.742385 -27.74723)
			(xy 392.788228 -27.717766) (xy 392.837798 -27.695125) (xy 392.890086 -27.679769) (xy 392.944026 -27.67201)
			(xy 392.971274 -27.671522) (xy 392.9972 -27.671965) (xy 393.048577 -27.678968) (xy 393.098533 -27.692863)
			(xy 393.146147 -27.713393) (xy 393.190544 -27.74018) (xy 393.230905 -27.772731) (xy 393.266488 -27.810447)
			(xy 393.281916 -27.831288) (xy 393.28764 -27.838633) (xy 393.303155 -27.84891) (xy 393.312142 -27.851354)
			(xy 393.342368 -27.858212) (xy 393.351643 -27.859973) (xy 393.370308 -27.857224) (xy 393.37869 -27.852878)
			(xy 393.404669 -27.838588) (xy 393.45952 -27.816076) (xy 393.516822 -27.800849) (xy 393.575613 -27.793161)
			(xy 393.605258 -27.79268) (xy 393.634901 -27.793184) (xy 393.693682 -27.800903) (xy 393.750981 -27.816128)
			(xy 393.805841 -27.838605) (xy 393.831826 -27.852878) (xy 393.84025 -27.857098) (xy 393.858871 -27.859848)
			(xy 393.868148 -27.858212) (xy 393.898374 -27.851354) (xy 393.907374 -27.848948) (xy 393.922876 -27.83864)
			(xy 393.9286 -27.831288) (xy 393.944 -27.810423) (xy 393.979574 -27.772688) (xy 394.019934 -27.740123)
			(xy 394.064335 -27.71333) (xy 394.111959 -27.692802) (xy 394.161925 -27.678918) (xy 394.213312 -27.671935)
			(xy 394.239242 -27.671522) (xy 394.266493 -27.671951) (xy 394.320441 -27.679713) (xy 394.372735 -27.695073)
			(xy 394.422311 -27.717718) (xy 394.468159 -27.747188) (xy 394.509348 -27.782882) (xy 394.545037 -27.824074)
			(xy 394.574502 -27.869926) (xy 394.597142 -27.919505) (xy 394.612496 -27.9718) (xy 394.620252 -28.025749)
			(xy 394.620252 -28.080251) (xy 394.612496 -28.1342) (xy 394.597142 -28.186495) (xy 394.574502 -28.236074)
			(xy 394.545037 -28.281926) (xy 394.509348 -28.323118) (xy 394.468159 -28.358812) (xy 394.42231 -28.388282)
			(xy 394.372735 -28.410927) (xy 394.320441 -28.426287) (xy 394.266493 -28.434049) (xy 394.239242 -28.434538)
			(xy 394.224449 -28.4344) (xy 394.194951 -28.432113) (xy 394.180314 -28.429966) (xy 394.169392 -28.428188)
			(xy 394.148056 -28.434284) (xy 394.080746 -28.491688) (xy 394.072776 -28.499278) (xy 394.063695 -28.5193)
			(xy 394.06322 -28.530296) (xy 394.06322 -28.834588) (xy 394.063726 -28.845577) (xy 394.0728 -28.86559)
			(xy 394.080746 -28.873196) (xy 394.148056 -28.9306) (xy 394.169392 -28.936696) (xy 394.180314 -28.934918)
			(xy 394.194952 -28.932781) (xy 394.224449 -28.93049) (xy 394.239242 -28.930346) (xy 394.266488 -28.930927)
			(xy 394.320425 -28.938687) (xy 394.372708 -28.954044) (xy 394.422274 -28.976685) (xy 394.468113 -29.006149)
			(xy 394.509294 -29.041836) (xy 394.544976 -29.08302) (xy 394.574435 -29.128863) (xy 394.59707 -29.178431)
			(xy 394.612421 -29.230716) (xy 394.620176 -29.284654) (xy 394.620176 -29.339146) (xy 394.612421 -29.393083)
			(xy 394.59707 -29.445369) (xy 394.574435 -29.494937) (xy 394.544976 -29.54078) (xy 394.509294 -29.581964)
			(xy 394.468113 -29.617651) (xy 394.422274 -29.647115) (xy 394.372708 -29.669756) (xy 394.320425 -29.685113)
			(xy 394.266488 -29.692873) (xy 394.239242 -29.693362) (xy 394.213316 -29.692914) (xy 394.161939 -29.685912)
			(xy 394.111983 -29.672019) (xy 394.064368 -29.65149) (xy 394.019971 -29.624704) (xy 393.97961 -29.592153)
			(xy 393.944028 -29.554437) (xy 393.9286 -29.533596) (xy 393.922853 -29.526271) (xy 393.907356 -29.51598)
			(xy 393.898374 -29.51353) (xy 393.868148 -29.506672) (xy 393.858872 -29.504922) (xy 393.840208 -29.507664)
			(xy 393.831826 -29.512006) (xy 393.805843 -29.526288) (xy 393.750994 -29.548802) (xy 393.693693 -29.564032)
			(xy 393.634903 -29.571722) (xy 393.605258 -29.572204) (xy 393.575616 -29.571695) (xy 393.516834 -29.563978)
			(xy 393.459536 -29.548754) (xy 393.404675 -29.526279) (xy 393.37869 -29.512006) (xy 393.370284 -29.507744)
			(xy 393.351648 -29.505021) (xy 393.342368 -29.506672) (xy 393.312142 -29.51353) (xy 393.303146 -29.515947)
			(xy 393.287642 -29.526247) (xy 393.281916 -29.533596) (xy 393.266502 -29.55445) (xy 393.230931 -29.592186)
			(xy 393.190574 -29.624752) (xy 393.146175 -29.651547) (xy 393.098553 -29.672077) (xy 393.048589 -29.685963)
			(xy 392.997203 -29.692948) (xy 392.971274 -29.693362) (xy 392.944021 -29.692966) (xy 392.890069 -29.685206)
			(xy 392.837771 -29.669847) (xy 392.788191 -29.647201) (xy 392.742339 -29.617731) (xy 392.701147 -29.582035)
			(xy 392.665454 -29.54084) (xy 392.635986 -29.494986) (xy 392.613344 -29.445404) (xy 392.597989 -29.393105)
			(xy 392.590232 -29.339153) (xy 390.867699 -29.339153) (xy 390.883246 -29.356505) (xy 390.914019 -29.403018)
			(xy 390.937691 -29.453515) (xy 390.953759 -29.506922) (xy 390.961879 -29.562098) (xy 390.962388 -29.589984)
			(xy 390.961879 -29.61787) (xy 390.953759 -29.673046) (xy 390.937691 -29.726453) (xy 390.914019 -29.77695)
			(xy 390.883246 -29.823463) (xy 390.846029 -29.865) (xy 390.803161 -29.900675) (xy 390.755555 -29.929729)
			(xy 390.704226 -29.951541) (xy 390.650269 -29.965647) (xy 390.594832 -29.971747) (xy 390.539098 -29.96971)
			(xy 390.484255 -29.95958) (xy 390.431471 -29.941573) (xy 390.381871 -29.916072) (xy 390.336513 -29.883621)
			(xy 390.296364 -29.844912) (xy 390.262278 -29.800769) (xy 390.234982 -29.752134) (xy 390.215059 -29.700043)
			(xy 390.202933 -29.645606) (xy 390.198862 -29.589984) (xy 388.930388 -29.589984) (xy 388.929879 -29.61787)
			(xy 388.921759 -29.673046) (xy 388.905691 -29.726453) (xy 388.882019 -29.77695) (xy 388.851246 -29.823463)
			(xy 388.814029 -29.865) (xy 388.771161 -29.900675) (xy 388.723555 -29.929729) (xy 388.672226 -29.951541)
			(xy 388.618269 -29.965647) (xy 388.562832 -29.971747) (xy 388.507098 -29.96971) (xy 388.452255 -29.95958)
			(xy 388.399471 -29.941573) (xy 388.349871 -29.916072) (xy 388.304513 -29.883621) (xy 388.264364 -29.844912)
			(xy 388.230278 -29.800769) (xy 388.202982 -29.752134) (xy 388.183059 -29.700043) (xy 388.170933 -29.645606)
			(xy 388.166862 -29.589984) (xy 386.426456 -29.589984) (xy 386.425947 -29.61787) (xy 386.417827 -29.673046)
			(xy 386.401759 -29.726453) (xy 386.378087 -29.77695) (xy 386.347314 -29.823463) (xy 386.310097 -29.865)
			(xy 386.267229 -29.900675) (xy 386.219623 -29.929729) (xy 386.168294 -29.951541) (xy 386.114337 -29.965647)
			(xy 386.0589 -29.971747) (xy 386.003166 -29.96971) (xy 385.948323 -29.95958) (xy 385.895539 -29.941573)
			(xy 385.845939 -29.916072) (xy 385.800581 -29.883621) (xy 385.760432 -29.844912) (xy 385.726346 -29.800769)
			(xy 385.69905 -29.752134) (xy 385.679127 -29.700043) (xy 385.667001 -29.645606) (xy 385.66293 -29.589984)
			(xy 384.329938 -29.589984) (xy 384.329938 -29.617251) (xy 384.322183 -29.671197) (xy 384.306829 -29.723491)
			(xy 384.28419 -29.773067) (xy 384.254726 -29.818918) (xy 384.219037 -29.860109) (xy 384.17785 -29.895802)
			(xy 384.132003 -29.92527) (xy 384.082428 -29.947915) (xy 384.030136 -29.963274) (xy 383.976191 -29.971035)
			(xy 383.94894 -29.971492) (xy 383.946146 -29.971492) (xy 383.936183 -29.971976) (xy 383.917754 -29.97956)
			(xy 383.910332 -29.986224) (xy 383.859024 -30.037024) (xy 383.852179 -30.044423) (xy 383.844449 -30.063021)
			(xy 383.844038 -30.073092) (xy 383.844038 -30.906974) (xy 383.844475 -30.917037) (xy 383.852213 -30.935619)
			(xy 383.859024 -30.943042) (xy 383.910332 -30.993842) (xy 383.917745 -31.000517) (xy 383.936181 -31.008081)
			(xy 383.946146 -31.008574) (xy 383.94894 -31.008574) (xy 383.976191 -31.009063) (xy 384.030137 -31.016824)
			(xy 384.082429 -31.032183) (xy 384.132004 -31.054828) (xy 384.177851 -31.084297) (xy 384.219038 -31.11999)
			(xy 384.254727 -31.161181) (xy 384.284191 -31.207032) (xy 384.306831 -31.256608) (xy 384.322184 -31.308903)
			(xy 384.32994 -31.362849) (xy 384.32994 -31.417351) (xy 384.322184 -31.471297) (xy 384.306831 -31.523592)
			(xy 384.284191 -31.573168) (xy 384.254727 -31.619019) (xy 384.234552 -31.642304) (xy 385.706618 -31.642304)
			(xy 385.710689 -31.586682) (xy 385.722815 -31.532245) (xy 385.742738 -31.480154) (xy 385.770034 -31.431519)
			(xy 385.80412 -31.387376) (xy 385.844269 -31.348667) (xy 385.889627 -31.316216) (xy 385.939227 -31.290715)
			(xy 385.992011 -31.272708) (xy 386.046854 -31.262578) (xy 386.102588 -31.260541) (xy 386.158025 -31.266641)
			(xy 386.211982 -31.280747) (xy 386.263311 -31.302559) (xy 386.310917 -31.331613) (xy 386.353785 -31.367288)
			(xy 386.374208 -31.390082) (xy 388.166862 -31.390082) (xy 388.170933 -31.33446) (xy 388.183059 -31.280023)
			(xy 388.202982 -31.227932) (xy 388.230278 -31.179297) (xy 388.264364 -31.135154) (xy 388.304513 -31.096445)
			(xy 388.349871 -31.063994) (xy 388.399471 -31.038493) (xy 388.452255 -31.020486) (xy 388.507098 -31.010356)
			(xy 388.562832 -31.008319) (xy 388.618269 -31.014419) (xy 388.672226 -31.028525) (xy 388.723555 -31.050337)
			(xy 388.771161 -31.079391) (xy 388.814029 -31.115066) (xy 388.851246 -31.156603) (xy 388.882019 -31.203116)
			(xy 388.905691 -31.253613) (xy 388.921759 -31.30702) (xy 388.929879 -31.362196) (xy 388.930388 -31.390082)
			(xy 390.198862 -31.390082) (xy 390.202933 -31.33446) (xy 390.215059 -31.280023) (xy 390.234982 -31.227932)
			(xy 390.262278 -31.179297) (xy 390.296364 -31.135154) (xy 390.336513 -31.096445) (xy 390.381871 -31.063994)
			(xy 390.431471 -31.038493) (xy 390.484255 -31.020486) (xy 390.539098 -31.010356) (xy 390.594832 -31.008319)
			(xy 390.650269 -31.014419) (xy 390.704226 -31.028525) (xy 390.755555 -31.050337) (xy 390.803161 -31.079391)
			(xy 390.846029 -31.115066) (xy 390.883246 -31.156603) (xy 390.914019 -31.203116) (xy 390.937691 -31.253613)
			(xy 390.953759 -31.30702) (xy 390.961879 -31.362196) (xy 390.962388 -31.390082) (xy 390.961879 -31.417968)
			(xy 390.953759 -31.473144) (xy 390.937691 -31.526551) (xy 390.914019 -31.577048) (xy 390.883246 -31.623561)
			(xy 390.846029 -31.665098) (xy 390.82782 -31.680252) (xy 392.59025 -31.680252) (xy 392.59025 -31.625748)
			(xy 392.598006 -31.571799) (xy 392.613361 -31.519502) (xy 392.636002 -31.469923) (xy 392.665468 -31.42407)
			(xy 392.701159 -31.382878) (xy 392.74235 -31.347184) (xy 392.7882 -31.317715) (xy 392.837778 -31.29507)
			(xy 392.890073 -31.279712) (xy 392.944022 -31.271952) (xy 392.971274 -31.271464) (xy 392.997201 -31.27189)
			(xy 393.048579 -31.278894) (xy 393.098536 -31.29279) (xy 393.146151 -31.313322) (xy 393.190548 -31.340113)
			(xy 393.230909 -31.372668) (xy 393.266489 -31.410388) (xy 393.281916 -31.43123) (xy 393.287652 -31.438565)
			(xy 393.303157 -31.448849) (xy 393.312142 -31.451296) (xy 393.342368 -31.458154) (xy 393.351643 -31.45991)
			(xy 393.370308 -31.457163) (xy 393.37869 -31.45282) (xy 393.404685 -31.438582) (xy 393.459552 -31.416166)
			(xy 393.51685 -31.401004) (xy 393.575623 -31.393351) (xy 393.605258 -31.392876) (xy 393.634896 -31.393334)
			(xy 393.693678 -31.400955) (xy 393.750981 -31.416114) (xy 393.805843 -31.438556) (xy 393.831826 -31.45282)
			(xy 393.840251 -31.457038) (xy 393.858871 -31.459791) (xy 393.868148 -31.458154) (xy 393.898374 -31.451296)
			(xy 393.90737 -31.448877) (xy 393.922873 -31.438577) (xy 393.9286 -31.43123) (xy 393.943983 -31.410352)
			(xy 393.979561 -31.37262) (xy 394.019925 -31.340058) (xy 394.06433 -31.313267) (xy 394.111955 -31.292741)
			(xy 394.161923 -31.278859) (xy 394.213311 -31.271877) (xy 394.239242 -31.271464) (xy 394.266489 -31.272009)
			(xy 394.320428 -31.27977) (xy 394.372714 -31.295127) (xy 394.422282 -31.317769) (xy 394.468124 -31.347235)
			(xy 394.509306 -31.382923) (xy 394.544991 -31.424109) (xy 394.574451 -31.469954) (xy 394.597087 -31.519525)
			(xy 394.612439 -31.571813) (xy 394.620194 -31.625753) (xy 394.620194 -31.680247) (xy 394.612439 -31.734187)
			(xy 394.597087 -31.786475) (xy 394.574451 -31.836046) (xy 394.544991 -31.881891) (xy 394.509306 -31.923077)
			(xy 394.468124 -31.958765) (xy 394.422282 -31.988231) (xy 394.372714 -32.010873) (xy 394.320428 -32.02623)
			(xy 394.266489 -32.033991) (xy 394.239242 -32.03448) (xy 394.224449 -32.034342) (xy 394.194951 -32.032055)
			(xy 394.180314 -32.029908) (xy 394.169392 -32.02813) (xy 394.148056 -32.034226) (xy 394.080746 -32.09163)
			(xy 394.072803 -32.099243) (xy 394.063707 -32.119248) (xy 394.06322 -32.130238) (xy 394.06322 -32.43453)
			(xy 394.063703 -32.445522) (xy 394.072793 -32.465534) (xy 394.080746 -32.473138) (xy 394.148056 -32.530542)
			(xy 394.169392 -32.536638) (xy 394.180314 -32.53486) (xy 394.194952 -32.532723) (xy 394.224449 -32.530432)
			(xy 394.239242 -32.530288) (xy 394.266491 -32.530785) (xy 394.320434 -32.538546) (xy 394.372723 -32.553905)
			(xy 394.422294 -32.576548) (xy 394.468139 -32.606015) (xy 394.509324 -32.641706) (xy 394.54501 -32.682895)
			(xy 394.574472 -32.728743) (xy 394.59711 -32.778317) (xy 394.612463 -32.830607) (xy 394.620218 -32.884551)
			(xy 394.620218 -32.939049) (xy 394.612463 -32.992993) (xy 394.59711 -33.045283) (xy 394.574472 -33.094857)
			(xy 394.54501 -33.140705) (xy 394.509324 -33.181894) (xy 394.468139 -33.217585) (xy 394.422294 -33.247052)
			(xy 394.372723 -33.269695) (xy 394.320434 -33.285054) (xy 394.266491 -33.292815) (xy 394.239242 -33.293304)
			(xy 394.213317 -33.292838) (xy 394.161941 -33.285838) (xy 394.111986 -33.271946) (xy 394.064372 -33.25142)
			(xy 394.019975 -33.224636) (xy 393.979613 -33.192089) (xy 393.944029 -33.154377) (xy 393.9286 -33.133538)
			(xy 393.922865 -33.126203) (xy 393.907359 -33.115919) (xy 393.898374 -33.113472) (xy 393.868148 -33.106614)
			(xy 393.858872 -33.104859) (xy 393.840208 -33.107603) (xy 393.831826 -33.111948) (xy 393.805826 -33.126177)
			(xy 393.750961 -33.148596) (xy 393.693665 -33.16376) (xy 393.634892 -33.171416) (xy 393.605258 -33.171892)
			(xy 393.575621 -33.171431) (xy 393.516838 -33.163811) (xy 393.459535 -33.148654) (xy 393.404673 -33.126213)
			(xy 393.37869 -33.111948) (xy 393.370283 -33.107687) (xy 393.351648 -33.104962) (xy 393.342368 -33.106614)
			(xy 393.312142 -33.113472) (xy 393.303152 -33.115908) (xy 393.287647 -33.126196) (xy 393.281916 -33.133538)
			(xy 393.266514 -33.154402) (xy 393.23094 -33.192135) (xy 393.19058 -33.224699) (xy 393.146179 -33.251492)
			(xy 393.098556 -33.272021) (xy 393.04859 -33.285905) (xy 392.997204 -33.29289) (xy 392.971274 -33.293304)
			(xy 392.944024 -33.292824) (xy 392.890078 -33.285065) (xy 392.837786 -33.269707) (xy 392.788212 -33.247064)
			(xy 392.742364 -33.217597) (xy 392.701176 -33.181905) (xy 392.665487 -33.140715) (xy 392.636023 -33.094866)
			(xy 392.613384 -33.04529) (xy 392.59803 -32.992996) (xy 392.590274 -32.93905) (xy 392.590274 -32.88455)
			(xy 392.59803 -32.830604) (xy 392.613384 -32.77831) (xy 392.636023 -32.728734) (xy 392.665487 -32.682885)
			(xy 392.701176 -32.641695) (xy 392.742364 -32.606003) (xy 392.788212 -32.576536) (xy 392.837786 -32.553893)
			(xy 392.890078 -32.538535) (xy 392.944024 -32.530776) (xy 392.971274 -32.530288) (xy 392.986067 -32.530425)
			(xy 393.015565 -32.532713) (xy 393.030202 -32.53486) (xy 393.041124 -32.536638) (xy 393.06246 -32.530542)
			(xy 393.12977 -32.473138) (xy 393.137731 -32.46554) (xy 393.146816 -32.445524) (xy 393.147296 -32.43453)
			(xy 393.147296 -32.130238) (xy 393.146826 -32.119245) (xy 393.137726 -32.099233) (xy 393.12977 -32.09163)
			(xy 393.06246 -32.034226) (xy 393.041124 -32.02813) (xy 393.030202 -32.029908) (xy 393.015563 -32.032043)
			(xy 392.986067 -32.034335) (xy 392.971274 -32.03448) (xy 392.944022 -32.034048) (xy 392.890073 -32.026288)
			(xy 392.837778 -32.01093) (xy 392.7882 -31.988285) (xy 392.74235 -31.958816) (xy 392.701159 -31.923122)
			(xy 392.665468 -31.88193) (xy 392.636002 -31.836077) (xy 392.613361 -31.786498) (xy 392.598006 -31.734201)
			(xy 392.59025 -31.680252) (xy 390.82782 -31.680252) (xy 390.803161 -31.700773) (xy 390.755555 -31.729827)
			(xy 390.704226 -31.751639) (xy 390.650269 -31.765745) (xy 390.594832 -31.771845) (xy 390.539098 -31.769808)
			(xy 390.484255 -31.759678) (xy 390.431471 -31.741671) (xy 390.381871 -31.71617) (xy 390.336513 -31.683719)
			(xy 390.296364 -31.64501) (xy 390.262278 -31.600867) (xy 390.234982 -31.552232) (xy 390.215059 -31.500141)
			(xy 390.202933 -31.445704) (xy 390.198862 -31.390082) (xy 388.930388 -31.390082) (xy 388.929879 -31.417968)
			(xy 388.921759 -31.473144) (xy 388.905691 -31.526551) (xy 388.882019 -31.577048) (xy 388.851246 -31.623561)
			(xy 388.814029 -31.665098) (xy 388.771161 -31.700773) (xy 388.723555 -31.729827) (xy 388.672226 -31.751639)
			(xy 388.618269 -31.765745) (xy 388.562832 -31.771845) (xy 388.507098 -31.769808) (xy 388.452255 -31.759678)
			(xy 388.399471 -31.741671) (xy 388.349871 -31.71617) (xy 388.304513 -31.683719) (xy 388.264364 -31.64501)
			(xy 388.230278 -31.600867) (xy 388.202982 -31.552232) (xy 388.183059 -31.500141) (xy 388.170933 -31.445704)
			(xy 388.166862 -31.390082) (xy 386.374208 -31.390082) (xy 386.391002 -31.408825) (xy 386.421775 -31.455338)
			(xy 386.445447 -31.505835) (xy 386.461515 -31.559242) (xy 386.469635 -31.614418) (xy 386.470144 -31.642304)
			(xy 386.469635 -31.67019) (xy 386.461515 -31.725366) (xy 386.445447 -31.778773) (xy 386.421775 -31.82927)
			(xy 386.391002 -31.875783) (xy 386.353785 -31.91732) (xy 386.310917 -31.952995) (xy 386.263311 -31.982049)
			(xy 386.211982 -32.003861) (xy 386.158025 -32.017967) (xy 386.102588 -32.024067) (xy 386.046854 -32.02203)
			(xy 385.992011 -32.0119) (xy 385.939227 -31.993893) (xy 385.889627 -31.968392) (xy 385.844269 -31.935941)
			(xy 385.80412 -31.897232) (xy 385.770034 -31.853089) (xy 385.742738 -31.804454) (xy 385.722815 -31.752363)
			(xy 385.710689 -31.697926) (xy 385.706618 -31.642304) (xy 384.234552 -31.642304) (xy 384.219038 -31.66021)
			(xy 384.177851 -31.695903) (xy 384.132004 -31.725372) (xy 384.082429 -31.748017) (xy 384.030137 -31.763376)
			(xy 383.976191 -31.771137) (xy 383.94894 -31.77159) (xy 383.946146 -31.77159) (xy 383.936183 -31.772074)
			(xy 383.917754 -31.779657) (xy 383.910332 -31.786322) (xy 383.859024 -31.837122) (xy 383.852178 -31.844521)
			(xy 383.844448 -31.863119) (xy 383.844038 -31.87319) (xy 383.844038 -32.707072) (xy 383.844475 -32.717136)
			(xy 383.852212 -32.735718) (xy 383.859024 -32.74314) (xy 383.910332 -32.79394) (xy 383.917745 -32.800615)
			(xy 383.936181 -32.808179) (xy 383.946146 -32.808672) (xy 383.94894 -32.808672) (xy 383.976191 -32.809161)
			(xy 384.030137 -32.816922) (xy 384.08243 -32.832281) (xy 384.132005 -32.854926) (xy 384.177852 -32.884395)
			(xy 384.21904 -32.920088) (xy 384.254729 -32.96128) (xy 384.284193 -33.007131) (xy 384.306832 -33.056708)
			(xy 384.322186 -33.109002) (xy 384.329942 -33.162949) (xy 384.329942 -33.19018) (xy 385.97408 -33.19018)
			(xy 385.978151 -33.134558) (xy 385.990277 -33.080121) (xy 386.0102 -33.02803) (xy 386.037496 -32.979395)
			(xy 386.071582 -32.935252) (xy 386.111731 -32.896543) (xy 386.157089 -32.864092) (xy 386.206689 -32.838591)
			(xy 386.259473 -32.820584) (xy 386.314316 -32.810454) (xy 386.37005 -32.808417) (xy 386.425487 -32.814517)
			(xy 386.479444 -32.828623) (xy 386.530773 -32.850435) (xy 386.578379 -32.879489) (xy 386.621247 -32.915164)
			(xy 386.658464 -32.956701) (xy 386.689237 -33.003214) (xy 386.712909 -33.053711) (xy 386.728977 -33.107118)
			(xy 386.737097 -33.162294) (xy 386.737606 -33.19018) (xy 388.166862 -33.19018) (xy 388.170933 -33.134558)
			(xy 388.183059 -33.080121) (xy 388.202982 -33.02803) (xy 388.230278 -32.979395) (xy 388.264364 -32.935252)
			(xy 388.304513 -32.896543) (xy 388.349871 -32.864092) (xy 388.399471 -32.838591) (xy 388.452255 -32.820584)
			(xy 388.507098 -32.810454) (xy 388.562832 -32.808417) (xy 388.618269 -32.814517) (xy 388.672226 -32.828623)
			(xy 388.723555 -32.850435) (xy 388.771161 -32.879489) (xy 388.814029 -32.915164) (xy 388.851246 -32.956701)
			(xy 388.882019 -33.003214) (xy 388.905691 -33.053711) (xy 388.921759 -33.107118) (xy 388.929879 -33.162294)
			(xy 388.930388 -33.19018) (xy 390.198862 -33.19018) (xy 390.202933 -33.134558) (xy 390.215059 -33.080121)
			(xy 390.234982 -33.02803) (xy 390.262278 -32.979395) (xy 390.296364 -32.935252) (xy 390.336513 -32.896543)
			(xy 390.381871 -32.864092) (xy 390.431471 -32.838591) (xy 390.484255 -32.820584) (xy 390.539098 -32.810454)
			(xy 390.594832 -32.808417) (xy 390.650269 -32.814517) (xy 390.704226 -32.828623) (xy 390.755555 -32.850435)
			(xy 390.803161 -32.879489) (xy 390.846029 -32.915164) (xy 390.883246 -32.956701) (xy 390.914019 -33.003214)
			(xy 390.937691 -33.053711) (xy 390.953759 -33.107118) (xy 390.961879 -33.162294) (xy 390.962388 -33.19018)
			(xy 390.961879 -33.218066) (xy 390.953759 -33.273242) (xy 390.937691 -33.326649) (xy 390.914019 -33.377146)
			(xy 390.883246 -33.423659) (xy 390.846029 -33.465196) (xy 390.803161 -33.500871) (xy 390.755555 -33.529925)
			(xy 390.704226 -33.551737) (xy 390.650269 -33.565843) (xy 390.594832 -33.571943) (xy 390.539098 -33.569906)
			(xy 390.484255 -33.559776) (xy 390.431471 -33.541769) (xy 390.381871 -33.516268) (xy 390.336513 -33.483817)
			(xy 390.296364 -33.445108) (xy 390.262278 -33.400965) (xy 390.234982 -33.35233) (xy 390.215059 -33.300239)
			(xy 390.202933 -33.245802) (xy 390.198862 -33.19018) (xy 388.930388 -33.19018) (xy 388.929879 -33.218066)
			(xy 388.921759 -33.273242) (xy 388.905691 -33.326649) (xy 388.882019 -33.377146) (xy 388.851246 -33.423659)
			(xy 388.814029 -33.465196) (xy 388.771161 -33.500871) (xy 388.723555 -33.529925) (xy 388.672226 -33.551737)
			(xy 388.618269 -33.565843) (xy 388.562832 -33.571943) (xy 388.507098 -33.569906) (xy 388.452255 -33.559776)
			(xy 388.399471 -33.541769) (xy 388.349871 -33.516268) (xy 388.304513 -33.483817) (xy 388.264364 -33.445108)
			(xy 388.230278 -33.400965) (xy 388.202982 -33.35233) (xy 388.183059 -33.300239) (xy 388.170933 -33.245802)
			(xy 388.166862 -33.19018) (xy 386.737606 -33.19018) (xy 386.737097 -33.218066) (xy 386.728977 -33.273242)
			(xy 386.712909 -33.326649) (xy 386.689237 -33.377146) (xy 386.658464 -33.423659) (xy 386.621247 -33.465196)
			(xy 386.578379 -33.500871) (xy 386.530773 -33.529925) (xy 386.479444 -33.551737) (xy 386.425487 -33.565843)
			(xy 386.37005 -33.571943) (xy 386.314316 -33.569906) (xy 386.259473 -33.559776) (xy 386.206689 -33.541769)
			(xy 386.157089 -33.516268) (xy 386.111731 -33.483817) (xy 386.071582 -33.445108) (xy 386.037496 -33.400965)
			(xy 386.0102 -33.35233) (xy 385.990277 -33.300239) (xy 385.978151 -33.245802) (xy 385.97408 -33.19018)
			(xy 384.329942 -33.19018) (xy 384.329942 -33.217451) (xy 384.322186 -33.271398) (xy 384.306833 -33.323692)
			(xy 384.284193 -33.373269) (xy 384.254729 -33.41912) (xy 384.21904 -33.460312) (xy 384.177852 -33.496005)
			(xy 384.132005 -33.525474) (xy 384.08243 -33.548119) (xy 384.030137 -33.563478) (xy 383.976191 -33.571239)
			(xy 383.94894 -33.571688) (xy 383.946146 -33.571688) (xy 383.936183 -33.572172) (xy 383.917754 -33.579755)
			(xy 383.910332 -33.58642) (xy 383.859024 -33.63722) (xy 383.852178 -33.644618) (xy 383.844447 -33.663217)
			(xy 383.844038 -33.673288) (xy 383.844038 -34.506916) (xy 383.844465 -34.516984) (xy 383.852188 -34.535581)
			(xy 383.859024 -34.542984) (xy 383.910332 -34.593784) (xy 383.917743 -34.600465) (xy 383.936179 -34.608038)
			(xy 383.946146 -34.608516) (xy 383.94894 -34.608516) (xy 383.976188 -34.609005) (xy 384.030128 -34.616766)
			(xy 384.082414 -34.632123) (xy 384.131983 -34.654765) (xy 384.177826 -34.684231) (xy 384.219008 -34.71992)
			(xy 384.254693 -34.761106) (xy 384.284154 -34.806952) (xy 384.306791 -34.856523) (xy 384.322143 -34.908812)
			(xy 384.329898 -34.962752) (xy 384.329898 -34.990024) (xy 385.97281 -34.990024) (xy 385.976881 -34.934402)
			(xy 385.989007 -34.879965) (xy 386.00893 -34.827874) (xy 386.036226 -34.779239) (xy 386.070312 -34.735096)
			(xy 386.110461 -34.696387) (xy 386.155819 -34.663936) (xy 386.205419 -34.638435) (xy 386.258203 -34.620428)
			(xy 386.313046 -34.610298) (xy 386.36878 -34.608261) (xy 386.424217 -34.614361) (xy 386.478174 -34.628467)
			(xy 386.529503 -34.650279) (xy 386.577109 -34.679333) (xy 386.619977 -34.715008) (xy 386.657194 -34.756545)
			(xy 386.687967 -34.803058) (xy 386.711639 -34.853555) (xy 386.727707 -34.906962) (xy 386.735827 -34.962138)
			(xy 386.736336 -34.990024) (xy 387.300976 -34.990024) (xy 387.305047 -34.934402) (xy 387.317173 -34.879965)
			(xy 387.337096 -34.827874) (xy 387.364392 -34.779239) (xy 387.398478 -34.735096) (xy 387.438627 -34.696387)
			(xy 387.483985 -34.663936) (xy 387.533585 -34.638435) (xy 387.586369 -34.620428) (xy 387.641212 -34.610298)
			(xy 387.696946 -34.608261) (xy 387.752383 -34.614361) (xy 387.80634 -34.628467) (xy 387.857669 -34.650279)
			(xy 387.905275 -34.679333) (xy 387.948143 -34.715008) (xy 387.98536 -34.756545) (xy 388.016133 -34.803058)
			(xy 388.039805 -34.853555) (xy 388.055873 -34.906962) (xy 388.063993 -34.962138) (xy 388.064502 -34.990024)
			(xy 390.198862 -34.990024) (xy 390.202933 -34.934402) (xy 390.215059 -34.879965) (xy 390.234982 -34.827874)
			(xy 390.262278 -34.779239) (xy 390.296364 -34.735096) (xy 390.336513 -34.696387) (xy 390.381871 -34.663936)
			(xy 390.431471 -34.638435) (xy 390.484255 -34.620428) (xy 390.539098 -34.610298) (xy 390.594832 -34.608261)
			(xy 390.650269 -34.614361) (xy 390.704226 -34.628467) (xy 390.755555 -34.650279) (xy 390.803161 -34.679333)
			(xy 390.846029 -34.715008) (xy 390.883246 -34.756545) (xy 390.914019 -34.803058) (xy 390.937691 -34.853555)
			(xy 390.953759 -34.906962) (xy 390.961879 -34.962138) (xy 390.962388 -34.990024) (xy 390.961879 -35.01791)
			(xy 390.953759 -35.073086) (xy 390.937691 -35.126493) (xy 390.914019 -35.17699) (xy 390.883246 -35.223503)
			(xy 390.846029 -35.26504) (xy 390.803161 -35.300715) (xy 390.755555 -35.329769) (xy 390.704226 -35.351581)
			(xy 390.650269 -35.365687) (xy 390.594832 -35.371787) (xy 390.539098 -35.36975) (xy 390.484255 -35.35962)
			(xy 390.431471 -35.341613) (xy 390.381871 -35.316112) (xy 390.336513 -35.283661) (xy 390.296364 -35.244952)
			(xy 390.262278 -35.200809) (xy 390.234982 -35.152174) (xy 390.215059 -35.100083) (xy 390.202933 -35.045646)
			(xy 390.198862 -34.990024) (xy 388.064502 -34.990024) (xy 388.063993 -35.01791) (xy 388.055873 -35.073086)
			(xy 388.039805 -35.126493) (xy 388.016133 -35.17699) (xy 387.98536 -35.223503) (xy 387.948143 -35.26504)
			(xy 387.905275 -35.300715) (xy 387.857669 -35.329769) (xy 387.80634 -35.351581) (xy 387.752383 -35.365687)
			(xy 387.696946 -35.371787) (xy 387.641212 -35.36975) (xy 387.586369 -35.35962) (xy 387.533585 -35.341613)
			(xy 387.483985 -35.316112) (xy 387.438627 -35.283661) (xy 387.398478 -35.244952) (xy 387.364392 -35.200809)
			(xy 387.337096 -35.152174) (xy 387.317173 -35.100083) (xy 387.305047 -35.045646) (xy 387.300976 -34.990024)
			(xy 386.736336 -34.990024) (xy 386.735827 -35.01791) (xy 386.727707 -35.073086) (xy 386.711639 -35.126493)
			(xy 386.687967 -35.17699) (xy 386.657194 -35.223503) (xy 386.619977 -35.26504) (xy 386.577109 -35.300715)
			(xy 386.529503 -35.329769) (xy 386.478174 -35.351581) (xy 386.424217 -35.365687) (xy 386.36878 -35.371787)
			(xy 386.313046 -35.36975) (xy 386.258203 -35.35962) (xy 386.205419 -35.341613) (xy 386.155819 -35.316112)
			(xy 386.110461 -35.283661) (xy 386.070312 -35.244952) (xy 386.036226 -35.200809) (xy 386.00893 -35.152174)
			(xy 385.989007 -35.100083) (xy 385.976881 -35.045646) (xy 385.97281 -34.990024) (xy 384.329898 -34.990024)
			(xy 384.329898 -35.017248) (xy 384.322143 -35.071188) (xy 384.306791 -35.123477) (xy 384.284154 -35.173048)
			(xy 384.254693 -35.218894) (xy 384.219008 -35.26008) (xy 384.177826 -35.295769) (xy 384.131983 -35.325235)
			(xy 384.082414 -35.347877) (xy 384.030128 -35.363234) (xy 383.976188 -35.370995) (xy 383.94894 -35.371532)
			(xy 383.946146 -35.371532) (xy 383.936183 -35.372017) (xy 383.917759 -35.379605) (xy 383.910332 -35.386264)
			(xy 383.859024 -35.437064) (xy 383.852185 -35.444465) (xy 383.84447 -35.463063) (xy 383.844038 -35.473132)
			(xy 383.844038 -38.193437) (xy 385.398271 -38.193437) (xy 385.398271 -38.106563) (xy 385.406286 -38.020059)
			(xy 385.42225 -37.934663) (xy 385.446024 -37.851105) (xy 385.477407 -37.770097) (xy 385.516131 -37.69233)
			(xy 385.561865 -37.618467) (xy 385.614219 -37.54914) (xy 385.672746 -37.484939) (xy 385.736948 -37.426412)
			(xy 385.806276 -37.374059) (xy 385.880138 -37.328326) (xy 385.957906 -37.289603) (xy 386.038914 -37.258221)
			(xy 386.122473 -37.234447) (xy 386.207868 -37.218485) (xy 386.294373 -37.21047) (xy 386.33781 -37.209984)
			(xy 386.415788 -37.209984) (xy 386.425811 -37.20957) (xy 386.44433 -37.201901) (xy 386.458504 -37.187727)
			(xy 386.466171 -37.169207) (xy 386.466588 -37.159184) (xy 386.466588 -37.151564) (xy 386.46227 -37.137594)
			(xy 386.458206 -37.131244) (xy 386.434287 -37.094009) (xy 386.392586 -37.015944) (xy 386.358201 -36.93439)
			(xy 386.331423 -36.850033) (xy 386.312474 -36.76358) (xy 386.301514 -36.675755) (xy 386.298636 -36.587297)
			(xy 386.303863 -36.498946) (xy 386.317151 -36.411443) (xy 386.338389 -36.325524) (xy 386.367398 -36.241908)
			(xy 386.403936 -36.161296) (xy 386.447697 -36.084366) (xy 386.498311 -36.011762) (xy 386.555357 -35.944093)
			(xy 386.618354 -35.881927) (xy 386.686774 -35.825786) (xy 386.760044 -35.776139) (xy 386.837549 -35.733405)
			(xy 386.918638 -35.69794) (xy 387.002632 -35.670044) (xy 387.088826 -35.649948) (xy 387.176497 -35.637824)
			(xy 387.26491 -35.633771) (xy 387.353323 -35.637824) (xy 387.440994 -35.649948) (xy 387.527188 -35.670044)
			(xy 387.611182 -35.69794) (xy 387.692271 -35.733405) (xy 387.769776 -35.776139) (xy 387.843046 -35.825786)
			(xy 387.905142 -35.876738) (xy 393.017246 -35.876738) (xy 393.021317 -35.821116) (xy 393.033443 -35.766679)
			(xy 393.053366 -35.714588) (xy 393.080662 -35.665953) (xy 393.114748 -35.62181) (xy 393.154897 -35.583101)
			(xy 393.200255 -35.55065) (xy 393.249855 -35.525149) (xy 393.302639 -35.507142) (xy 393.357482 -35.497012)
			(xy 393.413216 -35.494975) (xy 393.468653 -35.501075) (xy 393.52261 -35.515181) (xy 393.573939 -35.536993)
			(xy 393.621545 -35.566047) (xy 393.664413 -35.601722) (xy 393.70163 -35.643259) (xy 393.732403 -35.689772)
			(xy 393.756075 -35.740269) (xy 393.772143 -35.793676) (xy 393.780263 -35.848852) (xy 393.780772 -35.876738)
			(xy 393.780263 -35.904624) (xy 393.772143 -35.9598) (xy 393.756075 -36.013207) (xy 393.732403 -36.063704)
			(xy 393.70163 -36.110217) (xy 393.664413 -36.151754) (xy 393.621545 -36.187429) (xy 393.573939 -36.216483)
			(xy 393.52261 -36.238295) (xy 393.468653 -36.252401) (xy 393.413216 -36.258501) (xy 393.357482 -36.256464)
			(xy 393.302639 -36.246334) (xy 393.249855 -36.228327) (xy 393.200255 -36.202826) (xy 393.154897 -36.170375)
			(xy 393.114748 -36.131666) (xy 393.080662 -36.087523) (xy 393.053366 -36.038888) (xy 393.033443 -35.986797)
			(xy 393.021317 -35.93236) (xy 393.017246 -35.876738) (xy 387.905142 -35.876738) (xy 387.911466 -35.881927)
			(xy 387.974463 -35.944093) (xy 388.031509 -36.011762) (xy 388.082123 -36.084366) (xy 388.125884 -36.161296)
			(xy 388.162422 -36.241908) (xy 388.191431 -36.325524) (xy 388.212669 -36.411443) (xy 388.225957 -36.498946)
			(xy 388.228382 -36.539928) (xy 394.838664 -36.539928) (xy 394.838664 -36.479992) (xy 394.846487 -36.42057)
			(xy 394.862 -36.362677) (xy 394.884936 -36.307304) (xy 394.914903 -36.255398) (xy 394.95139 -36.207848)
			(xy 394.99377 -36.165468) (xy 395.04132 -36.128981) (xy 395.093226 -36.099014) (xy 395.148599 -36.076078)
			(xy 395.206492 -36.060565) (xy 395.265914 -36.052742) (xy 395.32585 -36.052742) (xy 395.385272 -36.060565)
			(xy 395.443165 -36.076078) (xy 395.498538 -36.099014) (xy 395.550444 -36.128981) (xy 395.597994 -36.165468)
			(xy 395.640374 -36.207848) (xy 395.676861 -36.255398) (xy 395.706828 -36.307304) (xy 395.729764 -36.362677)
			(xy 395.745277 -36.42057) (xy 395.7531 -36.479992) (xy 395.75359 -36.50996) (xy 395.7531 -36.539928)
			(xy 395.745277 -36.59935) (xy 395.729764 -36.657243) (xy 395.706828 -36.712616) (xy 395.676861 -36.764522)
			(xy 395.640374 -36.812072) (xy 395.597994 -36.854452) (xy 395.550444 -36.890939) (xy 395.498538 -36.920906)
			(xy 395.443165 -36.943842) (xy 395.385272 -36.959355) (xy 395.32585 -36.967178) (xy 395.265914 -36.967178)
			(xy 395.206492 -36.959355) (xy 395.148599 -36.943842) (xy 395.093226 -36.920906) (xy 395.04132 -36.890939)
			(xy 394.99377 -36.854452) (xy 394.95139 -36.812072) (xy 394.914903 -36.764522) (xy 394.884936 -36.712616)
			(xy 394.862 -36.657243) (xy 394.846487 -36.59935) (xy 394.838664 -36.539928) (xy 388.228382 -36.539928)
			(xy 388.231184 -36.587297) (xy 388.228306 -36.675755) (xy 388.217346 -36.76358) (xy 388.198397 -36.850033)
			(xy 388.171619 -36.93439) (xy 388.137234 -37.015944) (xy 388.095533 -37.094009) (xy 388.071614 -37.131244)
			(xy 388.063232 -37.143944) (xy 388.063232 -37.159184) (xy 388.063633 -37.169208) (xy 388.071304 -37.187731)
			(xy 388.085482 -37.201905) (xy 388.104008 -37.20957) (xy 388.114032 -37.209984) (xy 388.19201 -37.209984)
			(xy 388.23545 -37.21041) (xy 388.321958 -37.218427) (xy 388.407358 -37.234392) (xy 388.49092 -37.258168)
			(xy 388.571932 -37.289553) (xy 388.649703 -37.328279) (xy 388.723569 -37.374016) (xy 388.7929 -37.426373)
			(xy 388.846416 -37.47516) (xy 392.059158 -37.47516) (xy 392.063229 -37.419538) (xy 392.075355 -37.365101)
			(xy 392.095278 -37.31301) (xy 392.122574 -37.264375) (xy 392.15666 -37.220232) (xy 392.196809 -37.181523)
			(xy 392.242167 -37.149072) (xy 392.291767 -37.123571) (xy 392.344551 -37.105564) (xy 392.399394 -37.095434)
			(xy 392.455128 -37.093397) (xy 392.510565 -37.099497) (xy 392.564522 -37.113603) (xy 392.615851 -37.135415)
			(xy 392.663457 -37.164469) (xy 392.706325 -37.200144) (xy 392.743542 -37.241681) (xy 392.774315 -37.288194)
			(xy 392.797987 -37.338691) (xy 392.814055 -37.392098) (xy 392.822175 -37.447274) (xy 392.822684 -37.47516)
			(xy 392.822175 -37.503046) (xy 392.814055 -37.558222) (xy 392.797987 -37.611629) (xy 392.774315 -37.662126)
			(xy 392.754335 -37.692326) (xy 394.173184 -37.692326) (xy 394.173184 -37.63239) (xy 394.181007 -37.572968)
			(xy 394.19652 -37.515075) (xy 394.219456 -37.459702) (xy 394.249423 -37.407796) (xy 394.28591 -37.360246)
			(xy 394.32829 -37.317866) (xy 394.37584 -37.281379) (xy 394.427746 -37.251412) (xy 394.483119 -37.228476)
			(xy 394.541012 -37.212963) (xy 394.600434 -37.20514) (xy 394.66037 -37.20514) (xy 394.719792 -37.212963)
			(xy 394.777685 -37.228476) (xy 394.833058 -37.251412) (xy 394.884964 -37.281379) (xy 394.932514 -37.317866)
			(xy 394.974894 -37.360246) (xy 395.011381 -37.407796) (xy 395.041348 -37.459702) (xy 395.064284 -37.515075)
			(xy 395.079797 -37.572968) (xy 395.08762 -37.63239) (xy 395.08811 -37.662358) (xy 395.08762 -37.692326)
			(xy 395.079797 -37.751748) (xy 395.064284 -37.809641) (xy 395.041348 -37.865014) (xy 395.011381 -37.91692)
			(xy 394.974894 -37.96447) (xy 394.932514 -38.00685) (xy 394.884964 -38.043337) (xy 394.833058 -38.073304)
			(xy 394.777685 -38.09624) (xy 394.719792 -38.111753) (xy 394.66037 -38.119576) (xy 394.600434 -38.119576)
			(xy 394.541012 -38.111753) (xy 394.483119 -38.09624) (xy 394.427746 -38.073304) (xy 394.37584 -38.043337)
			(xy 394.32829 -38.00685) (xy 394.28591 -37.96447) (xy 394.249423 -37.91692) (xy 394.219456 -37.865014)
			(xy 394.19652 -37.809641) (xy 394.181007 -37.751748) (xy 394.173184 -37.692326) (xy 392.754335 -37.692326)
			(xy 392.743542 -37.708639) (xy 392.706325 -37.750176) (xy 392.663457 -37.785851) (xy 392.615851 -37.814905)
			(xy 392.564522 -37.836717) (xy 392.510565 -37.850823) (xy 392.455128 -37.856923) (xy 392.399394 -37.854886)
			(xy 392.344551 -37.844756) (xy 392.291767 -37.826749) (xy 392.242167 -37.801248) (xy 392.196809 -37.768797)
			(xy 392.15666 -37.730088) (xy 392.122574 -37.685945) (xy 392.095278 -37.63731) (xy 392.075355 -37.585219)
			(xy 392.063229 -37.530782) (xy 392.059158 -37.47516) (xy 388.846416 -37.47516) (xy 388.857104 -37.484903)
			(xy 388.915634 -37.549108) (xy 388.96799 -37.618439) (xy 389.013726 -37.692306) (xy 389.052451 -37.770077)
			(xy 389.083835 -37.851089) (xy 389.10761 -37.934652) (xy 389.123574 -38.020052) (xy 389.13159 -38.10656)
			(xy 389.13159 -38.19344) (xy 389.123574 -38.279948) (xy 389.10761 -38.365348) (xy 389.083835 -38.448911)
			(xy 389.067468 -38.49116) (xy 392.059158 -38.49116) (xy 392.063229 -38.435538) (xy 392.075355 -38.381101)
			(xy 392.095278 -38.32901) (xy 392.122574 -38.280375) (xy 392.15666 -38.236232) (xy 392.196809 -38.197523)
			(xy 392.242167 -38.165072) (xy 392.291767 -38.139571) (xy 392.344551 -38.121564) (xy 392.399394 -38.111434)
			(xy 392.455128 -38.109397) (xy 392.510565 -38.115497) (xy 392.564522 -38.129603) (xy 392.615851 -38.151415)
			(xy 392.663457 -38.180469) (xy 392.706325 -38.216144) (xy 392.743542 -38.257681) (xy 392.774315 -38.304194)
			(xy 392.797987 -38.354691) (xy 392.814055 -38.408098) (xy 392.822175 -38.463274) (xy 392.822684 -38.49116)
			(xy 392.822175 -38.519046) (xy 392.814055 -38.574222) (xy 392.797987 -38.627629) (xy 392.774315 -38.678126)
			(xy 392.759037 -38.701218) (xy 395.737586 -38.701218) (xy 395.741657 -38.645596) (xy 395.753783 -38.591159)
			(xy 395.773706 -38.539068) (xy 395.801002 -38.490433) (xy 395.835088 -38.44629) (xy 395.875237 -38.407581)
			(xy 395.920595 -38.37513) (xy 395.970195 -38.349629) (xy 396.022979 -38.331622) (xy 396.077822 -38.321492)
			(xy 396.133556 -38.319455) (xy 396.188993 -38.325555) (xy 396.24295 -38.339661) (xy 396.294279 -38.361473)
			(xy 396.341885 -38.390527) (xy 396.384753 -38.426202) (xy 396.42197 -38.467739) (xy 396.452743 -38.514252)
			(xy 396.476415 -38.564749) (xy 396.492483 -38.618156) (xy 396.500603 -38.673332) (xy 396.501112 -38.701218)
			(xy 396.500603 -38.729104) (xy 396.492483 -38.78428) (xy 396.476415 -38.837687) (xy 396.452743 -38.888184)
			(xy 396.42197 -38.934697) (xy 396.384753 -38.976234) (xy 396.341885 -39.011909) (xy 396.294279 -39.040963)
			(xy 396.24295 -39.062775) (xy 396.188993 -39.076881) (xy 396.133556 -39.082981) (xy 396.077822 -39.080944)
			(xy 396.022979 -39.070814) (xy 395.970195 -39.052807) (xy 395.920595 -39.027306) (xy 395.875237 -38.994855)
			(xy 395.835088 -38.956146) (xy 395.801002 -38.912003) (xy 395.773706 -38.863368) (xy 395.753783 -38.811277)
			(xy 395.741657 -38.75684) (xy 395.737586 -38.701218) (xy 392.759037 -38.701218) (xy 392.743542 -38.724639)
			(xy 392.706325 -38.766176) (xy 392.663457 -38.801851) (xy 392.615851 -38.830905) (xy 392.564522 -38.852717)
			(xy 392.510565 -38.866823) (xy 392.455128 -38.872923) (xy 392.399394 -38.870886) (xy 392.344551 -38.860756)
			(xy 392.291767 -38.842749) (xy 392.242167 -38.817248) (xy 392.196809 -38.784797) (xy 392.15666 -38.746088)
			(xy 392.122574 -38.701945) (xy 392.095278 -38.65331) (xy 392.075355 -38.601219) (xy 392.063229 -38.546782)
			(xy 392.059158 -38.49116) (xy 389.067468 -38.49116) (xy 389.052451 -38.529923) (xy 389.013726 -38.607694)
			(xy 388.96799 -38.681561) (xy 388.915634 -38.750892) (xy 388.857104 -38.815097) (xy 388.7929 -38.873627)
			(xy 388.723569 -38.925984) (xy 388.649703 -38.971721) (xy 388.571932 -39.010447) (xy 388.49092 -39.041832)
			(xy 388.407358 -39.065608) (xy 388.321958 -39.081573) (xy 388.23545 -39.08959) (xy 388.19201 -39.090092)
			(xy 386.33781 -39.090092) (xy 386.294373 -39.08953) (xy 386.207868 -39.081515) (xy 386.122473 -39.065553)
			(xy 386.038914 -39.041779) (xy 385.957906 -39.010397) (xy 385.880138 -38.971674) (xy 385.806276 -38.925941)
			(xy 385.736948 -38.873588) (xy 385.672746 -38.815061) (xy 385.614219 -38.75086) (xy 385.561865 -38.681533)
			(xy 385.516131 -38.60767) (xy 385.477407 -38.529903) (xy 385.446024 -38.448895) (xy 385.42225 -38.365337)
			(xy 385.406286 -38.279941) (xy 385.398271 -38.193437) (xy 383.844038 -38.193437) (xy 383.844038 -42.849038)
			(xy 395.191994 -42.849038) (xy 395.196065 -42.793416) (xy 395.208191 -42.738979) (xy 395.228114 -42.686888)
			(xy 395.25541 -42.638253) (xy 395.289496 -42.59411) (xy 395.329645 -42.555401) (xy 395.375003 -42.52295)
			(xy 395.424603 -42.497449) (xy 395.477387 -42.479442) (xy 395.53223 -42.469312) (xy 395.587964 -42.467275)
			(xy 395.643401 -42.473375) (xy 395.697358 -42.487481) (xy 395.748687 -42.509293) (xy 395.796293 -42.538347)
			(xy 395.839161 -42.574022) (xy 395.876378 -42.615559) (xy 395.907151 -42.662072) (xy 395.930823 -42.712569)
			(xy 395.946891 -42.765976) (xy 395.955011 -42.821152) (xy 395.95552 -42.849038) (xy 395.955011 -42.876924)
			(xy 395.946891 -42.9321) (xy 395.930823 -42.985507) (xy 395.907151 -43.036004) (xy 395.876378 -43.082517)
			(xy 395.839161 -43.124054) (xy 395.796293 -43.159729) (xy 395.748687 -43.188783) (xy 395.697358 -43.210595)
			(xy 395.643401 -43.224701) (xy 395.587964 -43.230801) (xy 395.53223 -43.228764) (xy 395.477387 -43.218634)
			(xy 395.424603 -43.200627) (xy 395.375003 -43.175126) (xy 395.329645 -43.142675) (xy 395.289496 -43.103966)
			(xy 395.25541 -43.059823) (xy 395.228114 -43.011188) (xy 395.208191 -42.959097) (xy 395.196065 -42.90466)
			(xy 395.191994 -42.849038) (xy 383.844038 -42.849038) (xy 383.844038 -43.719242) (xy 383.844501 -43.729118)
			(xy 383.851944 -43.747416) (xy 383.858516 -43.754802) (xy 383.85877 -43.755056) (xy 384.336798 -44.233084)
			(xy 384.337306 -44.233592) (xy 384.344687 -44.240177) (xy 384.362985 -44.247639) (xy 384.372866 -44.24807)
		)
		(stroke
			(width 0)
			(type solid)
		)
		(fill yes)
		(layer "B.Cu")
		(net "P12V_SSD13")
	)
	(gr_poly
		(pts
			(xy 46.214792 -44.24807) (xy 46.224965 -44.247618) (xy 46.243708 -44.239702) (xy 46.257893 -44.225116)
			(xy 46.262036 -44.215812) (xy 46.302422 -44.112942) (xy 46.295564 -44.082716) (xy 46.28388 -44.072048)
			(xy 46.26119 -44.0503) (xy 46.221379 -44.001665) (xy 46.188593 -43.948044) (xy 46.163446 -43.890443)
			(xy 46.146412 -43.829945) (xy 46.13781 -43.767685) (xy 46.137322 -43.73626) (xy 46.137812 -43.706292)
			(xy 46.145635 -43.64687) (xy 46.161148 -43.588977) (xy 46.184084 -43.533604) (xy 46.214051 -43.481698)
			(xy 46.250538 -43.434148) (xy 46.292918 -43.391768) (xy 46.340468 -43.355281) (xy 46.392374 -43.325314)
			(xy 46.447747 -43.302378) (xy 46.50564 -43.286865) (xy 46.565062 -43.279042) (xy 46.624998 -43.279042)
			(xy 46.68442 -43.286865) (xy 46.742313 -43.302378) (xy 46.797686 -43.325314) (xy 46.849592 -43.355281)
			(xy 46.897142 -43.391768) (xy 46.939522 -43.434148) (xy 46.976009 -43.481698) (xy 47.005976 -43.533604)
			(xy 47.028912 -43.588977) (xy 47.044425 -43.64687) (xy 47.052248 -43.706292) (xy 47.052738 -43.73626)
			(xy 47.052222 -43.767685) (xy 47.043632 -43.829946) (xy 47.026608 -43.890447) (xy 47.00147 -43.948052)
			(xy 46.968691 -44.001678) (xy 46.928885 -44.050317) (xy 46.90618 -44.072048) (xy 46.894496 -44.082716)
			(xy 46.887638 -44.112942) (xy 46.928024 -44.215812) (xy 46.93216 -44.225118) (xy 46.946358 -44.239693)
			(xy 46.965095 -44.247627) (xy 46.975268 -44.24807) (xy 47.877476 -44.24807) (xy 47.887348 -44.247599)
			(xy 47.905629 -44.240138) (xy 47.913036 -44.233592) (xy 47.91329 -44.233338) (xy 48.472598 -43.67403)
			(xy 48.473106 -43.673522) (xy 48.479689 -43.666142) (xy 48.487138 -43.647842) (xy 48.487584 -43.637962)
			(xy 48.487584 -37.58946) (xy 48.487156 -37.580071) (xy 48.480413 -37.562544) (xy 48.467837 -37.548598)
			(xy 48.459644 -37.543994) (xy 48.378872 -37.5031) (xy 48.370264 -37.499248) (xy 48.351514 -37.497395)
			(xy 48.333348 -37.502398) (xy 48.325532 -37.507672) (xy 48.300736 -37.525303) (xy 48.24672 -37.553298)
			(xy 48.188945 -37.572363) (xy 48.128876 -37.582014) (xy 48.098456 -37.582602) (xy 48.071207 -37.582113)
			(xy 48.017265 -37.574352) (xy 47.964976 -37.558993) (xy 47.915406 -37.53635) (xy 47.869561 -37.506883)
			(xy 47.828377 -37.471192) (xy 47.792691 -37.430003) (xy 47.763229 -37.384156) (xy 47.740592 -37.334582)
			(xy 47.725239 -37.282292) (xy 47.717484 -37.228349) (xy 47.717484 -37.173851) (xy 47.725239 -37.119908)
			(xy 47.740592 -37.067618) (xy 47.763229 -37.018044) (xy 47.792691 -36.972197) (xy 47.828377 -36.931008)
			(xy 47.869561 -36.895317) (xy 47.915406 -36.86585) (xy 47.964976 -36.843207) (xy 48.017265 -36.827848)
			(xy 48.071207 -36.820087) (xy 48.098456 -36.819586) (xy 48.128874 -36.820182) (xy 48.188939 -36.829843)
			(xy 48.24671 -36.848911) (xy 48.300724 -36.876903) (xy 48.325532 -36.894516) (xy 48.33331 -36.89988)
			(xy 48.351498 -36.904944) (xy 48.370279 -36.903021) (xy 48.378872 -36.899088) (xy 48.459644 -36.858194)
			(xy 48.467882 -36.853643) (xy 48.480504 -36.839701) (xy 48.487221 -36.822134) (xy 48.487584 -36.812728)
			(xy 48.487584 -35.109658) (xy 48.469042 -35.083496) (xy 48.453802 -35.078162) (xy 48.42753 -35.068318)
			(xy 48.377969 -35.042027) (xy 48.33279 -35.008765) (xy 48.292967 -34.969249) (xy 48.275748 -34.947098)
			(xy 48.270414 -34.939986) (xy 48.248316 -34.925254) (xy 48.244366 -34.922819) (xy 48.235808 -34.919232)
			(xy 48.231298 -34.918142) (xy 48.201072 -34.911284) (xy 48.182276 -34.914078) (xy 48.173894 -34.91865)
			(xy 48.155512 -34.928876) (xy 48.117224 -34.946302) (xy 48.09744 -34.953448) (xy 48.073239 -34.96149)
			(xy 48.023505 -34.972781) (xy 47.972825 -34.978479) (xy 47.947326 -34.978848) (xy 47.921826 -34.978488)
			(xy 47.871143 -34.972797) (xy 47.821408 -34.961506) (xy 47.797212 -34.953448) (xy 47.777427 -34.946304)
			(xy 47.739137 -34.928881) (xy 47.720758 -34.91865) (xy 47.712376 -34.914078) (xy 47.69358 -34.911284)
			(xy 47.663354 -34.918142) (xy 47.658834 -34.919205) (xy 47.650267 -34.922783) (xy 47.646336 -34.925254)
			(xy 47.623984 -34.94024) (xy 47.618904 -34.947352) (xy 47.600752 -34.970649) (xy 47.558471 -35.011882)
			(xy 47.510339 -35.046103) (xy 47.457505 -35.072492) (xy 47.401234 -35.090419) (xy 47.342872 -35.099456)
			(xy 47.313342 -35.100006) (xy 47.30242 -35.100006) (xy 47.302166 -35.099752) (xy 47.275451 -35.098516)
			(xy 47.222737 -35.089493) (xy 47.1718 -35.073199) (xy 47.123637 -35.049953) (xy 47.07919 -35.020211)
			(xy 47.039332 -34.984553) (xy 47.004843 -34.943681) (xy 46.976398 -34.898393) (xy 46.954554 -34.849577)
			(xy 46.93974 -34.79819) (xy 46.932246 -34.745238) (xy 46.931834 -34.718498) (xy 46.932298 -34.691246)
			(xy 46.940055 -34.637298) (xy 46.955412 -34.585003) (xy 46.978055 -34.535425) (xy 47.007523 -34.489576)
			(xy 47.043218 -34.448387) (xy 47.084411 -34.412697) (xy 47.130264 -34.383234) (xy 47.179844 -34.360596)
			(xy 47.232141 -34.345246) (xy 47.28609 -34.337494) (xy 47.313342 -34.33699) (xy 47.328135 -34.337134)
			(xy 47.357632 -34.339423) (xy 47.37227 -34.341562) (xy 47.383192 -34.34334) (xy 47.404528 -34.337244)
			(xy 47.48022 -34.272728) (xy 47.489364 -34.252662) (xy 47.489364 -33.93694) (xy 47.489364 -33.92551)
			(xy 47.48022 -33.905444) (xy 47.404528 -33.840928) (xy 47.383192 -33.834832) (xy 47.37227 -33.83661)
			(xy 47.357444 -33.838784) (xy 47.327564 -33.841076) (xy 47.31258 -33.841182) (xy 47.312326 -33.841182)
			(xy 47.285121 -33.840629) (xy 47.23128 -33.83276) (xy 47.179104 -33.817321) (xy 47.129651 -33.794624)
			(xy 47.083924 -33.765131) (xy 47.042852 -33.72944) (xy 47.007269 -33.688274) (xy 46.977896 -33.642471)
			(xy 46.955329 -33.592958) (xy 46.940026 -33.540742) (xy 46.932298 -33.48688) (xy 46.931834 -33.459674)
			(xy 46.932299 -33.432423) (xy 46.940059 -33.378478) (xy 46.955418 -33.326185) (xy 46.978063 -33.276611)
			(xy 47.007532 -33.230764) (xy 47.043226 -33.189578) (xy 47.084419 -33.153891) (xy 47.130271 -33.12443)
			(xy 47.179849 -33.101794) (xy 47.232144 -33.086445) (xy 47.286091 -33.078694) (xy 47.313342 -33.078166)
			(xy 47.313596 -33.078166) (xy 47.343101 -33.078724) (xy 47.401405 -33.087819) (xy 47.457615 -33.105778)
			(xy 47.510392 -33.132173) (xy 47.558479 -33.166375) (xy 47.60073 -33.20757) (xy 47.618904 -33.23082)
			(xy 47.623984 -33.237932) (xy 47.646336 -33.252918) (xy 47.650287 -33.25535) (xy 47.658846 -33.25893)
			(xy 47.663354 -33.26003) (xy 47.69358 -33.266888) (xy 47.712376 -33.264094) (xy 47.720758 -33.259522)
			(xy 47.739139 -33.249295) (xy 47.777426 -33.231866) (xy 47.797212 -33.224724) (xy 47.821412 -33.21668)
			(xy 47.871146 -33.205385) (xy 47.921826 -33.199681) (xy 47.947326 -33.199324) (xy 47.972826 -33.199687)
			(xy 48.023507 -33.205383) (xy 48.07324 -33.216679) (xy 48.09744 -33.224724) (xy 48.117224 -33.231869)
			(xy 48.155512 -33.249295) (xy 48.173894 -33.259522) (xy 48.182276 -33.264094) (xy 48.201072 -33.266888)
			(xy 48.231298 -33.26003) (xy 48.235819 -33.25897) (xy 48.24439 -33.255397) (xy 48.248316 -33.252918)
			(xy 48.270414 -33.238186) (xy 48.275748 -33.231074) (xy 48.29295 -33.20891) (xy 48.332777 -33.169394)
			(xy 48.377962 -33.136138) (xy 48.427531 -33.109858) (xy 48.453802 -33.10001) (xy 48.469042 -33.094676)
			(xy 48.487584 -33.068514) (xy 48.487584 -31.509462) (xy 48.469042 -31.4833) (xy 48.453802 -31.477966)
			(xy 48.42753 -31.468122) (xy 48.377969 -31.441832) (xy 48.33279 -31.40857) (xy 48.292966 -31.369053)
			(xy 48.275748 -31.346902) (xy 48.270414 -31.33979) (xy 48.248316 -31.325058) (xy 48.244366 -31.322622)
			(xy 48.235808 -31.319036) (xy 48.231298 -31.317946) (xy 48.201072 -31.311088) (xy 48.182276 -31.313882)
			(xy 48.173894 -31.318454) (xy 48.155512 -31.32868) (xy 48.117224 -31.346106) (xy 48.09744 -31.353252)
			(xy 48.073239 -31.361294) (xy 48.023505 -31.372585) (xy 47.972825 -31.378283) (xy 47.947326 -31.378652)
			(xy 47.921826 -31.378292) (xy 47.871143 -31.372601) (xy 47.821408 -31.36131) (xy 47.797212 -31.353252)
			(xy 47.777427 -31.346108) (xy 47.739137 -31.328685) (xy 47.720758 -31.318454) (xy 47.712376 -31.313882)
			(xy 47.69358 -31.311088) (xy 47.663354 -31.317946) (xy 47.658834 -31.319009) (xy 47.650267 -31.322588)
			(xy 47.646336 -31.325058) (xy 47.623984 -31.340044) (xy 47.618904 -31.347156) (xy 47.600752 -31.370453)
			(xy 47.558471 -31.411686) (xy 47.510338 -31.445906) (xy 47.457505 -31.472295) (xy 47.401234 -31.490222)
			(xy 47.342871 -31.499258) (xy 47.313342 -31.49981) (xy 47.30242 -31.49981) (xy 47.302166 -31.499556)
			(xy 47.275451 -31.49832) (xy 47.222737 -31.489297) (xy 47.1718 -31.473004) (xy 47.123636 -31.449758)
			(xy 47.079189 -31.420015) (xy 47.039331 -31.384358) (xy 47.004841 -31.343485) (xy 46.976395 -31.298197)
			(xy 46.954551 -31.249382) (xy 46.939737 -31.197994) (xy 46.932242 -31.145042) (xy 46.931834 -31.118302)
			(xy 46.932297 -31.09105) (xy 46.940054 -31.037101) (xy 46.95541 -30.984806) (xy 46.978053 -30.935228)
			(xy 47.007522 -30.889377) (xy 47.043216 -30.848188) (xy 47.08441 -30.812498) (xy 47.130263 -30.783034)
			(xy 47.179843 -30.760396) (xy 47.23214 -30.745046) (xy 47.28609 -30.737294) (xy 47.313342 -30.736794)
			(xy 47.328135 -30.736938) (xy 47.357632 -30.739227) (xy 47.37227 -30.741366) (xy 47.383192 -30.743144)
			(xy 47.404528 -30.737048) (xy 47.48022 -30.672532) (xy 47.489364 -30.652466) (xy 47.489364 -30.336744)
			(xy 47.489364 -30.325314) (xy 47.48022 -30.305248) (xy 47.404528 -30.240732) (xy 47.383192 -30.234636)
			(xy 47.37227 -30.236414) (xy 47.357444 -30.238588) (xy 47.327564 -30.24088) (xy 47.31258 -30.240986)
			(xy 47.312326 -30.240986) (xy 47.285121 -30.240433) (xy 47.23128 -30.232564) (xy 47.179103 -30.217125)
			(xy 47.12965 -30.194428) (xy 47.083923 -30.164935) (xy 47.042851 -30.129244) (xy 47.007267 -30.088079)
			(xy 46.977893 -30.042275) (xy 46.955326 -29.992763) (xy 46.940023 -29.940546) (xy 46.932294 -29.886685)
			(xy 46.931834 -29.859478) (xy 46.932299 -29.832227) (xy 46.940059 -29.778281) (xy 46.955417 -29.725988)
			(xy 46.978061 -29.676413) (xy 47.007531 -29.630566) (xy 47.043225 -29.58938) (xy 47.084417 -29.553692)
			(xy 47.13027 -29.524231) (xy 47.179848 -29.501595) (xy 47.232144 -29.486245) (xy 47.286091 -29.478494)
			(xy 47.313342 -29.47797) (xy 47.313596 -29.47797) (xy 47.343101 -29.478528) (xy 47.401405 -29.487623)
			(xy 47.457615 -29.505582) (xy 47.510392 -29.531977) (xy 47.558478 -29.56618) (xy 47.600729 -29.607374)
			(xy 47.618904 -29.630624) (xy 47.623984 -29.637736) (xy 47.646336 -29.652722) (xy 47.650287 -29.655154)
			(xy 47.658847 -29.658734) (xy 47.663354 -29.659834) (xy 47.69358 -29.666692) (xy 47.712376 -29.663898)
			(xy 47.720758 -29.659326) (xy 47.739139 -29.649099) (xy 47.777426 -29.63167) (xy 47.797212 -29.624528)
			(xy 47.821412 -29.616484) (xy 47.871146 -29.605188) (xy 47.921826 -29.599485) (xy 47.947326 -29.599128)
			(xy 47.972826 -29.599491) (xy 48.023507 -29.605187) (xy 48.07324 -29.616483) (xy 48.09744 -29.624528)
			(xy 48.117224 -29.631674) (xy 48.155512 -29.6491) (xy 48.173894 -29.659326) (xy 48.182276 -29.663898)
			(xy 48.201072 -29.666692) (xy 48.231298 -29.659834) (xy 48.235819 -29.658774) (xy 48.24439 -29.655202)
			(xy 48.248316 -29.652722) (xy 48.270414 -29.63799) (xy 48.275748 -29.630878) (xy 48.29295 -29.608714)
			(xy 48.332777 -29.569198) (xy 48.377961 -29.535941) (xy 48.42753 -29.509661) (xy 48.453802 -29.499814)
			(xy 48.469042 -29.49448) (xy 48.487584 -29.468318) (xy 48.487584 -19.837908) (xy 48.487375 -19.831327)
			(xy 48.484035 -19.818595) (xy 48.48098 -19.812762) (xy 48.46574 -19.786346) (xy 48.457612 -19.77771)
			(xy 48.452278 -19.774154) (xy 48.430477 -19.759653) (xy 48.390687 -19.72562) (xy 48.355922 -19.686467)
			(xy 48.341026 -19.664934) (xy 48.340772 -19.66468) (xy 48.340772 -19.664426) (xy 48.334483 -19.656131)
			(xy 48.316921 -19.64499) (xy 48.306736 -19.642836) (xy 48.23333 -19.631152) (xy 48.222967 -19.629978)
			(xy 48.202771 -19.635096) (xy 48.194214 -19.641058) (xy 48.174056 -19.656164) (xy 48.130524 -19.681511)
			(xy 48.084037 -19.700915) (xy 48.035404 -19.714041) (xy 47.985467 -19.72066) (xy 47.96028 -19.721068)
			(xy 47.95266 -19.721068) (xy 47.925764 -19.720074) (xy 47.872637 -19.711456) (xy 47.821249 -19.695457)
			(xy 47.77262 -19.672392) (xy 47.727717 -19.642721) (xy 47.68743 -19.607032) (xy 47.65256 -19.566035)
			(xy 47.623799 -19.520543) (xy 47.601718 -19.47146) (xy 47.586756 -19.41976) (xy 47.57921 -19.366471)
			(xy 47.578772 -19.33956) (xy 47.57926 -19.31231) (xy 47.587022 -19.258366) (xy 47.60238 -19.206075)
			(xy 47.625023 -19.156501) (xy 47.65449 -19.110654) (xy 47.690181 -19.069467) (xy 47.73137 -19.033778)
			(xy 47.777219 -19.004313) (xy 47.826793 -18.981673) (xy 47.879085 -18.966317) (xy 47.93303 -18.958559)
			(xy 47.96028 -18.958052) (xy 47.964344 -18.958052) (xy 47.979584 -18.958306) (xy 48.005746 -18.941288)
			(xy 48.048164 -18.840196) (xy 48.051714 -18.830751) (xy 48.051823 -18.81059) (xy 48.044108 -18.791963)
			(xy 48.037242 -18.78457) (xy 47.667926 -18.415254) (xy 47.660814 -18.407888) (xy 47.642018 -18.400268)
			(xy 35.929316 -18.400268) (xy 35.919266 -18.400774) (xy 35.900706 -18.408496) (xy 35.893248 -18.415254)
			(xy 35.558984 -18.749518) (xy 35.551618 -18.75663) (xy 35.543998 -18.775426) (xy 35.543998 -21.738336)
			(xy 37.41674 -21.738336) (xy 37.417241 -21.709596) (xy 37.425871 -21.652769) (xy 37.442928 -21.597878)
			(xy 37.468024 -21.546167) (xy 37.500592 -21.498805) (xy 37.519864 -21.477478) (xy 37.526468 -21.470366)
			(xy 37.53358 -21.45284) (xy 37.53358 -21.363432) (xy 37.526468 -21.345906) (xy 37.519864 -21.338794)
			(xy 37.500627 -21.317437) (xy 37.468057 -21.270081) (xy 37.442961 -21.218374) (xy 37.425907 -21.163488)
			(xy 37.41728 -21.106664) (xy 37.417276 -21.049189) (xy 37.425895 -20.992363) (xy 37.442942 -20.937475)
			(xy 37.468031 -20.885764) (xy 37.500594 -20.838404) (xy 37.519864 -20.817078) (xy 37.526468 -20.809966)
			(xy 37.53358 -20.79244) (xy 37.53358 -20.703032) (xy 37.526468 -20.685506) (xy 37.519864 -20.678394)
			(xy 37.500627 -20.657037) (xy 37.468057 -20.609681) (xy 37.442961 -20.557974) (xy 37.425907 -20.503088)
			(xy 37.41728 -20.446264) (xy 37.417276 -20.388789) (xy 37.425895 -20.331963) (xy 37.442942 -20.277075)
			(xy 37.468031 -20.225364) (xy 37.500594 -20.178004) (xy 37.519864 -20.156678) (xy 37.526468 -20.149566)
			(xy 37.53358 -20.13204) (xy 37.53358 -20.042632) (xy 37.526468 -20.025106) (xy 37.519864 -20.017994)
			(xy 37.500627 -19.996637) (xy 37.468057 -19.949281) (xy 37.442961 -19.897574) (xy 37.425907 -19.842688)
			(xy 37.41728 -19.785864) (xy 37.417276 -19.728389) (xy 37.425895 -19.671563) (xy 37.442942 -19.616675)
			(xy 37.468031 -19.564964) (xy 37.500594 -19.517604) (xy 37.519864 -19.496278) (xy 37.526468 -19.489166)
			(xy 37.53358 -19.47164) (xy 37.53358 -19.382232) (xy 37.526468 -19.364706) (xy 37.519864 -19.357594)
			(xy 37.500615 -19.336248) (xy 37.468044 -19.288892) (xy 37.442947 -19.237185) (xy 37.425892 -19.182298)
			(xy 37.417264 -19.125474) (xy 37.41674 -19.096736) (xy 37.417226 -19.069485) (xy 37.424982 -19.015537)
			(xy 37.440337 -18.963242) (xy 37.462979 -18.913665) (xy 37.492445 -18.867815) (xy 37.528136 -18.826624)
			(xy 37.569327 -18.790933) (xy 37.615177 -18.761467) (xy 37.664754 -18.738825) (xy 37.717049 -18.72347)
			(xy 37.770997 -18.715714) (xy 37.825499 -18.715714) (xy 37.879447 -18.72347) (xy 37.931742 -18.738825)
			(xy 37.981319 -18.761467) (xy 38.027169 -18.790933) (xy 38.06836 -18.826624) (xy 38.104051 -18.867815)
			(xy 38.133517 -18.913665) (xy 38.156159 -18.963242) (xy 38.171514 -19.015537) (xy 38.17927 -19.069485)
			(xy 38.179756 -19.096736) (xy 38.179239 -19.125475) (xy 38.170613 -19.182302) (xy 38.15356 -19.237192)
			(xy 38.128467 -19.288904) (xy 38.095902 -19.336267) (xy 38.076632 -19.357594) (xy 38.070028 -19.364706)
			(xy 38.062916 -19.382232) (xy 38.062916 -19.47164) (xy 38.070028 -19.489166) (xy 38.076632 -19.496278)
			(xy 38.095936 -19.517575) (xy 38.128495 -19.564944) (xy 38.153581 -19.616661) (xy 38.170626 -19.671556)
			(xy 38.179244 -19.728386) (xy 38.17924 -19.785866) (xy 38.170614 -19.842695) (xy 38.153562 -19.897588)
			(xy 38.128469 -19.949301) (xy 38.095903 -19.996666) (xy 38.076632 -20.017994) (xy 38.070028 -20.025106)
			(xy 38.062916 -20.042632) (xy 38.062916 -20.13204) (xy 38.070028 -20.149566) (xy 38.076632 -20.156678)
			(xy 38.095936 -20.177975) (xy 38.128495 -20.225344) (xy 38.153581 -20.277061) (xy 38.170626 -20.331956)
			(xy 38.174205 -20.35556) (xy 47.578262 -20.35556) (xy 47.582333 -20.299938) (xy 47.594459 -20.245501)
			(xy 47.614382 -20.19341) (xy 47.641678 -20.144775) (xy 47.675764 -20.100632) (xy 47.715913 -20.061923)
			(xy 47.761271 -20.029472) (xy 47.810871 -20.003971) (xy 47.863655 -19.985964) (xy 47.918498 -19.975834)
			(xy 47.974232 -19.973797) (xy 48.029669 -19.979897) (xy 48.083626 -19.994003) (xy 48.134955 -20.015815)
			(xy 48.182561 -20.044869) (xy 48.225429 -20.080544) (xy 48.262646 -20.122081) (xy 48.293419 -20.168594)
			(xy 48.317091 -20.219091) (xy 48.333159 -20.272498) (xy 48.341279 -20.327674) (xy 48.341788 -20.35556)
			(xy 48.341279 -20.383446) (xy 48.333159 -20.438622) (xy 48.317091 -20.492029) (xy 48.293419 -20.542526)
			(xy 48.262646 -20.589039) (xy 48.225429 -20.630576) (xy 48.182561 -20.666251) (xy 48.134955 -20.695305)
			(xy 48.083626 -20.717117) (xy 48.029669 -20.731223) (xy 47.974232 -20.737323) (xy 47.918498 -20.735286)
			(xy 47.863655 -20.725156) (xy 47.810871 -20.707149) (xy 47.761271 -20.681648) (xy 47.715913 -20.649197)
			(xy 47.675764 -20.610488) (xy 47.641678 -20.566345) (xy 47.614382 -20.51771) (xy 47.594459 -20.465619)
			(xy 47.582333 -20.411182) (xy 47.578262 -20.35556) (xy 38.174205 -20.35556) (xy 38.179244 -20.388786)
			(xy 38.17924 -20.446266) (xy 38.170614 -20.503095) (xy 38.153562 -20.557988) (xy 38.128469 -20.609701)
			(xy 38.095903 -20.657066) (xy 38.076632 -20.678394) (xy 38.070028 -20.685506) (xy 38.062916 -20.703032)
			(xy 38.062916 -20.79244) (xy 38.070028 -20.809966) (xy 38.076632 -20.817078) (xy 38.095936 -20.838375)
			(xy 38.128495 -20.885744) (xy 38.153581 -20.937461) (xy 38.170626 -20.992356) (xy 38.179244 -21.049186)
			(xy 38.17924 -21.106666) (xy 38.170614 -21.163495) (xy 38.153562 -21.218388) (xy 38.128469 -21.270101)
			(xy 38.095903 -21.317466) (xy 38.076632 -21.338794) (xy 38.070028 -21.345906) (xy 38.062916 -21.363432)
			(xy 38.062916 -21.37156) (xy 47.578262 -21.37156) (xy 47.582333 -21.315938) (xy 47.594459 -21.261501)
			(xy 47.614382 -21.20941) (xy 47.641678 -21.160775) (xy 47.675764 -21.116632) (xy 47.715913 -21.077923)
			(xy 47.761271 -21.045472) (xy 47.810871 -21.019971) (xy 47.863655 -21.001964) (xy 47.918498 -20.991834)
			(xy 47.974232 -20.989797) (xy 48.029669 -20.995897) (xy 48.083626 -21.010003) (xy 48.134955 -21.031815)
			(xy 48.182561 -21.060869) (xy 48.225429 -21.096544) (xy 48.262646 -21.138081) (xy 48.293419 -21.184594)
			(xy 48.317091 -21.235091) (xy 48.333159 -21.288498) (xy 48.341279 -21.343674) (xy 48.341788 -21.37156)
			(xy 48.341279 -21.399446) (xy 48.333159 -21.454622) (xy 48.317091 -21.508029) (xy 48.293419 -21.558526)
			(xy 48.262646 -21.605039) (xy 48.225429 -21.646576) (xy 48.182561 -21.682251) (xy 48.134955 -21.711305)
			(xy 48.083626 -21.733117) (xy 48.029669 -21.747223) (xy 47.974232 -21.753323) (xy 47.918498 -21.751286)
			(xy 47.863655 -21.741156) (xy 47.810871 -21.723149) (xy 47.761271 -21.697648) (xy 47.715913 -21.665197)
			(xy 47.675764 -21.626488) (xy 47.641678 -21.582345) (xy 47.614382 -21.53371) (xy 47.594459 -21.481619)
			(xy 47.582333 -21.427182) (xy 47.578262 -21.37156) (xy 38.062916 -21.37156) (xy 38.062916 -21.45284)
			(xy 38.070028 -21.470366) (xy 38.076632 -21.477478) (xy 38.095915 -21.498795) (xy 38.128481 -21.546159)
			(xy 38.153571 -21.597873) (xy 38.170619 -21.652766) (xy 38.179238 -21.709596) (xy 38.179756 -21.738336)
			(xy 38.17927 -21.765587) (xy 38.171514 -21.819535) (xy 38.156159 -21.87183) (xy 38.133517 -21.921407)
			(xy 38.104051 -21.967257) (xy 38.06836 -22.008448) (xy 38.027169 -22.044139) (xy 37.981319 -22.073605)
			(xy 37.931742 -22.096247) (xy 37.879447 -22.111602) (xy 37.825499 -22.119358) (xy 37.770997 -22.119358)
			(xy 37.717049 -22.111602) (xy 37.664754 -22.096247) (xy 37.615177 -22.073605) (xy 37.569327 -22.044139)
			(xy 37.528136 -22.008448) (xy 37.492445 -21.967257) (xy 37.462979 -21.921407) (xy 37.440337 -21.87183)
			(xy 37.424982 -21.819535) (xy 37.417226 -21.765587) (xy 37.41674 -21.738336) (xy 35.543998 -21.738336)
			(xy 35.543998 -23.055068) (xy 37.287182 -23.055068) (xy 37.287182 -22.995132) (xy 37.295005 -22.93571)
			(xy 37.310518 -22.877817) (xy 37.333454 -22.822444) (xy 37.363421 -22.770538) (xy 37.399908 -22.722988)
			(xy 37.442288 -22.680608) (xy 37.489838 -22.644121) (xy 37.541744 -22.614154) (xy 37.597117 -22.591218)
			(xy 37.65501 -22.575705) (xy 37.714432 -22.567882) (xy 37.774368 -22.567882) (xy 37.83379 -22.575705)
			(xy 37.891683 -22.591218) (xy 37.947056 -22.614154) (xy 37.998962 -22.644121) (xy 38.046512 -22.680608)
			(xy 38.088892 -22.722988) (xy 38.125379 -22.770538) (xy 38.155346 -22.822444) (xy 38.178282 -22.877817)
			(xy 38.193795 -22.93571) (xy 38.201618 -22.995132) (xy 38.202108 -23.0251) (xy 38.201884 -23.045661)
			(xy 38.198195 -23.086618) (xy 38.194742 -23.106888) (xy 38.192202 -23.120604) (xy 38.201092 -23.145496)
			(xy 38.287706 -23.22068) (xy 38.313614 -23.226014) (xy 38.326822 -23.221696) (xy 38.356023 -23.212601)
			(xy 38.416386 -23.202782) (xy 38.446964 -23.202138) (xy 38.465891 -23.202398) (xy 38.503553 -23.206217)
			(xy 38.522148 -23.209758) (xy 38.534848 -23.212044) (xy 38.55847 -23.205186) (xy 38.636956 -23.128986)
			(xy 38.644576 -23.105618) (xy 38.642544 -23.092918) (xy 38.639484 -23.073888) (xy 38.636173 -23.035483)
			(xy 38.63594 -23.01621) (xy 38.636371 -22.986242) (xy 38.644193 -22.926819) (xy 38.659704 -22.868926)
			(xy 38.682639 -22.813552) (xy 38.712605 -22.761645) (xy 38.74909 -22.714094) (xy 38.791469 -22.671711)
			(xy 38.839018 -22.635223) (xy 38.890922 -22.605253) (xy 38.946295 -22.582315) (xy 39.004187 -22.566799)
			(xy 39.06361 -22.558974) (xy 39.123545 -22.558971) (xy 39.182968 -22.566791) (xy 39.240862 -22.5823)
			(xy 39.296237 -22.605233) (xy 39.348144 -22.635198) (xy 39.395697 -22.671681) (xy 39.43808 -22.71406)
			(xy 39.47457 -22.761607) (xy 39.504541 -22.813511) (xy 39.527481 -22.868883) (xy 39.542998 -22.926775)
			(xy 39.550826 -22.986197) (xy 39.55083 -23.046132) (xy 39.543012 -23.105556) (xy 39.527504 -23.16345)
			(xy 39.504572 -23.218826) (xy 39.474609 -23.270734) (xy 39.438127 -23.318287) (xy 39.39575 -23.360672)
			(xy 39.348203 -23.397163) (xy 39.2963 -23.427136) (xy 39.240929 -23.450077) (xy 39.183038 -23.465596)
			(xy 39.123616 -23.473425) (xy 39.093648 -23.473918) (xy 39.059403 -23.47331) (xy 38.991677 -23.463108)
			(xy 38.958774 -23.453598) (xy 38.946582 -23.449788) (xy 38.922452 -23.45436) (xy 38.8366 -23.522178)
			(xy 38.826694 -23.544784) (xy 38.82771 -23.557738) (xy 38.828472 -23.583646) (xy 38.827986 -23.610897)
			(xy 38.826682 -23.619964) (xy 42.009296 -23.619964) (xy 42.009296 -23.560028) (xy 42.017119 -23.500606)
			(xy 42.032632 -23.442713) (xy 42.055568 -23.38734) (xy 42.085535 -23.335434) (xy 42.122022 -23.287884)
			(xy 42.164402 -23.245504) (xy 42.211952 -23.209017) (xy 42.263858 -23.17905) (xy 42.319231 -23.156114)
			(xy 42.377124 -23.140601) (xy 42.436546 -23.132778) (xy 42.496482 -23.132778) (xy 42.555904 -23.140601)
			(xy 42.613797 -23.156114) (xy 42.66917 -23.17905) (xy 42.721076 -23.209017) (xy 42.768626 -23.245504)
			(xy 42.811006 -23.287884) (xy 42.847493 -23.335434) (xy 42.87746 -23.38734) (xy 42.900396 -23.442713)
			(xy 42.915909 -23.500606) (xy 42.923732 -23.560028) (xy 42.924222 -23.589996) (xy 42.923732 -23.619964)
			(xy 42.915909 -23.679386) (xy 42.900396 -23.737279) (xy 42.87746 -23.792652) (xy 42.847493 -23.844558)
			(xy 42.820053 -23.880318) (xy 43.240704 -23.880318) (xy 43.244775 -23.824696) (xy 43.256901 -23.770259)
			(xy 43.276824 -23.718168) (xy 43.30412 -23.669533) (xy 43.338206 -23.62539) (xy 43.378355 -23.586681)
			(xy 43.423713 -23.55423) (xy 43.473313 -23.528729) (xy 43.526097 -23.510722) (xy 43.58094 -23.500592)
			(xy 43.636674 -23.498555) (xy 43.692111 -23.504655) (xy 43.746068 -23.518761) (xy 43.797397 -23.540573)
			(xy 43.845003 -23.569627) (xy 43.887871 -23.605302) (xy 43.925088 -23.646839) (xy 43.955861 -23.693352)
			(xy 43.979533 -23.743849) (xy 43.995601 -23.797256) (xy 44.003721 -23.852432) (xy 44.00423 -23.880318)
			(xy 44.256704 -23.880318) (xy 44.260775 -23.824696) (xy 44.272901 -23.770259) (xy 44.292824 -23.718168)
			(xy 44.32012 -23.669533) (xy 44.354206 -23.62539) (xy 44.394355 -23.586681) (xy 44.439713 -23.55423)
			(xy 44.489313 -23.528729) (xy 44.542097 -23.510722) (xy 44.59694 -23.500592) (xy 44.652674 -23.498555)
			(xy 44.708111 -23.504655) (xy 44.762068 -23.518761) (xy 44.813397 -23.540573) (xy 44.861003 -23.569627)
			(xy 44.903871 -23.605302) (xy 44.941088 -23.646839) (xy 44.971861 -23.693352) (xy 44.995533 -23.743849)
			(xy 45.011601 -23.797256) (xy 45.019721 -23.852432) (xy 45.02023 -23.880318) (xy 45.272704 -23.880318)
			(xy 45.276775 -23.824696) (xy 45.288901 -23.770259) (xy 45.308824 -23.718168) (xy 45.33612 -23.669533)
			(xy 45.370206 -23.62539) (xy 45.410355 -23.586681) (xy 45.455713 -23.55423) (xy 45.505313 -23.528729)
			(xy 45.558097 -23.510722) (xy 45.61294 -23.500592) (xy 45.668674 -23.498555) (xy 45.724111 -23.504655)
			(xy 45.778068 -23.518761) (xy 45.829397 -23.540573) (xy 45.877003 -23.569627) (xy 45.919871 -23.605302)
			(xy 45.957088 -23.646839) (xy 45.987861 -23.693352) (xy 46.011533 -23.743849) (xy 46.027601 -23.797256)
			(xy 46.035721 -23.852432) (xy 46.03623 -23.880318) (xy 46.29099 -23.880318) (xy 46.295061 -23.824696)
			(xy 46.307187 -23.770259) (xy 46.32711 -23.718168) (xy 46.354406 -23.669533) (xy 46.388492 -23.62539)
			(xy 46.428641 -23.586681) (xy 46.473999 -23.55423) (xy 46.523599 -23.528729) (xy 46.576383 -23.510722)
			(xy 46.631226 -23.500592) (xy 46.68696 -23.498555) (xy 46.742397 -23.504655) (xy 46.796354 -23.518761)
			(xy 46.847683 -23.540573) (xy 46.895289 -23.569627) (xy 46.938157 -23.605302) (xy 46.975374 -23.646839)
			(xy 47.006147 -23.693352) (xy 47.029819 -23.743849) (xy 47.045887 -23.797256) (xy 47.054007 -23.852432)
			(xy 47.054516 -23.880318) (xy 47.054007 -23.908204) (xy 47.045887 -23.96338) (xy 47.029819 -24.016787)
			(xy 47.006147 -24.067284) (xy 46.975374 -24.113797) (xy 46.938157 -24.155334) (xy 46.895289 -24.191009)
			(xy 46.847683 -24.220063) (xy 46.796354 -24.241875) (xy 46.742397 -24.255981) (xy 46.68696 -24.262081)
			(xy 46.631226 -24.260044) (xy 46.576383 -24.249914) (xy 46.523599 -24.231907) (xy 46.473999 -24.206406)
			(xy 46.428641 -24.173955) (xy 46.388492 -24.135246) (xy 46.354406 -24.091103) (xy 46.32711 -24.042468)
			(xy 46.307187 -23.990377) (xy 46.295061 -23.93594) (xy 46.29099 -23.880318) (xy 46.03623 -23.880318)
			(xy 46.035721 -23.908204) (xy 46.027601 -23.96338) (xy 46.011533 -24.016787) (xy 45.987861 -24.067284)
			(xy 45.957088 -24.113797) (xy 45.919871 -24.155334) (xy 45.877003 -24.191009) (xy 45.829397 -24.220063)
			(xy 45.778068 -24.241875) (xy 45.724111 -24.255981) (xy 45.668674 -24.262081) (xy 45.61294 -24.260044)
			(xy 45.558097 -24.249914) (xy 45.505313 -24.231907) (xy 45.455713 -24.206406) (xy 45.410355 -24.173955)
			(xy 45.370206 -24.135246) (xy 45.33612 -24.091103) (xy 45.308824 -24.042468) (xy 45.288901 -23.990377)
			(xy 45.276775 -23.93594) (xy 45.272704 -23.880318) (xy 45.02023 -23.880318) (xy 45.019721 -23.908204)
			(xy 45.011601 -23.96338) (xy 44.995533 -24.016787) (xy 44.971861 -24.067284) (xy 44.941088 -24.113797)
			(xy 44.903871 -24.155334) (xy 44.861003 -24.191009) (xy 44.813397 -24.220063) (xy 44.762068 -24.241875)
			(xy 44.708111 -24.255981) (xy 44.652674 -24.262081) (xy 44.59694 -24.260044) (xy 44.542097 -24.249914)
			(xy 44.489313 -24.231907) (xy 44.439713 -24.206406) (xy 44.394355 -24.173955) (xy 44.354206 -24.135246)
			(xy 44.32012 -24.091103) (xy 44.292824 -24.042468) (xy 44.272901 -23.990377) (xy 44.260775 -23.93594)
			(xy 44.256704 -23.880318) (xy 44.00423 -23.880318) (xy 44.003721 -23.908204) (xy 43.995601 -23.96338)
			(xy 43.979533 -24.016787) (xy 43.955861 -24.067284) (xy 43.925088 -24.113797) (xy 43.887871 -24.155334)
			(xy 43.845003 -24.191009) (xy 43.797397 -24.220063) (xy 43.746068 -24.241875) (xy 43.692111 -24.255981)
			(xy 43.636674 -24.262081) (xy 43.58094 -24.260044) (xy 43.526097 -24.249914) (xy 43.473313 -24.231907)
			(xy 43.423713 -24.206406) (xy 43.378355 -24.173955) (xy 43.338206 -24.135246) (xy 43.30412 -24.091103)
			(xy 43.276824 -24.042468) (xy 43.256901 -23.990377) (xy 43.244775 -23.93594) (xy 43.240704 -23.880318)
			(xy 42.820053 -23.880318) (xy 42.811006 -23.892108) (xy 42.768626 -23.934488) (xy 42.721076 -23.970975)
			(xy 42.66917 -24.000942) (xy 42.613797 -24.023878) (xy 42.555904 -24.039391) (xy 42.496482 -24.047214)
			(xy 42.436546 -24.047214) (xy 42.377124 -24.039391) (xy 42.319231 -24.023878) (xy 42.263858 -24.000942)
			(xy 42.211952 -23.970975) (xy 42.164402 -23.934488) (xy 42.122022 -23.892108) (xy 42.085535 -23.844558)
			(xy 42.055568 -23.792652) (xy 42.032632 -23.737279) (xy 42.017119 -23.679386) (xy 42.009296 -23.619964)
			(xy 38.826682 -23.619964) (xy 38.82023 -23.664845) (xy 38.804875 -23.71714) (xy 38.782233 -23.766717)
			(xy 38.752767 -23.812567) (xy 38.717076 -23.853758) (xy 38.675885 -23.889449) (xy 38.630035 -23.918915)
			(xy 38.580458 -23.941557) (xy 38.528163 -23.956912) (xy 38.474215 -23.964668) (xy 38.419713 -23.964668)
			(xy 38.365765 -23.956912) (xy 38.31347 -23.941557) (xy 38.263893 -23.918915) (xy 38.218043 -23.889449)
			(xy 38.176852 -23.853758) (xy 38.141161 -23.812567) (xy 38.111695 -23.766717) (xy 38.089053 -23.71714)
			(xy 38.073698 -23.664845) (xy 38.065942 -23.610897) (xy 38.065456 -23.583646) (xy 38.067234 -23.548086)
			(xy 38.068504 -23.53437) (xy 38.057582 -23.51024) (xy 37.964618 -23.44293) (xy 37.938202 -23.439882)
			(xy 37.925756 -23.44547) (xy 37.896995 -23.457278) (xy 37.837091 -23.473918) (xy 37.775486 -23.482302)
			(xy 37.7444 -23.482808) (xy 37.714432 -23.482318) (xy 37.65501 -23.474495) (xy 37.597117 -23.458982)
			(xy 37.541744 -23.436046) (xy 37.489838 -23.406079) (xy 37.442288 -23.369592) (xy 37.399908 -23.327212)
			(xy 37.363421 -23.279662) (xy 37.333454 -23.227756) (xy 37.310518 -23.172383) (xy 37.295005 -23.11449)
			(xy 37.287182 -23.055068) (xy 35.543998 -23.055068) (xy 35.543998 -24.189944) (xy 37.298882 -24.189944)
			(xy 37.302953 -24.134322) (xy 37.315079 -24.079885) (xy 37.335002 -24.027794) (xy 37.362298 -23.979159)
			(xy 37.396384 -23.935016) (xy 37.436533 -23.896307) (xy 37.481891 -23.863856) (xy 37.531491 -23.838355)
			(xy 37.584275 -23.820348) (xy 37.639118 -23.810218) (xy 37.694852 -23.808181) (xy 37.750289 -23.814281)
			(xy 37.804246 -23.828387) (xy 37.855575 -23.850199) (xy 37.903181 -23.879253) (xy 37.946049 -23.914928)
			(xy 37.983266 -23.956465) (xy 38.014039 -24.002978) (xy 38.037711 -24.053475) (xy 38.053779 -24.106882)
			(xy 38.061899 -24.162058) (xy 38.062408 -24.189944) (xy 39.821864 -24.189944) (xy 39.825935 -24.134322)
			(xy 39.838061 -24.079885) (xy 39.857984 -24.027794) (xy 39.88528 -23.979159) (xy 39.919366 -23.935016)
			(xy 39.959515 -23.896307) (xy 40.004873 -23.863856) (xy 40.054473 -23.838355) (xy 40.107257 -23.820348)
			(xy 40.1621 -23.810218) (xy 40.217834 -23.808181) (xy 40.273271 -23.814281) (xy 40.327228 -23.828387)
			(xy 40.378557 -23.850199) (xy 40.426163 -23.879253) (xy 40.469031 -23.914928) (xy 40.506248 -23.956465)
			(xy 40.537021 -24.002978) (xy 40.560693 -24.053475) (xy 40.576761 -24.106882) (xy 40.584881 -24.162058)
			(xy 40.58539 -24.189944) (xy 40.584881 -24.21783) (xy 40.576761 -24.273006) (xy 40.560693 -24.326413)
			(xy 40.537021 -24.37691) (xy 40.506248 -24.423423) (xy 40.469031 -24.46496) (xy 40.426163 -24.500635)
			(xy 40.378557 -24.529689) (xy 40.327228 -24.551501) (xy 40.273271 -24.565607) (xy 40.217834 -24.571707)
			(xy 40.1621 -24.56967) (xy 40.107257 -24.55954) (xy 40.054473 -24.541533) (xy 40.004873 -24.516032)
			(xy 39.959515 -24.483581) (xy 39.919366 -24.444872) (xy 39.88528 -24.400729) (xy 39.857984 -24.352094)
			(xy 39.838061 -24.300003) (xy 39.825935 -24.245566) (xy 39.821864 -24.189944) (xy 38.062408 -24.189944)
			(xy 38.061899 -24.21783) (xy 38.053779 -24.273006) (xy 38.037711 -24.326413) (xy 38.014039 -24.37691)
			(xy 37.983266 -24.423423) (xy 37.946049 -24.46496) (xy 37.903181 -24.500635) (xy 37.855575 -24.529689)
			(xy 37.804246 -24.551501) (xy 37.750289 -24.565607) (xy 37.694852 -24.571707) (xy 37.639118 -24.56967)
			(xy 37.584275 -24.55954) (xy 37.531491 -24.541533) (xy 37.481891 -24.516032) (xy 37.436533 -24.483581)
			(xy 37.396384 -24.444872) (xy 37.362298 -24.400729) (xy 37.335002 -24.352094) (xy 37.315079 -24.300003)
			(xy 37.302953 -24.245566) (xy 37.298882 -24.189944) (xy 35.543998 -24.189944) (xy 35.543998 -25.390094)
			(xy 39.809674 -25.390094) (xy 39.81016 -25.362843) (xy 39.817916 -25.308895) (xy 39.833271 -25.2566)
			(xy 39.855913 -25.207023) (xy 39.885379 -25.161173) (xy 39.92107 -25.119982) (xy 39.962261 -25.084291)
			(xy 40.008111 -25.054825) (xy 40.057688 -25.032183) (xy 40.109983 -25.016828) (xy 40.163931 -25.009072)
			(xy 40.218433 -25.009072) (xy 40.272381 -25.016828) (xy 40.324676 -25.032183) (xy 40.374253 -25.054825)
			(xy 40.420103 -25.084291) (xy 40.461294 -25.119982) (xy 40.496985 -25.161173) (xy 40.526451 -25.207023)
			(xy 40.549093 -25.2566) (xy 40.564448 -25.308895) (xy 40.572204 -25.362843) (xy 40.57269 -25.390094)
			(xy 40.572104 -25.419113) (xy 40.563314 -25.476482) (xy 40.545938 -25.531858) (xy 40.520376 -25.583963)
			(xy 40.487217 -25.631596) (xy 40.447226 -25.673658) (xy 40.424608 -25.691846) (xy 40.414062 -25.700615)
			(xy 40.397618 -25.722549) (xy 40.387612 -25.748071) (xy 40.384764 -25.775336) (xy 40.389282 -25.802374)
			(xy 40.400839 -25.827233) (xy 40.418599 -25.848115) (xy 40.429688 -25.856184) (xy 40.451324 -25.87151)
			(xy 40.490581 -25.907146) (xy 40.524525 -25.947876) (xy 40.5525 -25.992915) (xy 40.573967 -26.041394)
			(xy 40.588512 -26.09238) (xy 40.595856 -26.144888) (xy 40.596312 -26.171398) (xy 40.595826 -26.198649)
			(xy 40.58807 -26.252597) (xy 40.572715 -26.304892) (xy 40.550073 -26.354469) (xy 40.520607 -26.400319)
			(xy 40.484916 -26.44151) (xy 40.443725 -26.477201) (xy 40.397875 -26.506667) (xy 40.348298 -26.529309)
			(xy 40.296003 -26.544664) (xy 40.242055 -26.55242) (xy 40.187553 -26.55242) (xy 40.133605 -26.544664)
			(xy 40.08131 -26.529309) (xy 40.031733 -26.506667) (xy 39.985883 -26.477201) (xy 39.944692 -26.44151)
			(xy 39.909001 -26.400319) (xy 39.879535 -26.354469) (xy 39.856893 -26.304892) (xy 39.841538 -26.252597)
			(xy 39.833782 -26.198649) (xy 39.833296 -26.171398) (xy 39.833844 -26.142377) (xy 39.842636 -26.085005)
			(xy 39.860018 -26.029627) (xy 39.885587 -25.977521) (xy 39.918755 -25.929889) (xy 39.958755 -25.887832)
			(xy 39.981378 -25.869646) (xy 39.991934 -25.860888) (xy 40.00838 -25.838952) (xy 40.018388 -25.813427)
			(xy 40.021234 -25.786159) (xy 40.016714 -25.759118) (xy 40.005154 -25.734258) (xy 39.987389 -25.713377)
			(xy 39.976298 -25.705308) (xy 39.954655 -25.689991) (xy 39.915398 -25.654353) (xy 39.881456 -25.613621)
			(xy 39.853482 -25.568581) (xy 39.832016 -25.5201) (xy 39.817472 -25.469114) (xy 39.810129 -25.416604)
			(xy 39.809674 -25.390094) (xy 35.543998 -25.390094) (xy 35.543998 -25.501854) (xy 35.545014 -25.512014)
			(xy 35.547808 -25.526492) (xy 35.551872 -25.53589) (xy 35.610292 -25.593802) (xy 35.617701 -25.600487)
			(xy 35.636137 -25.608072) (xy 35.646106 -25.608534) (xy 35.6489 -25.608534) (xy 35.676148 -25.60902)
			(xy 35.73009 -25.616776) (xy 35.782379 -25.632129) (xy 35.831951 -25.654768) (xy 35.877796 -25.684231)
			(xy 35.918982 -25.719918) (xy 35.954669 -25.761104) (xy 35.984132 -25.806949) (xy 36.006771 -25.856521)
			(xy 36.022124 -25.90881) (xy 36.02988 -25.962752) (xy 36.02988 -25.990042) (xy 37.298882 -25.990042)
			(xy 37.302953 -25.93442) (xy 37.315079 -25.879983) (xy 37.335002 -25.827892) (xy 37.362298 -25.779257)
			(xy 37.396384 -25.735114) (xy 37.436533 -25.696405) (xy 37.481891 -25.663954) (xy 37.531491 -25.638453)
			(xy 37.584275 -25.620446) (xy 37.639118 -25.610316) (xy 37.694852 -25.608279) (xy 37.750289 -25.614379)
			(xy 37.804246 -25.628485) (xy 37.855575 -25.650297) (xy 37.903181 -25.679351) (xy 37.946049 -25.715026)
			(xy 37.983266 -25.756563) (xy 38.014039 -25.803076) (xy 38.037711 -25.853573) (xy 38.053779 -25.90698)
			(xy 38.061899 -25.962156) (xy 38.062408 -25.990042) (xy 38.061899 -26.017928) (xy 38.053779 -26.073104)
			(xy 38.037711 -26.126511) (xy 38.014039 -26.177008) (xy 37.983266 -26.223521) (xy 37.946049 -26.265058)
			(xy 37.903181 -26.300733) (xy 37.855575 -26.329787) (xy 37.804246 -26.351599) (xy 37.750289 -26.365705)
			(xy 37.694852 -26.371805) (xy 37.639118 -26.369768) (xy 37.584275 -26.359638) (xy 37.531491 -26.341631)
			(xy 37.481891 -26.31613) (xy 37.436533 -26.283679) (xy 37.396384 -26.24497) (xy 37.362298 -26.200827)
			(xy 37.335002 -26.152192) (xy 37.315079 -26.100101) (xy 37.302953 -26.045664) (xy 37.298882 -25.990042)
			(xy 36.02988 -25.990042) (xy 36.02988 -26.017248) (xy 36.022124 -26.07119) (xy 36.006771 -26.123479)
			(xy 35.984132 -26.173051) (xy 35.954669 -26.218896) (xy 35.918982 -26.260082) (xy 35.877796 -26.295769)
			(xy 35.831951 -26.325232) (xy 35.782379 -26.347871) (xy 35.73009 -26.363224) (xy 35.676148 -26.37098)
			(xy 35.6489 -26.37155) (xy 35.646106 -26.37155) (xy 35.636139 -26.372024) (xy 35.617701 -26.379599)
			(xy 35.610292 -26.386282) (xy 35.558984 -26.437082) (xy 35.552141 -26.444481) (xy 35.544424 -26.46308)
			(xy 35.543998 -26.47315) (xy 35.543998 -27.301952) (xy 35.545014 -27.312112) (xy 35.547808 -27.32659)
			(xy 35.551872 -27.335988) (xy 35.610292 -27.3939) (xy 35.617701 -27.400585) (xy 35.636137 -27.40817)
			(xy 35.646106 -27.408632) (xy 35.6489 -27.408632) (xy 35.676148 -27.409118) (xy 35.73009 -27.416874)
			(xy 35.78238 -27.432227) (xy 35.831952 -27.454866) (xy 35.877797 -27.484329) (xy 35.918983 -27.520017)
			(xy 35.954671 -27.561203) (xy 35.984134 -27.607048) (xy 36.006773 -27.65662) (xy 36.022126 -27.70891)
			(xy 36.029882 -27.762852) (xy 36.029882 -27.79014) (xy 37.36289 -27.79014) (xy 37.366961 -27.734518)
			(xy 37.379087 -27.680081) (xy 37.39901 -27.62799) (xy 37.426306 -27.579355) (xy 37.460392 -27.535212)
			(xy 37.500541 -27.496503) (xy 37.545899 -27.464052) (xy 37.595499 -27.438551) (xy 37.648283 -27.420544)
			(xy 37.703126 -27.410414) (xy 37.75886 -27.408377) (xy 37.814297 -27.414477) (xy 37.868254 -27.428583)
			(xy 37.919583 -27.450395) (xy 37.967189 -27.479449) (xy 38.010057 -27.515124) (xy 38.047274 -27.556661)
			(xy 38.078047 -27.603174) (xy 38.101719 -27.653671) (xy 38.117787 -27.707078) (xy 38.125907 -27.762254)
			(xy 38.126416 -27.79014) (xy 39.866822 -27.79014) (xy 39.870893 -27.734518) (xy 39.883019 -27.680081)
			(xy 39.902942 -27.62799) (xy 39.930238 -27.579355) (xy 39.964324 -27.535212) (xy 40.004473 -27.496503)
			(xy 40.049831 -27.464052) (xy 40.099431 -27.438551) (xy 40.152215 -27.420544) (xy 40.207058 -27.410414)
			(xy 40.262792 -27.408377) (xy 40.318229 -27.414477) (xy 40.372186 -27.428583) (xy 40.423515 -27.450395)
			(xy 40.471121 -27.479449) (xy 40.513989 -27.515124) (xy 40.551206 -27.556661) (xy 40.581979 -27.603174)
			(xy 40.605651 -27.653671) (xy 40.621719 -27.707078) (xy 40.629839 -27.762254) (xy 40.630348 -27.79014)
			(xy 40.629851 -27.817352) (xy 41.899795 -27.817352) (xy 41.899795 -27.762848) (xy 41.907553 -27.708899)
			(xy 41.922909 -27.656604) (xy 41.945552 -27.607026) (xy 41.975021 -27.561176) (xy 42.010715 -27.519987)
			(xy 42.051908 -27.484297) (xy 42.097761 -27.454833) (xy 42.147341 -27.432195) (xy 42.199639 -27.416844)
			(xy 42.253588 -27.409093) (xy 42.28084 -27.408632) (xy 42.306146 -27.40905) (xy 42.356318 -27.415714)
			(xy 42.405171 -27.428945) (xy 42.428668 -27.43835) (xy 42.436666 -27.441402) (xy 42.453743 -27.442484)
			(xy 42.470225 -27.437885) (xy 42.477436 -27.43327) (xy 42.502836 -27.41549) (xy 42.509713 -27.410204)
			(xy 42.519793 -27.396108) (xy 42.524594 -27.379456) (xy 42.524426 -27.370786) (xy 42.523664 -27.342846)
			(xy 42.523664 -26.479246) (xy 42.524172 -26.456894) (xy 42.52468 -26.444448) (xy 42.514266 -26.421842)
			(xy 42.429176 -26.355548) (xy 42.404792 -26.350976) (xy 42.392854 -26.354786) (xy 42.365519 -26.362633)
			(xy 42.309275 -26.371048) (xy 42.28084 -26.37155) (xy 42.253588 -26.371005) (xy 42.199639 -26.363254)
			(xy 42.147342 -26.347903) (xy 42.097762 -26.325265) (xy 42.051909 -26.295802) (xy 42.010716 -26.260112)
			(xy 41.975022 -26.218923) (xy 41.945554 -26.173073) (xy 41.922911 -26.123495) (xy 41.907555 -26.0712)
			(xy 41.899797 -26.017252) (xy 41.899797 -25.962748) (xy 41.907555 -25.9088) (xy 41.922911 -25.856505)
			(xy 41.945554 -25.806927) (xy 41.975022 -25.761077) (xy 42.010716 -25.719888) (xy 42.051909 -25.684198)
			(xy 42.097762 -25.654735) (xy 42.147342 -25.632097) (xy 42.199639 -25.616746) (xy 42.253588 -25.608995)
			(xy 42.28084 -25.608534) (xy 42.309793 -25.60904) (xy 42.367036 -25.617782) (xy 42.422299 -25.635075)
			(xy 42.474315 -25.660521) (xy 42.521887 -25.693536) (xy 42.563924 -25.733362) (xy 42.599458 -25.779083)
			(xy 42.627675 -25.829649) (xy 42.628573 -25.832054) (xy 44.18838 -25.832054) (xy 44.188878 -25.805452)
			(xy 44.196252 -25.752761) (xy 44.210879 -25.701607) (xy 44.232473 -25.652983) (xy 44.260617 -25.607832)
			(xy 44.294763 -25.567031) (xy 44.33425 -25.531373) (xy 44.35602 -25.516078) (xy 44.367494 -25.507737)
			(xy 44.385694 -25.485994) (xy 44.397209 -25.460082) (xy 44.401149 -25.432002) (xy 44.39721 -25.403922)
			(xy 44.385697 -25.37801) (xy 44.367498 -25.356266) (xy 44.35602 -25.34793) (xy 44.33425 -25.332634)
			(xy 44.294772 -25.296967) (xy 44.26063 -25.256164) (xy 44.232484 -25.211014) (xy 44.210882 -25.162393)
			(xy 44.196241 -25.111243) (xy 44.188845 -25.058556) (xy 44.18838 -25.031954) (xy 44.188866 -25.004703)
			(xy 44.196622 -24.950755) (xy 44.211977 -24.89846) (xy 44.234619 -24.848883) (xy 44.264085 -24.803033)
			(xy 44.299776 -24.761842) (xy 44.340967 -24.726151) (xy 44.386817 -24.696685) (xy 44.436394 -24.674043)
			(xy 44.488689 -24.658688) (xy 44.542637 -24.650932) (xy 44.597139 -24.650932) (xy 44.651087 -24.658688)
			(xy 44.703382 -24.674043) (xy 44.752959 -24.696685) (xy 44.798809 -24.726151) (xy 44.84 -24.761842)
			(xy 44.863201 -24.788618) (xy 46.793386 -24.788618) (xy 46.793386 -24.728682) (xy 46.801209 -24.66926)
			(xy 46.816722 -24.611367) (xy 46.839658 -24.555994) (xy 46.869625 -24.504088) (xy 46.906112 -24.456538)
			(xy 46.948492 -24.414158) (xy 46.996042 -24.377671) (xy 47.047948 -24.347704) (xy 47.103321 -24.324768)
			(xy 47.161214 -24.309255) (xy 47.220636 -24.301432) (xy 47.280572 -24.301432) (xy 47.339994 -24.309255)
			(xy 47.397887 -24.324768) (xy 47.45326 -24.347704) (xy 47.505166 -24.377671) (xy 47.552716 -24.414158)
			(xy 47.595096 -24.456538) (xy 47.631583 -24.504088) (xy 47.66155 -24.555994) (xy 47.684486 -24.611367)
			(xy 47.699999 -24.66926) (xy 47.707822 -24.728682) (xy 47.708312 -24.75865) (xy 47.707822 -24.788618)
			(xy 47.699999 -24.84804) (xy 47.684486 -24.905933) (xy 47.66155 -24.961306) (xy 47.631583 -25.013212)
			(xy 47.595096 -25.060762) (xy 47.552716 -25.103142) (xy 47.505166 -25.139629) (xy 47.45326 -25.169596)
			(xy 47.397887 -25.192532) (xy 47.339994 -25.208045) (xy 47.280572 -25.215868) (xy 47.220636 -25.215868)
			(xy 47.161214 -25.208045) (xy 47.103321 -25.192532) (xy 47.047948 -25.169596) (xy 46.996042 -25.139629)
			(xy 46.948492 -25.103142) (xy 46.906112 -25.060762) (xy 46.869625 -25.013212) (xy 46.839658 -24.961306)
			(xy 46.816722 -24.905933) (xy 46.801209 -24.84804) (xy 46.793386 -24.788618) (xy 44.863201 -24.788618)
			(xy 44.875691 -24.803033) (xy 44.905157 -24.848883) (xy 44.927799 -24.89846) (xy 44.943154 -24.950755)
			(xy 44.95091 -25.004703) (xy 44.951396 -25.031954) (xy 44.950914 -25.058557) (xy 44.943538 -25.111249)
			(xy 44.92891 -25.162404) (xy 44.907313 -25.211029) (xy 44.879167 -25.256179) (xy 44.845017 -25.296979)
			(xy 44.805528 -25.332636) (xy 44.783756 -25.34793) (xy 44.772276 -25.356262) (xy 44.75408 -25.378009)
			(xy 44.742569 -25.403922) (xy 44.738631 -25.432002) (xy 44.74257 -25.460082) (xy 44.754083 -25.485995)
			(xy 44.77228 -25.507741) (xy 44.783756 -25.516078) (xy 44.805524 -25.531376) (xy 44.845003 -25.567042)
			(xy 44.879147 -25.607845) (xy 44.907293 -25.652994) (xy 44.928896 -25.701615) (xy 44.943536 -25.752765)
			(xy 44.950932 -25.805452) (xy 44.951396 -25.832054) (xy 44.95091 -25.859305) (xy 44.943154 -25.913253)
			(xy 44.927799 -25.965548) (xy 44.905157 -26.015125) (xy 44.875691 -26.060975) (xy 44.84 -26.102166)
			(xy 44.798809 -26.137857) (xy 44.752959 -26.167323) (xy 44.703382 -26.189965) (xy 44.651087 -26.20532)
			(xy 44.597139 -26.213076) (xy 44.542637 -26.213076) (xy 44.488689 -26.20532) (xy 44.436394 -26.189965)
			(xy 44.386817 -26.167323) (xy 44.340967 -26.137857) (xy 44.299776 -26.102166) (xy 44.264085 -26.060975)
			(xy 44.234619 -26.015125) (xy 44.211977 -25.965548) (xy 44.196622 -25.913253) (xy 44.188866 -25.859305)
			(xy 44.18838 -25.832054) (xy 42.628573 -25.832054) (xy 42.647926 -25.883899) (xy 42.659745 -25.940586)
			(xy 42.66184 -25.969468) (xy 42.662348 -25.981914) (xy 42.675048 -26.00325) (xy 42.766742 -26.060654)
			(xy 42.79138 -26.062432) (xy 42.80281 -26.057606) (xy 42.83117 -26.046142) (xy 42.890167 -26.029985)
			(xy 42.950788 -26.021812) (xy 42.981372 -26.021284) (xy 43.011351 -26.021788) (xy 43.070795 -26.029613)
			(xy 43.128709 -26.045133) (xy 43.1841 -26.068083) (xy 43.23602 -26.098069) (xy 43.28358 -26.134577)
			(xy 43.325967 -26.176984) (xy 43.362452 -26.224561) (xy 43.392413 -26.276496) (xy 43.415337 -26.331898)
			(xy 43.423089 -26.360882) (xy 45.08957 -26.360882) (xy 45.093641 -26.30526) (xy 45.105767 -26.250823)
			(xy 45.12569 -26.198732) (xy 45.152986 -26.150097) (xy 45.187072 -26.105954) (xy 45.227221 -26.067245)
			(xy 45.272579 -26.034794) (xy 45.322179 -26.009293) (xy 45.374963 -25.991286) (xy 45.429806 -25.981156)
			(xy 45.48554 -25.979119) (xy 45.540977 -25.985219) (xy 45.594934 -25.999325) (xy 45.646263 -26.021137)
			(xy 45.693869 -26.050191) (xy 45.736737 -26.085866) (xy 45.773954 -26.127403) (xy 45.804727 -26.173916)
			(xy 45.828399 -26.224413) (xy 45.844467 -26.27782) (xy 45.852587 -26.332996) (xy 45.853096 -26.360882)
			(xy 46.10557 -26.360882) (xy 46.109641 -26.30526) (xy 46.121767 -26.250823) (xy 46.14169 -26.198732)
			(xy 46.168986 -26.150097) (xy 46.203072 -26.105954) (xy 46.243221 -26.067245) (xy 46.288579 -26.034794)
			(xy 46.338179 -26.009293) (xy 46.390963 -25.991286) (xy 46.445806 -25.981156) (xy 46.50154 -25.979119)
			(xy 46.556977 -25.985219) (xy 46.610934 -25.999325) (xy 46.662263 -26.021137) (xy 46.709869 -26.050191)
			(xy 46.752737 -26.085866) (xy 46.789954 -26.127403) (xy 46.820727 -26.173916) (xy 46.844399 -26.224413)
			(xy 46.860467 -26.27782) (xy 46.868587 -26.332996) (xy 46.869096 -26.360882) (xy 46.868587 -26.388768)
			(xy 46.860467 -26.443944) (xy 46.844399 -26.497351) (xy 46.820727 -26.547848) (xy 46.789954 -26.594361)
			(xy 46.752737 -26.635898) (xy 46.709869 -26.671573) (xy 46.662263 -26.700627) (xy 46.610934 -26.722439)
			(xy 46.556977 -26.736545) (xy 46.50154 -26.742645) (xy 46.445806 -26.740608) (xy 46.390963 -26.730478)
			(xy 46.338179 -26.712471) (xy 46.288579 -26.68697) (xy 46.243221 -26.654519) (xy 46.203072 -26.61581)
			(xy 46.168986 -26.571667) (xy 46.14169 -26.523032) (xy 46.121767 -26.470941) (xy 46.109641 -26.416504)
			(xy 46.10557 -26.360882) (xy 45.853096 -26.360882) (xy 45.852587 -26.388768) (xy 45.844467 -26.443944)
			(xy 45.828399 -26.497351) (xy 45.804727 -26.547848) (xy 45.773954 -26.594361) (xy 45.736737 -26.635898)
			(xy 45.693869 -26.671573) (xy 45.646263 -26.700627) (xy 45.594934 -26.722439) (xy 45.540977 -26.736545)
			(xy 45.48554 -26.742645) (xy 45.429806 -26.740608) (xy 45.374963 -26.730478) (xy 45.322179 -26.712471)
			(xy 45.272579 -26.68697) (xy 45.227221 -26.654519) (xy 45.187072 -26.61581) (xy 45.152986 -26.571667)
			(xy 45.12569 -26.523032) (xy 45.105767 -26.470941) (xy 45.093641 -26.416504) (xy 45.08957 -26.360882)
			(xy 43.423089 -26.360882) (xy 43.430829 -26.389819) (xy 43.438626 -26.449267) (xy 43.43908 -26.479246)
			(xy 43.43908 -26.971244) (xy 46.85106 -26.971244) (xy 46.855131 -26.915622) (xy 46.867257 -26.861185)
			(xy 46.88718 -26.809094) (xy 46.914476 -26.760459) (xy 46.948562 -26.716316) (xy 46.988711 -26.677607)
			(xy 47.034069 -26.645156) (xy 47.083669 -26.619655) (xy 47.136453 -26.601648) (xy 47.191296 -26.591518)
			(xy 47.24703 -26.589481) (xy 47.302467 -26.595581) (xy 47.356424 -26.609687) (xy 47.407753 -26.631499)
			(xy 47.455359 -26.660553) (xy 47.498227 -26.696228) (xy 47.535444 -26.737765) (xy 47.566217 -26.784278)
			(xy 47.589889 -26.834775) (xy 47.605957 -26.888182) (xy 47.614077 -26.943358) (xy 47.614586 -26.971244)
			(xy 47.614077 -26.99913) (xy 47.605957 -27.054306) (xy 47.589889 -27.107713) (xy 47.566217 -27.15821)
			(xy 47.535444 -27.204723) (xy 47.498227 -27.24626) (xy 47.455359 -27.281935) (xy 47.407753 -27.310989)
			(xy 47.356424 -27.332801) (xy 47.302467 -27.346907) (xy 47.24703 -27.353007) (xy 47.191296 -27.35097)
			(xy 47.136453 -27.34084) (xy 47.083669 -27.322833) (xy 47.034069 -27.297332) (xy 46.988711 -27.264881)
			(xy 46.948562 -27.226172) (xy 46.914476 -27.182029) (xy 46.88718 -27.133394) (xy 46.867257 -27.081303)
			(xy 46.855131 -27.026866) (xy 46.85106 -26.971244) (xy 43.43908 -26.971244) (xy 43.43908 -27.342846)
			(xy 43.438616 -27.37282) (xy 43.430788 -27.432255) (xy 43.415274 -27.490161) (xy 43.392336 -27.545547)
			(xy 43.362369 -27.597468) (xy 43.325884 -27.645035) (xy 43.283505 -27.687435) (xy 43.235956 -27.723943)
			(xy 43.18405 -27.753936) (xy 43.128675 -27.776901) (xy 43.070777 -27.792444) (xy 43.011346 -27.800301)
			(xy 42.981372 -27.800808) (xy 42.950235 -27.800278) (xy 42.888539 -27.791813) (xy 42.828554 -27.775083)
			(xy 42.799762 -27.763216) (xy 42.788586 -27.75839) (xy 42.764964 -27.75966) (xy 42.673778 -27.810968)
			(xy 42.660316 -27.830526) (xy 42.658792 -27.842464) (xy 42.654598 -27.869498) (xy 42.639417 -27.922057)
			(xy 42.616886 -27.97191) (xy 42.587468 -28.018035) (xy 42.551765 -28.059487) (xy 42.510509 -28.095416)
			(xy 42.464545 -28.125086) (xy 42.414816 -28.147889) (xy 42.36234 -28.163358) (xy 42.308194 -28.171175)
			(xy 42.28084 -28.171648) (xy 42.253588 -28.171107) (xy 42.199639 -28.163356) (xy 42.147341 -28.148005)
			(xy 42.097761 -28.125367) (xy 42.051908 -28.095903) (xy 42.010715 -28.060213) (xy 41.975021 -28.019024)
			(xy 41.945552 -27.973174) (xy 41.922909 -27.923596) (xy 41.907553 -27.871301) (xy 41.899795 -27.817352)
			(xy 40.629851 -27.817352) (xy 40.629839 -27.818026) (xy 40.621719 -27.873202) (xy 40.605651 -27.926609)
			(xy 40.581979 -27.977106) (xy 40.551206 -28.023619) (xy 40.513989 -28.065156) (xy 40.471121 -28.100831)
			(xy 40.423515 -28.129885) (xy 40.372186 -28.151697) (xy 40.318229 -28.165803) (xy 40.262792 -28.171903)
			(xy 40.207058 -28.169866) (xy 40.152215 -28.159736) (xy 40.099431 -28.141729) (xy 40.049831 -28.116228)
			(xy 40.004473 -28.083777) (xy 39.964324 -28.045068) (xy 39.930238 -28.000925) (xy 39.902942 -27.95229)
			(xy 39.883019 -27.900199) (xy 39.870893 -27.845762) (xy 39.866822 -27.79014) (xy 38.126416 -27.79014)
			(xy 38.125907 -27.818026) (xy 38.117787 -27.873202) (xy 38.101719 -27.926609) (xy 38.078047 -27.977106)
			(xy 38.047274 -28.023619) (xy 38.010057 -28.065156) (xy 37.967189 -28.100831) (xy 37.919583 -28.129885)
			(xy 37.868254 -28.151697) (xy 37.814297 -28.165803) (xy 37.75886 -28.171903) (xy 37.703126 -28.169866)
			(xy 37.648283 -28.159736) (xy 37.595499 -28.141729) (xy 37.545899 -28.116228) (xy 37.500541 -28.083777)
			(xy 37.460392 -28.045068) (xy 37.426306 -28.000925) (xy 37.39901 -27.95229) (xy 37.379087 -27.900199)
			(xy 37.366961 -27.845762) (xy 37.36289 -27.79014) (xy 36.029882 -27.79014) (xy 36.029882 -27.817348)
			(xy 36.022126 -27.87129) (xy 36.006773 -27.92358) (xy 35.984134 -27.973152) (xy 35.954671 -28.018997)
			(xy 35.918983 -28.060183) (xy 35.877797 -28.095871) (xy 35.831952 -28.125334) (xy 35.78238 -28.147973)
			(xy 35.73009 -28.163326) (xy 35.676148 -28.171082) (xy 35.6489 -28.171648) (xy 35.646106 -28.171648)
			(xy 35.636139 -28.172122) (xy 35.6177 -28.179697) (xy 35.610292 -28.18638) (xy 35.558984 -28.23718)
			(xy 35.552141 -28.244579) (xy 35.544423 -28.263178) (xy 35.543998 -28.273248) (xy 35.543998 -29.101796)
			(xy 35.545014 -29.111956) (xy 35.547808 -29.126434) (xy 35.551872 -29.135832) (xy 35.610292 -29.193744)
			(xy 35.617703 -29.200425) (xy 35.636139 -29.208003) (xy 35.646106 -29.208476) (xy 35.6489 -29.208476)
			(xy 35.676152 -29.208962) (xy 35.730102 -29.216719) (xy 35.782399 -29.232074) (xy 35.831979 -29.254717)
			(xy 35.877831 -29.284184) (xy 35.919023 -29.319877) (xy 35.954716 -29.361069) (xy 35.984183 -29.406921)
			(xy 36.006826 -29.456501) (xy 36.022181 -29.508798) (xy 36.029938 -29.562748) (xy 36.029938 -29.589984)
			(xy 37.36289 -29.589984) (xy 37.366961 -29.534362) (xy 37.379087 -29.479925) (xy 37.39901 -29.427834)
			(xy 37.426306 -29.379199) (xy 37.460392 -29.335056) (xy 37.500541 -29.296347) (xy 37.545899 -29.263896)
			(xy 37.595499 -29.238395) (xy 37.648283 -29.220388) (xy 37.703126 -29.210258) (xy 37.75886 -29.208221)
			(xy 37.814297 -29.214321) (xy 37.868254 -29.228427) (xy 37.919583 -29.250239) (xy 37.967189 -29.279293)
			(xy 38.010057 -29.314968) (xy 38.047274 -29.356505) (xy 38.078047 -29.403018) (xy 38.101719 -29.453515)
			(xy 38.117787 -29.506922) (xy 38.125907 -29.562098) (xy 38.126416 -29.589984) (xy 39.866822 -29.589984)
			(xy 39.870893 -29.534362) (xy 39.883019 -29.479925) (xy 39.902942 -29.427834) (xy 39.930238 -29.379199)
			(xy 39.964324 -29.335056) (xy 40.004473 -29.296347) (xy 40.049831 -29.263896) (xy 40.099431 -29.238395)
			(xy 40.152215 -29.220388) (xy 40.207058 -29.210258) (xy 40.262792 -29.208221) (xy 40.318229 -29.214321)
			(xy 40.372186 -29.228427) (xy 40.423515 -29.250239) (xy 40.471121 -29.279293) (xy 40.513989 -29.314968)
			(xy 40.551206 -29.356505) (xy 40.581979 -29.403018) (xy 40.605651 -29.453515) (xy 40.621719 -29.506922)
			(xy 40.629839 -29.562098) (xy 40.630348 -29.589984) (xy 41.898822 -29.589984) (xy 41.902893 -29.534362)
			(xy 41.915019 -29.479925) (xy 41.934942 -29.427834) (xy 41.962238 -29.379199) (xy 41.996324 -29.335056)
			(xy 42.036473 -29.296347) (xy 42.081831 -29.263896) (xy 42.131431 -29.238395) (xy 42.184215 -29.220388)
			(xy 42.239058 -29.210258) (xy 42.294792 -29.208221) (xy 42.350229 -29.214321) (xy 42.404186 -29.228427)
			(xy 42.455515 -29.250239) (xy 42.503121 -29.279293) (xy 42.545989 -29.314968) (xy 42.567663 -29.339158)
			(xy 44.290109 -29.339158) (xy 44.290109 -29.284642) (xy 44.297868 -29.230682) (xy 44.313227 -29.178375)
			(xy 44.335875 -29.128786) (xy 44.36535 -29.082926) (xy 44.401052 -29.041728) (xy 44.442253 -29.00603)
			(xy 44.488116 -28.976559) (xy 44.537707 -28.953916) (xy 44.590015 -28.938561) (xy 44.643976 -28.930807)
			(xy 44.671234 -28.930346) (xy 44.686027 -28.930487) (xy 44.715525 -28.932772) (xy 44.730162 -28.934918)
			(xy 44.741084 -28.936696) (xy 44.76242 -28.9306) (xy 44.82973 -28.873196) (xy 44.837703 -28.865609)
			(xy 44.846784 -28.845585) (xy 44.847256 -28.834588) (xy 44.847256 -28.530296) (xy 44.846736 -28.519309)
			(xy 44.837669 -28.499298) (xy 44.82973 -28.491688) (xy 44.76242 -28.434284) (xy 44.741084 -28.428188)
			(xy 44.730162 -28.429966) (xy 44.715524 -28.432106) (xy 44.686027 -28.434395) (xy 44.671234 -28.434538)
			(xy 44.643982 -28.434017) (xy 44.590031 -28.426265) (xy 44.537734 -28.410913) (xy 44.488153 -28.388274)
			(xy 44.442299 -28.358809) (xy 44.401106 -28.323118) (xy 44.365411 -28.281928) (xy 44.335942 -28.236077)
			(xy 44.313299 -28.186498) (xy 44.297943 -28.134202) (xy 44.290185 -28.080252) (xy 44.290185 -28.025748)
			(xy 44.297943 -27.971798) (xy 44.313299 -27.919502) (xy 44.335942 -27.869923) (xy 44.365411 -27.824072)
			(xy 44.401106 -27.782882) (xy 44.442299 -27.747191) (xy 44.488153 -27.717726) (xy 44.537734 -27.695087)
			(xy 44.590031 -27.679735) (xy 44.643982 -27.671983) (xy 44.671234 -27.671522) (xy 44.697162 -27.67192)
			(xy 44.74854 -27.678931) (xy 44.798497 -27.692834) (xy 44.846112 -27.713371) (xy 44.890508 -27.740165)
			(xy 44.930868 -27.772723) (xy 44.966449 -27.810445) (xy 44.981876 -27.831288) (xy 44.987614 -27.83862)
			(xy 45.003119 -27.848904) (xy 45.012102 -27.851354) (xy 45.042328 -27.858212) (xy 45.051606 -27.859951)
			(xy 45.070267 -27.857216) (xy 45.07865 -27.852878) (xy 45.104616 -27.838565) (xy 45.159472 -27.816059)
			(xy 45.216778 -27.800838) (xy 45.275572 -27.793157) (xy 45.305218 -27.79268) (xy 45.33486 -27.793201)
			(xy 45.393641 -27.800915) (xy 45.450939 -27.816135) (xy 45.505801 -27.838607) (xy 45.531786 -27.852878)
			(xy 45.540197 -27.857128) (xy 45.558829 -27.859859) (xy 45.568108 -27.858212) (xy 45.598334 -27.851354)
			(xy 45.607329 -27.848932) (xy 45.622833 -27.838636) (xy 45.62856 -27.831288) (xy 45.643984 -27.810442)
			(xy 45.679554 -27.772706) (xy 45.71991 -27.74014) (xy 45.764307 -27.713344) (xy 45.811926 -27.692813)
			(xy 45.861889 -27.678925) (xy 45.913273 -27.671938) (xy 45.939202 -27.671522) (xy 45.966455 -27.671948)
			(xy 46.020407 -27.679705) (xy 46.072706 -27.695062) (xy 46.122287 -27.717705) (xy 46.16814 -27.747174)
			(xy 46.209334 -27.782868) (xy 46.245028 -27.824061) (xy 46.274496 -27.869915) (xy 46.297139 -27.919496)
			(xy 46.312495 -27.971795) (xy 46.320252 -28.025747) (xy 46.320252 -28.080253) (xy 46.312495 -28.134205)
			(xy 46.297139 -28.186504) (xy 46.274496 -28.236085) (xy 46.245028 -28.281939) (xy 46.209334 -28.323132)
			(xy 46.16814 -28.358826) (xy 46.122287 -28.388295) (xy 46.072706 -28.410938) (xy 46.020407 -28.426295)
			(xy 45.966455 -28.434052) (xy 45.939202 -28.434538) (xy 45.924409 -28.434405) (xy 45.894911 -28.432114)
			(xy 45.880274 -28.429966) (xy 45.869352 -28.428188) (xy 45.848016 -28.434284) (xy 45.780706 -28.491688)
			(xy 45.772745 -28.499286) (xy 45.763657 -28.519302) (xy 45.76318 -28.530296) (xy 45.76318 -28.834588)
			(xy 45.763698 -28.845575) (xy 45.772765 -28.865587) (xy 45.780706 -28.873196) (xy 45.848016 -28.9306)
			(xy 45.869352 -28.936696) (xy 45.880274 -28.934918) (xy 45.894911 -28.932774) (xy 45.924409 -28.930488)
			(xy 45.939202 -28.930346) (xy 45.96645 -28.930924) (xy 46.020391 -28.93868) (xy 46.072679 -28.954034)
			(xy 46.12225 -28.976672) (xy 46.168094 -29.006135) (xy 46.209279 -29.041822) (xy 46.244966 -29.083007)
			(xy 46.274429 -29.128852) (xy 46.297067 -29.178423) (xy 46.31242 -29.230711) (xy 46.320176 -29.284652)
			(xy 46.320176 -29.339148) (xy 46.31242 -29.393089) (xy 46.297067 -29.445377) (xy 46.274429 -29.494948)
			(xy 46.244966 -29.540793) (xy 46.209279 -29.581978) (xy 46.168094 -29.617665) (xy 46.12225 -29.647128)
			(xy 46.072679 -29.669766) (xy 46.020391 -29.68512) (xy 45.96645 -29.692876) (xy 45.939202 -29.693362)
			(xy 45.913275 -29.692944) (xy 45.861897 -29.685937) (xy 45.81194 -29.672039) (xy 45.764325 -29.651505)
			(xy 45.719929 -29.624714) (xy 45.679568 -29.592158) (xy 45.643987 -29.554438) (xy 45.62856 -29.533596)
			(xy 45.622792 -29.52629) (xy 45.60731 -29.515989) (xy 45.598334 -29.51353) (xy 45.568108 -29.506672)
			(xy 45.558834 -29.5049) (xy 45.540168 -29.507657) (xy 45.531786 -29.512006) (xy 45.505812 -29.526304)
			(xy 45.450959 -29.548814) (xy 45.393655 -29.56404) (xy 45.334864 -29.571725) (xy 45.305218 -29.572204)
			(xy 45.275575 -29.571712) (xy 45.216793 -29.56399) (xy 45.159494 -29.548761) (xy 45.104634 -29.526281)
			(xy 45.07865 -29.512006) (xy 45.070231 -29.507773) (xy 45.051606 -29.505032) (xy 45.042328 -29.506672)
			(xy 45.012102 -29.51353) (xy 45.0031 -29.515931) (xy 44.9876 -29.526243) (xy 44.981876 -29.533596)
			(xy 44.966425 -29.554422) (xy 44.930861 -29.592159) (xy 44.89051 -29.624727) (xy 44.846117 -29.651525)
			(xy 44.798502 -29.67206) (xy 44.748542 -29.685952) (xy 44.697162 -29.692944) (xy 44.671234 -29.693362)
			(xy 44.643976 -29.692993) (xy 44.590015 -29.685239) (xy 44.537707 -29.669884) (xy 44.488116 -29.647241)
			(xy 44.442253 -29.61777) (xy 44.401052 -29.582072) (xy 44.36535 -29.540874) (xy 44.335875 -29.495014)
			(xy 44.313227 -29.445425) (xy 44.297868 -29.393118) (xy 44.290109 -29.339158) (xy 42.567663 -29.339158)
			(xy 42.583206 -29.356505) (xy 42.613979 -29.403018) (xy 42.637651 -29.453515) (xy 42.653719 -29.506922)
			(xy 42.661839 -29.562098) (xy 42.662348 -29.589984) (xy 42.661839 -29.61787) (xy 42.653719 -29.673046)
			(xy 42.637651 -29.726453) (xy 42.613979 -29.77695) (xy 42.583206 -29.823463) (xy 42.545989 -29.865)
			(xy 42.503121 -29.900675) (xy 42.455515 -29.929729) (xy 42.404186 -29.951541) (xy 42.350229 -29.965647)
			(xy 42.294792 -29.971747) (xy 42.239058 -29.96971) (xy 42.184215 -29.95958) (xy 42.131431 -29.941573)
			(xy 42.081831 -29.916072) (xy 42.036473 -29.883621) (xy 41.996324 -29.844912) (xy 41.962238 -29.800769)
			(xy 41.934942 -29.752134) (xy 41.915019 -29.700043) (xy 41.902893 -29.645606) (xy 41.898822 -29.589984)
			(xy 40.630348 -29.589984) (xy 40.629839 -29.61787) (xy 40.621719 -29.673046) (xy 40.605651 -29.726453)
			(xy 40.581979 -29.77695) (xy 40.551206 -29.823463) (xy 40.513989 -29.865) (xy 40.471121 -29.900675)
			(xy 40.423515 -29.929729) (xy 40.372186 -29.951541) (xy 40.318229 -29.965647) (xy 40.262792 -29.971747)
			(xy 40.207058 -29.96971) (xy 40.152215 -29.95958) (xy 40.099431 -29.941573) (xy 40.049831 -29.916072)
			(xy 40.004473 -29.883621) (xy 39.964324 -29.844912) (xy 39.930238 -29.800769) (xy 39.902942 -29.752134)
			(xy 39.883019 -29.700043) (xy 39.870893 -29.645606) (xy 39.866822 -29.589984) (xy 38.126416 -29.589984)
			(xy 38.125907 -29.61787) (xy 38.117787 -29.673046) (xy 38.101719 -29.726453) (xy 38.078047 -29.77695)
			(xy 38.047274 -29.823463) (xy 38.010057 -29.865) (xy 37.967189 -29.900675) (xy 37.919583 -29.929729)
			(xy 37.868254 -29.951541) (xy 37.814297 -29.965647) (xy 37.75886 -29.971747) (xy 37.703126 -29.96971)
			(xy 37.648283 -29.95958) (xy 37.595499 -29.941573) (xy 37.545899 -29.916072) (xy 37.500541 -29.883621)
			(xy 37.460392 -29.844912) (xy 37.426306 -29.800769) (xy 37.39901 -29.752134) (xy 37.379087 -29.700043)
			(xy 37.366961 -29.645606) (xy 37.36289 -29.589984) (xy 36.029938 -29.589984) (xy 36.029938 -29.617252)
			(xy 36.022181 -29.671202) (xy 36.006826 -29.723499) (xy 35.984183 -29.773079) (xy 35.954716 -29.818931)
			(xy 35.919023 -29.860123) (xy 35.877831 -29.895816) (xy 35.831979 -29.925283) (xy 35.782399 -29.947926)
			(xy 35.730102 -29.963281) (xy 35.676152 -29.971038) (xy 35.6489 -29.971492) (xy 35.646106 -29.971492)
			(xy 35.636138 -29.971965) (xy 35.617694 -29.979533) (xy 35.610292 -29.986224) (xy 35.558984 -30.037024)
			(xy 35.552132 -30.04442) (xy 35.544393 -30.063019) (xy 35.543998 -30.073092) (xy 35.543998 -30.901894)
			(xy 35.545014 -30.912054) (xy 35.547808 -30.926532) (xy 35.551872 -30.93593) (xy 35.610292 -30.993842)
			(xy 35.617703 -31.000523) (xy 35.636139 -31.008102) (xy 35.646106 -31.008574) (xy 35.6489 -31.008574)
			(xy 35.676153 -31.00906) (xy 35.730103 -31.016817) (xy 35.7824 -31.032173) (xy 35.83198 -31.054815)
			(xy 35.877832 -31.084282) (xy 35.919024 -31.119976) (xy 35.954718 -31.161168) (xy 35.984185 -31.20702)
			(xy 36.006827 -31.2566) (xy 36.022183 -31.308897) (xy 36.02994 -31.362847) (xy 36.02994 -31.417353)
			(xy 36.022183 -31.471303) (xy 36.006827 -31.5236) (xy 35.984185 -31.57318) (xy 35.954718 -31.619032)
			(xy 35.934552 -31.642304) (xy 37.406578 -31.642304) (xy 37.410649 -31.586682) (xy 37.422775 -31.532245)
			(xy 37.442698 -31.480154) (xy 37.469994 -31.431519) (xy 37.50408 -31.387376) (xy 37.544229 -31.348667)
			(xy 37.589587 -31.316216) (xy 37.639187 -31.290715) (xy 37.691971 -31.272708) (xy 37.746814 -31.262578)
			(xy 37.802548 -31.260541) (xy 37.857985 -31.266641) (xy 37.911942 -31.280747) (xy 37.963271 -31.302559)
			(xy 38.010877 -31.331613) (xy 38.053745 -31.367288) (xy 38.074168 -31.390082) (xy 39.866822 -31.390082)
			(xy 39.870893 -31.33446) (xy 39.883019 -31.280023) (xy 39.902942 -31.227932) (xy 39.930238 -31.179297)
			(xy 39.964324 -31.135154) (xy 40.004473 -31.096445) (xy 40.049831 -31.063994) (xy 40.099431 -31.038493)
			(xy 40.152215 -31.020486) (xy 40.207058 -31.010356) (xy 40.262792 -31.008319) (xy 40.318229 -31.014419)
			(xy 40.372186 -31.028525) (xy 40.423515 -31.050337) (xy 40.471121 -31.079391) (xy 40.513989 -31.115066)
			(xy 40.551206 -31.156603) (xy 40.581979 -31.203116) (xy 40.605651 -31.253613) (xy 40.621719 -31.30702)
			(xy 40.629839 -31.362196) (xy 40.630348 -31.390082) (xy 41.898822 -31.390082) (xy 41.902893 -31.33446)
			(xy 41.915019 -31.280023) (xy 41.934942 -31.227932) (xy 41.962238 -31.179297) (xy 41.996324 -31.135154)
			(xy 42.036473 -31.096445) (xy 42.081831 -31.063994) (xy 42.131431 -31.038493) (xy 42.184215 -31.020486)
			(xy 42.239058 -31.010356) (xy 42.294792 -31.008319) (xy 42.350229 -31.014419) (xy 42.404186 -31.028525)
			(xy 42.455515 -31.050337) (xy 42.503121 -31.079391) (xy 42.545989 -31.115066) (xy 42.583206 -31.156603)
			(xy 42.613979 -31.203116) (xy 42.637651 -31.253613) (xy 42.653719 -31.30702) (xy 42.661839 -31.362196)
			(xy 42.662348 -31.390082) (xy 42.661839 -31.417968) (xy 42.653719 -31.473144) (xy 42.637651 -31.526551)
			(xy 42.613979 -31.577048) (xy 42.583206 -31.623561) (xy 42.545989 -31.665098) (xy 42.527775 -31.680256)
			(xy 44.290127 -31.680256) (xy 44.290127 -31.625744) (xy 44.297885 -31.571786) (xy 44.313244 -31.519481)
			(xy 44.335891 -31.469895) (xy 44.365364 -31.424037) (xy 44.401064 -31.38284) (xy 44.442264 -31.347144)
			(xy 44.488125 -31.317675) (xy 44.537713 -31.295032) (xy 44.590019 -31.279678) (xy 44.643978 -31.271925)
			(xy 44.671234 -31.271464) (xy 44.697162 -31.271845) (xy 44.748543 -31.278857) (xy 44.798501 -31.292761)
			(xy 44.846116 -31.3133) (xy 44.890512 -31.340098) (xy 44.930871 -31.372659) (xy 44.96645 -31.410385)
			(xy 44.981876 -31.43123) (xy 44.987626 -31.438552) (xy 45.003121 -31.448843) (xy 45.012102 -31.451296)
			(xy 45.042328 -31.458154) (xy 45.051606 -31.459888) (xy 45.070267 -31.457156) (xy 45.07865 -31.45282)
			(xy 45.104633 -31.438559) (xy 45.159504 -31.416148) (xy 45.216806 -31.400993) (xy 45.275582 -31.393347)
			(xy 45.305218 -31.392876) (xy 45.334856 -31.393308) (xy 45.39364 -31.400937) (xy 45.450943 -31.416103)
			(xy 45.505804 -31.438552) (xy 45.531786 -31.45282) (xy 45.540199 -31.457068) (xy 45.558829 -31.459802)
			(xy 45.568108 -31.458154) (xy 45.598334 -31.451296) (xy 45.607324 -31.44886) (xy 45.62283 -31.438573)
			(xy 45.62856 -31.43123) (xy 45.643967 -31.410371) (xy 45.679542 -31.372639) (xy 45.719901 -31.340075)
			(xy 45.764301 -31.313282) (xy 45.811923 -31.292753) (xy 45.861887 -31.278867) (xy 45.913273 -31.271879)
			(xy 45.939202 -31.271464) (xy 45.966451 -31.272006) (xy 46.020395 -31.279763) (xy 46.072685 -31.295117)
			(xy 46.122258 -31.317756) (xy 46.168105 -31.34722) (xy 46.209292 -31.382909) (xy 46.244981 -31.424096)
			(xy 46.274445 -31.469943) (xy 46.297084 -31.519517) (xy 46.312438 -31.571807) (xy 46.320194 -31.625751)
			(xy 46.320194 -31.680249) (xy 46.312438 -31.734193) (xy 46.297084 -31.786483) (xy 46.274445 -31.836057)
			(xy 46.244981 -31.881904) (xy 46.209292 -31.923091) (xy 46.168105 -31.95878) (xy 46.122258 -31.988244)
			(xy 46.072685 -32.010883) (xy 46.020395 -32.026237) (xy 45.966451 -32.033994) (xy 45.939202 -32.03448)
			(xy 45.924409 -32.034346) (xy 45.894911 -32.032056) (xy 45.880274 -32.029908) (xy 45.869352 -32.02813)
			(xy 45.848016 -32.034226) (xy 45.780706 -32.09163) (xy 45.772772 -32.099252) (xy 45.763668 -32.119249)
			(xy 45.76318 -32.130238) (xy 45.76318 -32.43453) (xy 45.763675 -32.44552) (xy 45.772758 -32.465532)
			(xy 45.780706 -32.473138) (xy 45.848016 -32.530542) (xy 45.869352 -32.536638) (xy 45.880274 -32.53486)
			(xy 45.894911 -32.532716) (xy 45.924409 -32.53043) (xy 45.939202 -32.530288) (xy 45.966453 -32.530782)
			(xy 46.0204 -32.538539) (xy 46.072694 -32.553894) (xy 46.12227 -32.576535) (xy 46.16812 -32.606001)
			(xy 46.209309 -32.641692) (xy 46.245 -32.682882) (xy 46.274466 -32.728732) (xy 46.297107 -32.778308)
			(xy 46.312462 -32.830602) (xy 46.320218 -32.884549) (xy 46.320218 -32.939051) (xy 46.312462 -32.992998)
			(xy 46.297107 -33.045292) (xy 46.274466 -33.094868) (xy 46.245 -33.140718) (xy 46.209309 -33.181908)
			(xy 46.16812 -33.217599) (xy 46.12227 -33.247065) (xy 46.072694 -33.269706) (xy 46.0204 -33.285061)
			(xy 45.966453 -33.292818) (xy 45.939202 -33.293304) (xy 45.913276 -33.292868) (xy 45.861899 -33.285862)
			(xy 45.811944 -33.271966) (xy 45.764329 -33.251434) (xy 45.719933 -33.224646) (xy 45.679571 -33.192094)
			(xy 45.643988 -33.154378) (xy 45.62856 -33.133538) (xy 45.622804 -33.126222) (xy 45.607313 -33.115928)
			(xy 45.598334 -33.113472) (xy 45.568108 -33.106614) (xy 45.558835 -33.104837) (xy 45.540167 -33.107596)
			(xy 45.531786 -33.111948) (xy 45.505794 -33.126192) (xy 45.450926 -33.148608) (xy 45.393627 -33.163768)
			(xy 45.334853 -33.171419) (xy 45.305218 -33.171892) (xy 45.27558 -33.171448) (xy 45.216797 -33.163824)
			(xy 45.159494 -33.148661) (xy 45.104632 -33.126215) (xy 45.07865 -33.111948) (xy 45.07023 -33.107717)
			(xy 45.051606 -33.104973) (xy 45.042328 -33.106614) (xy 45.012102 -33.113472) (xy 45.003107 -33.115891)
			(xy 44.987604 -33.126191) (xy 44.981876 -33.133538) (xy 44.966437 -33.154373) (xy 44.930869 -33.192108)
			(xy 44.890516 -33.224674) (xy 44.846121 -33.251471) (xy 44.798504 -33.272004) (xy 44.748544 -33.285894)
			(xy 44.697162 -33.292886) (xy 44.671234 -33.293304) (xy 44.643979 -33.292851) (xy 44.590024 -33.285098)
			(xy 44.537722 -33.269745) (xy 44.488137 -33.247104) (xy 44.442279 -33.217636) (xy 44.401082 -33.181942)
			(xy 44.365384 -33.140748) (xy 44.335913 -33.094893) (xy 44.313267 -33.04531) (xy 44.297909 -32.993009)
			(xy 44.290151 -32.939055) (xy 44.290151 -32.884545) (xy 44.297909 -32.830591) (xy 44.313267 -32.77829)
			(xy 44.335913 -32.728707) (xy 44.365384 -32.682852) (xy 44.401082 -32.641658) (xy 44.442279 -32.605964)
			(xy 44.488137 -32.576496) (xy 44.537722 -32.553855) (xy 44.590024 -32.538502) (xy 44.643979 -32.530749)
			(xy 44.671234 -32.530288) (xy 44.686027 -32.530429) (xy 44.715525 -32.532714) (xy 44.730162 -32.53486)
			(xy 44.741084 -32.536638) (xy 44.76242 -32.530542) (xy 44.82973 -32.473138) (xy 44.837684 -32.465535)
			(xy 44.846775 -32.445523) (xy 44.847256 -32.43453) (xy 44.847256 -32.130238) (xy 44.846768 -32.119247)
			(xy 44.837679 -32.099236) (xy 44.82973 -32.09163) (xy 44.76242 -32.034226) (xy 44.741084 -32.02813)
			(xy 44.730162 -32.029908) (xy 44.715524 -32.032048) (xy 44.686027 -32.034337) (xy 44.671234 -32.03448)
			(xy 44.643978 -32.034075) (xy 44.590019 -32.026322) (xy 44.537713 -32.010968) (xy 44.488125 -31.988325)
			(xy 44.442264 -31.958856) (xy 44.401064 -31.92316) (xy 44.365364 -31.881963) (xy 44.335891 -31.836105)
			(xy 44.313244 -31.786519) (xy 44.297885 -31.734214) (xy 44.290127 -31.680256) (xy 42.527775 -31.680256)
			(xy 42.503121 -31.700773) (xy 42.455515 -31.729827) (xy 42.404186 -31.751639) (xy 42.350229 -31.765745)
			(xy 42.294792 -31.771845) (xy 42.239058 -31.769808) (xy 42.184215 -31.759678) (xy 42.131431 -31.741671)
			(xy 42.081831 -31.71617) (xy 42.036473 -31.683719) (xy 41.996324 -31.64501) (xy 41.962238 -31.600867)
			(xy 41.934942 -31.552232) (xy 41.915019 -31.500141) (xy 41.902893 -31.445704) (xy 41.898822 -31.390082)
			(xy 40.630348 -31.390082) (xy 40.629839 -31.417968) (xy 40.621719 -31.473144) (xy 40.605651 -31.526551)
			(xy 40.581979 -31.577048) (xy 40.551206 -31.623561) (xy 40.513989 -31.665098) (xy 40.471121 -31.700773)
			(xy 40.423515 -31.729827) (xy 40.372186 -31.751639) (xy 40.318229 -31.765745) (xy 40.262792 -31.771845)
			(xy 40.207058 -31.769808) (xy 40.152215 -31.759678) (xy 40.099431 -31.741671) (xy 40.049831 -31.71617)
			(xy 40.004473 -31.683719) (xy 39.964324 -31.64501) (xy 39.930238 -31.600867) (xy 39.902942 -31.552232)
			(xy 39.883019 -31.500141) (xy 39.870893 -31.445704) (xy 39.866822 -31.390082) (xy 38.074168 -31.390082)
			(xy 38.090962 -31.408825) (xy 38.121735 -31.455338) (xy 38.145407 -31.505835) (xy 38.161475 -31.559242)
			(xy 38.169595 -31.614418) (xy 38.170104 -31.642304) (xy 38.169595 -31.67019) (xy 38.161475 -31.725366)
			(xy 38.145407 -31.778773) (xy 38.121735 -31.82927) (xy 38.090962 -31.875783) (xy 38.053745 -31.91732)
			(xy 38.010877 -31.952995) (xy 37.963271 -31.982049) (xy 37.911942 -32.003861) (xy 37.857985 -32.017967)
			(xy 37.802548 -32.024067) (xy 37.746814 -32.02203) (xy 37.691971 -32.0119) (xy 37.639187 -31.993893)
			(xy 37.589587 -31.968392) (xy 37.544229 -31.935941) (xy 37.50408 -31.897232) (xy 37.469994 -31.853089)
			(xy 37.442698 -31.804454) (xy 37.422775 -31.752363) (xy 37.410649 -31.697926) (xy 37.406578 -31.642304)
			(xy 35.934552 -31.642304) (xy 35.919024 -31.660224) (xy 35.877832 -31.695918) (xy 35.83198 -31.725385)
			(xy 35.7824 -31.748027) (xy 35.730103 -31.763383) (xy 35.676153 -31.77114) (xy 35.6489 -31.77159)
			(xy 35.646106 -31.77159) (xy 35.636138 -31.772063) (xy 35.617694 -31.779631) (xy 35.610292 -31.786322)
			(xy 35.558984 -31.837122) (xy 35.552132 -31.844518) (xy 35.544392 -31.863117) (xy 35.543998 -31.87319)
			(xy 35.543998 -32.701992) (xy 35.545014 -32.712152) (xy 35.547808 -32.72663) (xy 35.551872 -32.736028)
			(xy 35.610292 -32.79394) (xy 35.617703 -32.800621) (xy 35.636139 -32.8082) (xy 35.646106 -32.808672)
			(xy 35.6489 -32.808672) (xy 35.676153 -32.809158) (xy 35.730103 -32.816915) (xy 35.782401 -32.832271)
			(xy 35.831981 -32.854913) (xy 35.877833 -32.884381) (xy 35.919026 -32.920074) (xy 35.954719 -32.961267)
			(xy 35.984187 -33.007119) (xy 36.006829 -33.056699) (xy 36.022185 -33.108997) (xy 36.029942 -33.162947)
			(xy 36.029942 -33.19018) (xy 37.67404 -33.19018) (xy 37.678111 -33.134558) (xy 37.690237 -33.080121)
			(xy 37.71016 -33.02803) (xy 37.737456 -32.979395) (xy 37.771542 -32.935252) (xy 37.811691 -32.896543)
			(xy 37.857049 -32.864092) (xy 37.906649 -32.838591) (xy 37.959433 -32.820584) (xy 38.014276 -32.810454)
			(xy 38.07001 -32.808417) (xy 38.125447 -32.814517) (xy 38.179404 -32.828623) (xy 38.230733 -32.850435)
			(xy 38.278339 -32.879489) (xy 38.321207 -32.915164) (xy 38.358424 -32.956701) (xy 38.389197 -33.003214)
			(xy 38.412869 -33.053711) (xy 38.428937 -33.107118) (xy 38.437057 -33.162294) (xy 38.437566 -33.19018)
			(xy 39.866822 -33.19018) (xy 39.870893 -33.134558) (xy 39.883019 -33.080121) (xy 39.902942 -33.02803)
			(xy 39.930238 -32.979395) (xy 39.964324 -32.935252) (xy 40.004473 -32.896543) (xy 40.049831 -32.864092)
			(xy 40.099431 -32.838591) (xy 40.152215 -32.820584) (xy 40.207058 -32.810454) (xy 40.262792 -32.808417)
			(xy 40.318229 -32.814517) (xy 40.372186 -32.828623) (xy 40.423515 -32.850435) (xy 40.471121 -32.879489)
			(xy 40.513989 -32.915164) (xy 40.551206 -32.956701) (xy 40.581979 -33.003214) (xy 40.605651 -33.053711)
			(xy 40.621719 -33.107118) (xy 40.629839 -33.162294) (xy 40.630348 -33.19018) (xy 41.898822 -33.19018)
			(xy 41.902893 -33.134558) (xy 41.915019 -33.080121) (xy 41.934942 -33.02803) (xy 41.962238 -32.979395)
			(xy 41.996324 -32.935252) (xy 42.036473 -32.896543) (xy 42.081831 -32.864092) (xy 42.131431 -32.838591)
			(xy 42.184215 -32.820584) (xy 42.239058 -32.810454) (xy 42.294792 -32.808417) (xy 42.350229 -32.814517)
			(xy 42.404186 -32.828623) (xy 42.455515 -32.850435) (xy 42.503121 -32.879489) (xy 42.545989 -32.915164)
			(xy 42.583206 -32.956701) (xy 42.613979 -33.003214) (xy 42.637651 -33.053711) (xy 42.653719 -33.107118)
			(xy 42.661839 -33.162294) (xy 42.662348 -33.19018) (xy 42.661839 -33.218066) (xy 42.653719 -33.273242)
			(xy 42.637651 -33.326649) (xy 42.613979 -33.377146) (xy 42.583206 -33.423659) (xy 42.545989 -33.465196)
			(xy 42.503121 -33.500871) (xy 42.455515 -33.529925) (xy 42.404186 -33.551737) (xy 42.350229 -33.565843)
			(xy 42.294792 -33.571943) (xy 42.239058 -33.569906) (xy 42.184215 -33.559776) (xy 42.131431 -33.541769)
			(xy 42.081831 -33.516268) (xy 42.036473 -33.483817) (xy 41.996324 -33.445108) (xy 41.962238 -33.400965)
			(xy 41.934942 -33.35233) (xy 41.915019 -33.300239) (xy 41.902893 -33.245802) (xy 41.898822 -33.19018)
			(xy 40.630348 -33.19018) (xy 40.629839 -33.218066) (xy 40.621719 -33.273242) (xy 40.605651 -33.326649)
			(xy 40.581979 -33.377146) (xy 40.551206 -33.423659) (xy 40.513989 -33.465196) (xy 40.471121 -33.500871)
			(xy 40.423515 -33.529925) (xy 40.372186 -33.551737) (xy 40.318229 -33.565843) (xy 40.262792 -33.571943)
			(xy 40.207058 -33.569906) (xy 40.152215 -33.559776) (xy 40.099431 -33.541769) (xy 40.049831 -33.516268)
			(xy 40.004473 -33.483817) (xy 39.964324 -33.445108) (xy 39.930238 -33.400965) (xy 39.902942 -33.35233)
			(xy 39.883019 -33.300239) (xy 39.870893 -33.245802) (xy 39.866822 -33.19018) (xy 38.437566 -33.19018)
			(xy 38.437057 -33.218066) (xy 38.428937 -33.273242) (xy 38.412869 -33.326649) (xy 38.389197 -33.377146)
			(xy 38.358424 -33.423659) (xy 38.321207 -33.465196) (xy 38.278339 -33.500871) (xy 38.230733 -33.529925)
			(xy 38.179404 -33.551737) (xy 38.125447 -33.565843) (xy 38.07001 -33.571943) (xy 38.014276 -33.569906)
			(xy 37.959433 -33.559776) (xy 37.906649 -33.541769) (xy 37.857049 -33.516268) (xy 37.811691 -33.483817)
			(xy 37.771542 -33.445108) (xy 37.737456 -33.400965) (xy 37.71016 -33.35233) (xy 37.690237 -33.300239)
			(xy 37.678111 -33.245802) (xy 37.67404 -33.19018) (xy 36.029942 -33.19018) (xy 36.029942 -33.217453)
			(xy 36.022185 -33.271403) (xy 36.006829 -33.323701) (xy 35.984187 -33.373281) (xy 35.954719 -33.419133)
			(xy 35.919026 -33.460326) (xy 35.877833 -33.496019) (xy 35.831981 -33.525487) (xy 35.782401 -33.548129)
			(xy 35.730103 -33.563485) (xy 35.676153 -33.571242) (xy 35.6489 -33.571688) (xy 35.646106 -33.571688)
			(xy 35.636138 -33.572161) (xy 35.617694 -33.579729) (xy 35.610292 -33.58642) (xy 35.558984 -33.63722)
			(xy 35.552132 -33.644616) (xy 35.544391 -33.663215) (xy 35.543998 -33.673288) (xy 35.543998 -34.501836)
			(xy 35.545014 -34.511996) (xy 35.547808 -34.526474) (xy 35.551872 -34.535872) (xy 35.610292 -34.593784)
			(xy 35.6177 -34.600471) (xy 35.636137 -34.608059) (xy 35.646106 -34.608516) (xy 35.6489 -34.608516)
			(xy 35.676149 -34.609002) (xy 35.730094 -34.616758) (xy 35.782385 -34.632112) (xy 35.831959 -34.654752)
			(xy 35.877807 -34.684216) (xy 35.918994 -34.719906) (xy 35.954684 -34.761093) (xy 35.984148 -34.806941)
			(xy 36.006788 -34.856515) (xy 36.022142 -34.908806) (xy 36.029898 -34.962751) (xy 36.029898 -34.990024)
			(xy 37.67277 -34.990024) (xy 37.676841 -34.934402) (xy 37.688967 -34.879965) (xy 37.70889 -34.827874)
			(xy 37.736186 -34.779239) (xy 37.770272 -34.735096) (xy 37.810421 -34.696387) (xy 37.855779 -34.663936)
			(xy 37.905379 -34.638435) (xy 37.958163 -34.620428) (xy 38.013006 -34.610298) (xy 38.06874 -34.608261)
			(xy 38.124177 -34.614361) (xy 38.178134 -34.628467) (xy 38.229463 -34.650279) (xy 38.277069 -34.679333)
			(xy 38.319937 -34.715008) (xy 38.357154 -34.756545) (xy 38.387927 -34.803058) (xy 38.411599 -34.853555)
			(xy 38.427667 -34.906962) (xy 38.435787 -34.962138) (xy 38.436296 -34.990024) (xy 39.000936 -34.990024)
			(xy 39.005007 -34.934402) (xy 39.017133 -34.879965) (xy 39.037056 -34.827874) (xy 39.064352 -34.779239)
			(xy 39.098438 -34.735096) (xy 39.138587 -34.696387) (xy 39.183945 -34.663936) (xy 39.233545 -34.638435)
			(xy 39.286329 -34.620428) (xy 39.341172 -34.610298) (xy 39.396906 -34.608261) (xy 39.452343 -34.614361)
			(xy 39.5063 -34.628467) (xy 39.557629 -34.650279) (xy 39.605235 -34.679333) (xy 39.648103 -34.715008)
			(xy 39.68532 -34.756545) (xy 39.716093 -34.803058) (xy 39.739765 -34.853555) (xy 39.755833 -34.906962)
			(xy 39.763953 -34.962138) (xy 39.764462 -34.990024) (xy 41.898822 -34.990024) (xy 41.902893 -34.934402)
			(xy 41.915019 -34.879965) (xy 41.934942 -34.827874) (xy 41.962238 -34.779239) (xy 41.996324 -34.735096)
			(xy 42.036473 -34.696387) (xy 42.081831 -34.663936) (xy 42.131431 -34.638435) (xy 42.184215 -34.620428)
			(xy 42.239058 -34.610298) (xy 42.294792 -34.608261) (xy 42.350229 -34.614361) (xy 42.404186 -34.628467)
			(xy 42.455515 -34.650279) (xy 42.503121 -34.679333) (xy 42.545989 -34.715008) (xy 42.583206 -34.756545)
			(xy 42.613979 -34.803058) (xy 42.637651 -34.853555) (xy 42.653719 -34.906962) (xy 42.661839 -34.962138)
			(xy 42.662348 -34.990024) (xy 42.661839 -35.01791) (xy 42.653719 -35.073086) (xy 42.637651 -35.126493)
			(xy 42.613979 -35.17699) (xy 42.583206 -35.223503) (xy 42.545989 -35.26504) (xy 42.503121 -35.300715)
			(xy 42.455515 -35.329769) (xy 42.404186 -35.351581) (xy 42.350229 -35.365687) (xy 42.294792 -35.371787)
			(xy 42.239058 -35.36975) (xy 42.184215 -35.35962) (xy 42.131431 -35.341613) (xy 42.081831 -35.316112)
			(xy 42.036473 -35.283661) (xy 41.996324 -35.244952) (xy 41.962238 -35.200809) (xy 41.934942 -35.152174)
			(xy 41.915019 -35.100083) (xy 41.902893 -35.045646) (xy 41.898822 -34.990024) (xy 39.764462 -34.990024)
			(xy 39.763953 -35.01791) (xy 39.755833 -35.073086) (xy 39.739765 -35.126493) (xy 39.716093 -35.17699)
			(xy 39.68532 -35.223503) (xy 39.648103 -35.26504) (xy 39.605235 -35.300715) (xy 39.557629 -35.329769)
			(xy 39.5063 -35.351581) (xy 39.452343 -35.365687) (xy 39.396906 -35.371787) (xy 39.341172 -35.36975)
			(xy 39.286329 -35.35962) (xy 39.233545 -35.341613) (xy 39.183945 -35.316112) (xy 39.138587 -35.283661)
			(xy 39.098438 -35.244952) (xy 39.064352 -35.200809) (xy 39.037056 -35.152174) (xy 39.017133 -35.100083)
			(xy 39.005007 -35.045646) (xy 39.000936 -34.990024) (xy 38.436296 -34.990024) (xy 38.435787 -35.01791)
			(xy 38.427667 -35.073086) (xy 38.411599 -35.126493) (xy 38.387927 -35.17699) (xy 38.357154 -35.223503)
			(xy 38.319937 -35.26504) (xy 38.277069 -35.300715) (xy 38.229463 -35.329769) (xy 38.178134 -35.351581)
			(xy 38.124177 -35.365687) (xy 38.06874 -35.371787) (xy 38.013006 -35.36975) (xy 37.958163 -35.35962)
			(xy 37.905379 -35.341613) (xy 37.855779 -35.316112) (xy 37.810421 -35.283661) (xy 37.770272 -35.244952)
			(xy 37.736186 -35.200809) (xy 37.70889 -35.152174) (xy 37.688967 -35.100083) (xy 37.676841 -35.045646)
			(xy 37.67277 -34.990024) (xy 36.029898 -34.990024) (xy 36.029898 -35.017249) (xy 36.022142 -35.071194)
			(xy 36.006788 -35.123485) (xy 35.984148 -35.173059) (xy 35.954684 -35.218907) (xy 35.918994 -35.260094)
			(xy 35.877807 -35.295784) (xy 35.831959 -35.325248) (xy 35.782385 -35.347888) (xy 35.730094 -35.363242)
			(xy 35.676149 -35.370998) (xy 35.6489 -35.371532) (xy 35.646106 -35.371532) (xy 35.636139 -35.372006)
			(xy 35.617698 -35.379579) (xy 35.610292 -35.386264) (xy 35.558984 -35.437064) (xy 35.552139 -35.444462)
			(xy 35.544414 -35.463061) (xy 35.543998 -35.473132) (xy 35.543998 -38.193478) (xy 37.098216 -38.193478)
			(xy 37.098216 -38.106602) (xy 37.106232 -38.020096) (xy 37.122195 -37.934699) (xy 37.14597 -37.851139)
			(xy 37.177353 -37.770129) (xy 37.216077 -37.69236) (xy 37.261812 -37.618496) (xy 37.314167 -37.549168)
			(xy 37.372695 -37.484965) (xy 37.436898 -37.426437) (xy 37.506226 -37.374082) (xy 37.58009 -37.328347)
			(xy 37.657859 -37.289623) (xy 37.738869 -37.25824) (xy 37.822429 -37.234465) (xy 37.907826 -37.218502)
			(xy 37.994332 -37.210486) (xy 38.03777 -37.209984) (xy 38.115748 -37.209984) (xy 38.125761 -37.209551)
			(xy 38.144257 -37.201872) (xy 38.158408 -37.187703) (xy 38.166063 -37.169197) (xy 38.166548 -37.159184)
			(xy 38.166548 -37.151564) (xy 38.16223 -37.137594) (xy 38.158166 -37.131244) (xy 38.134247 -37.094009)
			(xy 38.092546 -37.015944) (xy 38.058161 -36.93439) (xy 38.031383 -36.850033) (xy 38.012434 -36.76358)
			(xy 38.001474 -36.675755) (xy 37.998596 -36.587297) (xy 38.003823 -36.498946) (xy 38.017111 -36.411443)
			(xy 38.038349 -36.325524) (xy 38.067358 -36.241908) (xy 38.103896 -36.161296) (xy 38.147657 -36.084366)
			(xy 38.198271 -36.011762) (xy 38.255317 -35.944093) (xy 38.318314 -35.881927) (xy 38.386734 -35.825786)
			(xy 38.460004 -35.776139) (xy 38.537509 -35.733405) (xy 38.618598 -35.69794) (xy 38.702592 -35.670044)
			(xy 38.788786 -35.649948) (xy 38.876457 -35.637824) (xy 38.96487 -35.633771) (xy 39.053283 -35.637824)
			(xy 39.140954 -35.649948) (xy 39.227148 -35.670044) (xy 39.311142 -35.69794) (xy 39.392231 -35.733405)
			(xy 39.469736 -35.776139) (xy 39.543006 -35.825786) (xy 39.605102 -35.876738) (xy 44.717206 -35.876738)
			(xy 44.721277 -35.821116) (xy 44.733403 -35.766679) (xy 44.753326 -35.714588) (xy 44.780622 -35.665953)
			(xy 44.814708 -35.62181) (xy 44.854857 -35.583101) (xy 44.900215 -35.55065) (xy 44.949815 -35.525149)
			(xy 45.002599 -35.507142) (xy 45.057442 -35.497012) (xy 45.113176 -35.494975) (xy 45.168613 -35.501075)
			(xy 45.22257 -35.515181) (xy 45.273899 -35.536993) (xy 45.321505 -35.566047) (xy 45.364373 -35.601722)
			(xy 45.40159 -35.643259) (xy 45.432363 -35.689772) (xy 45.456035 -35.740269) (xy 45.472103 -35.793676)
			(xy 45.480223 -35.848852) (xy 45.480732 -35.876738) (xy 45.480223 -35.904624) (xy 45.472103 -35.9598)
			(xy 45.456035 -36.013207) (xy 45.432363 -36.063704) (xy 45.40159 -36.110217) (xy 45.364373 -36.151754)
			(xy 45.321505 -36.187429) (xy 45.273899 -36.216483) (xy 45.22257 -36.238295) (xy 45.168613 -36.252401)
			(xy 45.113176 -36.258501) (xy 45.057442 -36.256464) (xy 45.002599 -36.246334) (xy 44.949815 -36.228327)
			(xy 44.900215 -36.202826) (xy 44.854857 -36.170375) (xy 44.814708 -36.131666) (xy 44.780622 -36.087523)
			(xy 44.753326 -36.038888) (xy 44.733403 -35.986797) (xy 44.721277 -35.93236) (xy 44.717206 -35.876738)
			(xy 39.605102 -35.876738) (xy 39.611426 -35.881927) (xy 39.674423 -35.944093) (xy 39.731469 -36.011762)
			(xy 39.782083 -36.084366) (xy 39.825844 -36.161296) (xy 39.862382 -36.241908) (xy 39.891391 -36.325524)
			(xy 39.912629 -36.411443) (xy 39.925917 -36.498946) (xy 39.928342 -36.539928) (xy 46.538624 -36.539928)
			(xy 46.538624 -36.479992) (xy 46.546447 -36.42057) (xy 46.56196 -36.362677) (xy 46.584896 -36.307304)
			(xy 46.614863 -36.255398) (xy 46.65135 -36.207848) (xy 46.69373 -36.165468) (xy 46.74128 -36.128981)
			(xy 46.793186 -36.099014) (xy 46.848559 -36.076078) (xy 46.906452 -36.060565) (xy 46.965874 -36.052742)
			(xy 47.02581 -36.052742) (xy 47.085232 -36.060565) (xy 47.143125 -36.076078) (xy 47.198498 -36.099014)
			(xy 47.250404 -36.128981) (xy 47.297954 -36.165468) (xy 47.340334 -36.207848) (xy 47.376821 -36.255398)
			(xy 47.406788 -36.307304) (xy 47.429724 -36.362677) (xy 47.445237 -36.42057) (xy 47.45306 -36.479992)
			(xy 47.45355 -36.50996) (xy 47.45306 -36.539928) (xy 47.445237 -36.59935) (xy 47.429724 -36.657243)
			(xy 47.406788 -36.712616) (xy 47.376821 -36.764522) (xy 47.340334 -36.812072) (xy 47.297954 -36.854452)
			(xy 47.250404 -36.890939) (xy 47.198498 -36.920906) (xy 47.143125 -36.943842) (xy 47.085232 -36.959355)
			(xy 47.02581 -36.967178) (xy 46.965874 -36.967178) (xy 46.906452 -36.959355) (xy 46.848559 -36.943842)
			(xy 46.793186 -36.920906) (xy 46.74128 -36.890939) (xy 46.69373 -36.854452) (xy 46.65135 -36.812072)
			(xy 46.614863 -36.764522) (xy 46.584896 -36.712616) (xy 46.56196 -36.657243) (xy 46.546447 -36.59935)
			(xy 46.538624 -36.539928) (xy 39.928342 -36.539928) (xy 39.931144 -36.587297) (xy 39.928266 -36.675755)
			(xy 39.917306 -36.76358) (xy 39.898357 -36.850033) (xy 39.871579 -36.93439) (xy 39.837194 -37.015944)
			(xy 39.795493 -37.094009) (xy 39.771574 -37.131244) (xy 39.763192 -37.143944) (xy 39.763192 -37.159184)
			(xy 39.763632 -37.169203) (xy 39.771295 -37.187718) (xy 39.785461 -37.201891) (xy 39.803973 -37.209563)
			(xy 39.813992 -37.209984) (xy 39.89197 -37.209984) (xy 39.935408 -37.21049) (xy 40.021914 -37.218506)
			(xy 40.10731 -37.234469) (xy 40.19087 -37.258244) (xy 40.27188 -37.289627) (xy 40.349648 -37.328351)
			(xy 40.423511 -37.374085) (xy 40.49284 -37.42644) (xy 40.546283 -37.47516) (xy 43.759118 -37.47516)
			(xy 43.763189 -37.419538) (xy 43.775315 -37.365101) (xy 43.795238 -37.31301) (xy 43.822534 -37.264375)
			(xy 43.85662 -37.220232) (xy 43.896769 -37.181523) (xy 43.942127 -37.149072) (xy 43.991727 -37.123571)
			(xy 44.044511 -37.105564) (xy 44.099354 -37.095434) (xy 44.155088 -37.093397) (xy 44.210525 -37.099497)
			(xy 44.264482 -37.113603) (xy 44.315811 -37.135415) (xy 44.363417 -37.164469) (xy 44.406285 -37.200144)
			(xy 44.443502 -37.241681) (xy 44.474275 -37.288194) (xy 44.497947 -37.338691) (xy 44.514015 -37.392098)
			(xy 44.522135 -37.447274) (xy 44.522644 -37.47516) (xy 44.522135 -37.503046) (xy 44.514015 -37.558222)
			(xy 44.497947 -37.611629) (xy 44.474275 -37.662126) (xy 44.454295 -37.692326) (xy 45.873144 -37.692326)
			(xy 45.873144 -37.63239) (xy 45.880967 -37.572968) (xy 45.89648 -37.515075) (xy 45.919416 -37.459702)
			(xy 45.949383 -37.407796) (xy 45.98587 -37.360246) (xy 46.02825 -37.317866) (xy 46.0758 -37.281379)
			(xy 46.127706 -37.251412) (xy 46.183079 -37.228476) (xy 46.240972 -37.212963) (xy 46.300394 -37.20514)
			(xy 46.36033 -37.20514) (xy 46.419752 -37.212963) (xy 46.477645 -37.228476) (xy 46.533018 -37.251412)
			(xy 46.584924 -37.281379) (xy 46.632474 -37.317866) (xy 46.674854 -37.360246) (xy 46.711341 -37.407796)
			(xy 46.741308 -37.459702) (xy 46.764244 -37.515075) (xy 46.779757 -37.572968) (xy 46.78758 -37.63239)
			(xy 46.78807 -37.662358) (xy 46.78758 -37.692326) (xy 46.779757 -37.751748) (xy 46.764244 -37.809641)
			(xy 46.741308 -37.865014) (xy 46.711341 -37.91692) (xy 46.674854 -37.96447) (xy 46.632474 -38.00685)
			(xy 46.584924 -38.043337) (xy 46.533018 -38.073304) (xy 46.477645 -38.09624) (xy 46.419752 -38.111753)
			(xy 46.36033 -38.119576) (xy 46.300394 -38.119576) (xy 46.240972 -38.111753) (xy 46.183079 -38.09624)
			(xy 46.127706 -38.073304) (xy 46.0758 -38.043337) (xy 46.02825 -38.00685) (xy 45.98587 -37.96447)
			(xy 45.949383 -37.91692) (xy 45.919416 -37.865014) (xy 45.89648 -37.809641) (xy 45.880967 -37.751748)
			(xy 45.873144 -37.692326) (xy 44.454295 -37.692326) (xy 44.443502 -37.708639) (xy 44.406285 -37.750176)
			(xy 44.363417 -37.785851) (xy 44.315811 -37.814905) (xy 44.264482 -37.836717) (xy 44.210525 -37.850823)
			(xy 44.155088 -37.856923) (xy 44.099354 -37.854886) (xy 44.044511 -37.844756) (xy 43.991727 -37.826749)
			(xy 43.942127 -37.801248) (xy 43.896769 -37.768797) (xy 43.85662 -37.730088) (xy 43.822534 -37.685945)
			(xy 43.795238 -37.63731) (xy 43.775315 -37.585219) (xy 43.763189 -37.530782) (xy 43.759118 -37.47516)
			(xy 40.546283 -37.47516) (xy 40.557042 -37.484968) (xy 40.61557 -37.54917) (xy 40.667925 -37.618499)
			(xy 40.713659 -37.692362) (xy 40.752383 -37.77013) (xy 40.783766 -37.85114) (xy 40.807541 -37.9347)
			(xy 40.823504 -38.020096) (xy 40.83152 -38.106602) (xy 40.83152 -38.193478) (xy 40.823504 -38.279984)
			(xy 40.807541 -38.36538) (xy 40.783766 -38.44894) (xy 40.76741 -38.49116) (xy 43.759118 -38.49116)
			(xy 43.763189 -38.435538) (xy 43.775315 -38.381101) (xy 43.795238 -38.32901) (xy 43.822534 -38.280375)
			(xy 43.85662 -38.236232) (xy 43.896769 -38.197523) (xy 43.942127 -38.165072) (xy 43.991727 -38.139571)
			(xy 44.044511 -38.121564) (xy 44.099354 -38.111434) (xy 44.155088 -38.109397) (xy 44.210525 -38.115497)
			(xy 44.264482 -38.129603) (xy 44.315811 -38.151415) (xy 44.363417 -38.180469) (xy 44.406285 -38.216144)
			(xy 44.443502 -38.257681) (xy 44.474275 -38.304194) (xy 44.497947 -38.354691) (xy 44.514015 -38.408098)
			(xy 44.522135 -38.463274) (xy 44.522644 -38.49116) (xy 44.522135 -38.519046) (xy 44.514015 -38.574222)
			(xy 44.497947 -38.627629) (xy 44.474275 -38.678126) (xy 44.458997 -38.701218) (xy 47.437546 -38.701218)
			(xy 47.441617 -38.645596) (xy 47.453743 -38.591159) (xy 47.473666 -38.539068) (xy 47.500962 -38.490433)
			(xy 47.535048 -38.44629) (xy 47.575197 -38.407581) (xy 47.620555 -38.37513) (xy 47.670155 -38.349629)
			(xy 47.722939 -38.331622) (xy 47.777782 -38.321492) (xy 47.833516 -38.319455) (xy 47.888953 -38.325555)
			(xy 47.94291 -38.339661) (xy 47.994239 -38.361473) (xy 48.041845 -38.390527) (xy 48.084713 -38.426202)
			(xy 48.12193 -38.467739) (xy 48.152703 -38.514252) (xy 48.176375 -38.564749) (xy 48.192443 -38.618156)
			(xy 48.200563 -38.673332) (xy 48.201072 -38.701218) (xy 48.200563 -38.729104) (xy 48.192443 -38.78428)
			(xy 48.176375 -38.837687) (xy 48.152703 -38.888184) (xy 48.12193 -38.934697) (xy 48.084713 -38.976234)
			(xy 48.041845 -39.011909) (xy 47.994239 -39.040963) (xy 47.94291 -39.062775) (xy 47.888953 -39.076881)
			(xy 47.833516 -39.082981) (xy 47.777782 -39.080944) (xy 47.722939 -39.070814) (xy 47.670155 -39.052807)
			(xy 47.620555 -39.027306) (xy 47.575197 -38.994855) (xy 47.535048 -38.956146) (xy 47.500962 -38.912003)
			(xy 47.473666 -38.863368) (xy 47.453743 -38.811277) (xy 47.441617 -38.75684) (xy 47.437546 -38.701218)
			(xy 44.458997 -38.701218) (xy 44.443502 -38.724639) (xy 44.406285 -38.766176) (xy 44.363417 -38.801851)
			(xy 44.315811 -38.830905) (xy 44.264482 -38.852717) (xy 44.210525 -38.866823) (xy 44.155088 -38.872923)
			(xy 44.099354 -38.870886) (xy 44.044511 -38.860756) (xy 43.991727 -38.842749) (xy 43.942127 -38.817248)
			(xy 43.896769 -38.784797) (xy 43.85662 -38.746088) (xy 43.822534 -38.701945) (xy 43.795238 -38.65331)
			(xy 43.775315 -38.601219) (xy 43.763189 -38.546782) (xy 43.759118 -38.49116) (xy 40.76741 -38.49116)
			(xy 40.752383 -38.52995) (xy 40.713659 -38.607718) (xy 40.667925 -38.681581) (xy 40.61557 -38.75091)
			(xy 40.557042 -38.815112) (xy 40.49284 -38.87364) (xy 40.423511 -38.925995) (xy 40.349648 -38.971729)
			(xy 40.27188 -39.010453) (xy 40.19087 -39.041836) (xy 40.10731 -39.065611) (xy 40.021914 -39.081574)
			(xy 39.935408 -39.08959) (xy 39.89197 -39.090092) (xy 38.03777 -39.090092) (xy 37.994332 -39.089594)
			(xy 37.907826 -39.081578) (xy 37.822429 -39.065615) (xy 37.738869 -39.04184) (xy 37.657859 -39.010457)
			(xy 37.58009 -38.971733) (xy 37.506226 -38.925998) (xy 37.436898 -38.873643) (xy 37.372695 -38.815115)
			(xy 37.314167 -38.750912) (xy 37.261812 -38.681584) (xy 37.216077 -38.60772) (xy 37.177353 -38.529951)
			(xy 37.14597 -38.448941) (xy 37.122195 -38.365381) (xy 37.106232 -38.279984) (xy 37.098216 -38.193478)
			(xy 35.543998 -38.193478) (xy 35.543998 -42.849038) (xy 46.891954 -42.849038) (xy 46.896025 -42.793416)
			(xy 46.908151 -42.738979) (xy 46.928074 -42.686888) (xy 46.95537 -42.638253) (xy 46.989456 -42.59411)
			(xy 47.029605 -42.555401) (xy 47.074963 -42.52295) (xy 47.124563 -42.497449) (xy 47.177347 -42.479442)
			(xy 47.23219 -42.469312) (xy 47.287924 -42.467275) (xy 47.343361 -42.473375) (xy 47.397318 -42.487481)
			(xy 47.448647 -42.509293) (xy 47.496253 -42.538347) (xy 47.539121 -42.574022) (xy 47.576338 -42.615559)
			(xy 47.607111 -42.662072) (xy 47.630783 -42.712569) (xy 47.646851 -42.765976) (xy 47.654971 -42.821152)
			(xy 47.65548 -42.849038) (xy 47.654971 -42.876924) (xy 47.646851 -42.9321) (xy 47.630783 -42.985507)
			(xy 47.607111 -43.036004) (xy 47.576338 -43.082517) (xy 47.539121 -43.124054) (xy 47.496253 -43.159729)
			(xy 47.448647 -43.188783) (xy 47.397318 -43.210595) (xy 47.343361 -43.224701) (xy 47.287924 -43.230801)
			(xy 47.23219 -43.228764) (xy 47.177347 -43.218634) (xy 47.124563 -43.200627) (xy 47.074963 -43.175126)
			(xy 47.029605 -43.142675) (xy 46.989456 -43.103966) (xy 46.95537 -43.059823) (xy 46.928074 -43.011188)
			(xy 46.908151 -42.959097) (xy 46.896025 -42.90466) (xy 46.891954 -42.849038) (xy 35.543998 -42.849038)
			(xy 35.543998 -43.719242) (xy 35.544462 -43.729117) (xy 35.551912 -43.74741) (xy 35.558476 -43.754802)
			(xy 35.55873 -43.755056) (xy 36.036758 -44.233084) (xy 36.037266 -44.233592) (xy 36.04465 -44.240168)
			(xy 36.062948 -44.247608) (xy 36.072826 -44.24807)
		)
		(stroke
			(width 0)
			(type solid)
		)
		(fill yes)
		(layer "B.Cu")
		(net "P12V_SSD1")
	)
	(gr_poly
		(pts
			(xy 420.51478 -44.24807) (xy 420.524954 -44.24762) (xy 420.543701 -44.239707) (xy 420.55789 -44.22512)
			(xy 420.562024 -44.215812) (xy 420.60241 -44.112942) (xy 420.595552 -44.082716) (xy 420.583868 -44.072048)
			(xy 420.561178 -44.0503) (xy 420.521369 -44.001665) (xy 420.488583 -43.948043) (xy 420.463437 -43.890442)
			(xy 420.446403 -43.829944) (xy 420.437802 -43.767685) (xy 420.43731 -43.73626) (xy 420.4378 -43.706292)
			(xy 420.445623 -43.64687) (xy 420.461136 -43.588977) (xy 420.484072 -43.533604) (xy 420.514039 -43.481698)
			(xy 420.550526 -43.434148) (xy 420.592906 -43.391768) (xy 420.640456 -43.355281) (xy 420.692362 -43.325314)
			(xy 420.747735 -43.302378) (xy 420.805628 -43.286865) (xy 420.86505 -43.279042) (xy 420.924986 -43.279042)
			(xy 420.984408 -43.286865) (xy 421.042301 -43.302378) (xy 421.097674 -43.325314) (xy 421.14958 -43.355281)
			(xy 421.19713 -43.391768) (xy 421.23951 -43.434148) (xy 421.275997 -43.481698) (xy 421.305964 -43.533604)
			(xy 421.3289 -43.588977) (xy 421.344413 -43.64687) (xy 421.352236 -43.706292) (xy 421.352726 -43.73626)
			(xy 421.352645 -43.748987) (xy 421.351249 -43.774401) (xy 421.349932 -43.78706) (xy 421.350186 -43.78706)
			(xy 421.345977 -43.819423) (xy 421.32957 -43.882589) (xy 421.304356 -43.942782) (xy 421.270846 -43.998784)
			(xy 421.229721 -44.049456) (xy 421.206168 -44.072048) (xy 421.194738 -44.08297) (xy 421.187626 -44.113196)
			(xy 421.228012 -44.215812) (xy 421.232148 -44.225119) (xy 421.246345 -44.239698) (xy 421.265082 -44.247636)
			(xy 421.275256 -44.24807) (xy 422.177464 -44.24807) (xy 422.187337 -44.247601) (xy 422.205621 -44.240143)
			(xy 422.213024 -44.233592) (xy 422.213278 -44.233338) (xy 422.772586 -43.67403) (xy 422.773094 -43.673522)
			(xy 422.779668 -43.666138) (xy 422.787103 -43.647839) (xy 422.787572 -43.637962) (xy 422.787572 -37.58946)
			(xy 422.787144 -37.580071) (xy 422.7804 -37.562546) (xy 422.767822 -37.548602) (xy 422.759632 -37.543994)
			(xy 422.67886 -37.5031) (xy 422.670252 -37.49925) (xy 422.651504 -37.497401) (xy 422.633342 -37.502407)
			(xy 422.62552 -37.507672) (xy 422.600724 -37.525303) (xy 422.546707 -37.553296) (xy 422.488932 -37.572359)
			(xy 422.428864 -37.582008) (xy 422.398444 -37.582602) (xy 422.37119 -37.582142) (xy 422.317235 -37.57439)
			(xy 422.264932 -37.559038) (xy 422.215348 -37.536398) (xy 422.16949 -37.506932) (xy 422.128292 -37.471239)
			(xy 422.092594 -37.430046) (xy 422.063123 -37.384191) (xy 422.040477 -37.334609) (xy 422.025119 -37.282308)
			(xy 422.017361 -37.228354) (xy 422.017361 -37.173846) (xy 422.025119 -37.119892) (xy 422.040477 -37.067591)
			(xy 422.063123 -37.018009) (xy 422.092594 -36.972154) (xy 422.128292 -36.930961) (xy 422.16949 -36.895268)
			(xy 422.215347 -36.865802) (xy 422.264932 -36.843162) (xy 422.317235 -36.82781) (xy 422.37119 -36.820058)
			(xy 422.398444 -36.819586) (xy 422.428863 -36.820181) (xy 422.488928 -36.82984) (xy 422.5467 -36.848907)
			(xy 422.600715 -36.876898) (xy 422.62552 -36.894516) (xy 422.633298 -36.899882) (xy 422.651487 -36.904951)
			(xy 422.670271 -36.903031) (xy 422.67886 -36.899088) (xy 422.759632 -36.858194) (xy 422.767871 -36.853644)
			(xy 422.780497 -36.839703) (xy 422.787215 -36.822134) (xy 422.787572 -36.812728) (xy 422.787572 -35.109658)
			(xy 422.76903 -35.083496) (xy 422.75379 -35.078162) (xy 422.727519 -35.068317) (xy 422.677959 -35.042025)
			(xy 422.632781 -35.008763) (xy 422.592959 -34.969245) (xy 422.575736 -34.947098) (xy 422.570402 -34.939986)
			(xy 422.548304 -34.925254) (xy 422.544354 -34.922819) (xy 422.535795 -34.919235) (xy 422.531286 -34.918142)
			(xy 422.50106 -34.911284) (xy 422.482264 -34.914078) (xy 422.473882 -34.91865) (xy 422.4555 -34.928876)
			(xy 422.417211 -34.946301) (xy 422.397428 -34.953448) (xy 422.373227 -34.96149) (xy 422.323493 -34.972779)
			(xy 422.272813 -34.978476) (xy 422.247314 -34.978848) (xy 422.221814 -34.978488) (xy 422.171132 -34.972795)
			(xy 422.121397 -34.961503) (xy 422.0972 -34.953448) (xy 422.077415 -34.946304) (xy 422.039126 -34.92888)
			(xy 422.020746 -34.91865) (xy 422.012364 -34.914078) (xy 421.993568 -34.911284) (xy 421.963342 -34.918142)
			(xy 421.958823 -34.919206) (xy 421.950257 -34.922786) (xy 421.946324 -34.925254) (xy 421.923972 -34.94024)
			(xy 421.918892 -34.947352) (xy 421.900742 -34.970654) (xy 421.858464 -35.011897) (xy 421.810333 -35.046128)
			(xy 421.757499 -35.07253) (xy 421.701227 -35.09047) (xy 421.642862 -35.099519) (xy 421.61333 -35.100006)
			(xy 421.602408 -35.100006) (xy 421.602154 -35.099752) (xy 421.575439 -35.098515) (xy 421.522727 -35.089491)
			(xy 421.471791 -35.073196) (xy 421.423629 -35.04995) (xy 421.379184 -35.020206) (xy 421.339328 -34.984549)
			(xy 421.304839 -34.943677) (xy 421.276395 -34.89839) (xy 421.254553 -34.849575) (xy 421.239739 -34.798188)
			(xy 421.232245 -34.745237) (xy 421.231822 -34.718498) (xy 421.232285 -34.691246) (xy 421.240043 -34.637297)
			(xy 421.255399 -34.585001) (xy 421.278042 -34.535423) (xy 421.307511 -34.489572) (xy 421.343205 -34.448382)
			(xy 421.384398 -34.412692) (xy 421.430251 -34.383227) (xy 421.479831 -34.360588) (xy 421.532128 -34.345236)
			(xy 421.586078 -34.337483) (xy 421.61333 -34.33699) (xy 421.628123 -34.337133) (xy 421.65762 -34.339421)
			(xy 421.672258 -34.341562) (xy 421.68318 -34.34334) (xy 421.704516 -34.337244) (xy 421.780208 -34.272728)
			(xy 421.789352 -34.252662) (xy 421.789352 -33.93694) (xy 421.789352 -33.92551) (xy 421.780208 -33.905444)
			(xy 421.704516 -33.840928) (xy 421.68318 -33.834832) (xy 421.672258 -33.83661) (xy 421.657432 -33.838784)
			(xy 421.627552 -33.841075) (xy 421.612568 -33.841182) (xy 421.612314 -33.841182) (xy 421.585109 -33.840629)
			(xy 421.53127 -33.832758) (xy 421.479095 -33.817318) (xy 421.429643 -33.79462) (xy 421.383918 -33.765127)
			(xy 421.342848 -33.729435) (xy 421.307266 -33.68827) (xy 421.277894 -33.642468) (xy 421.255328 -33.592956)
			(xy 421.240026 -33.54074) (xy 421.232298 -33.48688) (xy 421.231822 -33.459674) (xy 421.232287 -33.432423)
			(xy 421.240047 -33.378477) (xy 421.255406 -33.326184) (xy 421.27805 -33.276609) (xy 421.307519 -33.230761)
			(xy 421.343214 -33.189574) (xy 421.384406 -33.153886) (xy 421.430258 -33.124423) (xy 421.479836 -33.101786)
			(xy 421.532131 -33.086435) (xy 421.586079 -33.078683) (xy 421.61333 -33.078166) (xy 421.613584 -33.078166)
			(xy 421.643089 -33.078723) (xy 421.701394 -33.087816) (xy 421.757606 -33.105774) (xy 421.810384 -33.132168)
			(xy 421.858473 -33.16637) (xy 421.900725 -33.207564) (xy 421.918892 -33.23082) (xy 421.923972 -33.237932)
			(xy 421.946324 -33.252918) (xy 421.950275 -33.255351) (xy 421.958834 -33.258933) (xy 421.963342 -33.26003)
			(xy 421.993568 -33.266888) (xy 422.012364 -33.264094) (xy 422.020746 -33.259522) (xy 422.039129 -33.249298)
			(xy 422.077418 -33.231876) (xy 422.0972 -33.224724) (xy 422.1214 -33.216679) (xy 422.171134 -33.205383)
			(xy 422.221814 -33.199678) (xy 422.247314 -33.199324) (xy 422.272814 -33.199686) (xy 422.323495 -33.205381)
			(xy 422.373229 -33.216676) (xy 422.397428 -33.224724) (xy 422.417212 -33.231869) (xy 422.455501 -33.249294)
			(xy 422.473882 -33.259522) (xy 422.482264 -33.264094) (xy 422.50106 -33.266888) (xy 422.531286 -33.26003)
			(xy 422.535804 -33.258963) (xy 422.544366 -33.255377) (xy 422.548304 -33.252918) (xy 422.570402 -33.238186)
			(xy 422.575736 -33.231074) (xy 422.592938 -33.208909) (xy 422.632764 -33.169392) (xy 422.677949 -33.136135)
			(xy 422.727517 -33.109854) (xy 422.75379 -33.10001) (xy 422.76903 -33.094676) (xy 422.787572 -33.068514)
			(xy 422.787572 -31.509462) (xy 422.76903 -31.4833) (xy 422.75379 -31.477966) (xy 422.727518 -31.468122)
			(xy 422.677959 -31.44183) (xy 422.632781 -31.408567) (xy 422.592958 -31.36905) (xy 422.575736 -31.346902)
			(xy 422.570402 -31.33979) (xy 422.548304 -31.325058) (xy 422.544354 -31.322624) (xy 422.535795 -31.319039)
			(xy 422.531286 -31.317946) (xy 422.50106 -31.311088) (xy 422.482264 -31.313882) (xy 422.473882 -31.318454)
			(xy 422.4555 -31.328679) (xy 422.417211 -31.346105) (xy 422.397428 -31.353252) (xy 422.373227 -31.361294)
			(xy 422.323493 -31.372583) (xy 422.272813 -31.37828) (xy 422.247314 -31.378652) (xy 422.221814 -31.378292)
			(xy 422.171132 -31.372599) (xy 422.121397 -31.361307) (xy 422.0972 -31.353252) (xy 422.077415 -31.346108)
			(xy 422.039126 -31.328684) (xy 422.020746 -31.318454) (xy 422.012364 -31.313882) (xy 421.993568 -31.311088)
			(xy 421.963342 -31.317946) (xy 421.958823 -31.31901) (xy 421.950257 -31.32259) (xy 421.946324 -31.325058)
			(xy 421.923972 -31.340044) (xy 421.918892 -31.347156) (xy 421.900742 -31.370458) (xy 421.858464 -31.4117)
			(xy 421.810332 -31.445931) (xy 421.757499 -31.472333) (xy 421.701227 -31.490272) (xy 421.642862 -31.499322)
			(xy 421.61333 -31.49981) (xy 421.602408 -31.49981) (xy 421.602154 -31.499556) (xy 421.575439 -31.498319)
			(xy 421.522727 -31.489295) (xy 421.471791 -31.473) (xy 421.423628 -31.449754) (xy 421.379183 -31.420011)
			(xy 421.339326 -31.384354) (xy 421.304838 -31.343481) (xy 421.276393 -31.298194) (xy 421.25455 -31.249379)
			(xy 421.239736 -31.197993) (xy 421.232242 -31.145041) (xy 421.231822 -31.118302) (xy 421.232285 -31.09105)
			(xy 421.240042 -31.0371) (xy 421.255398 -30.984804) (xy 421.278041 -30.935225) (xy 421.30751 -30.889374)
			(xy 421.343204 -30.848184) (xy 421.384397 -30.812493) (xy 421.43025 -30.783028) (xy 421.47983 -30.760388)
			(xy 421.532128 -30.745036) (xy 421.586078 -30.737283) (xy 421.61333 -30.736794) (xy 421.628123 -30.736937)
			(xy 421.65762 -30.739225) (xy 421.672258 -30.741366) (xy 421.68318 -30.743144) (xy 421.704516 -30.737048)
			(xy 421.780208 -30.672532) (xy 421.789352 -30.652466) (xy 421.789352 -30.336744) (xy 421.789352 -30.325314)
			(xy 421.780208 -30.305248) (xy 421.704516 -30.240732) (xy 421.68318 -30.234636) (xy 421.672258 -30.236414)
			(xy 421.657432 -30.238588) (xy 421.627552 -30.240879) (xy 421.612568 -30.240986) (xy 421.612314 -30.240986)
			(xy 421.585109 -30.240433) (xy 421.53127 -30.232562) (xy 421.479094 -30.217122) (xy 421.429643 -30.194424)
			(xy 421.383917 -30.164931) (xy 421.342847 -30.12924) (xy 421.307264 -30.088075) (xy 421.277892 -30.042272)
			(xy 421.255325 -29.99276) (xy 421.240022 -29.940544) (xy 421.232294 -29.886684) (xy 421.231822 -29.859478)
			(xy 421.232287 -29.832227) (xy 421.240047 -29.77828) (xy 421.255405 -29.725987) (xy 421.278049 -29.676411)
			(xy 421.307518 -29.630563) (xy 421.343212 -29.589375) (xy 421.384405 -29.553687) (xy 421.430257 -29.524224)
			(xy 421.479835 -29.501587) (xy 421.532131 -29.486235) (xy 421.586079 -29.478483) (xy 421.61333 -29.47797)
			(xy 421.613584 -29.47797) (xy 421.643089 -29.478527) (xy 421.701394 -29.48762) (xy 421.757606 -29.505578)
			(xy 421.810384 -29.531973) (xy 421.858472 -29.566174) (xy 421.900724 -29.607369) (xy 421.918892 -29.630624)
			(xy 421.923972 -29.637736) (xy 421.946324 -29.652722) (xy 421.950275 -29.655155) (xy 421.958834 -29.658736)
			(xy 421.963342 -29.659834) (xy 421.993568 -29.666692) (xy 422.012364 -29.663898) (xy 422.020746 -29.659326)
			(xy 422.039129 -29.649102) (xy 422.077418 -29.63168) (xy 422.0972 -29.624528) (xy 422.1214 -29.616483)
			(xy 422.171134 -29.605186) (xy 422.221814 -29.599481) (xy 422.247314 -29.599128) (xy 422.272814 -29.59949)
			(xy 422.323495 -29.605185) (xy 422.373229 -29.61648) (xy 422.397428 -29.624528) (xy 422.417212 -29.631673)
			(xy 422.455501 -29.649098) (xy 422.473882 -29.659326) (xy 422.482264 -29.663898) (xy 422.50106 -29.666692)
			(xy 422.531286 -29.659834) (xy 422.535804 -29.658767) (xy 422.544366 -29.655182) (xy 422.548304 -29.652722)
			(xy 422.570402 -29.63799) (xy 422.575736 -29.630878) (xy 422.592938 -29.608713) (xy 422.632764 -29.569196)
			(xy 422.677948 -29.535938) (xy 422.727516 -29.509657) (xy 422.75379 -29.499814) (xy 422.76903 -29.49448)
			(xy 422.787572 -29.468318) (xy 422.787572 -19.837908) (xy 422.787363 -19.831327) (xy 422.784022 -19.818595)
			(xy 422.780968 -19.812762) (xy 422.765728 -19.786346) (xy 422.7576 -19.77771) (xy 422.752266 -19.774154)
			(xy 422.730465 -19.759653) (xy 422.690676 -19.725618) (xy 422.655913 -19.686465) (xy 422.641014 -19.664934)
			(xy 422.64076 -19.66468) (xy 422.64076 -19.664426) (xy 422.63447 -19.656132) (xy 422.616907 -19.644995)
			(xy 422.606724 -19.642836) (xy 422.533318 -19.631152) (xy 422.522956 -19.629981) (xy 422.502763 -19.635102)
			(xy 422.494202 -19.641058) (xy 422.474044 -19.656163) (xy 422.430511 -19.681509) (xy 422.384025 -19.700912)
			(xy 422.335391 -19.714036) (xy 422.285455 -19.720653) (xy 422.260268 -19.721068) (xy 422.252648 -19.721068)
			(xy 422.225752 -19.720073) (xy 422.172627 -19.711454) (xy 422.12124 -19.695454) (xy 422.072613 -19.672388)
			(xy 422.027711 -19.642717) (xy 421.987425 -19.607028) (xy 421.952557 -19.566031) (xy 421.923797 -19.52054)
			(xy 421.901717 -19.471457) (xy 421.886755 -19.419759) (xy 421.87921 -19.36647) (xy 421.87876 -19.33956)
			(xy 421.879248 -19.31231) (xy 421.887009 -19.258365) (xy 421.902368 -19.206073) (xy 421.925011 -19.156499)
			(xy 421.954478 -19.110651) (xy 421.990169 -19.069463) (xy 422.031357 -19.033773) (xy 422.077206 -19.004307)
			(xy 422.12678 -18.981665) (xy 422.179073 -18.966308) (xy 422.233018 -18.958548) (xy 422.260268 -18.958052)
			(xy 422.264332 -18.958052) (xy 422.279572 -18.958306) (xy 422.305734 -18.941288) (xy 422.348152 -18.840196)
			(xy 422.351703 -18.830751) (xy 422.351812 -18.81059) (xy 422.344095 -18.791964) (xy 422.33723 -18.78457)
			(xy 421.967914 -18.415254) (xy 421.960802 -18.407888) (xy 421.942006 -18.400268) (xy 410.229304 -18.400268)
			(xy 410.219233 -18.40069) (xy 410.200624 -18.408399) (xy 410.193236 -18.415254) (xy 409.858972 -18.749518)
			(xy 409.851606 -18.75663) (xy 409.843986 -18.775426) (xy 409.843986 -21.738336) (xy 411.716728 -21.738336)
			(xy 411.717232 -21.709597) (xy 411.725862 -21.652769) (xy 411.742918 -21.597879) (xy 411.768014 -21.546168)
			(xy 411.800581 -21.498805) (xy 411.819852 -21.477478) (xy 411.826456 -21.470366) (xy 411.833568 -21.45284)
			(xy 411.833568 -21.363432) (xy 411.826456 -21.345906) (xy 411.819852 -21.338794) (xy 411.800616 -21.317437)
			(xy 411.768047 -21.27008) (xy 411.742951 -21.218374) (xy 411.725897 -21.163487) (xy 411.717271 -21.106664)
			(xy 411.717267 -21.049189) (xy 411.725886 -20.992364) (xy 411.742932 -20.937475) (xy 411.76802 -20.885765)
			(xy 411.800583 -20.838404) (xy 411.819852 -20.817078) (xy 411.826456 -20.809966) (xy 411.833568 -20.79244)
			(xy 411.833568 -20.703032) (xy 411.826456 -20.685506) (xy 411.819852 -20.678394) (xy 411.800616 -20.657037)
			(xy 411.768047 -20.60968) (xy 411.742951 -20.557974) (xy 411.725897 -20.503087) (xy 411.717271 -20.446264)
			(xy 411.717267 -20.388789) (xy 411.725886 -20.331964) (xy 411.742932 -20.277075) (xy 411.76802 -20.225365)
			(xy 411.800583 -20.178004) (xy 411.819852 -20.156678) (xy 411.826456 -20.149566) (xy 411.833568 -20.13204)
			(xy 411.833568 -20.042632) (xy 411.826456 -20.025106) (xy 411.819852 -20.017994) (xy 411.800616 -19.996637)
			(xy 411.768047 -19.94928) (xy 411.742951 -19.897574) (xy 411.725897 -19.842687) (xy 411.717271 -19.785864)
			(xy 411.717267 -19.728389) (xy 411.725886 -19.671564) (xy 411.742932 -19.616675) (xy 411.76802 -19.564965)
			(xy 411.800583 -19.517604) (xy 411.819852 -19.496278) (xy 411.826456 -19.489166) (xy 411.833568 -19.47164)
			(xy 411.833568 -19.382232) (xy 411.826456 -19.364706) (xy 411.819852 -19.357594) (xy 411.800601 -19.33625)
			(xy 411.768031 -19.288893) (xy 411.742935 -19.237186) (xy 411.72588 -19.182298) (xy 411.717252 -19.125474)
			(xy 411.716728 -19.096736) (xy 411.717214 -19.069485) (xy 411.72497 -19.015537) (xy 411.740325 -18.963242)
			(xy 411.762967 -18.913665) (xy 411.792433 -18.867815) (xy 411.828124 -18.826624) (xy 411.869315 -18.790933)
			(xy 411.915165 -18.761467) (xy 411.964742 -18.738825) (xy 412.017037 -18.72347) (xy 412.070985 -18.715714)
			(xy 412.125487 -18.715714) (xy 412.179435 -18.72347) (xy 412.23173 -18.738825) (xy 412.281307 -18.761467)
			(xy 412.327157 -18.790933) (xy 412.368348 -18.826624) (xy 412.404039 -18.867815) (xy 412.433505 -18.913665)
			(xy 412.456147 -18.963242) (xy 412.471502 -19.015537) (xy 412.479258 -19.069485) (xy 412.479744 -19.096736)
			(xy 412.47923 -19.125475) (xy 412.470604 -19.182302) (xy 412.45355 -19.237193) (xy 412.428457 -19.288904)
			(xy 412.395891 -19.336267) (xy 412.37662 -19.357594) (xy 412.370016 -19.364706) (xy 412.362904 -19.382232)
			(xy 412.362904 -19.47164) (xy 412.370016 -19.489166) (xy 412.37662 -19.496278) (xy 412.395924 -19.517575)
			(xy 412.428485 -19.564944) (xy 412.453572 -19.616661) (xy 412.470617 -19.671556) (xy 412.479235 -19.728386)
			(xy 412.479231 -19.785866) (xy 412.470605 -19.842696) (xy 412.453552 -19.897588) (xy 412.428458 -19.949302)
			(xy 412.395892 -19.996666) (xy 412.37662 -20.017994) (xy 412.370016 -20.025106) (xy 412.362904 -20.042632)
			(xy 412.362904 -20.13204) (xy 412.370016 -20.149566) (xy 412.37662 -20.156678) (xy 412.395924 -20.177975)
			(xy 412.428485 -20.225344) (xy 412.453572 -20.277061) (xy 412.470617 -20.331956) (xy 412.474196 -20.35556)
			(xy 421.87825 -20.35556) (xy 421.882321 -20.299938) (xy 421.894447 -20.245501) (xy 421.91437 -20.19341)
			(xy 421.941666 -20.144775) (xy 421.975752 -20.100632) (xy 422.015901 -20.061923) (xy 422.061259 -20.029472)
			(xy 422.110859 -20.003971) (xy 422.163643 -19.985964) (xy 422.218486 -19.975834) (xy 422.27422 -19.973797)
			(xy 422.329657 -19.979897) (xy 422.383614 -19.994003) (xy 422.434943 -20.015815) (xy 422.482549 -20.044869)
			(xy 422.525417 -20.080544) (xy 422.562634 -20.122081) (xy 422.593407 -20.168594) (xy 422.617079 -20.219091)
			(xy 422.633147 -20.272498) (xy 422.641267 -20.327674) (xy 422.641776 -20.35556) (xy 422.641267 -20.383446)
			(xy 422.633147 -20.438622) (xy 422.617079 -20.492029) (xy 422.593407 -20.542526) (xy 422.562634 -20.589039)
			(xy 422.525417 -20.630576) (xy 422.482549 -20.666251) (xy 422.434943 -20.695305) (xy 422.383614 -20.717117)
			(xy 422.329657 -20.731223) (xy 422.27422 -20.737323) (xy 422.218486 -20.735286) (xy 422.163643 -20.725156)
			(xy 422.110859 -20.707149) (xy 422.061259 -20.681648) (xy 422.015901 -20.649197) (xy 421.975752 -20.610488)
			(xy 421.941666 -20.566345) (xy 421.91437 -20.51771) (xy 421.894447 -20.465619) (xy 421.882321 -20.411182)
			(xy 421.87825 -20.35556) (xy 412.474196 -20.35556) (xy 412.479235 -20.388786) (xy 412.479231 -20.446266)
			(xy 412.470605 -20.503096) (xy 412.453552 -20.557988) (xy 412.428458 -20.609702) (xy 412.395892 -20.657066)
			(xy 412.37662 -20.678394) (xy 412.370016 -20.685506) (xy 412.362904 -20.703032) (xy 412.362904 -20.79244)
			(xy 412.370016 -20.809966) (xy 412.37662 -20.817078) (xy 412.395924 -20.838375) (xy 412.428485 -20.885744)
			(xy 412.453572 -20.937461) (xy 412.470617 -20.992356) (xy 412.479235 -21.049186) (xy 412.479231 -21.106666)
			(xy 412.470605 -21.163496) (xy 412.453552 -21.218388) (xy 412.428458 -21.270102) (xy 412.395892 -21.317466)
			(xy 412.37662 -21.338794) (xy 412.370016 -21.345906) (xy 412.362904 -21.363432) (xy 412.362904 -21.37156)
			(xy 421.87825 -21.37156) (xy 421.882321 -21.315938) (xy 421.894447 -21.261501) (xy 421.91437 -21.20941)
			(xy 421.941666 -21.160775) (xy 421.975752 -21.116632) (xy 422.015901 -21.077923) (xy 422.061259 -21.045472)
			(xy 422.110859 -21.019971) (xy 422.163643 -21.001964) (xy 422.218486 -20.991834) (xy 422.27422 -20.989797)
			(xy 422.329657 -20.995897) (xy 422.383614 -21.010003) (xy 422.434943 -21.031815) (xy 422.482549 -21.060869)
			(xy 422.525417 -21.096544) (xy 422.562634 -21.138081) (xy 422.593407 -21.184594) (xy 422.617079 -21.235091)
			(xy 422.633147 -21.288498) (xy 422.641267 -21.343674) (xy 422.641776 -21.37156) (xy 422.641267 -21.399446)
			(xy 422.633147 -21.454622) (xy 422.617079 -21.508029) (xy 422.593407 -21.558526) (xy 422.562634 -21.605039)
			(xy 422.525417 -21.646576) (xy 422.482549 -21.682251) (xy 422.434943 -21.711305) (xy 422.383614 -21.733117)
			(xy 422.329657 -21.747223) (xy 422.27422 -21.753323) (xy 422.218486 -21.751286) (xy 422.163643 -21.741156)
			(xy 422.110859 -21.723149) (xy 422.061259 -21.697648) (xy 422.015901 -21.665197) (xy 421.975752 -21.626488)
			(xy 421.941666 -21.582345) (xy 421.91437 -21.53371) (xy 421.894447 -21.481619) (xy 421.882321 -21.427182)
			(xy 421.87825 -21.37156) (xy 412.362904 -21.37156) (xy 412.362904 -21.45284) (xy 412.370016 -21.470366)
			(xy 412.37662 -21.477478) (xy 412.395901 -21.498796) (xy 412.428467 -21.54616) (xy 412.453559 -21.597874)
			(xy 412.470607 -21.652767) (xy 412.479226 -21.709596) (xy 412.479744 -21.738336) (xy 412.479258 -21.765587)
			(xy 412.471502 -21.819535) (xy 412.456147 -21.87183) (xy 412.433505 -21.921407) (xy 412.404039 -21.967257)
			(xy 412.368348 -22.008448) (xy 412.327157 -22.044139) (xy 412.281307 -22.073605) (xy 412.23173 -22.096247)
			(xy 412.179435 -22.111602) (xy 412.125487 -22.119358) (xy 412.070985 -22.119358) (xy 412.017037 -22.111602)
			(xy 411.964742 -22.096247) (xy 411.915165 -22.073605) (xy 411.869315 -22.044139) (xy 411.828124 -22.008448)
			(xy 411.792433 -21.967257) (xy 411.762967 -21.921407) (xy 411.740325 -21.87183) (xy 411.72497 -21.819535)
			(xy 411.717214 -21.765587) (xy 411.716728 -21.738336) (xy 409.843986 -21.738336) (xy 409.843986 -23.055059)
			(xy 411.587193 -23.055059) (xy 411.587195 -22.995125) (xy 411.595018 -22.935705) (xy 411.610531 -22.877814)
			(xy 411.633468 -22.822443) (xy 411.663435 -22.77054) (xy 411.699921 -22.722992) (xy 411.742301 -22.680613)
			(xy 411.78985 -22.644128) (xy 411.841754 -22.614162) (xy 411.897125 -22.591227) (xy 411.955017 -22.575716)
			(xy 412.014437 -22.567894) (xy 412.074371 -22.567894) (xy 412.133791 -22.575718) (xy 412.191682 -22.59123)
			(xy 412.247053 -22.614166) (xy 412.298957 -22.644133) (xy 412.346505 -22.680618) (xy 412.388884 -22.722998)
			(xy 412.425369 -22.770546) (xy 412.455336 -22.82245) (xy 412.478271 -22.877821) (xy 412.493783 -22.935713)
			(xy 412.501606 -22.995133) (xy 412.502096 -23.0251) (xy 412.501872 -23.045661) (xy 412.498183 -23.086618)
			(xy 412.49473 -23.106888) (xy 412.49219 -23.120604) (xy 412.50108 -23.145496) (xy 412.587694 -23.22068)
			(xy 412.613602 -23.226014) (xy 412.62681 -23.221696) (xy 412.656011 -23.212604) (xy 412.716374 -23.202783)
			(xy 412.746952 -23.202138) (xy 412.765879 -23.2024) (xy 412.803541 -23.206217) (xy 412.822136 -23.209758)
			(xy 412.834836 -23.212044) (xy 412.858458 -23.205186) (xy 412.936944 -23.128986) (xy 412.944564 -23.105618)
			(xy 412.942532 -23.092918) (xy 412.939472 -23.073888) (xy 412.936161 -23.035483) (xy 412.935928 -23.01621)
			(xy 412.936371 -22.986242) (xy 412.944193 -22.926819) (xy 412.959704 -22.868925) (xy 412.982639 -22.813551)
			(xy 413.012606 -22.761644) (xy 413.049091 -22.714092) (xy 413.091471 -22.67171) (xy 413.13902 -22.635222)
			(xy 413.190925 -22.605252) (xy 413.246298 -22.582314) (xy 413.304191 -22.566799) (xy 413.363613 -22.558973)
			(xy 413.423549 -22.558971) (xy 413.482973 -22.566791) (xy 413.540867 -22.582302) (xy 413.596242 -22.605235)
			(xy 413.648149 -22.635201) (xy 413.695701 -22.671685) (xy 413.738084 -22.714064) (xy 413.774573 -22.761613)
			(xy 413.804544 -22.813517) (xy 413.827484 -22.868889) (xy 413.843 -22.926782) (xy 413.850826 -22.986205)
			(xy 413.85083 -23.046141) (xy 413.84301 -23.105564) (xy 413.827501 -23.163459) (xy 413.804568 -23.218834)
			(xy 413.774604 -23.270742) (xy 413.73812 -23.318295) (xy 413.695742 -23.360679) (xy 413.648195 -23.397169)
			(xy 413.596291 -23.42714) (xy 413.540919 -23.450081) (xy 413.483026 -23.465598) (xy 413.423604 -23.473426)
			(xy 413.393636 -23.473918) (xy 413.359391 -23.473313) (xy 413.291665 -23.463109) (xy 413.258762 -23.453598)
			(xy 413.24657 -23.449788) (xy 413.22244 -23.45436) (xy 413.136588 -23.522178) (xy 413.126682 -23.544784)
			(xy 413.127698 -23.557738) (xy 413.12846 -23.583646) (xy 413.127974 -23.610897) (xy 413.12667 -23.619964)
			(xy 416.309284 -23.619964) (xy 416.309284 -23.560028) (xy 416.317107 -23.500606) (xy 416.33262 -23.442713)
			(xy 416.355556 -23.38734) (xy 416.385523 -23.335434) (xy 416.42201 -23.287884) (xy 416.46439 -23.245504)
			(xy 416.51194 -23.209017) (xy 416.563846 -23.17905) (xy 416.619219 -23.156114) (xy 416.677112 -23.140601)
			(xy 416.736534 -23.132778) (xy 416.79647 -23.132778) (xy 416.855892 -23.140601) (xy 416.913785 -23.156114)
			(xy 416.969158 -23.17905) (xy 417.021064 -23.209017) (xy 417.068614 -23.245504) (xy 417.110994 -23.287884)
			(xy 417.147481 -23.335434) (xy 417.177448 -23.38734) (xy 417.200384 -23.442713) (xy 417.215897 -23.500606)
			(xy 417.22372 -23.560028) (xy 417.22421 -23.589996) (xy 417.22372 -23.619964) (xy 417.215897 -23.679386)
			(xy 417.200384 -23.737279) (xy 417.177448 -23.792652) (xy 417.147481 -23.844558) (xy 417.120041 -23.880318)
			(xy 417.540692 -23.880318) (xy 417.544763 -23.824696) (xy 417.556889 -23.770259) (xy 417.576812 -23.718168)
			(xy 417.604108 -23.669533) (xy 417.638194 -23.62539) (xy 417.678343 -23.586681) (xy 417.723701 -23.55423)
			(xy 417.773301 -23.528729) (xy 417.826085 -23.510722) (xy 417.880928 -23.500592) (xy 417.936662 -23.498555)
			(xy 417.992099 -23.504655) (xy 418.046056 -23.518761) (xy 418.097385 -23.540573) (xy 418.144991 -23.569627)
			(xy 418.187859 -23.605302) (xy 418.225076 -23.646839) (xy 418.255849 -23.693352) (xy 418.279521 -23.743849)
			(xy 418.295589 -23.797256) (xy 418.303709 -23.852432) (xy 418.304218 -23.880318) (xy 418.556692 -23.880318)
			(xy 418.560763 -23.824696) (xy 418.572889 -23.770259) (xy 418.592812 -23.718168) (xy 418.620108 -23.669533)
			(xy 418.654194 -23.62539) (xy 418.694343 -23.586681) (xy 418.739701 -23.55423) (xy 418.789301 -23.528729)
			(xy 418.842085 -23.510722) (xy 418.896928 -23.500592) (xy 418.952662 -23.498555) (xy 419.008099 -23.504655)
			(xy 419.062056 -23.518761) (xy 419.113385 -23.540573) (xy 419.160991 -23.569627) (xy 419.203859 -23.605302)
			(xy 419.241076 -23.646839) (xy 419.271849 -23.693352) (xy 419.295521 -23.743849) (xy 419.311589 -23.797256)
			(xy 419.319709 -23.852432) (xy 419.320218 -23.880318) (xy 419.572692 -23.880318) (xy 419.576763 -23.824696)
			(xy 419.588889 -23.770259) (xy 419.608812 -23.718168) (xy 419.636108 -23.669533) (xy 419.670194 -23.62539)
			(xy 419.710343 -23.586681) (xy 419.755701 -23.55423) (xy 419.805301 -23.528729) (xy 419.858085 -23.510722)
			(xy 419.912928 -23.500592) (xy 419.968662 -23.498555) (xy 420.024099 -23.504655) (xy 420.078056 -23.518761)
			(xy 420.129385 -23.540573) (xy 420.176991 -23.569627) (xy 420.219859 -23.605302) (xy 420.257076 -23.646839)
			(xy 420.287849 -23.693352) (xy 420.311521 -23.743849) (xy 420.327589 -23.797256) (xy 420.335709 -23.852432)
			(xy 420.336218 -23.880318) (xy 420.590978 -23.880318) (xy 420.595049 -23.824696) (xy 420.607175 -23.770259)
			(xy 420.627098 -23.718168) (xy 420.654394 -23.669533) (xy 420.68848 -23.62539) (xy 420.728629 -23.586681)
			(xy 420.773987 -23.55423) (xy 420.823587 -23.528729) (xy 420.876371 -23.510722) (xy 420.931214 -23.500592)
			(xy 420.986948 -23.498555) (xy 421.042385 -23.504655) (xy 421.096342 -23.518761) (xy 421.147671 -23.540573)
			(xy 421.195277 -23.569627) (xy 421.238145 -23.605302) (xy 421.275362 -23.646839) (xy 421.306135 -23.693352)
			(xy 421.329807 -23.743849) (xy 421.345875 -23.797256) (xy 421.353995 -23.852432) (xy 421.354504 -23.880318)
			(xy 421.353995 -23.908204) (xy 421.345875 -23.96338) (xy 421.329807 -24.016787) (xy 421.306135 -24.067284)
			(xy 421.275362 -24.113797) (xy 421.238145 -24.155334) (xy 421.195277 -24.191009) (xy 421.147671 -24.220063)
			(xy 421.096342 -24.241875) (xy 421.042385 -24.255981) (xy 420.986948 -24.262081) (xy 420.931214 -24.260044)
			(xy 420.876371 -24.249914) (xy 420.823587 -24.231907) (xy 420.773987 -24.206406) (xy 420.728629 -24.173955)
			(xy 420.68848 -24.135246) (xy 420.654394 -24.091103) (xy 420.627098 -24.042468) (xy 420.607175 -23.990377)
			(xy 420.595049 -23.93594) (xy 420.590978 -23.880318) (xy 420.336218 -23.880318) (xy 420.335709 -23.908204)
			(xy 420.327589 -23.96338) (xy 420.311521 -24.016787) (xy 420.287849 -24.067284) (xy 420.257076 -24.113797)
			(xy 420.219859 -24.155334) (xy 420.176991 -24.191009) (xy 420.129385 -24.220063) (xy 420.078056 -24.241875)
			(xy 420.024099 -24.255981) (xy 419.968662 -24.262081) (xy 419.912928 -24.260044) (xy 419.858085 -24.249914)
			(xy 419.805301 -24.231907) (xy 419.755701 -24.206406) (xy 419.710343 -24.173955) (xy 419.670194 -24.135246)
			(xy 419.636108 -24.091103) (xy 419.608812 -24.042468) (xy 419.588889 -23.990377) (xy 419.576763 -23.93594)
			(xy 419.572692 -23.880318) (xy 419.320218 -23.880318) (xy 419.319709 -23.908204) (xy 419.311589 -23.96338)
			(xy 419.295521 -24.016787) (xy 419.271849 -24.067284) (xy 419.241076 -24.113797) (xy 419.203859 -24.155334)
			(xy 419.160991 -24.191009) (xy 419.113385 -24.220063) (xy 419.062056 -24.241875) (xy 419.008099 -24.255981)
			(xy 418.952662 -24.262081) (xy 418.896928 -24.260044) (xy 418.842085 -24.249914) (xy 418.789301 -24.231907)
			(xy 418.739701 -24.206406) (xy 418.694343 -24.173955) (xy 418.654194 -24.135246) (xy 418.620108 -24.091103)
			(xy 418.592812 -24.042468) (xy 418.572889 -23.990377) (xy 418.560763 -23.93594) (xy 418.556692 -23.880318)
			(xy 418.304218 -23.880318) (xy 418.303709 -23.908204) (xy 418.295589 -23.96338) (xy 418.279521 -24.016787)
			(xy 418.255849 -24.067284) (xy 418.225076 -24.113797) (xy 418.187859 -24.155334) (xy 418.144991 -24.191009)
			(xy 418.097385 -24.220063) (xy 418.046056 -24.241875) (xy 417.992099 -24.255981) (xy 417.936662 -24.262081)
			(xy 417.880928 -24.260044) (xy 417.826085 -24.249914) (xy 417.773301 -24.231907) (xy 417.723701 -24.206406)
			(xy 417.678343 -24.173955) (xy 417.638194 -24.135246) (xy 417.604108 -24.091103) (xy 417.576812 -24.042468)
			(xy 417.556889 -23.990377) (xy 417.544763 -23.93594) (xy 417.540692 -23.880318) (xy 417.120041 -23.880318)
			(xy 417.110994 -23.892108) (xy 417.068614 -23.934488) (xy 417.021064 -23.970975) (xy 416.969158 -24.000942)
			(xy 416.913785 -24.023878) (xy 416.855892 -24.039391) (xy 416.79647 -24.047214) (xy 416.736534 -24.047214)
			(xy 416.677112 -24.039391) (xy 416.619219 -24.023878) (xy 416.563846 -24.000942) (xy 416.51194 -23.970975)
			(xy 416.46439 -23.934488) (xy 416.42201 -23.892108) (xy 416.385523 -23.844558) (xy 416.355556 -23.792652)
			(xy 416.33262 -23.737279) (xy 416.317107 -23.679386) (xy 416.309284 -23.619964) (xy 413.12667 -23.619964)
			(xy 413.120218 -23.664845) (xy 413.104863 -23.71714) (xy 413.082221 -23.766717) (xy 413.052755 -23.812567)
			(xy 413.017064 -23.853758) (xy 412.975873 -23.889449) (xy 412.930023 -23.918915) (xy 412.880446 -23.941557)
			(xy 412.828151 -23.956912) (xy 412.774203 -23.964668) (xy 412.719701 -23.964668) (xy 412.665753 -23.956912)
			(xy 412.613458 -23.941557) (xy 412.563881 -23.918915) (xy 412.518031 -23.889449) (xy 412.47684 -23.853758)
			(xy 412.441149 -23.812567) (xy 412.411683 -23.766717) (xy 412.389041 -23.71714) (xy 412.373686 -23.664845)
			(xy 412.36593 -23.610897) (xy 412.365444 -23.583646) (xy 412.367222 -23.548086) (xy 412.368492 -23.53437)
			(xy 412.35757 -23.51024) (xy 412.264606 -23.44293) (xy 412.23819 -23.439882) (xy 412.225744 -23.44547)
			(xy 412.196984 -23.457282) (xy 412.13708 -23.473921) (xy 412.075475 -23.482302) (xy 412.044388 -23.482808)
			(xy 412.014421 -23.482305) (xy 411.955001 -23.474481) (xy 411.89711 -23.458967) (xy 411.841739 -23.436031)
			(xy 411.789836 -23.406063) (xy 411.742289 -23.369577) (xy 411.69991 -23.327196) (xy 411.663426 -23.279647)
			(xy 411.633461 -23.227743) (xy 411.610526 -23.172371) (xy 411.595015 -23.11448) (xy 411.587193 -23.055059)
			(xy 409.843986 -23.055059) (xy 409.843986 -24.189944) (xy 411.59887 -24.189944) (xy 411.602941 -24.134322)
			(xy 411.615067 -24.079885) (xy 411.63499 -24.027794) (xy 411.662286 -23.979159) (xy 411.696372 -23.935016)
			(xy 411.736521 -23.896307) (xy 411.781879 -23.863856) (xy 411.831479 -23.838355) (xy 411.884263 -23.820348)
			(xy 411.939106 -23.810218) (xy 411.99484 -23.808181) (xy 412.050277 -23.814281) (xy 412.104234 -23.828387)
			(xy 412.155563 -23.850199) (xy 412.203169 -23.879253) (xy 412.246037 -23.914928) (xy 412.283254 -23.956465)
			(xy 412.314027 -24.002978) (xy 412.337699 -24.053475) (xy 412.353767 -24.106882) (xy 412.361887 -24.162058)
			(xy 412.362396 -24.189944) (xy 414.121852 -24.189944) (xy 414.125923 -24.134322) (xy 414.138049 -24.079885)
			(xy 414.157972 -24.027794) (xy 414.185268 -23.979159) (xy 414.219354 -23.935016) (xy 414.259503 -23.896307)
			(xy 414.304861 -23.863856) (xy 414.354461 -23.838355) (xy 414.407245 -23.820348) (xy 414.462088 -23.810218)
			(xy 414.517822 -23.808181) (xy 414.573259 -23.814281) (xy 414.627216 -23.828387) (xy 414.678545 -23.850199)
			(xy 414.726151 -23.879253) (xy 414.769019 -23.914928) (xy 414.806236 -23.956465) (xy 414.837009 -24.002978)
			(xy 414.860681 -24.053475) (xy 414.876749 -24.106882) (xy 414.884869 -24.162058) (xy 414.885378 -24.189944)
			(xy 414.884869 -24.21783) (xy 414.876749 -24.273006) (xy 414.860681 -24.326413) (xy 414.837009 -24.37691)
			(xy 414.806236 -24.423423) (xy 414.769019 -24.46496) (xy 414.726151 -24.500635) (xy 414.678545 -24.529689)
			(xy 414.627216 -24.551501) (xy 414.573259 -24.565607) (xy 414.517822 -24.571707) (xy 414.462088 -24.56967)
			(xy 414.407245 -24.55954) (xy 414.354461 -24.541533) (xy 414.304861 -24.516032) (xy 414.259503 -24.483581)
			(xy 414.219354 -24.444872) (xy 414.185268 -24.400729) (xy 414.157972 -24.352094) (xy 414.138049 -24.300003)
			(xy 414.125923 -24.245566) (xy 414.121852 -24.189944) (xy 412.362396 -24.189944) (xy 412.361887 -24.21783)
			(xy 412.353767 -24.273006) (xy 412.337699 -24.326413) (xy 412.314027 -24.37691) (xy 412.283254 -24.423423)
			(xy 412.246037 -24.46496) (xy 412.203169 -24.500635) (xy 412.155563 -24.529689) (xy 412.104234 -24.551501)
			(xy 412.050277 -24.565607) (xy 411.99484 -24.571707) (xy 411.939106 -24.56967) (xy 411.884263 -24.55954)
			(xy 411.831479 -24.541533) (xy 411.781879 -24.516032) (xy 411.736521 -24.483581) (xy 411.696372 -24.444872)
			(xy 411.662286 -24.400729) (xy 411.63499 -24.352094) (xy 411.615067 -24.300003) (xy 411.602941 -24.245566)
			(xy 411.59887 -24.189944) (xy 409.843986 -24.189944) (xy 409.843986 -25.390094) (xy 414.033462 -25.390094)
			(xy 414.033952 -25.360126) (xy 414.041775 -25.300704) (xy 414.057288 -25.242811) (xy 414.080224 -25.187438)
			(xy 414.110191 -25.135532) (xy 414.146678 -25.087982) (xy 414.189058 -25.045602) (xy 414.236608 -25.009115)
			(xy 414.288514 -24.979148) (xy 414.343887 -24.956212) (xy 414.40178 -24.940699) (xy 414.461202 -24.932876)
			(xy 414.521138 -24.932876) (xy 414.58056 -24.940699) (xy 414.638453 -24.956212) (xy 414.693826 -24.979148)
			(xy 414.745732 -25.009115) (xy 414.793282 -25.045602) (xy 414.835662 -25.087982) (xy 414.872149 -25.135532)
			(xy 414.902116 -25.187438) (xy 414.925052 -25.242811) (xy 414.940565 -25.300704) (xy 414.948388 -25.360126)
			(xy 414.948878 -25.390094) (xy 414.948452 -25.418879) (xy 414.941233 -25.475994) (xy 414.926909 -25.531753)
			(xy 414.905705 -25.585275) (xy 414.877956 -25.635716) (xy 414.844101 -25.682279) (xy 414.804674 -25.724228)
			(xy 414.782762 -25.7429) (xy 414.77438 -25.749758) (xy 414.764728 -25.769316) (xy 414.761426 -25.867106)
			(xy 414.769554 -25.887172) (xy 414.777682 -25.894792) (xy 414.796087 -25.912864) (xy 414.828323 -25.953132)
			(xy 414.854846 -25.997373) (xy 414.875172 -26.044782) (xy 414.888932 -26.094494) (xy 414.895875 -26.145607)
			(xy 414.8963 -26.171398) (xy 414.895814 -26.198649) (xy 414.888058 -26.252597) (xy 414.872703 -26.304892)
			(xy 414.850061 -26.354469) (xy 414.820595 -26.400319) (xy 414.784904 -26.44151) (xy 414.743713 -26.477201)
			(xy 414.697863 -26.506667) (xy 414.648286 -26.529309) (xy 414.595991 -26.544664) (xy 414.542043 -26.55242)
			(xy 414.487541 -26.55242) (xy 414.433593 -26.544664) (xy 414.381298 -26.529309) (xy 414.331721 -26.506667)
			(xy 414.285871 -26.477201) (xy 414.24468 -26.44151) (xy 414.208989 -26.400319) (xy 414.179523 -26.354469)
			(xy 414.156881 -26.304892) (xy 414.141526 -26.252597) (xy 414.13377 -26.198649) (xy 414.133284 -26.171398)
			(xy 414.133805 -26.142755) (xy 414.142403 -26.086117) (xy 414.159373 -26.031401) (xy 414.184336 -25.979839)
			(xy 414.216729 -25.93259) (xy 414.2359 -25.911302) (xy 414.243266 -25.903174) (xy 414.250124 -25.8826)
			(xy 414.24098 -25.785064) (xy 414.230312 -25.766268) (xy 414.221422 -25.759918) (xy 414.196879 -25.741362)
			(xy 414.152484 -25.698761) (xy 414.114193 -25.6506) (xy 414.082695 -25.597745) (xy 414.058559 -25.541149)
			(xy 414.042218 -25.48183) (xy 414.033967 -25.420858) (xy 414.033462 -25.390094) (xy 409.843986 -25.390094)
			(xy 409.843986 -25.506934) (xy 409.844415 -25.517002) (xy 409.852136 -25.535599) (xy 409.858972 -25.543002)
			(xy 409.91028 -25.593802) (xy 409.917689 -25.600489) (xy 409.936125 -25.608078) (xy 409.946094 -25.608534)
			(xy 409.948888 -25.608534) (xy 409.976138 -25.608996) (xy 410.030085 -25.616751) (xy 410.082378 -25.632104)
			(xy 410.131954 -25.654744) (xy 410.177804 -25.684208) (xy 410.218994 -25.719898) (xy 410.254685 -25.761086)
			(xy 410.28415 -25.806935) (xy 410.306791 -25.856511) (xy 410.322146 -25.908804) (xy 410.329903 -25.96275)
			(xy 410.329903 -25.990042) (xy 411.59887 -25.990042) (xy 411.602941 -25.93442) (xy 411.615067 -25.879983)
			(xy 411.63499 -25.827892) (xy 411.662286 -25.779257) (xy 411.696372 -25.735114) (xy 411.736521 -25.696405)
			(xy 411.781879 -25.663954) (xy 411.831479 -25.638453) (xy 411.884263 -25.620446) (xy 411.939106 -25.610316)
			(xy 411.99484 -25.608279) (xy 412.050277 -25.614379) (xy 412.104234 -25.628485) (xy 412.155563 -25.650297)
			(xy 412.203169 -25.679351) (xy 412.246037 -25.715026) (xy 412.283254 -25.756563) (xy 412.314027 -25.803076)
			(xy 412.337699 -25.853573) (xy 412.353767 -25.90698) (xy 412.361887 -25.962156) (xy 412.362396 -25.990042)
			(xy 412.361887 -26.017928) (xy 412.353767 -26.073104) (xy 412.337699 -26.126511) (xy 412.314027 -26.177008)
			(xy 412.283254 -26.223521) (xy 412.246037 -26.265058) (xy 412.203169 -26.300733) (xy 412.155563 -26.329787)
			(xy 412.104234 -26.351599) (xy 412.050277 -26.365705) (xy 411.99484 -26.371805) (xy 411.939106 -26.369768)
			(xy 411.884263 -26.359638) (xy 411.831479 -26.341631) (xy 411.781879 -26.31613) (xy 411.736521 -26.283679)
			(xy 411.696372 -26.24497) (xy 411.662286 -26.200827) (xy 411.63499 -26.152192) (xy 411.615067 -26.100101)
			(xy 411.602941 -26.045664) (xy 411.59887 -25.990042) (xy 410.329903 -25.990042) (xy 410.329903 -26.01725)
			(xy 410.322146 -26.071196) (xy 410.306791 -26.123489) (xy 410.28415 -26.173065) (xy 410.254685 -26.218914)
			(xy 410.218994 -26.260102) (xy 410.177804 -26.295792) (xy 410.131954 -26.325256) (xy 410.082378 -26.347896)
			(xy 410.030085 -26.363249) (xy 409.976138 -26.371004) (xy 409.948888 -26.37155) (xy 409.946094 -26.37155)
			(xy 409.936128 -26.372027) (xy 409.917693 -26.379604) (xy 409.91028 -26.386282) (xy 409.858972 -26.437082)
			(xy 409.852131 -26.444481) (xy 409.844415 -26.463081) (xy 409.843986 -26.47315) (xy 409.843986 -27.307032)
			(xy 409.844414 -27.3171) (xy 409.852135 -27.335697) (xy 409.858972 -27.3431) (xy 409.91028 -27.3939)
			(xy 409.917689 -27.400587) (xy 409.936125 -27.408177) (xy 409.946094 -27.408632) (xy 409.948888 -27.408632)
			(xy 409.976139 -27.409094) (xy 410.030085 -27.416849) (xy 410.082379 -27.432203) (xy 410.131955 -27.454842)
			(xy 410.177805 -27.484307) (xy 410.218995 -27.519997) (xy 410.254686 -27.561185) (xy 410.284152 -27.607034)
			(xy 410.306793 -27.65661) (xy 410.322148 -27.708903) (xy 410.329905 -27.762849) (xy 410.329905 -27.79014)
			(xy 411.662878 -27.79014) (xy 411.666949 -27.734518) (xy 411.679075 -27.680081) (xy 411.698998 -27.62799)
			(xy 411.726294 -27.579355) (xy 411.76038 -27.535212) (xy 411.800529 -27.496503) (xy 411.845887 -27.464052)
			(xy 411.895487 -27.438551) (xy 411.948271 -27.420544) (xy 412.003114 -27.410414) (xy 412.058848 -27.408377)
			(xy 412.114285 -27.414477) (xy 412.168242 -27.428583) (xy 412.219571 -27.450395) (xy 412.267177 -27.479449)
			(xy 412.310045 -27.515124) (xy 412.347262 -27.556661) (xy 412.378035 -27.603174) (xy 412.401707 -27.653671)
			(xy 412.417775 -27.707078) (xy 412.425895 -27.762254) (xy 412.426404 -27.79014) (xy 414.16681 -27.79014)
			(xy 414.170881 -27.734518) (xy 414.183007 -27.680081) (xy 414.20293 -27.62799) (xy 414.230226 -27.579355)
			(xy 414.264312 -27.535212) (xy 414.304461 -27.496503) (xy 414.349819 -27.464052) (xy 414.399419 -27.438551)
			(xy 414.452203 -27.420544) (xy 414.507046 -27.410414) (xy 414.56278 -27.408377) (xy 414.618217 -27.414477)
			(xy 414.672174 -27.428583) (xy 414.723503 -27.450395) (xy 414.771109 -27.479449) (xy 414.813977 -27.515124)
			(xy 414.851194 -27.556661) (xy 414.881967 -27.603174) (xy 414.905639 -27.653671) (xy 414.921707 -27.707078)
			(xy 414.929827 -27.762254) (xy 414.930336 -27.79014) (xy 414.929839 -27.817351) (xy 416.199795 -27.817351)
			(xy 416.199795 -27.762849) (xy 416.207552 -27.708901) (xy 416.222908 -27.656606) (xy 416.24555 -27.60703)
			(xy 416.275018 -27.56118) (xy 416.310711 -27.519991) (xy 416.351902 -27.484301) (xy 416.397754 -27.454837)
			(xy 416.447333 -27.432198) (xy 416.499628 -27.416846) (xy 416.553577 -27.409093) (xy 416.580828 -27.408632)
			(xy 416.606135 -27.409022) (xy 416.656308 -27.415697) (xy 416.70516 -27.42894) (xy 416.728656 -27.43835)
			(xy 416.736657 -27.441393) (xy 416.753732 -27.442478) (xy 416.770213 -27.437883) (xy 416.777424 -27.43327)
			(xy 416.802824 -27.41549) (xy 416.809699 -27.410201) (xy 416.81978 -27.396107) (xy 416.824582 -27.379456)
			(xy 416.824414 -27.370786) (xy 416.823652 -27.342846) (xy 416.823652 -26.479246) (xy 416.82416 -26.456894)
			(xy 416.824668 -26.444448) (xy 416.814254 -26.421842) (xy 416.729164 -26.355548) (xy 416.70478 -26.350976)
			(xy 416.692842 -26.354786) (xy 416.665507 -26.362636) (xy 416.609263 -26.371048) (xy 416.580828 -26.37155)
			(xy 416.553577 -26.371005) (xy 416.499629 -26.363252) (xy 416.447333 -26.3479) (xy 416.397755 -26.325261)
			(xy 416.351904 -26.295797) (xy 416.310712 -26.260108) (xy 416.275019 -26.218919) (xy 416.245552 -26.173069)
			(xy 416.22291 -26.123493) (xy 416.207554 -26.071199) (xy 416.199797 -26.017251) (xy 416.199797 -25.962749)
			(xy 416.207554 -25.908801) (xy 416.22291 -25.856507) (xy 416.245552 -25.806931) (xy 416.275019 -25.761081)
			(xy 416.310712 -25.719892) (xy 416.351904 -25.684203) (xy 416.397755 -25.654739) (xy 416.447333 -25.6321)
			(xy 416.499629 -25.616748) (xy 416.553577 -25.608995) (xy 416.580828 -25.608534) (xy 416.609781 -25.609051)
			(xy 416.667023 -25.617791) (xy 416.722286 -25.635083) (xy 416.774302 -25.660527) (xy 416.821874 -25.693541)
			(xy 416.863911 -25.733366) (xy 416.899446 -25.779085) (xy 416.927663 -25.829651) (xy 416.92856 -25.832054)
			(xy 418.488368 -25.832054) (xy 418.488828 -25.80545) (xy 418.496204 -25.752756) (xy 418.510834 -25.701599)
			(xy 418.532434 -25.652974) (xy 418.560584 -25.607823) (xy 418.594739 -25.567024) (xy 418.634233 -25.53137)
			(xy 418.656008 -25.516078) (xy 418.667483 -25.507738) (xy 418.685685 -25.485995) (xy 418.697201 -25.460083)
			(xy 418.701142 -25.432002) (xy 418.697203 -25.403921) (xy 418.685688 -25.378008) (xy 418.667487 -25.356265)
			(xy 418.656008 -25.34793) (xy 418.634236 -25.332638) (xy 418.594758 -25.29697) (xy 418.560616 -25.256166)
			(xy 418.532471 -25.211015) (xy 418.510869 -25.162394) (xy 418.496229 -25.111244) (xy 418.488833 -25.058556)
			(xy 418.488368 -25.031954) (xy 418.488854 -25.004703) (xy 418.49661 -24.950755) (xy 418.511965 -24.89846)
			(xy 418.534607 -24.848883) (xy 418.564073 -24.803033) (xy 418.599764 -24.761842) (xy 418.640955 -24.726151)
			(xy 418.686805 -24.696685) (xy 418.736382 -24.674043) (xy 418.788677 -24.658688) (xy 418.842625 -24.650932)
			(xy 418.897127 -24.650932) (xy 418.951075 -24.658688) (xy 419.00337 -24.674043) (xy 419.052947 -24.696685)
			(xy 419.098797 -24.726151) (xy 419.139988 -24.761842) (xy 419.163189 -24.788618) (xy 421.093374 -24.788618)
			(xy 421.093374 -24.728682) (xy 421.101197 -24.66926) (xy 421.11671 -24.611367) (xy 421.139646 -24.555994)
			(xy 421.169613 -24.504088) (xy 421.2061 -24.456538) (xy 421.24848 -24.414158) (xy 421.29603 -24.377671)
			(xy 421.347936 -24.347704) (xy 421.403309 -24.324768) (xy 421.461202 -24.309255) (xy 421.520624 -24.301432)
			(xy 421.58056 -24.301432) (xy 421.639982 -24.309255) (xy 421.697875 -24.324768) (xy 421.753248 -24.347704)
			(xy 421.805154 -24.377671) (xy 421.852704 -24.414158) (xy 421.895084 -24.456538) (xy 421.931571 -24.504088)
			(xy 421.961538 -24.555994) (xy 421.984474 -24.611367) (xy 421.999987 -24.66926) (xy 422.00781 -24.728682)
			(xy 422.0083 -24.75865) (xy 422.00781 -24.788618) (xy 421.999987 -24.84804) (xy 421.984474 -24.905933)
			(xy 421.961538 -24.961306) (xy 421.931571 -25.013212) (xy 421.895084 -25.060762) (xy 421.852704 -25.103142)
			(xy 421.805154 -25.139629) (xy 421.753248 -25.169596) (xy 421.697875 -25.192532) (xy 421.639982 -25.208045)
			(xy 421.58056 -25.215868) (xy 421.520624 -25.215868) (xy 421.461202 -25.208045) (xy 421.403309 -25.192532)
			(xy 421.347936 -25.169596) (xy 421.29603 -25.139629) (xy 421.24848 -25.103142) (xy 421.2061 -25.060762)
			(xy 421.169613 -25.013212) (xy 421.139646 -24.961306) (xy 421.11671 -24.905933) (xy 421.101197 -24.84804)
			(xy 421.093374 -24.788618) (xy 419.163189 -24.788618) (xy 419.175679 -24.803033) (xy 419.205145 -24.848883)
			(xy 419.227787 -24.89846) (xy 419.243142 -24.950755) (xy 419.250898 -25.004703) (xy 419.251384 -25.031954)
			(xy 419.250907 -25.058557) (xy 419.243531 -25.111249) (xy 419.228903 -25.162405) (xy 419.207305 -25.21103)
			(xy 419.179157 -25.256181) (xy 419.145007 -25.29698) (xy 419.105517 -25.332637) (xy 419.083744 -25.34793)
			(xy 419.072256 -25.356257) (xy 419.054044 -25.377999) (xy 419.042522 -25.403916) (xy 419.038581 -25.432002)
			(xy 419.042524 -25.460089) (xy 419.054047 -25.486004) (xy 419.072259 -25.507746) (xy 419.083744 -25.516078)
			(xy 419.105509 -25.53138) (xy 419.144989 -25.567044) (xy 419.179133 -25.607847) (xy 419.20728 -25.652995)
			(xy 419.228883 -25.701616) (xy 419.243524 -25.752765) (xy 419.25092 -25.805452) (xy 419.251384 -25.832054)
			(xy 419.250898 -25.859305) (xy 419.243142 -25.913253) (xy 419.227787 -25.965548) (xy 419.205145 -26.015125)
			(xy 419.175679 -26.060975) (xy 419.139988 -26.102166) (xy 419.098797 -26.137857) (xy 419.052947 -26.167323)
			(xy 419.00337 -26.189965) (xy 418.951075 -26.20532) (xy 418.897127 -26.213076) (xy 418.842625 -26.213076)
			(xy 418.788677 -26.20532) (xy 418.736382 -26.189965) (xy 418.686805 -26.167323) (xy 418.640955 -26.137857)
			(xy 418.599764 -26.102166) (xy 418.564073 -26.060975) (xy 418.534607 -26.015125) (xy 418.511965 -25.965548)
			(xy 418.49661 -25.913253) (xy 418.488854 -25.859305) (xy 418.488368 -25.832054) (xy 416.92856 -25.832054)
			(xy 416.947914 -25.8839) (xy 416.959733 -25.940586) (xy 416.961828 -25.969468) (xy 416.962336 -25.981914)
			(xy 416.975036 -26.00325) (xy 417.06673 -26.060654) (xy 417.091368 -26.062432) (xy 417.102798 -26.057606)
			(xy 417.131159 -26.046146) (xy 417.190155 -26.029987) (xy 417.250776 -26.021813) (xy 417.28136 -26.021284)
			(xy 417.311338 -26.021799) (xy 417.370782 -26.029623) (xy 417.428696 -26.045142) (xy 417.484087 -26.06809)
			(xy 417.536007 -26.098075) (xy 417.583568 -26.134582) (xy 417.625954 -26.176987) (xy 417.66244 -26.224564)
			(xy 417.692401 -26.276498) (xy 417.715324 -26.3319) (xy 417.723076 -26.360882) (xy 419.389558 -26.360882)
			(xy 419.393629 -26.30526) (xy 419.405755 -26.250823) (xy 419.425678 -26.198732) (xy 419.452974 -26.150097)
			(xy 419.48706 -26.105954) (xy 419.527209 -26.067245) (xy 419.572567 -26.034794) (xy 419.622167 -26.009293)
			(xy 419.674951 -25.991286) (xy 419.729794 -25.981156) (xy 419.785528 -25.979119) (xy 419.840965 -25.985219)
			(xy 419.894922 -25.999325) (xy 419.946251 -26.021137) (xy 419.993857 -26.050191) (xy 420.036725 -26.085866)
			(xy 420.073942 -26.127403) (xy 420.104715 -26.173916) (xy 420.128387 -26.224413) (xy 420.144455 -26.27782)
			(xy 420.152575 -26.332996) (xy 420.153084 -26.360882) (xy 420.405558 -26.360882) (xy 420.409629 -26.30526)
			(xy 420.421755 -26.250823) (xy 420.441678 -26.198732) (xy 420.468974 -26.150097) (xy 420.50306 -26.105954)
			(xy 420.543209 -26.067245) (xy 420.588567 -26.034794) (xy 420.638167 -26.009293) (xy 420.690951 -25.991286)
			(xy 420.745794 -25.981156) (xy 420.801528 -25.979119) (xy 420.856965 -25.985219) (xy 420.910922 -25.999325)
			(xy 420.962251 -26.021137) (xy 421.009857 -26.050191) (xy 421.052725 -26.085866) (xy 421.089942 -26.127403)
			(xy 421.120715 -26.173916) (xy 421.144387 -26.224413) (xy 421.160455 -26.27782) (xy 421.168575 -26.332996)
			(xy 421.169084 -26.360882) (xy 421.168575 -26.388768) (xy 421.160455 -26.443944) (xy 421.144387 -26.497351)
			(xy 421.120715 -26.547848) (xy 421.089942 -26.594361) (xy 421.052725 -26.635898) (xy 421.009857 -26.671573)
			(xy 420.962251 -26.700627) (xy 420.910922 -26.722439) (xy 420.856965 -26.736545) (xy 420.801528 -26.742645)
			(xy 420.745794 -26.740608) (xy 420.690951 -26.730478) (xy 420.638167 -26.712471) (xy 420.588567 -26.68697)
			(xy 420.543209 -26.654519) (xy 420.50306 -26.61581) (xy 420.468974 -26.571667) (xy 420.441678 -26.523032)
			(xy 420.421755 -26.470941) (xy 420.409629 -26.416504) (xy 420.405558 -26.360882) (xy 420.153084 -26.360882)
			(xy 420.152575 -26.388768) (xy 420.144455 -26.443944) (xy 420.128387 -26.497351) (xy 420.104715 -26.547848)
			(xy 420.073942 -26.594361) (xy 420.036725 -26.635898) (xy 419.993857 -26.671573) (xy 419.946251 -26.700627)
			(xy 419.894922 -26.722439) (xy 419.840965 -26.736545) (xy 419.785528 -26.742645) (xy 419.729794 -26.740608)
			(xy 419.674951 -26.730478) (xy 419.622167 -26.712471) (xy 419.572567 -26.68697) (xy 419.527209 -26.654519)
			(xy 419.48706 -26.61581) (xy 419.452974 -26.571667) (xy 419.425678 -26.523032) (xy 419.405755 -26.470941)
			(xy 419.393629 -26.416504) (xy 419.389558 -26.360882) (xy 417.723076 -26.360882) (xy 417.730817 -26.38982)
			(xy 417.738614 -26.449267) (xy 417.739068 -26.479246) (xy 417.739068 -26.971244) (xy 421.151048 -26.971244)
			(xy 421.155119 -26.915622) (xy 421.167245 -26.861185) (xy 421.187168 -26.809094) (xy 421.214464 -26.760459)
			(xy 421.24855 -26.716316) (xy 421.288699 -26.677607) (xy 421.334057 -26.645156) (xy 421.383657 -26.619655)
			(xy 421.436441 -26.601648) (xy 421.491284 -26.591518) (xy 421.547018 -26.589481) (xy 421.602455 -26.595581)
			(xy 421.656412 -26.609687) (xy 421.707741 -26.631499) (xy 421.755347 -26.660553) (xy 421.798215 -26.696228)
			(xy 421.835432 -26.737765) (xy 421.866205 -26.784278) (xy 421.889877 -26.834775) (xy 421.905945 -26.888182)
			(xy 421.914065 -26.943358) (xy 421.914574 -26.971244) (xy 421.914065 -26.99913) (xy 421.905945 -27.054306)
			(xy 421.889877 -27.107713) (xy 421.866205 -27.15821) (xy 421.835432 -27.204723) (xy 421.798215 -27.24626)
			(xy 421.755347 -27.281935) (xy 421.707741 -27.310989) (xy 421.656412 -27.332801) (xy 421.602455 -27.346907)
			(xy 421.547018 -27.353007) (xy 421.491284 -27.35097) (xy 421.436441 -27.34084) (xy 421.383657 -27.322833)
			(xy 421.334057 -27.297332) (xy 421.288699 -27.264881) (xy 421.24855 -27.226172) (xy 421.214464 -27.182029)
			(xy 421.187168 -27.133394) (xy 421.167245 -27.081303) (xy 421.155119 -27.026866) (xy 421.151048 -26.971244)
			(xy 417.739068 -26.971244) (xy 417.739068 -27.342846) (xy 417.738616 -27.372821) (xy 417.730788 -27.432256)
			(xy 417.715273 -27.490163) (xy 417.692335 -27.54555) (xy 417.662367 -27.597471) (xy 417.62588 -27.645039)
			(xy 417.5835 -27.687439) (xy 417.53595 -27.723948) (xy 417.484042 -27.75394) (xy 417.428666 -27.776904)
			(xy 417.370767 -27.792446) (xy 417.311334 -27.800302) (xy 417.28136 -27.800808) (xy 417.250223 -27.800282)
			(xy 417.188527 -27.791815) (xy 417.128542 -27.775083) (xy 417.09975 -27.763216) (xy 417.088574 -27.75839)
			(xy 417.064952 -27.75966) (xy 416.973766 -27.810968) (xy 416.960304 -27.830526) (xy 416.95878 -27.842464)
			(xy 416.954598 -27.8695) (xy 416.939416 -27.92206) (xy 416.916884 -27.971914) (xy 416.887464 -28.01804)
			(xy 416.85176 -28.059492) (xy 416.810503 -28.095421) (xy 416.764538 -28.12509) (xy 416.714807 -28.147893)
			(xy 416.66233 -28.16336) (xy 416.608182 -28.171176) (xy 416.580828 -28.171648) (xy 416.553577 -28.171107)
			(xy 416.499628 -28.163354) (xy 416.447333 -28.148002) (xy 416.397754 -28.125363) (xy 416.351902 -28.095899)
			(xy 416.310711 -28.060209) (xy 416.275018 -28.01902) (xy 416.24555 -27.97317) (xy 416.222908 -27.923594)
			(xy 416.207552 -27.871299) (xy 416.199795 -27.817351) (xy 414.929839 -27.817351) (xy 414.929827 -27.818026)
			(xy 414.921707 -27.873202) (xy 414.905639 -27.926609) (xy 414.881967 -27.977106) (xy 414.851194 -28.023619)
			(xy 414.813977 -28.065156) (xy 414.771109 -28.100831) (xy 414.723503 -28.129885) (xy 414.672174 -28.151697)
			(xy 414.618217 -28.165803) (xy 414.56278 -28.171903) (xy 414.507046 -28.169866) (xy 414.452203 -28.159736)
			(xy 414.399419 -28.141729) (xy 414.349819 -28.116228) (xy 414.304461 -28.083777) (xy 414.264312 -28.045068)
			(xy 414.230226 -28.000925) (xy 414.20293 -27.95229) (xy 414.183007 -27.900199) (xy 414.170881 -27.845762)
			(xy 414.16681 -27.79014) (xy 412.426404 -27.79014) (xy 412.425895 -27.818026) (xy 412.417775 -27.873202)
			(xy 412.401707 -27.926609) (xy 412.378035 -27.977106) (xy 412.347262 -28.023619) (xy 412.310045 -28.065156)
			(xy 412.267177 -28.100831) (xy 412.219571 -28.129885) (xy 412.168242 -28.151697) (xy 412.114285 -28.165803)
			(xy 412.058848 -28.171903) (xy 412.003114 -28.169866) (xy 411.948271 -28.159736) (xy 411.895487 -28.141729)
			(xy 411.845887 -28.116228) (xy 411.800529 -28.083777) (xy 411.76038 -28.045068) (xy 411.726294 -28.000925)
			(xy 411.698998 -27.95229) (xy 411.679075 -27.900199) (xy 411.666949 -27.845762) (xy 411.662878 -27.79014)
			(xy 410.329905 -27.79014) (xy 410.329905 -27.817351) (xy 410.322148 -27.871297) (xy 410.306793 -27.92359)
			(xy 410.284152 -27.973166) (xy 410.254686 -28.019015) (xy 410.218995 -28.060203) (xy 410.177805 -28.095893)
			(xy 410.131955 -28.125358) (xy 410.082379 -28.147997) (xy 410.030085 -28.163351) (xy 409.976139 -28.171106)
			(xy 409.948888 -28.171648) (xy 409.946094 -28.171648) (xy 409.936128 -28.172125) (xy 409.917692 -28.179702)
			(xy 409.91028 -28.18638) (xy 409.858972 -28.23718) (xy 409.85213 -28.244579) (xy 409.844414 -28.263179)
			(xy 409.843986 -28.273248) (xy 409.843986 -29.106876) (xy 409.844422 -29.11694) (xy 409.852155 -29.135526)
			(xy 409.858972 -29.142944) (xy 409.91028 -29.193744) (xy 409.917691 -29.200427) (xy 409.936126 -29.208009)
			(xy 409.946094 -29.208476) (xy 409.948888 -29.208476) (xy 409.976143 -29.208938) (xy 410.030097 -29.216694)
			(xy 410.082399 -29.23205) (xy 410.131982 -29.254692) (xy 410.177839 -29.284161) (xy 410.219035 -29.319857)
			(xy 410.254731 -29.361051) (xy 410.284202 -29.406907) (xy 410.306846 -29.45649) (xy 410.322203 -29.508791)
			(xy 410.329961 -29.562745) (xy 410.329961 -29.589984) (xy 411.662878 -29.589984) (xy 411.666949 -29.534362)
			(xy 411.679075 -29.479925) (xy 411.698998 -29.427834) (xy 411.726294 -29.379199) (xy 411.76038 -29.335056)
			(xy 411.800529 -29.296347) (xy 411.845887 -29.263896) (xy 411.895487 -29.238395) (xy 411.948271 -29.220388)
			(xy 412.003114 -29.210258) (xy 412.058848 -29.208221) (xy 412.114285 -29.214321) (xy 412.168242 -29.228427)
			(xy 412.219571 -29.250239) (xy 412.267177 -29.279293) (xy 412.310045 -29.314968) (xy 412.347262 -29.356505)
			(xy 412.378035 -29.403018) (xy 412.401707 -29.453515) (xy 412.417775 -29.506922) (xy 412.425895 -29.562098)
			(xy 412.426404 -29.589984) (xy 414.16681 -29.589984) (xy 414.170881 -29.534362) (xy 414.183007 -29.479925)
			(xy 414.20293 -29.427834) (xy 414.230226 -29.379199) (xy 414.264312 -29.335056) (xy 414.304461 -29.296347)
			(xy 414.349819 -29.263896) (xy 414.399419 -29.238395) (xy 414.452203 -29.220388) (xy 414.507046 -29.210258)
			(xy 414.56278 -29.208221) (xy 414.618217 -29.214321) (xy 414.672174 -29.228427) (xy 414.723503 -29.250239)
			(xy 414.771109 -29.279293) (xy 414.813977 -29.314968) (xy 414.851194 -29.356505) (xy 414.881967 -29.403018)
			(xy 414.905639 -29.453515) (xy 414.921707 -29.506922) (xy 414.929827 -29.562098) (xy 414.930336 -29.589984)
			(xy 416.19881 -29.589984) (xy 416.202881 -29.534362) (xy 416.215007 -29.479925) (xy 416.23493 -29.427834)
			(xy 416.262226 -29.379199) (xy 416.296312 -29.335056) (xy 416.336461 -29.296347) (xy 416.381819 -29.263896)
			(xy 416.431419 -29.238395) (xy 416.484203 -29.220388) (xy 416.539046 -29.210258) (xy 416.59478 -29.208221)
			(xy 416.650217 -29.214321) (xy 416.704174 -29.228427) (xy 416.755503 -29.250239) (xy 416.803109 -29.279293)
			(xy 416.845977 -29.314968) (xy 416.86765 -29.339157) (xy 418.590109 -29.339157) (xy 418.590109 -29.284643)
			(xy 418.597868 -29.230683) (xy 418.613227 -29.178377) (xy 418.635873 -29.12879) (xy 418.665347 -29.08293)
			(xy 418.701047 -29.041732) (xy 418.742248 -29.006034) (xy 418.788109 -28.976563) (xy 418.837698 -28.953919)
			(xy 418.890005 -28.938563) (xy 418.943965 -28.930807) (xy 418.971222 -28.930346) (xy 418.986015 -28.930477)
			(xy 419.015513 -28.932769) (xy 419.03015 -28.934918) (xy 419.041072 -28.936696) (xy 419.062408 -28.9306)
			(xy 419.129718 -28.873196) (xy 419.137689 -28.865607) (xy 419.146771 -28.845584) (xy 419.147244 -28.834588)
			(xy 419.147244 -28.530296) (xy 419.146727 -28.519309) (xy 419.137658 -28.499297) (xy 419.129718 -28.491688)
			(xy 419.062408 -28.434284) (xy 419.041072 -28.428188) (xy 419.03015 -28.429966) (xy 419.015512 -28.432107)
			(xy 418.986015 -28.434395) (xy 418.971222 -28.434538) (xy 418.94397 -28.434016) (xy 418.890021 -28.426262)
			(xy 418.837725 -28.410909) (xy 418.788146 -28.38827) (xy 418.742294 -28.358805) (xy 418.701101 -28.323114)
			(xy 418.665408 -28.281924) (xy 418.635941 -28.236074) (xy 418.613298 -28.186496) (xy 418.597942 -28.1342)
			(xy 418.590185 -28.080252) (xy 418.590185 -28.025748) (xy 418.597942 -27.9718) (xy 418.613298 -27.919504)
			(xy 418.635941 -27.869926) (xy 418.665408 -27.824076) (xy 418.701101 -27.782886) (xy 418.742294 -27.747195)
			(xy 418.788146 -27.71773) (xy 418.837725 -27.69509) (xy 418.890021 -27.679738) (xy 418.94397 -27.671984)
			(xy 418.971222 -27.671522) (xy 418.997149 -27.671929) (xy 419.048528 -27.678939) (xy 419.098484 -27.692839)
			(xy 419.146099 -27.713375) (xy 419.190495 -27.740168) (xy 419.230856 -27.772725) (xy 419.266437 -27.810445)
			(xy 419.281864 -27.831288) (xy 419.287607 -27.838616) (xy 419.303108 -27.848903) (xy 419.31209 -27.851354)
			(xy 419.342316 -27.858212) (xy 419.351594 -27.859945) (xy 419.370255 -27.857214) (xy 419.378638 -27.852878)
			(xy 419.404607 -27.838569) (xy 419.459462 -27.816062) (xy 419.516767 -27.80084) (xy 419.57556 -27.793158)
			(xy 419.605206 -27.79268) (xy 419.634849 -27.793164) (xy 419.693632 -27.800889) (xy 419.75093 -27.81612)
			(xy 419.80579 -27.838602) (xy 419.831774 -27.852878) (xy 419.840188 -27.857122) (xy 419.858817 -27.859856)
			(xy 419.868096 -27.858212) (xy 419.898322 -27.851354) (xy 419.907315 -27.848927) (xy 419.922821 -27.838634)
			(xy 419.928548 -27.831288) (xy 419.94398 -27.810447) (xy 419.979548 -27.772712) (xy 420.019902 -27.740145)
			(xy 420.064299 -27.713349) (xy 420.111917 -27.692816) (xy 420.161878 -27.678928) (xy 420.213262 -27.671938)
			(xy 420.23919 -27.671522) (xy 420.266445 -27.671924) (xy 420.320402 -27.679681) (xy 420.372705 -27.695037)
			(xy 420.42229 -27.717681) (xy 420.468148 -27.747151) (xy 420.509346 -27.782847) (xy 420.545043 -27.824044)
			(xy 420.574514 -27.869901) (xy 420.597159 -27.919486) (xy 420.612517 -27.971788) (xy 420.620275 -28.025745)
			(xy 420.620275 -28.080255) (xy 420.612517 -28.134212) (xy 420.597159 -28.186514) (xy 420.574514 -28.236099)
			(xy 420.545043 -28.281956) (xy 420.509346 -28.323153) (xy 420.468148 -28.358849) (xy 420.42229 -28.388319)
			(xy 420.372705 -28.410963) (xy 420.320402 -28.426319) (xy 420.266445 -28.434076) (xy 420.23919 -28.434538)
			(xy 420.224397 -28.434406) (xy 420.194899 -28.432115) (xy 420.180262 -28.429966) (xy 420.16934 -28.428188)
			(xy 420.148004 -28.434284) (xy 420.080694 -28.491688) (xy 420.072732 -28.499285) (xy 420.063644 -28.519302)
			(xy 420.063168 -28.530296) (xy 420.063168 -28.834588) (xy 420.06369 -28.845575) (xy 420.072754 -28.865587)
			(xy 420.080694 -28.873196) (xy 420.148004 -28.9306) (xy 420.16934 -28.936696) (xy 420.180262 -28.934918)
			(xy 420.1949 -28.932775) (xy 420.224397 -28.930488) (xy 420.23919 -28.930346) (xy 420.26644 -28.930901)
			(xy 420.320386 -28.938655) (xy 420.372678 -28.954009) (xy 420.422254 -28.976648) (xy 420.468103 -29.006112)
			(xy 420.509291 -29.041801) (xy 420.544982 -29.082989) (xy 420.574447 -29.128838) (xy 420.597088 -29.178412)
			(xy 420.612442 -29.230705) (xy 420.620199 -29.28465) (xy 420.620199 -29.33915) (xy 420.612442 -29.393095)
			(xy 420.597088 -29.445388) (xy 420.574447 -29.494962) (xy 420.544982 -29.540811) (xy 420.509291 -29.581999)
			(xy 420.468103 -29.617688) (xy 420.422254 -29.647152) (xy 420.372678 -29.669791) (xy 420.320386 -29.685145)
			(xy 420.26644 -29.692899) (xy 420.23919 -29.693362) (xy 420.213263 -29.692953) (xy 420.161884 -29.685944)
			(xy 420.111927 -29.672044) (xy 420.064312 -29.651509) (xy 420.019916 -29.624717) (xy 419.979556 -29.59216)
			(xy 419.943975 -29.554439) (xy 419.928548 -29.533596) (xy 419.922784 -29.526286) (xy 419.907299 -29.515987)
			(xy 419.898322 -29.51353) (xy 419.868096 -29.506672) (xy 419.858817 -29.504948) (xy 419.840157 -29.507673)
			(xy 419.831774 -29.512006) (xy 419.805802 -29.526309) (xy 419.750949 -29.548818) (xy 419.693644 -29.564042)
			(xy 419.634852 -29.571725) (xy 419.605206 -29.572204) (xy 419.575563 -29.571717) (xy 419.51678 -29.563993)
			(xy 419.459482 -29.548764) (xy 419.404622 -29.526282) (xy 419.378638 -29.512006) (xy 419.370222 -29.507768)
			(xy 419.351595 -29.50503) (xy 419.342316 -29.506672) (xy 419.31209 -29.51353) (xy 419.3031 -29.515967)
			(xy 419.287593 -29.526253) (xy 419.281864 -29.533596) (xy 419.26642 -29.554428) (xy 419.230855 -29.592164)
			(xy 419.190502 -29.624732) (xy 419.146108 -29.65153) (xy 419.098492 -29.672064) (xy 419.048532 -29.685954)
			(xy 418.99715 -29.692945) (xy 418.971222 -29.693362) (xy 418.943965 -29.692993) (xy 418.890005 -29.685237)
			(xy 418.837698 -29.669881) (xy 418.788109 -29.647237) (xy 418.742248 -29.617766) (xy 418.701047 -29.582068)
			(xy 418.665347 -29.54087) (xy 418.635873 -29.49501) (xy 418.613227 -29.445423) (xy 418.597868 -29.393117)
			(xy 418.590109 -29.339157) (xy 416.86765 -29.339157) (xy 416.883194 -29.356505) (xy 416.913967 -29.403018)
			(xy 416.937639 -29.453515) (xy 416.953707 -29.506922) (xy 416.961827 -29.562098) (xy 416.962336 -29.589984)
			(xy 416.961827 -29.61787) (xy 416.953707 -29.673046) (xy 416.937639 -29.726453) (xy 416.913967 -29.77695)
			(xy 416.883194 -29.823463) (xy 416.845977 -29.865) (xy 416.803109 -29.900675) (xy 416.755503 -29.929729)
			(xy 416.704174 -29.951541) (xy 416.650217 -29.965647) (xy 416.59478 -29.971747) (xy 416.539046 -29.96971)
			(xy 416.484203 -29.95958) (xy 416.431419 -29.941573) (xy 416.381819 -29.916072) (xy 416.336461 -29.883621)
			(xy 416.296312 -29.844912) (xy 416.262226 -29.800769) (xy 416.23493 -29.752134) (xy 416.215007 -29.700043)
			(xy 416.202881 -29.645606) (xy 416.19881 -29.589984) (xy 414.930336 -29.589984) (xy 414.929827 -29.61787)
			(xy 414.921707 -29.673046) (xy 414.905639 -29.726453) (xy 414.881967 -29.77695) (xy 414.851194 -29.823463)
			(xy 414.813977 -29.865) (xy 414.771109 -29.900675) (xy 414.723503 -29.929729) (xy 414.672174 -29.951541)
			(xy 414.618217 -29.965647) (xy 414.56278 -29.971747) (xy 414.507046 -29.96971) (xy 414.452203 -29.95958)
			(xy 414.399419 -29.941573) (xy 414.349819 -29.916072) (xy 414.304461 -29.883621) (xy 414.264312 -29.844912)
			(xy 414.230226 -29.800769) (xy 414.20293 -29.752134) (xy 414.183007 -29.700043) (xy 414.170881 -29.645606)
			(xy 414.16681 -29.589984) (xy 412.426404 -29.589984) (xy 412.425895 -29.61787) (xy 412.417775 -29.673046)
			(xy 412.401707 -29.726453) (xy 412.378035 -29.77695) (xy 412.347262 -29.823463) (xy 412.310045 -29.865)
			(xy 412.267177 -29.900675) (xy 412.219571 -29.929729) (xy 412.168242 -29.951541) (xy 412.114285 -29.965647)
			(xy 412.058848 -29.971747) (xy 412.003114 -29.96971) (xy 411.948271 -29.95958) (xy 411.895487 -29.941573)
			(xy 411.845887 -29.916072) (xy 411.800529 -29.883621) (xy 411.76038 -29.844912) (xy 411.726294 -29.800769)
			(xy 411.698998 -29.752134) (xy 411.679075 -29.700043) (xy 411.666949 -29.645606) (xy 411.662878 -29.589984)
			(xy 410.329961 -29.589984) (xy 410.329961 -29.617255) (xy 410.322203 -29.671209) (xy 410.306846 -29.72351)
			(xy 410.284202 -29.773093) (xy 410.254731 -29.818949) (xy 410.219035 -29.860143) (xy 410.177839 -29.895839)
			(xy 410.131982 -29.925308) (xy 410.082399 -29.94795) (xy 410.030097 -29.963306) (xy 409.976143 -29.971062)
			(xy 409.948888 -29.971492) (xy 409.946094 -29.971492) (xy 409.936127 -29.971967) (xy 409.917686 -29.979539)
			(xy 409.91028 -29.986224) (xy 409.858972 -30.037024) (xy 409.852122 -30.04442) (xy 409.844384 -30.063019)
			(xy 409.843986 -30.073092) (xy 409.843986 -30.906974) (xy 409.844422 -30.917039) (xy 409.852154 -30.935625)
			(xy 409.858972 -30.943042) (xy 409.91028 -30.993842) (xy 409.91769 -31.000525) (xy 409.936126 -31.008108)
			(xy 409.946094 -31.008574) (xy 409.948888 -31.008574) (xy 409.976143 -31.009036) (xy 410.030098 -31.016792)
			(xy 410.082399 -31.032148) (xy 410.131983 -31.054791) (xy 410.17784 -31.08426) (xy 410.219036 -31.119955)
			(xy 410.254733 -31.16115) (xy 410.284204 -31.207006) (xy 410.306848 -31.256589) (xy 410.322205 -31.308891)
			(xy 410.329963 -31.362845) (xy 410.329963 -31.417355) (xy 410.322205 -31.471309) (xy 410.306848 -31.523611)
			(xy 410.284204 -31.573194) (xy 410.254733 -31.61905) (xy 410.234583 -31.642304) (xy 411.706566 -31.642304)
			(xy 411.710637 -31.586682) (xy 411.722763 -31.532245) (xy 411.742686 -31.480154) (xy 411.769982 -31.431519)
			(xy 411.804068 -31.387376) (xy 411.844217 -31.348667) (xy 411.889575 -31.316216) (xy 411.939175 -31.290715)
			(xy 411.991959 -31.272708) (xy 412.046802 -31.262578) (xy 412.102536 -31.260541) (xy 412.157973 -31.266641)
			(xy 412.21193 -31.280747) (xy 412.263259 -31.302559) (xy 412.310865 -31.331613) (xy 412.353733 -31.367288)
			(xy 412.374156 -31.390082) (xy 414.16681 -31.390082) (xy 414.170881 -31.33446) (xy 414.183007 -31.280023)
			(xy 414.20293 -31.227932) (xy 414.230226 -31.179297) (xy 414.264312 -31.135154) (xy 414.304461 -31.096445)
			(xy 414.349819 -31.063994) (xy 414.399419 -31.038493) (xy 414.452203 -31.020486) (xy 414.507046 -31.010356)
			(xy 414.56278 -31.008319) (xy 414.618217 -31.014419) (xy 414.672174 -31.028525) (xy 414.723503 -31.050337)
			(xy 414.771109 -31.079391) (xy 414.813977 -31.115066) (xy 414.851194 -31.156603) (xy 414.881967 -31.203116)
			(xy 414.905639 -31.253613) (xy 414.921707 -31.30702) (xy 414.929827 -31.362196) (xy 414.930336 -31.390082)
			(xy 416.19881 -31.390082) (xy 416.202881 -31.33446) (xy 416.215007 -31.280023) (xy 416.23493 -31.227932)
			(xy 416.262226 -31.179297) (xy 416.296312 -31.135154) (xy 416.336461 -31.096445) (xy 416.381819 -31.063994)
			(xy 416.431419 -31.038493) (xy 416.484203 -31.020486) (xy 416.539046 -31.010356) (xy 416.59478 -31.008319)
			(xy 416.650217 -31.014419) (xy 416.704174 -31.028525) (xy 416.755503 -31.050337) (xy 416.803109 -31.079391)
			(xy 416.845977 -31.115066) (xy 416.883194 -31.156603) (xy 416.913967 -31.203116) (xy 416.937639 -31.253613)
			(xy 416.953707 -31.30702) (xy 416.961827 -31.362196) (xy 416.962336 -31.390082) (xy 416.961827 -31.417968)
			(xy 416.953707 -31.473144) (xy 416.937639 -31.526551) (xy 416.913967 -31.577048) (xy 416.883194 -31.623561)
			(xy 416.845977 -31.665098) (xy 416.827763 -31.680256) (xy 418.590127 -31.680256) (xy 418.590127 -31.625744)
			(xy 418.597885 -31.571787) (xy 418.613243 -31.519484) (xy 418.635889 -31.469898) (xy 418.665361 -31.424041)
			(xy 418.70106 -31.382845) (xy 418.742258 -31.347148) (xy 418.788118 -31.317679) (xy 418.837704 -31.295036)
			(xy 418.890009 -31.27968) (xy 418.943966 -31.271925) (xy 418.971222 -31.271464) (xy 418.99715 -31.271854)
			(xy 419.04853 -31.278864) (xy 419.098488 -31.292767) (xy 419.146103 -31.313305) (xy 419.190499 -31.340101)
			(xy 419.230859 -31.372661) (xy 419.266438 -31.410385) (xy 419.281864 -31.43123) (xy 419.287618 -31.438549)
			(xy 419.30311 -31.448842) (xy 419.31209 -31.451296) (xy 419.342316 -31.458154) (xy 419.351595 -31.459882)
			(xy 419.370255 -31.457154) (xy 419.378638 -31.45282) (xy 419.404623 -31.438564) (xy 419.459494 -31.416152)
			(xy 419.516795 -31.400995) (xy 419.57557 -31.393348) (xy 419.605206 -31.392876) (xy 419.634844 -31.393313)
			(xy 419.693627 -31.400941) (xy 419.750931 -31.416105) (xy 419.805792 -31.438553) (xy 419.831774 -31.45282)
			(xy 419.840189 -31.457062) (xy 419.858817 -31.459799) (xy 419.868096 -31.458154) (xy 419.898322 -31.451296)
			(xy 419.90731 -31.448855) (xy 419.922817 -31.438571) (xy 419.928548 -31.43123) (xy 419.943963 -31.410376)
			(xy 419.979536 -31.372644) (xy 420.019894 -31.34008) (xy 420.064293 -31.313286) (xy 420.111913 -31.292756)
			(xy 420.161877 -31.278869) (xy 420.213261 -31.27188) (xy 420.23919 -31.271464) (xy 420.266441 -31.271983)
			(xy 420.320389 -31.279738) (xy 420.372685 -31.295092) (xy 420.422262 -31.317732) (xy 420.468113 -31.347198)
			(xy 420.509304 -31.382889) (xy 420.544996 -31.424079) (xy 420.574463 -31.469929) (xy 420.597105 -31.519506)
			(xy 420.61246 -31.571801) (xy 420.620217 -31.625749) (xy 420.620217 -31.680251) (xy 420.61246 -31.734199)
			(xy 420.597105 -31.786494) (xy 420.574463 -31.836071) (xy 420.544996 -31.881921) (xy 420.509304 -31.923111)
			(xy 420.468113 -31.958802) (xy 420.422262 -31.988268) (xy 420.372685 -32.010908) (xy 420.320389 -32.026262)
			(xy 420.266441 -32.034017) (xy 420.23919 -32.03448) (xy 420.224397 -32.034348) (xy 420.194899 -32.032057)
			(xy 420.180262 -32.029908) (xy 420.16934 -32.02813) (xy 420.148004 -32.034226) (xy 420.080694 -32.09163)
			(xy 420.072758 -32.09925) (xy 420.063656 -32.119249) (xy 420.063168 -32.130238) (xy 420.063168 -32.43453)
			(xy 420.063667 -32.44552) (xy 420.072748 -32.465531) (xy 420.080694 -32.473138) (xy 420.148004 -32.530542)
			(xy 420.16934 -32.536638) (xy 420.180262 -32.53486) (xy 420.1949 -32.532717) (xy 420.224397 -32.53043)
			(xy 420.23919 -32.530288) (xy 420.266443 -32.530759) (xy 420.320394 -32.538514) (xy 420.372693 -32.553869)
			(xy 420.422274 -32.576511) (xy 420.468128 -32.605978) (xy 420.509321 -32.641672) (xy 420.545016 -32.682864)
			(xy 420.574484 -32.728717) (xy 420.597127 -32.778298) (xy 420.612483 -32.830596) (xy 420.620241 -32.884547)
			(xy 420.620241 -32.939053) (xy 420.612483 -32.993004) (xy 420.597127 -33.045302) (xy 420.574484 -33.094883)
			(xy 420.545016 -33.140736) (xy 420.509321 -33.181928) (xy 420.468128 -33.217622) (xy 420.422274 -33.247089)
			(xy 420.372693 -33.269731) (xy 420.320394 -33.285086) (xy 420.266443 -33.292841) (xy 420.23919 -33.293304)
			(xy 420.213263 -33.292877) (xy 420.161886 -33.28587) (xy 420.111931 -33.271972) (xy 420.064316 -33.251439)
			(xy 420.01992 -33.224649) (xy 419.979559 -33.192096) (xy 419.943976 -33.154379) (xy 419.928548 -33.133538)
			(xy 419.922796 -33.126218) (xy 419.907302 -33.115926) (xy 419.898322 -33.113472) (xy 419.868096 -33.106614)
			(xy 419.858817 -33.104884) (xy 419.840156 -33.107612) (xy 419.831774 -33.111948) (xy 419.805785 -33.126197)
			(xy 419.750916 -33.148611) (xy 419.693616 -33.16377) (xy 419.634841 -33.17142) (xy 419.605206 -33.171892)
			(xy 419.575568 -33.171454) (xy 419.516785 -33.163827) (xy 419.459481 -33.148663) (xy 419.40462 -33.126215)
			(xy 419.378638 -33.111948) (xy 419.370221 -33.107711) (xy 419.351594 -33.104971) (xy 419.342316 -33.106614)
			(xy 419.31209 -33.113472) (xy 419.303107 -33.115928) (xy 419.287598 -33.126202) (xy 419.281864 -33.133538)
			(xy 419.266433 -33.154379) (xy 419.230863 -33.192113) (xy 419.190508 -33.224679) (xy 419.146112 -33.251475)
			(xy 419.098494 -33.272007) (xy 419.048533 -33.285897) (xy 418.99715 -33.292887) (xy 418.971222 -33.293304)
			(xy 418.943968 -33.29285) (xy 418.890014 -33.285096) (xy 418.837713 -33.269741) (xy 418.78813 -33.2471)
			(xy 418.742273 -33.217632) (xy 418.701077 -33.181938) (xy 418.665381 -33.140744) (xy 418.635911 -33.09489)
			(xy 418.613266 -33.045308) (xy 418.597909 -32.993008) (xy 418.590151 -32.939054) (xy 418.590151 -32.884546)
			(xy 418.597909 -32.830592) (xy 418.613266 -32.778292) (xy 418.635911 -32.72871) (xy 418.665381 -32.682856)
			(xy 418.701077 -32.641662) (xy 418.742273 -32.605968) (xy 418.78813 -32.5765) (xy 418.837713 -32.553859)
			(xy 418.890014 -32.538504) (xy 418.943968 -32.53075) (xy 418.971222 -32.530288) (xy 418.986015 -32.530419)
			(xy 419.015513 -32.532711) (xy 419.03015 -32.53486) (xy 419.041072 -32.536638) (xy 419.062408 -32.530542)
			(xy 419.129718 -32.473138) (xy 419.13767 -32.465533) (xy 419.146763 -32.445522) (xy 419.147244 -32.43453)
			(xy 419.147244 -32.130238) (xy 419.146759 -32.119247) (xy 419.137668 -32.099236) (xy 419.129718 -32.09163)
			(xy 419.062408 -32.034226) (xy 419.041072 -32.02813) (xy 419.03015 -32.029908) (xy 419.015512 -32.032049)
			(xy 418.986015 -32.034337) (xy 418.971222 -32.03448) (xy 418.943966 -32.034075) (xy 418.890009 -32.02632)
			(xy 418.837704 -32.010964) (xy 418.788118 -31.988321) (xy 418.742258 -31.958852) (xy 418.70106 -31.923155)
			(xy 418.665361 -31.881959) (xy 418.635889 -31.836102) (xy 418.613243 -31.786516) (xy 418.597885 -31.734213)
			(xy 418.590127 -31.680256) (xy 416.827763 -31.680256) (xy 416.803109 -31.700773) (xy 416.755503 -31.729827)
			(xy 416.704174 -31.751639) (xy 416.650217 -31.765745) (xy 416.59478 -31.771845) (xy 416.539046 -31.769808)
			(xy 416.484203 -31.759678) (xy 416.431419 -31.741671) (xy 416.381819 -31.71617) (xy 416.336461 -31.683719)
			(xy 416.296312 -31.64501) (xy 416.262226 -31.600867) (xy 416.23493 -31.552232) (xy 416.215007 -31.500141)
			(xy 416.202881 -31.445704) (xy 416.19881 -31.390082) (xy 414.930336 -31.390082) (xy 414.929827 -31.417968)
			(xy 414.921707 -31.473144) (xy 414.905639 -31.526551) (xy 414.881967 -31.577048) (xy 414.851194 -31.623561)
			(xy 414.813977 -31.665098) (xy 414.771109 -31.700773) (xy 414.723503 -31.729827) (xy 414.672174 -31.751639)
			(xy 414.618217 -31.765745) (xy 414.56278 -31.771845) (xy 414.507046 -31.769808) (xy 414.452203 -31.759678)
			(xy 414.399419 -31.741671) (xy 414.349819 -31.71617) (xy 414.304461 -31.683719) (xy 414.264312 -31.64501)
			(xy 414.230226 -31.600867) (xy 414.20293 -31.552232) (xy 414.183007 -31.500141) (xy 414.170881 -31.445704)
			(xy 414.16681 -31.390082) (xy 412.374156 -31.390082) (xy 412.39095 -31.408825) (xy 412.421723 -31.455338)
			(xy 412.445395 -31.505835) (xy 412.461463 -31.559242) (xy 412.469583 -31.614418) (xy 412.470092 -31.642304)
			(xy 412.469583 -31.67019) (xy 412.461463 -31.725366) (xy 412.445395 -31.778773) (xy 412.421723 -31.82927)
			(xy 412.39095 -31.875783) (xy 412.353733 -31.91732) (xy 412.310865 -31.952995) (xy 412.263259 -31.982049)
			(xy 412.21193 -32.003861) (xy 412.157973 -32.017967) (xy 412.102536 -32.024067) (xy 412.046802 -32.02203)
			(xy 411.991959 -32.0119) (xy 411.939175 -31.993893) (xy 411.889575 -31.968392) (xy 411.844217 -31.935941)
			(xy 411.804068 -31.897232) (xy 411.769982 -31.853089) (xy 411.742686 -31.804454) (xy 411.722763 -31.752363)
			(xy 411.710637 -31.697926) (xy 411.706566 -31.642304) (xy 410.234583 -31.642304) (xy 410.219036 -31.660245)
			(xy 410.17784 -31.69594) (xy 410.131983 -31.725409) (xy 410.082399 -31.748052) (xy 410.030098 -31.763408)
			(xy 409.976143 -31.771164) (xy 409.948888 -31.77159) (xy 409.946094 -31.77159) (xy 409.936127 -31.772065)
			(xy 409.917686 -31.779636) (xy 409.91028 -31.786322) (xy 409.858972 -31.837122) (xy 409.852121 -31.844518)
			(xy 409.844383 -31.863117) (xy 409.843986 -31.87319) (xy 409.843986 -32.707072) (xy 409.844422 -32.717137)
			(xy 409.852153 -32.735724) (xy 409.858972 -32.74314) (xy 409.91028 -32.79394) (xy 409.91769 -32.800623)
			(xy 409.936126 -32.808206) (xy 409.946094 -32.808672) (xy 409.948888 -32.808672) (xy 409.976143 -32.809134)
			(xy 410.030098 -32.81689) (xy 410.0824 -32.832246) (xy 410.131984 -32.854889) (xy 410.177841 -32.884358)
			(xy 410.219038 -32.920054) (xy 410.254735 -32.961249) (xy 410.284205 -33.007105) (xy 410.30685 -33.056689)
			(xy 410.322207 -33.10899) (xy 410.329965 -33.162945) (xy 410.329965 -33.19018) (xy 411.974028 -33.19018)
			(xy 411.978099 -33.134558) (xy 411.990225 -33.080121) (xy 412.010148 -33.02803) (xy 412.037444 -32.979395)
			(xy 412.07153 -32.935252) (xy 412.111679 -32.896543) (xy 412.157037 -32.864092) (xy 412.206637 -32.838591)
			(xy 412.259421 -32.820584) (xy 412.314264 -32.810454) (xy 412.369998 -32.808417) (xy 412.425435 -32.814517)
			(xy 412.479392 -32.828623) (xy 412.530721 -32.850435) (xy 412.578327 -32.879489) (xy 412.621195 -32.915164)
			(xy 412.658412 -32.956701) (xy 412.689185 -33.003214) (xy 412.712857 -33.053711) (xy 412.728925 -33.107118)
			(xy 412.737045 -33.162294) (xy 412.737554 -33.19018) (xy 414.16681 -33.19018) (xy 414.170881 -33.134558)
			(xy 414.183007 -33.080121) (xy 414.20293 -33.02803) (xy 414.230226 -32.979395) (xy 414.264312 -32.935252)
			(xy 414.304461 -32.896543) (xy 414.349819 -32.864092) (xy 414.399419 -32.838591) (xy 414.452203 -32.820584)
			(xy 414.507046 -32.810454) (xy 414.56278 -32.808417) (xy 414.618217 -32.814517) (xy 414.672174 -32.828623)
			(xy 414.723503 -32.850435) (xy 414.771109 -32.879489) (xy 414.813977 -32.915164) (xy 414.851194 -32.956701)
			(xy 414.881967 -33.003214) (xy 414.905639 -33.053711) (xy 414.921707 -33.107118) (xy 414.929827 -33.162294)
			(xy 414.930336 -33.19018) (xy 416.19881 -33.19018) (xy 416.202881 -33.134558) (xy 416.215007 -33.080121)
			(xy 416.23493 -33.02803) (xy 416.262226 -32.979395) (xy 416.296312 -32.935252) (xy 416.336461 -32.896543)
			(xy 416.381819 -32.864092) (xy 416.431419 -32.838591) (xy 416.484203 -32.820584) (xy 416.539046 -32.810454)
			(xy 416.59478 -32.808417) (xy 416.650217 -32.814517) (xy 416.704174 -32.828623) (xy 416.755503 -32.850435)
			(xy 416.803109 -32.879489) (xy 416.845977 -32.915164) (xy 416.883194 -32.956701) (xy 416.913967 -33.003214)
			(xy 416.937639 -33.053711) (xy 416.953707 -33.107118) (xy 416.961827 -33.162294) (xy 416.962336 -33.19018)
			(xy 416.961827 -33.218066) (xy 416.953707 -33.273242) (xy 416.937639 -33.326649) (xy 416.913967 -33.377146)
			(xy 416.883194 -33.423659) (xy 416.845977 -33.465196) (xy 416.803109 -33.500871) (xy 416.755503 -33.529925)
			(xy 416.704174 -33.551737) (xy 416.650217 -33.565843) (xy 416.59478 -33.571943) (xy 416.539046 -33.569906)
			(xy 416.484203 -33.559776) (xy 416.431419 -33.541769) (xy 416.381819 -33.516268) (xy 416.336461 -33.483817)
			(xy 416.296312 -33.445108) (xy 416.262226 -33.400965) (xy 416.23493 -33.35233) (xy 416.215007 -33.300239)
			(xy 416.202881 -33.245802) (xy 416.19881 -33.19018) (xy 414.930336 -33.19018) (xy 414.929827 -33.218066)
			(xy 414.921707 -33.273242) (xy 414.905639 -33.326649) (xy 414.881967 -33.377146) (xy 414.851194 -33.423659)
			(xy 414.813977 -33.465196) (xy 414.771109 -33.500871) (xy 414.723503 -33.529925) (xy 414.672174 -33.551737)
			(xy 414.618217 -33.565843) (xy 414.56278 -33.571943) (xy 414.507046 -33.569906) (xy 414.452203 -33.559776)
			(xy 414.399419 -33.541769) (xy 414.349819 -33.516268) (xy 414.304461 -33.483817) (xy 414.264312 -33.445108)
			(xy 414.230226 -33.400965) (xy 414.20293 -33.35233) (xy 414.183007 -33.300239) (xy 414.170881 -33.245802)
			(xy 414.16681 -33.19018) (xy 412.737554 -33.19018) (xy 412.737045 -33.218066) (xy 412.728925 -33.273242)
			(xy 412.712857 -33.326649) (xy 412.689185 -33.377146) (xy 412.658412 -33.423659) (xy 412.621195 -33.465196)
			(xy 412.578327 -33.500871) (xy 412.530721 -33.529925) (xy 412.479392 -33.551737) (xy 412.425435 -33.565843)
			(xy 412.369998 -33.571943) (xy 412.314264 -33.569906) (xy 412.259421 -33.559776) (xy 412.206637 -33.541769)
			(xy 412.157037 -33.516268) (xy 412.111679 -33.483817) (xy 412.07153 -33.445108) (xy 412.037444 -33.400965)
			(xy 412.010148 -33.35233) (xy 411.990225 -33.300239) (xy 411.978099 -33.245802) (xy 411.974028 -33.19018)
			(xy 410.329965 -33.19018) (xy 410.329965 -33.217455) (xy 410.322207 -33.27141) (xy 410.30685 -33.323711)
			(xy 410.284205 -33.373295) (xy 410.254735 -33.419151) (xy 410.219038 -33.460346) (xy 410.177841 -33.496042)
			(xy 410.131984 -33.525511) (xy 410.0824 -33.548154) (xy 410.030098 -33.56351) (xy 409.976143 -33.571266)
			(xy 409.948888 -33.571688) (xy 409.946094 -33.571688) (xy 409.936127 -33.572163) (xy 409.917686 -33.579734)
			(xy 409.91028 -33.58642) (xy 409.858972 -33.63722) (xy 409.852121 -33.644616) (xy 409.844382 -33.663215)
			(xy 409.843986 -33.673288) (xy 409.843986 -34.506916) (xy 409.844411 -34.516985) (xy 409.852128 -34.535587)
			(xy 409.858972 -34.542984) (xy 409.91028 -34.593784) (xy 409.917688 -34.600473) (xy 409.936124 -34.608065)
			(xy 409.946094 -34.608516) (xy 409.948888 -34.608516) (xy 409.97614 -34.608978) (xy 410.030089 -34.616734)
			(xy 410.082385 -34.632088) (xy 410.131963 -34.654728) (xy 410.177815 -34.684194) (xy 410.219006 -34.719885)
			(xy 410.254699 -34.761076) (xy 410.284166 -34.806926) (xy 410.306808 -34.856504) (xy 410.322164 -34.9088)
			(xy 410.329921 -34.962748) (xy 410.329921 -34.990024) (xy 411.972758 -34.990024) (xy 411.976829 -34.934402)
			(xy 411.988955 -34.879965) (xy 412.008878 -34.827874) (xy 412.036174 -34.779239) (xy 412.07026 -34.735096)
			(xy 412.110409 -34.696387) (xy 412.155767 -34.663936) (xy 412.205367 -34.638435) (xy 412.258151 -34.620428)
			(xy 412.312994 -34.610298) (xy 412.368728 -34.608261) (xy 412.424165 -34.614361) (xy 412.478122 -34.628467)
			(xy 412.529451 -34.650279) (xy 412.577057 -34.679333) (xy 412.619925 -34.715008) (xy 412.657142 -34.756545)
			(xy 412.687915 -34.803058) (xy 412.711587 -34.853555) (xy 412.727655 -34.906962) (xy 412.735775 -34.962138)
			(xy 412.736284 -34.990024) (xy 413.300924 -34.990024) (xy 413.304995 -34.934402) (xy 413.317121 -34.879965)
			(xy 413.337044 -34.827874) (xy 413.36434 -34.779239) (xy 413.398426 -34.735096) (xy 413.438575 -34.696387)
			(xy 413.483933 -34.663936) (xy 413.533533 -34.638435) (xy 413.586317 -34.620428) (xy 413.64116 -34.610298)
			(xy 413.696894 -34.608261) (xy 413.752331 -34.614361) (xy 413.806288 -34.628467) (xy 413.857617 -34.650279)
			(xy 413.905223 -34.679333) (xy 413.948091 -34.715008) (xy 413.985308 -34.756545) (xy 414.016081 -34.803058)
			(xy 414.039753 -34.853555) (xy 414.055821 -34.906962) (xy 414.063941 -34.962138) (xy 414.06445 -34.990024)
			(xy 416.19881 -34.990024) (xy 416.202881 -34.934402) (xy 416.215007 -34.879965) (xy 416.23493 -34.827874)
			(xy 416.262226 -34.779239) (xy 416.296312 -34.735096) (xy 416.336461 -34.696387) (xy 416.381819 -34.663936)
			(xy 416.431419 -34.638435) (xy 416.484203 -34.620428) (xy 416.539046 -34.610298) (xy 416.59478 -34.608261)
			(xy 416.650217 -34.614361) (xy 416.704174 -34.628467) (xy 416.755503 -34.650279) (xy 416.803109 -34.679333)
			(xy 416.845977 -34.715008) (xy 416.883194 -34.756545) (xy 416.913967 -34.803058) (xy 416.937639 -34.853555)
			(xy 416.953707 -34.906962) (xy 416.961827 -34.962138) (xy 416.962336 -34.990024) (xy 416.961827 -35.01791)
			(xy 416.953707 -35.073086) (xy 416.937639 -35.126493) (xy 416.913967 -35.17699) (xy 416.883194 -35.223503)
			(xy 416.845977 -35.26504) (xy 416.803109 -35.300715) (xy 416.755503 -35.329769) (xy 416.704174 -35.351581)
			(xy 416.650217 -35.365687) (xy 416.59478 -35.371787) (xy 416.539046 -35.36975) (xy 416.484203 -35.35962)
			(xy 416.431419 -35.341613) (xy 416.381819 -35.316112) (xy 416.336461 -35.283661) (xy 416.296312 -35.244952)
			(xy 416.262226 -35.200809) (xy 416.23493 -35.152174) (xy 416.215007 -35.100083) (xy 416.202881 -35.045646)
			(xy 416.19881 -34.990024) (xy 414.06445 -34.990024) (xy 414.063941 -35.01791) (xy 414.055821 -35.073086)
			(xy 414.039753 -35.126493) (xy 414.016081 -35.17699) (xy 413.985308 -35.223503) (xy 413.948091 -35.26504)
			(xy 413.905223 -35.300715) (xy 413.857617 -35.329769) (xy 413.806288 -35.351581) (xy 413.752331 -35.365687)
			(xy 413.696894 -35.371787) (xy 413.64116 -35.36975) (xy 413.586317 -35.35962) (xy 413.533533 -35.341613)
			(xy 413.483933 -35.316112) (xy 413.438575 -35.283661) (xy 413.398426 -35.244952) (xy 413.36434 -35.200809)
			(xy 413.337044 -35.152174) (xy 413.317121 -35.100083) (xy 413.304995 -35.045646) (xy 413.300924 -34.990024)
			(xy 412.736284 -34.990024) (xy 412.735775 -35.01791) (xy 412.727655 -35.073086) (xy 412.711587 -35.126493)
			(xy 412.687915 -35.17699) (xy 412.657142 -35.223503) (xy 412.619925 -35.26504) (xy 412.577057 -35.300715)
			(xy 412.529451 -35.329769) (xy 412.478122 -35.351581) (xy 412.424165 -35.365687) (xy 412.368728 -35.371787)
			(xy 412.312994 -35.36975) (xy 412.258151 -35.35962) (xy 412.205367 -35.341613) (xy 412.155767 -35.316112)
			(xy 412.110409 -35.283661) (xy 412.07026 -35.244952) (xy 412.036174 -35.200809) (xy 412.008878 -35.152174)
			(xy 411.988955 -35.100083) (xy 411.976829 -35.045646) (xy 411.972758 -34.990024) (xy 410.329921 -34.990024)
			(xy 410.329921 -35.017252) (xy 410.322164 -35.0712) (xy 410.306808 -35.123496) (xy 410.284166 -35.173074)
			(xy 410.254699 -35.218924) (xy 410.219006 -35.260115) (xy 410.177815 -35.295806) (xy 410.131963 -35.325272)
			(xy 410.082385 -35.347912) (xy 410.030089 -35.363266) (xy 409.97614 -35.371022) (xy 409.948888 -35.371532)
			(xy 409.946094 -35.371532) (xy 409.936128 -35.372008) (xy 409.91769 -35.379584) (xy 409.91028 -35.386264)
			(xy 409.858972 -35.437064) (xy 409.852128 -35.444462) (xy 409.844405 -35.463062) (xy 409.843986 -35.473132)
			(xy 409.843986 -38.193435) (xy 411.398285 -38.193435) (xy 411.398285 -38.106565) (xy 411.406301 -38.020065)
			(xy 411.422263 -37.934674) (xy 411.446035 -37.85112) (xy 411.477415 -37.770115) (xy 411.516136 -37.692352)
			(xy 411.561866 -37.618492) (xy 411.614216 -37.549167) (xy 411.672738 -37.484968) (xy 411.736935 -37.426443)
			(xy 411.806258 -37.37409) (xy 411.880115 -37.328356) (xy 411.957877 -37.289632) (xy 412.03888 -37.258248)
			(xy 412.122433 -37.234472) (xy 412.207824 -37.218506) (xy 412.294323 -37.210487) (xy 412.337758 -37.209984)
			(xy 412.415736 -37.209984) (xy 412.425748 -37.209541) (xy 412.444244 -37.201867) (xy 412.458396 -37.1877)
			(xy 412.466051 -37.169196) (xy 412.466536 -37.159184) (xy 412.466536 -37.151564) (xy 412.462218 -37.137594)
			(xy 412.458154 -37.131244) (xy 412.434754 -37.094768) (xy 412.393762 -37.018407) (xy 412.359777 -36.938681)
			(xy 412.333071 -36.856231) (xy 412.313861 -36.771719) (xy 412.3023 -36.685826) (xy 412.298481 -36.599243)
			(xy 412.302436 -36.512665) (xy 412.314131 -36.42679) (xy 412.333474 -36.342309) (xy 412.360309 -36.2599)
			(xy 412.394419 -36.180228) (xy 412.43553 -36.103931) (xy 412.483312 -36.031626) (xy 412.537381 -35.963892)
			(xy 412.597301 -35.901275) (xy 412.66259 -35.844278) (xy 412.732723 -35.793361) (xy 412.807136 -35.748932)
			(xy 412.885231 -35.711349) (xy 412.966379 -35.680915) (xy 413.049928 -35.657873) (xy 413.135205 -35.642411)
			(xy 413.221524 -35.634651) (xy 413.264858 -35.634168) (xy 413.265112 -35.634168) (xy 413.308444 -35.634637)
			(xy 413.394759 -35.64241) (xy 413.48003 -35.657885) (xy 413.563572 -35.680936) (xy 413.644713 -35.711379)
			(xy 413.722801 -35.748968) (xy 413.797207 -35.793401) (xy 413.867334 -35.844322) (xy 413.904462 -35.876738)
			(xy 419.017194 -35.876738) (xy 419.021265 -35.821116) (xy 419.033391 -35.766679) (xy 419.053314 -35.714588)
			(xy 419.08061 -35.665953) (xy 419.114696 -35.62181) (xy 419.154845 -35.583101) (xy 419.200203 -35.55065)
			(xy 419.249803 -35.525149) (xy 419.302587 -35.507142) (xy 419.35743 -35.497012) (xy 419.413164 -35.494975)
			(xy 419.468601 -35.501075) (xy 419.522558 -35.515181) (xy 419.573887 -35.536993) (xy 419.621493 -35.566047)
			(xy 419.664361 -35.601722) (xy 419.701578 -35.643259) (xy 419.732351 -35.689772) (xy 419.756023 -35.740269)
			(xy 419.772091 -35.793676) (xy 419.780211 -35.848852) (xy 419.78072 -35.876738) (xy 419.780211 -35.904624)
			(xy 419.772091 -35.9598) (xy 419.756023 -36.013207) (xy 419.732351 -36.063704) (xy 419.701578 -36.110217)
			(xy 419.664361 -36.151754) (xy 419.621493 -36.187429) (xy 419.573887 -36.216483) (xy 419.522558 -36.238295)
			(xy 419.468601 -36.252401) (xy 419.413164 -36.258501) (xy 419.35743 -36.256464) (xy 419.302587 -36.246334)
			(xy 419.249803 -36.228327) (xy 419.200203 -36.202826) (xy 419.154845 -36.170375) (xy 419.114696 -36.131666)
			(xy 419.08061 -36.087523) (xy 419.053314 -36.038888) (xy 419.033391 -35.986797) (xy 419.021265 -35.93236)
			(xy 419.017194 -35.876738) (xy 413.904462 -35.876738) (xy 413.932617 -35.90132) (xy 413.992532 -35.963936)
			(xy 414.046597 -36.031669) (xy 414.094376 -36.103972) (xy 414.135486 -36.180265) (xy 414.169596 -36.259934)
			(xy 414.196432 -36.342338) (xy 414.215778 -36.426815) (xy 414.227479 -36.512686) (xy 414.228725 -36.539928)
			(xy 420.838612 -36.539928) (xy 420.838612 -36.479992) (xy 420.846435 -36.42057) (xy 420.861948 -36.362677)
			(xy 420.884884 -36.307304) (xy 420.914851 -36.255398) (xy 420.951338 -36.207848) (xy 420.993718 -36.165468)
			(xy 421.041268 -36.128981) (xy 421.093174 -36.099014) (xy 421.148547 -36.076078) (xy 421.20644 -36.060565)
			(xy 421.265862 -36.052742) (xy 421.325798 -36.052742) (xy 421.38522 -36.060565) (xy 421.443113 -36.076078)
			(xy 421.498486 -36.099014) (xy 421.550392 -36.128981) (xy 421.597942 -36.165468) (xy 421.640322 -36.207848)
			(xy 421.676809 -36.255398) (xy 421.706776 -36.307304) (xy 421.729712 -36.362677) (xy 421.745225 -36.42057)
			(xy 421.753048 -36.479992) (xy 421.753538 -36.50996) (xy 421.753048 -36.539928) (xy 421.745225 -36.59935)
			(xy 421.729712 -36.657243) (xy 421.706776 -36.712616) (xy 421.676809 -36.764522) (xy 421.640322 -36.812072)
			(xy 421.597942 -36.854452) (xy 421.550392 -36.890939) (xy 421.498486 -36.920906) (xy 421.443113 -36.943842)
			(xy 421.38522 -36.959355) (xy 421.325798 -36.967178) (xy 421.265862 -36.967178) (xy 421.20644 -36.959355)
			(xy 421.148547 -36.943842) (xy 421.093174 -36.920906) (xy 421.041268 -36.890939) (xy 420.993718 -36.854452)
			(xy 420.951338 -36.812072) (xy 420.914851 -36.764522) (xy 420.884884 -36.712616) (xy 420.861948 -36.657243)
			(xy 420.846435 -36.59935) (xy 420.838612 -36.539928) (xy 414.228725 -36.539928) (xy 414.23144 -36.599259)
			(xy 414.22763 -36.68584) (xy 414.216078 -36.77173) (xy 414.196879 -36.856241) (xy 414.170187 -36.938692)
			(xy 414.136215 -37.01842) (xy 414.095238 -37.094784) (xy 414.071816 -37.131244) (xy 414.063434 -37.143944)
			(xy 414.063434 -37.159184) (xy 414.063833 -37.169209) (xy 414.071504 -37.187732) (xy 414.085683 -37.201906)
			(xy 414.104209 -37.20957) (xy 414.114234 -37.209984) (xy 414.191958 -37.209984) (xy 414.2354 -37.210393)
			(xy 414.321913 -37.218406) (xy 414.407318 -37.234367) (xy 414.490886 -37.258141) (xy 414.571903 -37.289524)
			(xy 414.64968 -37.328249) (xy 414.723551 -37.373985) (xy 414.792887 -37.426343) (xy 414.84644 -37.47516)
			(xy 418.059106 -37.47516) (xy 418.063177 -37.419538) (xy 418.075303 -37.365101) (xy 418.095226 -37.31301)
			(xy 418.122522 -37.264375) (xy 418.156608 -37.220232) (xy 418.196757 -37.181523) (xy 418.242115 -37.149072)
			(xy 418.291715 -37.123571) (xy 418.344499 -37.105564) (xy 418.399342 -37.095434) (xy 418.455076 -37.093397)
			(xy 418.510513 -37.099497) (xy 418.56447 -37.113603) (xy 418.615799 -37.135415) (xy 418.663405 -37.164469)
			(xy 418.706273 -37.200144) (xy 418.74349 -37.241681) (xy 418.774263 -37.288194) (xy 418.797935 -37.338691)
			(xy 418.814003 -37.392098) (xy 418.822123 -37.447274) (xy 418.822632 -37.47516) (xy 418.822123 -37.503046)
			(xy 418.814003 -37.558222) (xy 418.797935 -37.611629) (xy 418.774263 -37.662126) (xy 418.754283 -37.692326)
			(xy 420.173132 -37.692326) (xy 420.173132 -37.63239) (xy 420.180955 -37.572968) (xy 420.196468 -37.515075)
			(xy 420.219404 -37.459702) (xy 420.249371 -37.407796) (xy 420.285858 -37.360246) (xy 420.328238 -37.317866)
			(xy 420.375788 -37.281379) (xy 420.427694 -37.251412) (xy 420.483067 -37.228476) (xy 420.54096 -37.212963)
			(xy 420.600382 -37.20514) (xy 420.660318 -37.20514) (xy 420.71974 -37.212963) (xy 420.777633 -37.228476)
			(xy 420.833006 -37.251412) (xy 420.884912 -37.281379) (xy 420.932462 -37.317866) (xy 420.974842 -37.360246)
			(xy 421.011329 -37.407796) (xy 421.041296 -37.459702) (xy 421.064232 -37.515075) (xy 421.079745 -37.572968)
			(xy 421.087568 -37.63239) (xy 421.088058 -37.662358) (xy 421.087568 -37.692326) (xy 421.079745 -37.751748)
			(xy 421.064232 -37.809641) (xy 421.041296 -37.865014) (xy 421.011329 -37.91692) (xy 420.974842 -37.96447)
			(xy 420.932462 -38.00685) (xy 420.884912 -38.043337) (xy 420.833006 -38.073304) (xy 420.777633 -38.09624)
			(xy 420.71974 -38.111753) (xy 420.660318 -38.119576) (xy 420.600382 -38.119576) (xy 420.54096 -38.111753)
			(xy 420.483067 -38.09624) (xy 420.427694 -38.073304) (xy 420.375788 -38.043337) (xy 420.328238 -38.00685)
			(xy 420.285858 -37.96447) (xy 420.249371 -37.91692) (xy 420.219404 -37.865014) (xy 420.196468 -37.809641)
			(xy 420.180955 -37.751748) (xy 420.173132 -37.692326) (xy 418.754283 -37.692326) (xy 418.74349 -37.708639)
			(xy 418.706273 -37.750176) (xy 418.663405 -37.785851) (xy 418.615799 -37.814905) (xy 418.56447 -37.836717)
			(xy 418.510513 -37.850823) (xy 418.455076 -37.856923) (xy 418.399342 -37.854886) (xy 418.344499 -37.844756)
			(xy 418.291715 -37.826749) (xy 418.242115 -37.801248) (xy 418.196757 -37.768797) (xy 418.156608 -37.730088)
			(xy 418.122522 -37.685945) (xy 418.095226 -37.63731) (xy 418.075303 -37.585219) (xy 418.063177 -37.530782)
			(xy 418.059106 -37.47516) (xy 414.84644 -37.47516) (xy 414.857096 -37.484874) (xy 414.915631 -37.549081)
			(xy 414.967991 -37.618414) (xy 415.01373 -37.692284) (xy 415.052459 -37.770058) (xy 415.083846 -37.851074)
			(xy 415.107623 -37.934641) (xy 415.123588 -38.020045) (xy 415.131605 -38.106558) (xy 415.131605 -38.193442)
			(xy 415.123588 -38.279955) (xy 415.107623 -38.365359) (xy 415.083846 -38.448926) (xy 415.067484 -38.49116)
			(xy 418.059106 -38.49116) (xy 418.063177 -38.435538) (xy 418.075303 -38.381101) (xy 418.095226 -38.32901)
			(xy 418.122522 -38.280375) (xy 418.156608 -38.236232) (xy 418.196757 -38.197523) (xy 418.242115 -38.165072)
			(xy 418.291715 -38.139571) (xy 418.344499 -38.121564) (xy 418.399342 -38.111434) (xy 418.455076 -38.109397)
			(xy 418.510513 -38.115497) (xy 418.56447 -38.129603) (xy 418.615799 -38.151415) (xy 418.663405 -38.180469)
			(xy 418.706273 -38.216144) (xy 418.74349 -38.257681) (xy 418.774263 -38.304194) (xy 418.797935 -38.354691)
			(xy 418.814003 -38.408098) (xy 418.822123 -38.463274) (xy 418.822632 -38.49116) (xy 418.822123 -38.519046)
			(xy 418.814003 -38.574222) (xy 418.797935 -38.627629) (xy 418.774263 -38.678126) (xy 418.758985 -38.701218)
			(xy 421.737534 -38.701218) (xy 421.741605 -38.645596) (xy 421.753731 -38.591159) (xy 421.773654 -38.539068)
			(xy 421.80095 -38.490433) (xy 421.835036 -38.44629) (xy 421.875185 -38.407581) (xy 421.920543 -38.37513)
			(xy 421.970143 -38.349629) (xy 422.022927 -38.331622) (xy 422.07777 -38.321492) (xy 422.133504 -38.319455)
			(xy 422.188941 -38.325555) (xy 422.242898 -38.339661) (xy 422.294227 -38.361473) (xy 422.341833 -38.390527)
			(xy 422.384701 -38.426202) (xy 422.421918 -38.467739) (xy 422.452691 -38.514252) (xy 422.476363 -38.564749)
			(xy 422.492431 -38.618156) (xy 422.500551 -38.673332) (xy 422.50106 -38.701218) (xy 422.500551 -38.729104)
			(xy 422.492431 -38.78428) (xy 422.476363 -38.837687) (xy 422.452691 -38.888184) (xy 422.421918 -38.934697)
			(xy 422.384701 -38.976234) (xy 422.341833 -39.011909) (xy 422.294227 -39.040963) (xy 422.242898 -39.062775)
			(xy 422.188941 -39.076881) (xy 422.133504 -39.082981) (xy 422.07777 -39.080944) (xy 422.022927 -39.070814)
			(xy 421.970143 -39.052807) (xy 421.920543 -39.027306) (xy 421.875185 -38.994855) (xy 421.835036 -38.956146)
			(xy 421.80095 -38.912003) (xy 421.773654 -38.863368) (xy 421.753731 -38.811277) (xy 421.741605 -38.75684)
			(xy 421.737534 -38.701218) (xy 418.758985 -38.701218) (xy 418.74349 -38.724639) (xy 418.706273 -38.766176)
			(xy 418.663405 -38.801851) (xy 418.615799 -38.830905) (xy 418.56447 -38.852717) (xy 418.510513 -38.866823)
			(xy 418.455076 -38.872923) (xy 418.399342 -38.870886) (xy 418.344499 -38.860756) (xy 418.291715 -38.842749)
			(xy 418.242115 -38.817248) (xy 418.196757 -38.784797) (xy 418.156608 -38.746088) (xy 418.122522 -38.701945)
			(xy 418.095226 -38.65331) (xy 418.075303 -38.601219) (xy 418.063177 -38.546782) (xy 418.059106 -38.49116)
			(xy 415.067484 -38.49116) (xy 415.052459 -38.529942) (xy 415.01373 -38.607716) (xy 414.967991 -38.681586)
			(xy 414.915631 -38.750919) (xy 414.857096 -38.815126) (xy 414.792887 -38.873657) (xy 414.723551 -38.926015)
			(xy 414.64968 -38.971751) (xy 414.571903 -39.010476) (xy 414.490886 -39.041859) (xy 414.407318 -39.065633)
			(xy 414.321913 -39.081594) (xy 414.2354 -39.089607) (xy 414.191958 -39.090092) (xy 412.337758 -39.090092)
			(xy 412.294323 -39.089513) (xy 412.207824 -39.081494) (xy 412.122433 -39.065528) (xy 412.03888 -39.041752)
			(xy 411.957877 -39.010368) (xy 411.880115 -38.971644) (xy 411.806258 -38.92591) (xy 411.736935 -38.873557)
			(xy 411.672738 -38.815032) (xy 411.614216 -38.750833) (xy 411.561866 -38.681508) (xy 411.516136 -38.607648)
			(xy 411.477415 -38.529885) (xy 411.446035 -38.44888) (xy 411.422263 -38.365326) (xy 411.406301 -38.279935)
			(xy 411.398285 -38.193435) (xy 409.843986 -38.193435) (xy 409.843986 -42.849038) (xy 421.191942 -42.849038)
			(xy 421.196013 -42.793416) (xy 421.208139 -42.738979) (xy 421.228062 -42.686888) (xy 421.255358 -42.638253)
			(xy 421.289444 -42.59411) (xy 421.329593 -42.555401) (xy 421.374951 -42.52295) (xy 421.424551 -42.497449)
			(xy 421.477335 -42.479442) (xy 421.532178 -42.469312) (xy 421.587912 -42.467275) (xy 421.643349 -42.473375)
			(xy 421.697306 -42.487481) (xy 421.748635 -42.509293) (xy 421.796241 -42.538347) (xy 421.839109 -42.574022)
			(xy 421.876326 -42.615559) (xy 421.907099 -42.662072) (xy 421.930771 -42.712569) (xy 421.946839 -42.765976)
			(xy 421.954959 -42.821152) (xy 421.955468 -42.849038) (xy 421.954959 -42.876924) (xy 421.946839 -42.9321)
			(xy 421.930771 -42.985507) (xy 421.907099 -43.036004) (xy 421.876326 -43.082517) (xy 421.839109 -43.124054)
			(xy 421.796241 -43.159729) (xy 421.748635 -43.188783) (xy 421.697306 -43.210595) (xy 421.643349 -43.224701)
			(xy 421.587912 -43.230801) (xy 421.532178 -43.228764) (xy 421.477335 -43.218634) (xy 421.424551 -43.200627)
			(xy 421.374951 -43.175126) (xy 421.329593 -43.142675) (xy 421.289444 -43.103966) (xy 421.255358 -43.059823)
			(xy 421.228062 -43.011188) (xy 421.208139 -42.959097) (xy 421.196013 -42.90466) (xy 421.191942 -42.849038)
			(xy 409.843986 -42.849038) (xy 409.843986 -43.719242) (xy 409.84445 -43.729117) (xy 409.851898 -43.747411)
			(xy 409.858464 -43.754802) (xy 409.858718 -43.755056) (xy 410.336746 -44.233084) (xy 410.337254 -44.233592)
			(xy 410.344637 -44.24017) (xy 410.362936 -44.247614) (xy 410.372814 -44.24807)
		)
		(stroke
			(width 0)
			(type solid)
		)
		(fill yes)
		(layer "B.Cu")
		(net "P12V_SSD14")
	)
	(gr_poly
		(pts
			(xy 304.414682 -44.24807) (xy 304.424856 -44.247619) (xy 304.443602 -44.239706) (xy 304.45779 -44.225119)
			(xy 304.461926 -44.215812) (xy 304.502312 -44.112942) (xy 304.495454 -44.082716) (xy 304.48377 -44.072048)
			(xy 304.46108 -44.0503) (xy 304.42127 -44.001665) (xy 304.388485 -43.948043) (xy 304.363339 -43.890442)
			(xy 304.346305 -43.829944) (xy 304.337703 -43.767685) (xy 304.337212 -43.73626) (xy 304.337702 -43.706292)
			(xy 304.345525 -43.64687) (xy 304.361038 -43.588977) (xy 304.383974 -43.533604) (xy 304.413941 -43.481698)
			(xy 304.450428 -43.434148) (xy 304.492808 -43.391768) (xy 304.540358 -43.355281) (xy 304.592264 -43.325314)
			(xy 304.647637 -43.302378) (xy 304.70553 -43.286865) (xy 304.764952 -43.279042) (xy 304.824888 -43.279042)
			(xy 304.88431 -43.286865) (xy 304.942203 -43.302378) (xy 304.997576 -43.325314) (xy 305.049482 -43.355281)
			(xy 305.097032 -43.391768) (xy 305.139412 -43.434148) (xy 305.175899 -43.481698) (xy 305.205866 -43.533604)
			(xy 305.228802 -43.588977) (xy 305.244315 -43.64687) (xy 305.252138 -43.706292) (xy 305.252628 -43.73626)
			(xy 305.252547 -43.748987) (xy 305.251151 -43.774401) (xy 305.249834 -43.78706) (xy 305.250088 -43.78706)
			(xy 305.245879 -43.819423) (xy 305.229472 -43.882589) (xy 305.204258 -43.942782) (xy 305.170748 -43.998784)
			(xy 305.129623 -44.049457) (xy 305.10607 -44.072048) (xy 305.09464 -44.08297) (xy 305.087528 -44.113196)
			(xy 305.127914 -44.215812) (xy 305.13205 -44.225119) (xy 305.146247 -44.239697) (xy 305.164985 -44.247635)
			(xy 305.175158 -44.24807) (xy 306.077366 -44.24807) (xy 306.087239 -44.247601) (xy 306.105522 -44.240142)
			(xy 306.112926 -44.233592) (xy 306.11318 -44.233338) (xy 306.672488 -43.67403) (xy 306.672996 -43.673522)
			(xy 306.67957 -43.666137) (xy 306.687005 -43.647839) (xy 306.687474 -43.637962) (xy 306.687474 -37.58946)
			(xy 306.687046 -37.580071) (xy 306.680302 -37.562545) (xy 306.667725 -37.548601) (xy 306.659534 -37.543994)
			(xy 306.578762 -37.5031) (xy 306.570154 -37.49925) (xy 306.551406 -37.4974) (xy 306.533243 -37.502406)
			(xy 306.525422 -37.507672) (xy 306.500626 -37.525303) (xy 306.44661 -37.553296) (xy 306.388834 -37.57236)
			(xy 306.328766 -37.582009) (xy 306.298346 -37.582602) (xy 306.271091 -37.582142) (xy 306.217136 -37.57439)
			(xy 306.164834 -37.559038) (xy 306.115249 -37.536399) (xy 306.069391 -37.506933) (xy 306.028193 -37.47124)
			(xy 305.992495 -37.430046) (xy 305.963023 -37.384192) (xy 305.940378 -37.334609) (xy 305.92502 -37.282309)
			(xy 305.917261 -37.228355) (xy 305.917261 -37.173845) (xy 305.92502 -37.119891) (xy 305.940378 -37.067591)
			(xy 305.963023 -37.018008) (xy 305.992495 -36.972154) (xy 306.028193 -36.93096) (xy 306.069391 -36.895267)
			(xy 306.115249 -36.865801) (xy 306.164834 -36.843162) (xy 306.217136 -36.82781) (xy 306.271091 -36.820058)
			(xy 306.298346 -36.819586) (xy 306.328764 -36.820181) (xy 306.38883 -36.829841) (xy 306.446602 -36.848908)
			(xy 306.500617 -36.876899) (xy 306.525422 -36.894516) (xy 306.5332 -36.899882) (xy 306.551389 -36.90495)
			(xy 306.570172 -36.903029) (xy 306.578762 -36.899088) (xy 306.659534 -36.858194) (xy 306.667773 -36.853644)
			(xy 306.680398 -36.839702) (xy 306.687116 -36.822134) (xy 306.687474 -36.812728) (xy 306.687474 -35.109658)
			(xy 306.668932 -35.083496) (xy 306.653692 -35.078162) (xy 306.62742 -35.068318) (xy 306.577861 -35.042026)
			(xy 306.532683 -35.008763) (xy 306.49286 -34.969246) (xy 306.475638 -34.947098) (xy 306.470304 -34.939986)
			(xy 306.448206 -34.925254) (xy 306.444256 -34.922819) (xy 306.435698 -34.919235) (xy 306.431188 -34.918142)
			(xy 306.400962 -34.911284) (xy 306.382166 -34.914078) (xy 306.373784 -34.91865) (xy 306.355402 -34.928876)
			(xy 306.317114 -34.946301) (xy 306.29733 -34.953448) (xy 306.273129 -34.96149) (xy 306.223395 -34.972779)
			(xy 306.172715 -34.978477) (xy 306.147216 -34.978848) (xy 306.121716 -34.978488) (xy 306.071034 -34.972796)
			(xy 306.021299 -34.961503) (xy 305.997102 -34.953448) (xy 305.977317 -34.946304) (xy 305.939028 -34.92888)
			(xy 305.920648 -34.91865) (xy 305.912266 -34.914078) (xy 305.89347 -34.911284) (xy 305.863244 -34.918142)
			(xy 305.858724 -34.919206) (xy 305.850159 -34.922786) (xy 305.846226 -34.925254) (xy 305.823874 -34.94024)
			(xy 305.818794 -34.947352) (xy 305.800644 -34.970654) (xy 305.758366 -35.011897) (xy 305.710235 -35.046129)
			(xy 305.657402 -35.072531) (xy 305.601129 -35.090471) (xy 305.542764 -35.099521) (xy 305.513232 -35.100006)
			(xy 305.50231 -35.100006) (xy 305.502056 -35.099752) (xy 305.475341 -35.098515) (xy 305.422629 -35.089492)
			(xy 305.371693 -35.073197) (xy 305.32353 -35.04995) (xy 305.279085 -35.020207) (xy 305.239228 -34.98455)
			(xy 305.20474 -34.943678) (xy 305.176296 -34.89839) (xy 305.154453 -34.849575) (xy 305.13964 -34.798189)
			(xy 305.132146 -34.745237) (xy 305.131724 -34.718498) (xy 305.132187 -34.691246) (xy 305.139945 -34.637297)
			(xy 305.155301 -34.585001) (xy 305.177944 -34.535423) (xy 305.207413 -34.489573) (xy 305.243107 -34.448383)
			(xy 305.2843 -34.412693) (xy 305.330153 -34.383228) (xy 305.379733 -34.36059) (xy 305.43203 -34.345238)
			(xy 305.48598 -34.337485) (xy 305.513232 -34.33699) (xy 305.528025 -34.337133) (xy 305.557522 -34.339422)
			(xy 305.57216 -34.341562) (xy 305.583082 -34.34334) (xy 305.604418 -34.337244) (xy 305.671474 -34.280094)
			(xy 305.679623 -34.27251) (xy 305.689003 -34.25235) (xy 305.689508 -34.241232) (xy 305.689508 -33.93694)
			(xy 305.688943 -33.925833) (xy 305.67959 -33.905682) (xy 305.671474 -33.898078) (xy 305.604418 -33.840928)
			(xy 305.583082 -33.834832) (xy 305.57216 -33.83661) (xy 305.557334 -33.838784) (xy 305.527454 -33.841075)
			(xy 305.51247 -33.841182) (xy 305.512216 -33.841182) (xy 305.485011 -33.840629) (xy 305.431172 -33.832758)
			(xy 305.378996 -33.817318) (xy 305.329545 -33.794621) (xy 305.283819 -33.765127) (xy 305.242749 -33.729436)
			(xy 305.207166 -33.688271) (xy 305.177794 -33.642468) (xy 305.155228 -33.592956) (xy 305.139926 -33.54074)
			(xy 305.132198 -33.48688) (xy 305.131724 -33.459674) (xy 305.132189 -33.432423) (xy 305.139949 -33.378477)
			(xy 305.155308 -33.326184) (xy 305.177952 -33.276609) (xy 305.207422 -33.230762) (xy 305.243116 -33.189575)
			(xy 305.284308 -33.153887) (xy 305.33016 -33.124424) (xy 305.379738 -33.101788) (xy 305.432034 -33.086437)
			(xy 305.485981 -33.078685) (xy 305.513232 -33.078166) (xy 305.513486 -33.078166) (xy 305.542991 -33.078723)
			(xy 305.601296 -33.087817) (xy 305.657508 -33.105775) (xy 305.710286 -33.132169) (xy 305.758374 -33.166371)
			(xy 305.800626 -33.207565) (xy 305.818794 -33.23082) (xy 305.823874 -33.237932) (xy 305.846226 -33.252918)
			(xy 305.850177 -33.255351) (xy 305.858736 -33.258932) (xy 305.863244 -33.26003) (xy 305.89347 -33.266888)
			(xy 305.912266 -33.264094) (xy 305.920648 -33.259522) (xy 305.939031 -33.249298) (xy 305.97732 -33.231876)
			(xy 305.997102 -33.224724) (xy 306.021302 -33.216679) (xy 306.071036 -33.205383) (xy 306.121716 -33.199678)
			(xy 306.147216 -33.199324) (xy 306.172716 -33.199686) (xy 306.223397 -33.205381) (xy 306.273131 -33.216676)
			(xy 306.29733 -33.224724) (xy 306.317114 -33.231869) (xy 306.355403 -33.249294) (xy 306.373784 -33.259522)
			(xy 306.382166 -33.264094) (xy 306.400962 -33.266888) (xy 306.431188 -33.26003) (xy 306.435706 -33.258963)
			(xy 306.444268 -33.255377) (xy 306.448206 -33.252918) (xy 306.470304 -33.238186) (xy 306.475638 -33.231074)
			(xy 306.49284 -33.208909) (xy 306.532666 -33.169393) (xy 306.577851 -33.136135) (xy 306.627419 -33.109855)
			(xy 306.653692 -33.10001) (xy 306.668932 -33.094676) (xy 306.687474 -33.068514) (xy 306.687474 -31.509462)
			(xy 306.668932 -31.4833) (xy 306.653692 -31.477966) (xy 306.62742 -31.468122) (xy 306.57786 -31.44183)
			(xy 306.532682 -31.408568) (xy 306.492859 -31.369051) (xy 306.475638 -31.346902) (xy 306.470304 -31.33979)
			(xy 306.448206 -31.325058) (xy 306.444256 -31.322624) (xy 306.435698 -31.319039) (xy 306.431188 -31.317946)
			(xy 306.400962 -31.311088) (xy 306.382166 -31.313882) (xy 306.373784 -31.318454) (xy 306.355402 -31.32868)
			(xy 306.317113 -31.346105) (xy 306.29733 -31.353252) (xy 306.273129 -31.361294) (xy 306.223395 -31.372583)
			(xy 306.172715 -31.378281) (xy 306.147216 -31.378652) (xy 306.121716 -31.378292) (xy 306.071034 -31.3726)
			(xy 306.021299 -31.361307) (xy 305.997102 -31.353252) (xy 305.977317 -31.346108) (xy 305.939028 -31.328684)
			(xy 305.920648 -31.318454) (xy 305.912266 -31.313882) (xy 305.89347 -31.311088) (xy 305.863244 -31.317946)
			(xy 305.858724 -31.31901) (xy 305.850159 -31.32259) (xy 305.846226 -31.325058) (xy 305.823874 -31.340044)
			(xy 305.818794 -31.347156) (xy 305.800644 -31.370458) (xy 305.758366 -31.411701) (xy 305.710235 -31.445932)
			(xy 305.657401 -31.472333) (xy 305.601129 -31.490274) (xy 305.542764 -31.499323) (xy 305.513232 -31.49981)
			(xy 305.50231 -31.49981) (xy 305.502056 -31.499556) (xy 305.475341 -31.498319) (xy 305.422629 -31.489296)
			(xy 305.371692 -31.473001) (xy 305.32353 -31.449754) (xy 305.279084 -31.420011) (xy 305.239227 -31.384354)
			(xy 305.204738 -31.343482) (xy 305.176294 -31.298195) (xy 305.15445 -31.24938) (xy 305.139636 -31.197993)
			(xy 305.132142 -31.145041) (xy 305.131724 -31.118302) (xy 305.132187 -31.09105) (xy 305.139944 -31.0371)
			(xy 305.1553 -30.984804) (xy 305.177943 -30.935226) (xy 305.207412 -30.889375) (xy 305.243106 -30.848184)
			(xy 305.284299 -30.812494) (xy 305.330152 -30.783029) (xy 305.379732 -30.76039) (xy 305.43203 -30.745038)
			(xy 305.48598 -30.737285) (xy 305.513232 -30.736794) (xy 305.528025 -30.736937) (xy 305.557522 -30.739226)
			(xy 305.57216 -30.741366) (xy 305.583082 -30.743144) (xy 305.604418 -30.737048) (xy 305.671474 -30.679898)
			(xy 305.679624 -30.672314) (xy 305.689006 -30.652155) (xy 305.689508 -30.641036) (xy 305.689508 -30.336744)
			(xy 305.688944 -30.325637) (xy 305.679592 -30.305485) (xy 305.671474 -30.297882) (xy 305.604418 -30.240732)
			(xy 305.583082 -30.234636) (xy 305.57216 -30.236414) (xy 305.557334 -30.238588) (xy 305.527454 -30.240879)
			(xy 305.51247 -30.240986) (xy 305.512216 -30.240986) (xy 305.485011 -30.240433) (xy 305.431171 -30.232563)
			(xy 305.378996 -30.217122) (xy 305.329544 -30.194425) (xy 305.283818 -30.164931) (xy 305.242748 -30.12924)
			(xy 305.207165 -30.088075) (xy 305.177792 -30.042272) (xy 305.155225 -29.992761) (xy 305.139922 -29.940545)
			(xy 305.132194 -29.886684) (xy 305.131724 -29.859478) (xy 305.132189 -29.832227) (xy 305.139949 -29.77828)
			(xy 305.155307 -29.725987) (xy 305.177951 -29.676411) (xy 305.20742 -29.630563) (xy 305.243114 -29.589376)
			(xy 305.284307 -29.553688) (xy 305.330159 -29.524225) (xy 305.379737 -29.501588) (xy 305.432033 -29.486237)
			(xy 305.485981 -29.478485) (xy 305.513232 -29.47797) (xy 305.513486 -29.47797) (xy 305.542991 -29.478527)
			(xy 305.601296 -29.487621) (xy 305.657507 -29.505579) (xy 305.710285 -29.531973) (xy 305.758373 -29.566175)
			(xy 305.800625 -29.60737) (xy 305.818794 -29.630624) (xy 305.823874 -29.637736) (xy 305.846226 -29.652722)
			(xy 305.850177 -29.655155) (xy 305.858736 -29.658736) (xy 305.863244 -29.659834) (xy 305.89347 -29.666692)
			(xy 305.912266 -29.663898) (xy 305.920648 -29.659326) (xy 305.939031 -29.649102) (xy 305.97732 -29.63168)
			(xy 305.997102 -29.624528) (xy 306.021302 -29.616483) (xy 306.071036 -29.605187) (xy 306.121716 -29.599482)
			(xy 306.147216 -29.599128) (xy 306.172716 -29.59949) (xy 306.223397 -29.605185) (xy 306.273131 -29.61648)
			(xy 306.29733 -29.624528) (xy 306.317114 -29.631673) (xy 306.355403 -29.649099) (xy 306.373784 -29.659326)
			(xy 306.382166 -29.663898) (xy 306.400962 -29.666692) (xy 306.431188 -29.659834) (xy 306.435706 -29.658767)
			(xy 306.444268 -29.655181) (xy 306.448206 -29.652722) (xy 306.470304 -29.63799) (xy 306.475638 -29.630878)
			(xy 306.49284 -29.608713) (xy 306.532666 -29.569196) (xy 306.57785 -29.535938) (xy 306.627419 -29.509657)
			(xy 306.653692 -29.499814) (xy 306.668932 -29.49448) (xy 306.687474 -29.468318) (xy 306.687474 -19.837908)
			(xy 306.687265 -19.831327) (xy 306.683924 -19.818595) (xy 306.68087 -19.812762) (xy 306.66563 -19.786346)
			(xy 306.657502 -19.77771) (xy 306.652168 -19.774154) (xy 306.630367 -19.759653) (xy 306.590578 -19.725619)
			(xy 306.555814 -19.686465) (xy 306.540916 -19.664934) (xy 306.540662 -19.66468) (xy 306.540662 -19.664426)
			(xy 306.534372 -19.656132) (xy 306.516809 -19.644994) (xy 306.506626 -19.642836) (xy 306.43322 -19.631152)
			(xy 306.422858 -19.62998) (xy 306.402664 -19.635101) (xy 306.394104 -19.641058) (xy 306.373946 -19.656163)
			(xy 306.330413 -19.681509) (xy 306.283927 -19.700912) (xy 306.235293 -19.714037) (xy 306.185357 -19.720654)
			(xy 306.16017 -19.721068) (xy 306.15255 -19.721068) (xy 306.125654 -19.720073) (xy 306.072529 -19.711455)
			(xy 306.021142 -19.695454) (xy 305.972514 -19.672389) (xy 305.927612 -19.642718) (xy 305.887326 -19.607029)
			(xy 305.852457 -19.566032) (xy 305.823697 -19.52054) (xy 305.801617 -19.471458) (xy 305.786655 -19.419759)
			(xy 305.77911 -19.36647) (xy 305.778662 -19.33956) (xy 305.77915 -19.31231) (xy 305.786911 -19.258365)
			(xy 305.80227 -19.206073) (xy 305.824913 -19.156499) (xy 305.85438 -19.110652) (xy 305.890071 -19.069464)
			(xy 305.93126 -19.033774) (xy 305.977108 -19.004308) (xy 306.026683 -18.981666) (xy 306.078975 -18.966309)
			(xy 306.13292 -18.95855) (xy 306.16017 -18.958052) (xy 306.164234 -18.958052) (xy 306.179474 -18.958306)
			(xy 306.205636 -18.941288) (xy 306.248054 -18.840196) (xy 306.251605 -18.830751) (xy 306.251714 -18.81059)
			(xy 306.243997 -18.791964) (xy 306.237132 -18.78457) (xy 305.867816 -18.415254) (xy 305.860704 -18.407888)
			(xy 305.841908 -18.400268) (xy 294.129206 -18.400268) (xy 294.119135 -18.400689) (xy 294.100526 -18.408398)
			(xy 294.093138 -18.415254) (xy 293.758874 -18.749518) (xy 293.751508 -18.75663) (xy 293.743888 -18.775426)
			(xy 293.743888 -21.738336) (xy 295.61663 -21.738336) (xy 295.617134 -21.709597) (xy 295.625764 -21.652769)
			(xy 295.64282 -21.597879) (xy 295.667915 -21.546168) (xy 295.700483 -21.498805) (xy 295.719754 -21.477478)
			(xy 295.726358 -21.470366) (xy 295.73347 -21.45284) (xy 295.73347 -21.363432) (xy 295.726358 -21.345906)
			(xy 295.719754 -21.338794) (xy 295.700518 -21.317437) (xy 295.667949 -21.270081) (xy 295.642853 -21.218374)
			(xy 295.625799 -21.163487) (xy 295.617172 -21.106664) (xy 295.617168 -21.049189) (xy 295.625787 -20.992364)
			(xy 295.642834 -20.937475) (xy 295.667922 -20.885765) (xy 295.700485 -20.838404) (xy 295.719754 -20.817078)
			(xy 295.726358 -20.809966) (xy 295.73347 -20.79244) (xy 295.73347 -20.703032) (xy 295.726358 -20.685506)
			(xy 295.719754 -20.678394) (xy 295.700518 -20.657037) (xy 295.667949 -20.609681) (xy 295.642853 -20.557974)
			(xy 295.625799 -20.503087) (xy 295.617172 -20.446264) (xy 295.617168 -20.388789) (xy 295.625787 -20.331964)
			(xy 295.642834 -20.277075) (xy 295.667922 -20.225365) (xy 295.700485 -20.178004) (xy 295.719754 -20.156678)
			(xy 295.726358 -20.149566) (xy 295.73347 -20.13204) (xy 295.73347 -20.042632) (xy 295.726358 -20.025106)
			(xy 295.719754 -20.017994) (xy 295.700518 -19.996637) (xy 295.667949 -19.949281) (xy 295.642853 -19.897574)
			(xy 295.625799 -19.842687) (xy 295.617172 -19.785864) (xy 295.617168 -19.728389) (xy 295.625787 -19.671564)
			(xy 295.642834 -19.616675) (xy 295.667922 -19.564965) (xy 295.700485 -19.517604) (xy 295.719754 -19.496278)
			(xy 295.726358 -19.489166) (xy 295.73347 -19.47164) (xy 295.73347 -19.382232) (xy 295.726358 -19.364706)
			(xy 295.719754 -19.357594) (xy 295.700503 -19.33625) (xy 295.667933 -19.288893) (xy 295.642837 -19.237186)
			(xy 295.625782 -19.182298) (xy 295.617154 -19.125474) (xy 295.61663 -19.096736) (xy 295.617116 -19.069485)
			(xy 295.624872 -19.015537) (xy 295.640227 -18.963242) (xy 295.662869 -18.913665) (xy 295.692335 -18.867815)
			(xy 295.728026 -18.826624) (xy 295.769217 -18.790933) (xy 295.815067 -18.761467) (xy 295.864644 -18.738825)
			(xy 295.916939 -18.72347) (xy 295.970887 -18.715714) (xy 296.025389 -18.715714) (xy 296.079337 -18.72347)
			(xy 296.131632 -18.738825) (xy 296.181209 -18.761467) (xy 296.227059 -18.790933) (xy 296.26825 -18.826624)
			(xy 296.303941 -18.867815) (xy 296.333407 -18.913665) (xy 296.356049 -18.963242) (xy 296.371404 -19.015537)
			(xy 296.37916 -19.069485) (xy 296.379646 -19.096736) (xy 296.379132 -19.125475) (xy 296.370505 -19.182302)
			(xy 296.353452 -19.237193) (xy 296.328359 -19.288904) (xy 296.295793 -19.336267) (xy 296.276522 -19.357594)
			(xy 296.269918 -19.364706) (xy 296.262806 -19.382232) (xy 296.262806 -19.47164) (xy 296.269918 -19.489166)
			(xy 296.276522 -19.496278) (xy 296.295826 -19.517575) (xy 296.328387 -19.564944) (xy 296.353473 -19.616661)
			(xy 296.370518 -19.671556) (xy 296.379136 -19.728386) (xy 296.379133 -19.785866) (xy 296.370507 -19.842696)
			(xy 296.353454 -19.897588) (xy 296.32836 -19.949302) (xy 296.295793 -19.996666) (xy 296.276522 -20.017994)
			(xy 296.269918 -20.025106) (xy 296.262806 -20.042632) (xy 296.262806 -20.13204) (xy 296.269918 -20.149566)
			(xy 296.276522 -20.156678) (xy 296.295826 -20.177975) (xy 296.328387 -20.225344) (xy 296.353473 -20.277061)
			(xy 296.370518 -20.331956) (xy 296.374097 -20.35556) (xy 305.778152 -20.35556) (xy 305.782223 -20.299938)
			(xy 305.794349 -20.245501) (xy 305.814272 -20.19341) (xy 305.841568 -20.144775) (xy 305.875654 -20.100632)
			(xy 305.915803 -20.061923) (xy 305.961161 -20.029472) (xy 306.010761 -20.003971) (xy 306.063545 -19.985964)
			(xy 306.118388 -19.975834) (xy 306.174122 -19.973797) (xy 306.229559 -19.979897) (xy 306.283516 -19.994003)
			(xy 306.334845 -20.015815) (xy 306.382451 -20.044869) (xy 306.425319 -20.080544) (xy 306.462536 -20.122081)
			(xy 306.493309 -20.168594) (xy 306.516981 -20.219091) (xy 306.533049 -20.272498) (xy 306.541169 -20.327674)
			(xy 306.541678 -20.35556) (xy 306.541169 -20.383446) (xy 306.533049 -20.438622) (xy 306.516981 -20.492029)
			(xy 306.493309 -20.542526) (xy 306.462536 -20.589039) (xy 306.425319 -20.630576) (xy 306.382451 -20.666251)
			(xy 306.334845 -20.695305) (xy 306.283516 -20.717117) (xy 306.229559 -20.731223) (xy 306.174122 -20.737323)
			(xy 306.118388 -20.735286) (xy 306.063545 -20.725156) (xy 306.010761 -20.707149) (xy 305.961161 -20.681648)
			(xy 305.915803 -20.649197) (xy 305.875654 -20.610488) (xy 305.841568 -20.566345) (xy 305.814272 -20.51771)
			(xy 305.794349 -20.465619) (xy 305.782223 -20.411182) (xy 305.778152 -20.35556) (xy 296.374097 -20.35556)
			(xy 296.379136 -20.388786) (xy 296.379133 -20.446266) (xy 296.370507 -20.503096) (xy 296.353454 -20.557988)
			(xy 296.32836 -20.609702) (xy 296.295793 -20.657066) (xy 296.276522 -20.678394) (xy 296.269918 -20.685506)
			(xy 296.262806 -20.703032) (xy 296.262806 -20.79244) (xy 296.269918 -20.809966) (xy 296.276522 -20.817078)
			(xy 296.295826 -20.838375) (xy 296.328387 -20.885744) (xy 296.353473 -20.937461) (xy 296.370518 -20.992356)
			(xy 296.379136 -21.049186) (xy 296.379133 -21.106666) (xy 296.370507 -21.163496) (xy 296.353454 -21.218388)
			(xy 296.32836 -21.270102) (xy 296.295793 -21.317466) (xy 296.276522 -21.338794) (xy 296.269918 -21.345906)
			(xy 296.262806 -21.363432) (xy 296.262806 -21.37156) (xy 305.778152 -21.37156) (xy 305.782223 -21.315938)
			(xy 305.794349 -21.261501) (xy 305.814272 -21.20941) (xy 305.841568 -21.160775) (xy 305.875654 -21.116632)
			(xy 305.915803 -21.077923) (xy 305.961161 -21.045472) (xy 306.010761 -21.019971) (xy 306.063545 -21.001964)
			(xy 306.118388 -20.991834) (xy 306.174122 -20.989797) (xy 306.229559 -20.995897) (xy 306.283516 -21.010003)
			(xy 306.334845 -21.031815) (xy 306.382451 -21.060869) (xy 306.425319 -21.096544) (xy 306.462536 -21.138081)
			(xy 306.493309 -21.184594) (xy 306.516981 -21.235091) (xy 306.533049 -21.288498) (xy 306.541169 -21.343674)
			(xy 306.541678 -21.37156) (xy 306.541169 -21.399446) (xy 306.533049 -21.454622) (xy 306.516981 -21.508029)
			(xy 306.493309 -21.558526) (xy 306.462536 -21.605039) (xy 306.425319 -21.646576) (xy 306.382451 -21.682251)
			(xy 306.334845 -21.711305) (xy 306.283516 -21.733117) (xy 306.229559 -21.747223) (xy 306.174122 -21.753323)
			(xy 306.118388 -21.751286) (xy 306.063545 -21.741156) (xy 306.010761 -21.723149) (xy 305.961161 -21.697648)
			(xy 305.915803 -21.665197) (xy 305.875654 -21.626488) (xy 305.841568 -21.582345) (xy 305.814272 -21.53371)
			(xy 305.794349 -21.481619) (xy 305.782223 -21.427182) (xy 305.778152 -21.37156) (xy 296.262806 -21.37156)
			(xy 296.262806 -21.45284) (xy 296.269918 -21.470366) (xy 296.276522 -21.477478) (xy 296.295803 -21.498796)
			(xy 296.328369 -21.54616) (xy 296.353461 -21.597874) (xy 296.370509 -21.652767) (xy 296.379128 -21.709596)
			(xy 296.379646 -21.738336) (xy 296.37916 -21.765587) (xy 296.371404 -21.819535) (xy 296.356049 -21.87183)
			(xy 296.333407 -21.921407) (xy 296.303941 -21.967257) (xy 296.26825 -22.008448) (xy 296.227059 -22.044139)
			(xy 296.181209 -22.073605) (xy 296.131632 -22.096247) (xy 296.079337 -22.111602) (xy 296.025389 -22.119358)
			(xy 295.970887 -22.119358) (xy 295.916939 -22.111602) (xy 295.864644 -22.096247) (xy 295.815067 -22.073605)
			(xy 295.769217 -22.044139) (xy 295.728026 -22.008448) (xy 295.692335 -21.967257) (xy 295.662869 -21.921407)
			(xy 295.640227 -21.87183) (xy 295.624872 -21.819535) (xy 295.617116 -21.765587) (xy 295.61663 -21.738336)
			(xy 293.743888 -21.738336) (xy 293.743888 -23.05506) (xy 295.487092 -23.05506) (xy 295.487092 -22.995126)
			(xy 295.494916 -22.935706) (xy 295.510429 -22.877814) (xy 295.533365 -22.822443) (xy 295.563333 -22.770539)
			(xy 295.599819 -22.722991) (xy 295.642199 -22.680612) (xy 295.689748 -22.644127) (xy 295.741652 -22.614161)
			(xy 295.797024 -22.591226) (xy 295.854915 -22.575714) (xy 295.914336 -22.567892) (xy 295.97427 -22.567892)
			(xy 296.033691 -22.575716) (xy 296.091583 -22.591228) (xy 296.146954 -22.614164) (xy 296.198858 -22.644131)
			(xy 296.246406 -22.680616) (xy 296.288786 -22.722996) (xy 296.325271 -22.770545) (xy 296.355238 -22.822449)
			(xy 296.378173 -22.877821) (xy 296.393685 -22.935712) (xy 296.401508 -22.995133) (xy 296.401998 -23.0251)
			(xy 296.401929 -23.037188) (xy 296.400657 -23.061331) (xy 296.399458 -23.07336) (xy 296.398188 -23.085552)
			(xy 296.407078 -23.108412) (xy 296.48785 -23.179786) (xy 296.511472 -23.185628) (xy 296.52341 -23.182834)
			(xy 296.544761 -23.178188) (xy 296.588175 -23.173218) (xy 296.610024 -23.172928) (xy 296.635807 -23.173316)
			(xy 296.68691 -23.180203) (xy 296.711878 -23.186644) (xy 296.72407 -23.1902) (xy 296.748962 -23.184612)
			(xy 296.832274 -23.112222) (xy 296.841418 -23.088346) (xy 296.83964 -23.075646) (xy 296.837842 -23.060853)
			(xy 296.835934 -23.031111) (xy 296.83583 -23.01621) (xy 296.836271 -22.986242) (xy 296.844093 -22.926819)
			(xy 296.859604 -22.868925) (xy 296.882539 -22.813551) (xy 296.912506 -22.761644) (xy 296.948991 -22.714093)
			(xy 296.99137 -22.67171) (xy 297.03892 -22.635222) (xy 297.090824 -22.605252) (xy 297.146197 -22.582314)
			(xy 297.20409 -22.566799) (xy 297.263513 -22.558973) (xy 297.323449 -22.558971) (xy 297.382872 -22.566791)
			(xy 297.440766 -22.582301) (xy 297.496141 -22.605235) (xy 297.548048 -22.6352) (xy 297.5956 -22.671685)
			(xy 297.637984 -22.714063) (xy 297.674473 -22.761612) (xy 297.704444 -22.813516) (xy 297.727383 -22.868888)
			(xy 297.742899 -22.926781) (xy 297.750726 -22.986203) (xy 297.75073 -23.046139) (xy 297.74291 -23.105563)
			(xy 297.727402 -23.163457) (xy 297.704469 -23.218832) (xy 297.674505 -23.270741) (xy 297.638022 -23.318293)
			(xy 297.595644 -23.360678) (xy 297.548096 -23.397168) (xy 297.496192 -23.42714) (xy 297.440821 -23.45008)
			(xy 297.382928 -23.465597) (xy 297.323506 -23.473425) (xy 297.293538 -23.473918) (xy 297.265514 -23.473501)
			(xy 297.209884 -23.466682) (xy 297.155506 -23.453106) (xy 297.1292 -23.443438) (xy 297.117262 -23.438866)
			(xy 297.092116 -23.442168) (xy 297.0022 -23.505922) (xy 296.99077 -23.528782) (xy 296.991278 -23.541736)
			(xy 296.991532 -23.554436) (xy 296.991018 -23.581697) (xy 296.98551 -23.619964) (xy 300.209186 -23.619964)
			(xy 300.209186 -23.560028) (xy 300.217009 -23.500606) (xy 300.232522 -23.442713) (xy 300.255458 -23.38734)
			(xy 300.285425 -23.335434) (xy 300.321912 -23.287884) (xy 300.364292 -23.245504) (xy 300.411842 -23.209017)
			(xy 300.463748 -23.17905) (xy 300.519121 -23.156114) (xy 300.577014 -23.140601) (xy 300.636436 -23.132778)
			(xy 300.696372 -23.132778) (xy 300.755794 -23.140601) (xy 300.813687 -23.156114) (xy 300.86906 -23.17905)
			(xy 300.920966 -23.209017) (xy 300.968516 -23.245504) (xy 301.010896 -23.287884) (xy 301.047383 -23.335434)
			(xy 301.07735 -23.38734) (xy 301.100286 -23.442713) (xy 301.115799 -23.500606) (xy 301.123622 -23.560028)
			(xy 301.124112 -23.589996) (xy 301.123622 -23.619964) (xy 301.115799 -23.679386) (xy 301.100286 -23.737279)
			(xy 301.07735 -23.792652) (xy 301.047383 -23.844558) (xy 301.019943 -23.880318) (xy 301.440594 -23.880318)
			(xy 301.444665 -23.824696) (xy 301.456791 -23.770259) (xy 301.476714 -23.718168) (xy 301.50401 -23.669533)
			(xy 301.538096 -23.62539) (xy 301.578245 -23.586681) (xy 301.623603 -23.55423) (xy 301.673203 -23.528729)
			(xy 301.725987 -23.510722) (xy 301.78083 -23.500592) (xy 301.836564 -23.498555) (xy 301.892001 -23.504655)
			(xy 301.945958 -23.518761) (xy 301.997287 -23.540573) (xy 302.044893 -23.569627) (xy 302.087761 -23.605302)
			(xy 302.124978 -23.646839) (xy 302.155751 -23.693352) (xy 302.179423 -23.743849) (xy 302.195491 -23.797256)
			(xy 302.203611 -23.852432) (xy 302.20412 -23.880318) (xy 302.456594 -23.880318) (xy 302.460665 -23.824696)
			(xy 302.472791 -23.770259) (xy 302.492714 -23.718168) (xy 302.52001 -23.669533) (xy 302.554096 -23.62539)
			(xy 302.594245 -23.586681) (xy 302.639603 -23.55423) (xy 302.689203 -23.528729) (xy 302.741987 -23.510722)
			(xy 302.79683 -23.500592) (xy 302.852564 -23.498555) (xy 302.908001 -23.504655) (xy 302.961958 -23.518761)
			(xy 303.013287 -23.540573) (xy 303.060893 -23.569627) (xy 303.103761 -23.605302) (xy 303.140978 -23.646839)
			(xy 303.171751 -23.693352) (xy 303.195423 -23.743849) (xy 303.211491 -23.797256) (xy 303.219611 -23.852432)
			(xy 303.22012 -23.880318) (xy 303.472594 -23.880318) (xy 303.476665 -23.824696) (xy 303.488791 -23.770259)
			(xy 303.508714 -23.718168) (xy 303.53601 -23.669533) (xy 303.570096 -23.62539) (xy 303.610245 -23.586681)
			(xy 303.655603 -23.55423) (xy 303.705203 -23.528729) (xy 303.757987 -23.510722) (xy 303.81283 -23.500592)
			(xy 303.868564 -23.498555) (xy 303.924001 -23.504655) (xy 303.977958 -23.518761) (xy 304.029287 -23.540573)
			(xy 304.076893 -23.569627) (xy 304.119761 -23.605302) (xy 304.156978 -23.646839) (xy 304.187751 -23.693352)
			(xy 304.211423 -23.743849) (xy 304.227491 -23.797256) (xy 304.235611 -23.852432) (xy 304.23612 -23.880318)
			(xy 304.49088 -23.880318) (xy 304.494951 -23.824696) (xy 304.507077 -23.770259) (xy 304.527 -23.718168)
			(xy 304.554296 -23.669533) (xy 304.588382 -23.62539) (xy 304.628531 -23.586681) (xy 304.673889 -23.55423)
			(xy 304.723489 -23.528729) (xy 304.776273 -23.510722) (xy 304.831116 -23.500592) (xy 304.88685 -23.498555)
			(xy 304.942287 -23.504655) (xy 304.996244 -23.518761) (xy 305.047573 -23.540573) (xy 305.095179 -23.569627)
			(xy 305.138047 -23.605302) (xy 305.175264 -23.646839) (xy 305.206037 -23.693352) (xy 305.229709 -23.743849)
			(xy 305.245777 -23.797256) (xy 305.253897 -23.852432) (xy 305.254406 -23.880318) (xy 305.253897 -23.908204)
			(xy 305.245777 -23.96338) (xy 305.229709 -24.016787) (xy 305.206037 -24.067284) (xy 305.175264 -24.113797)
			(xy 305.138047 -24.155334) (xy 305.095179 -24.191009) (xy 305.047573 -24.220063) (xy 304.996244 -24.241875)
			(xy 304.942287 -24.255981) (xy 304.88685 -24.262081) (xy 304.831116 -24.260044) (xy 304.776273 -24.249914)
			(xy 304.723489 -24.231907) (xy 304.673889 -24.206406) (xy 304.628531 -24.173955) (xy 304.588382 -24.135246)
			(xy 304.554296 -24.091103) (xy 304.527 -24.042468) (xy 304.507077 -23.990377) (xy 304.494951 -23.93594)
			(xy 304.49088 -23.880318) (xy 304.23612 -23.880318) (xy 304.235611 -23.908204) (xy 304.227491 -23.96338)
			(xy 304.211423 -24.016787) (xy 304.187751 -24.067284) (xy 304.156978 -24.113797) (xy 304.119761 -24.155334)
			(xy 304.076893 -24.191009) (xy 304.029287 -24.220063) (xy 303.977958 -24.241875) (xy 303.924001 -24.255981)
			(xy 303.868564 -24.262081) (xy 303.81283 -24.260044) (xy 303.757987 -24.249914) (xy 303.705203 -24.231907)
			(xy 303.655603 -24.206406) (xy 303.610245 -24.173955) (xy 303.570096 -24.135246) (xy 303.53601 -24.091103)
			(xy 303.508714 -24.042468) (xy 303.488791 -23.990377) (xy 303.476665 -23.93594) (xy 303.472594 -23.880318)
			(xy 303.22012 -23.880318) (xy 303.219611 -23.908204) (xy 303.211491 -23.96338) (xy 303.195423 -24.016787)
			(xy 303.171751 -24.067284) (xy 303.140978 -24.113797) (xy 303.103761 -24.155334) (xy 303.060893 -24.191009)
			(xy 303.013287 -24.220063) (xy 302.961958 -24.241875) (xy 302.908001 -24.255981) (xy 302.852564 -24.262081)
			(xy 302.79683 -24.260044) (xy 302.741987 -24.249914) (xy 302.689203 -24.231907) (xy 302.639603 -24.206406)
			(xy 302.594245 -24.173955) (xy 302.554096 -24.135246) (xy 302.52001 -24.091103) (xy 302.492714 -24.042468)
			(xy 302.472791 -23.990377) (xy 302.460665 -23.93594) (xy 302.456594 -23.880318) (xy 302.20412 -23.880318)
			(xy 302.203611 -23.908204) (xy 302.195491 -23.96338) (xy 302.179423 -24.016787) (xy 302.155751 -24.067284)
			(xy 302.124978 -24.113797) (xy 302.087761 -24.155334) (xy 302.044893 -24.191009) (xy 301.997287 -24.220063)
			(xy 301.945958 -24.241875) (xy 301.892001 -24.255981) (xy 301.836564 -24.262081) (xy 301.78083 -24.260044)
			(xy 301.725987 -24.249914) (xy 301.673203 -24.231907) (xy 301.623603 -24.206406) (xy 301.578245 -24.173955)
			(xy 301.538096 -24.135246) (xy 301.50401 -24.091103) (xy 301.476714 -24.042468) (xy 301.456791 -23.990377)
			(xy 301.444665 -23.93594) (xy 301.440594 -23.880318) (xy 301.019943 -23.880318) (xy 301.010896 -23.892108)
			(xy 300.968516 -23.934488) (xy 300.920966 -23.970975) (xy 300.86906 -24.000942) (xy 300.813687 -24.023878)
			(xy 300.755794 -24.039391) (xy 300.696372 -24.047214) (xy 300.636436 -24.047214) (xy 300.577014 -24.039391)
			(xy 300.519121 -24.023878) (xy 300.463748 -24.000942) (xy 300.411842 -23.970975) (xy 300.364292 -23.934488)
			(xy 300.321912 -23.892108) (xy 300.285425 -23.844558) (xy 300.255458 -23.792652) (xy 300.232522 -23.737279)
			(xy 300.217009 -23.679386) (xy 300.209186 -23.619964) (xy 296.98551 -23.619964) (xy 296.983251 -23.635663)
			(xy 296.96788 -23.687974) (xy 296.945218 -23.737563) (xy 296.915727 -23.783421) (xy 296.880008 -23.824613)
			(xy 296.838789 -23.860301) (xy 296.792908 -23.889757) (xy 296.743301 -23.912381) (xy 296.690979 -23.927712)
			(xy 296.637007 -23.935438) (xy 296.582485 -23.935402) (xy 296.528524 -23.927604) (xy 296.476222 -23.912203)
			(xy 296.426646 -23.889513) (xy 296.380804 -23.859996) (xy 296.339632 -23.824254) (xy 296.303968 -23.783014)
			(xy 296.274539 -23.737116) (xy 296.251943 -23.687497) (xy 296.236642 -23.635166) (xy 296.228946 -23.58119)
			(xy 296.228516 -23.553928) (xy 296.228516 -23.541482) (xy 296.21734 -23.519638) (xy 296.12971 -23.457154)
			(xy 296.10558 -23.453598) (xy 296.093642 -23.457662) (xy 296.069562 -23.465644) (xy 296.020075 -23.476821)
			(xy 295.969656 -23.482455) (xy 295.94429 -23.482808) (xy 295.914323 -23.482307) (xy 295.854902 -23.474483)
			(xy 295.797011 -23.45897) (xy 295.74164 -23.436033) (xy 295.689737 -23.406065) (xy 295.642189 -23.369579)
			(xy 295.59981 -23.327199) (xy 295.563325 -23.27965) (xy 295.533359 -23.227745) (xy 295.510425 -23.172373)
			(xy 295.494914 -23.114481) (xy 295.487092 -23.05506) (xy 293.743888 -23.05506) (xy 293.743888 -24.189944)
			(xy 295.498772 -24.189944) (xy 295.502843 -24.134322) (xy 295.514969 -24.079885) (xy 295.534892 -24.027794)
			(xy 295.562188 -23.979159) (xy 295.596274 -23.935016) (xy 295.636423 -23.896307) (xy 295.681781 -23.863856)
			(xy 295.731381 -23.838355) (xy 295.784165 -23.820348) (xy 295.839008 -23.810218) (xy 295.894742 -23.808181)
			(xy 295.950179 -23.814281) (xy 296.004136 -23.828387) (xy 296.055465 -23.850199) (xy 296.103071 -23.879253)
			(xy 296.145939 -23.914928) (xy 296.183156 -23.956465) (xy 296.213929 -24.002978) (xy 296.237601 -24.053475)
			(xy 296.253669 -24.106882) (xy 296.261789 -24.162058) (xy 296.262298 -24.189944) (xy 298.021754 -24.189944)
			(xy 298.025825 -24.134322) (xy 298.037951 -24.079885) (xy 298.057874 -24.027794) (xy 298.08517 -23.979159)
			(xy 298.119256 -23.935016) (xy 298.159405 -23.896307) (xy 298.204763 -23.863856) (xy 298.254363 -23.838355)
			(xy 298.307147 -23.820348) (xy 298.36199 -23.810218) (xy 298.417724 -23.808181) (xy 298.473161 -23.814281)
			(xy 298.527118 -23.828387) (xy 298.578447 -23.850199) (xy 298.626053 -23.879253) (xy 298.668921 -23.914928)
			(xy 298.706138 -23.956465) (xy 298.736911 -24.002978) (xy 298.760583 -24.053475) (xy 298.776651 -24.106882)
			(xy 298.784771 -24.162058) (xy 298.78528 -24.189944) (xy 298.784771 -24.21783) (xy 298.776651 -24.273006)
			(xy 298.760583 -24.326413) (xy 298.736911 -24.37691) (xy 298.706138 -24.423423) (xy 298.668921 -24.46496)
			(xy 298.626053 -24.500635) (xy 298.578447 -24.529689) (xy 298.527118 -24.551501) (xy 298.473161 -24.565607)
			(xy 298.417724 -24.571707) (xy 298.36199 -24.56967) (xy 298.307147 -24.55954) (xy 298.254363 -24.541533)
			(xy 298.204763 -24.516032) (xy 298.159405 -24.483581) (xy 298.119256 -24.444872) (xy 298.08517 -24.400729)
			(xy 298.057874 -24.352094) (xy 298.037951 -24.300003) (xy 298.025825 -24.245566) (xy 298.021754 -24.189944)
			(xy 296.262298 -24.189944) (xy 296.261789 -24.21783) (xy 296.253669 -24.273006) (xy 296.237601 -24.326413)
			(xy 296.213929 -24.37691) (xy 296.183156 -24.423423) (xy 296.145939 -24.46496) (xy 296.103071 -24.500635)
			(xy 296.055465 -24.529689) (xy 296.004136 -24.551501) (xy 295.950179 -24.565607) (xy 295.894742 -24.571707)
			(xy 295.839008 -24.56967) (xy 295.784165 -24.55954) (xy 295.731381 -24.541533) (xy 295.681781 -24.516032)
			(xy 295.636423 -24.483581) (xy 295.596274 -24.444872) (xy 295.562188 -24.400729) (xy 295.534892 -24.352094)
			(xy 295.514969 -24.300003) (xy 295.502843 -24.245566) (xy 295.498772 -24.189944) (xy 293.743888 -24.189944)
			(xy 293.743888 -25.390094) (xy 297.933364 -25.390094) (xy 297.933854 -25.360126) (xy 297.941677 -25.300704)
			(xy 297.95719 -25.242811) (xy 297.980126 -25.187438) (xy 298.010093 -25.135532) (xy 298.04658 -25.087982)
			(xy 298.08896 -25.045602) (xy 298.13651 -25.009115) (xy 298.188416 -24.979148) (xy 298.243789 -24.956212)
			(xy 298.301682 -24.940699) (xy 298.361104 -24.932876) (xy 298.42104 -24.932876) (xy 298.480462 -24.940699)
			(xy 298.538355 -24.956212) (xy 298.593728 -24.979148) (xy 298.645634 -25.009115) (xy 298.693184 -25.045602)
			(xy 298.735564 -25.087982) (xy 298.772051 -25.135532) (xy 298.802018 -25.187438) (xy 298.824954 -25.242811)
			(xy 298.840467 -25.300704) (xy 298.84829 -25.360126) (xy 298.84878 -25.390094) (xy 298.848353 -25.418879)
			(xy 298.841134 -25.475994) (xy 298.82681 -25.531753) (xy 298.805606 -25.585275) (xy 298.777858 -25.635716)
			(xy 298.744003 -25.682279) (xy 298.704576 -25.724228) (xy 298.682664 -25.7429) (xy 298.674282 -25.749758)
			(xy 298.66463 -25.769316) (xy 298.661328 -25.867106) (xy 298.669456 -25.887172) (xy 298.677584 -25.894792)
			(xy 298.695989 -25.912864) (xy 298.728225 -25.953132) (xy 298.754748 -25.997373) (xy 298.775074 -26.044781)
			(xy 298.788834 -26.094494) (xy 298.795777 -26.145607) (xy 298.796202 -26.171398) (xy 298.795716 -26.198649)
			(xy 298.78796 -26.252597) (xy 298.772605 -26.304892) (xy 298.749963 -26.354469) (xy 298.720497 -26.400319)
			(xy 298.684806 -26.44151) (xy 298.643615 -26.477201) (xy 298.597765 -26.506667) (xy 298.548188 -26.529309)
			(xy 298.495893 -26.544664) (xy 298.441945 -26.55242) (xy 298.387443 -26.55242) (xy 298.333495 -26.544664)
			(xy 298.2812 -26.529309) (xy 298.231623 -26.506667) (xy 298.185773 -26.477201) (xy 298.144582 -26.44151)
			(xy 298.108891 -26.400319) (xy 298.079425 -26.354469) (xy 298.056783 -26.304892) (xy 298.041428 -26.252597)
			(xy 298.033672 -26.198649) (xy 298.033186 -26.171398) (xy 298.033707 -26.142755) (xy 298.042304 -26.086117)
			(xy 298.059275 -26.031401) (xy 298.084238 -25.979839) (xy 298.116631 -25.93259) (xy 298.135802 -25.911302)
			(xy 298.143168 -25.903174) (xy 298.150026 -25.8826) (xy 298.140882 -25.785064) (xy 298.130214 -25.766268)
			(xy 298.121324 -25.759918) (xy 298.096781 -25.741361) (xy 298.052386 -25.698761) (xy 298.014095 -25.6506)
			(xy 297.982598 -25.597745) (xy 297.958461 -25.541149) (xy 297.94212 -25.48183) (xy 297.933869 -25.420858)
			(xy 297.933364 -25.390094) (xy 293.743888 -25.390094) (xy 293.743888 -25.506934) (xy 293.744317 -25.517002)
			(xy 293.752039 -25.535598) (xy 293.758874 -25.543002) (xy 293.810182 -25.593802) (xy 293.817591 -25.600489)
			(xy 293.836027 -25.608077) (xy 293.845996 -25.608534) (xy 293.84879 -25.608534) (xy 293.87604 -25.608997)
			(xy 293.929986 -25.616752) (xy 293.98228 -25.632105) (xy 294.031856 -25.654744) (xy 294.077705 -25.684209)
			(xy 294.118894 -25.719899) (xy 294.154585 -25.761087) (xy 294.184051 -25.806936) (xy 294.206692 -25.856511)
			(xy 294.222046 -25.908804) (xy 294.229803 -25.96275) (xy 294.229803 -25.990042) (xy 295.498772 -25.990042)
			(xy 295.502843 -25.93442) (xy 295.514969 -25.879983) (xy 295.534892 -25.827892) (xy 295.562188 -25.779257)
			(xy 295.596274 -25.735114) (xy 295.636423 -25.696405) (xy 295.681781 -25.663954) (xy 295.731381 -25.638453)
			(xy 295.784165 -25.620446) (xy 295.839008 -25.610316) (xy 295.894742 -25.608279) (xy 295.950179 -25.614379)
			(xy 296.004136 -25.628485) (xy 296.055465 -25.650297) (xy 296.103071 -25.679351) (xy 296.145939 -25.715026)
			(xy 296.183156 -25.756563) (xy 296.213929 -25.803076) (xy 296.237601 -25.853573) (xy 296.253669 -25.90698)
			(xy 296.261789 -25.962156) (xy 296.262298 -25.990042) (xy 296.261789 -26.017928) (xy 296.253669 -26.073104)
			(xy 296.237601 -26.126511) (xy 296.213929 -26.177008) (xy 296.183156 -26.223521) (xy 296.145939 -26.265058)
			(xy 296.103071 -26.300733) (xy 296.055465 -26.329787) (xy 296.004136 -26.351599) (xy 295.950179 -26.365705)
			(xy 295.894742 -26.371805) (xy 295.839008 -26.369768) (xy 295.784165 -26.359638) (xy 295.731381 -26.341631)
			(xy 295.681781 -26.31613) (xy 295.636423 -26.283679) (xy 295.596274 -26.24497) (xy 295.562188 -26.200827)
			(xy 295.534892 -26.152192) (xy 295.514969 -26.100101) (xy 295.502843 -26.045664) (xy 295.498772 -25.990042)
			(xy 294.229803 -25.990042) (xy 294.229803 -26.01725) (xy 294.222046 -26.071196) (xy 294.206692 -26.123489)
			(xy 294.184051 -26.173064) (xy 294.154585 -26.218913) (xy 294.118894 -26.260101) (xy 294.077705 -26.295791)
			(xy 294.031856 -26.325256) (xy 293.98228 -26.347895) (xy 293.929986 -26.363248) (xy 293.87604 -26.371003)
			(xy 293.84879 -26.37155) (xy 293.845996 -26.37155) (xy 293.83603 -26.372026) (xy 293.817594 -26.379604)
			(xy 293.810182 -26.386282) (xy 293.758874 -26.437082) (xy 293.752032 -26.444481) (xy 293.744316 -26.463081)
			(xy 293.743888 -26.47315) (xy 293.743888 -27.307032) (xy 293.744316 -27.3171) (xy 293.752038 -27.335697)
			(xy 293.758874 -27.3431) (xy 293.810182 -27.3939) (xy 293.817591 -27.400587) (xy 293.836027 -27.408176)
			(xy 293.845996 -27.408632) (xy 293.84879 -27.408632) (xy 293.87604 -27.409095) (xy 293.929987 -27.41685)
			(xy 293.98228 -27.432203) (xy 294.031857 -27.454843) (xy 294.077706 -27.484307) (xy 294.118896 -27.519997)
			(xy 294.154587 -27.561186) (xy 294.184053 -27.607035) (xy 294.206693 -27.65661) (xy 294.222048 -27.708903)
			(xy 294.229805 -27.76285) (xy 294.229805 -27.79014) (xy 295.56278 -27.79014) (xy 295.566851 -27.734518)
			(xy 295.578977 -27.680081) (xy 295.5989 -27.62799) (xy 295.626196 -27.579355) (xy 295.660282 -27.535212)
			(xy 295.700431 -27.496503) (xy 295.745789 -27.464052) (xy 295.795389 -27.438551) (xy 295.848173 -27.420544)
			(xy 295.903016 -27.410414) (xy 295.95875 -27.408377) (xy 296.014187 -27.414477) (xy 296.068144 -27.428583)
			(xy 296.119473 -27.450395) (xy 296.167079 -27.479449) (xy 296.209947 -27.515124) (xy 296.247164 -27.556661)
			(xy 296.277937 -27.603174) (xy 296.301609 -27.653671) (xy 296.317677 -27.707078) (xy 296.325797 -27.762254)
			(xy 296.326306 -27.79014) (xy 298.066712 -27.79014) (xy 298.070783 -27.734518) (xy 298.082909 -27.680081)
			(xy 298.102832 -27.62799) (xy 298.130128 -27.579355) (xy 298.164214 -27.535212) (xy 298.204363 -27.496503)
			(xy 298.249721 -27.464052) (xy 298.299321 -27.438551) (xy 298.352105 -27.420544) (xy 298.406948 -27.410414)
			(xy 298.462682 -27.408377) (xy 298.518119 -27.414477) (xy 298.572076 -27.428583) (xy 298.623405 -27.450395)
			(xy 298.671011 -27.479449) (xy 298.713879 -27.515124) (xy 298.751096 -27.556661) (xy 298.781869 -27.603174)
			(xy 298.805541 -27.653671) (xy 298.821609 -27.707078) (xy 298.829729 -27.762254) (xy 298.830238 -27.79014)
			(xy 298.829741 -27.817351) (xy 300.099695 -27.817351) (xy 300.099695 -27.762849) (xy 300.107452 -27.708901)
			(xy 300.122808 -27.656606) (xy 300.145451 -27.607029) (xy 300.174918 -27.561179) (xy 300.210611 -27.51999)
			(xy 300.251803 -27.4843) (xy 300.297655 -27.454836) (xy 300.347234 -27.432198) (xy 300.39953 -27.416846)
			(xy 300.453479 -27.409093) (xy 300.48073 -27.408632) (xy 300.506037 -27.409021) (xy 300.55621 -27.415697)
			(xy 300.605062 -27.42894) (xy 300.628558 -27.43835) (xy 300.636558 -27.441394) (xy 300.653634 -27.442479)
			(xy 300.670115 -27.437884) (xy 300.677326 -27.43327) (xy 300.702726 -27.41549) (xy 300.709601 -27.410202)
			(xy 300.719682 -27.396107) (xy 300.724484 -27.379456) (xy 300.724316 -27.370786) (xy 300.7233 -27.342846)
			(xy 300.7233 -26.479246) (xy 300.724062 -26.456894) (xy 300.72457 -26.444448) (xy 300.714156 -26.421842)
			(xy 300.629066 -26.355548) (xy 300.604682 -26.350976) (xy 300.592744 -26.354786) (xy 300.565409 -26.362636)
			(xy 300.509165 -26.371048) (xy 300.48073 -26.37155) (xy 300.453479 -26.371005) (xy 300.399531 -26.363252)
			(xy 300.347235 -26.3479) (xy 300.297656 -26.325262) (xy 300.251805 -26.295798) (xy 300.210613 -26.260108)
			(xy 300.17492 -26.21892) (xy 300.145452 -26.17307) (xy 300.12281 -26.123493) (xy 300.107454 -26.071199)
			(xy 300.099697 -26.017251) (xy 300.099697 -25.962749) (xy 300.107454 -25.908801) (xy 300.12281 -25.856507)
			(xy 300.145452 -25.80693) (xy 300.17492 -25.76108) (xy 300.210613 -25.719892) (xy 300.251805 -25.684202)
			(xy 300.297656 -25.654738) (xy 300.347235 -25.6321) (xy 300.399531 -25.616748) (xy 300.453479 -25.608995)
			(xy 300.48073 -25.608534) (xy 300.509683 -25.609049) (xy 300.566925 -25.61779) (xy 300.622189 -25.635081)
			(xy 300.674204 -25.660526) (xy 300.721777 -25.69354) (xy 300.763813 -25.733365) (xy 300.799348 -25.779085)
			(xy 300.827565 -25.82965) (xy 300.828462 -25.832054) (xy 302.38827 -25.832054) (xy 302.388729 -25.80545)
			(xy 302.396105 -25.752756) (xy 302.410735 -25.701599) (xy 302.432335 -25.652973) (xy 302.460486 -25.607822)
			(xy 302.49464 -25.567024) (xy 302.534135 -25.53137) (xy 302.55591 -25.516078) (xy 302.567385 -25.507738)
			(xy 302.585587 -25.485995) (xy 302.597103 -25.460083) (xy 302.601043 -25.432002) (xy 302.597104 -25.403921)
			(xy 302.585589 -25.378009) (xy 302.567389 -25.356265) (xy 302.55591 -25.34793) (xy 302.534138 -25.332637)
			(xy 302.49466 -25.29697) (xy 302.460518 -25.256165) (xy 302.432374 -25.211015) (xy 302.410771 -25.162394)
			(xy 302.396131 -25.111244) (xy 302.388735 -25.058556) (xy 302.38827 -25.031954) (xy 302.388756 -25.004703)
			(xy 302.396512 -24.950755) (xy 302.411867 -24.89846) (xy 302.434509 -24.848883) (xy 302.463975 -24.803033)
			(xy 302.499666 -24.761842) (xy 302.540857 -24.726151) (xy 302.586707 -24.696685) (xy 302.636284 -24.674043)
			(xy 302.688579 -24.658688) (xy 302.742527 -24.650932) (xy 302.797029 -24.650932) (xy 302.850977 -24.658688)
			(xy 302.903272 -24.674043) (xy 302.952849 -24.696685) (xy 302.998699 -24.726151) (xy 303.03989 -24.761842)
			(xy 303.063091 -24.788618) (xy 304.993276 -24.788618) (xy 304.993276 -24.728682) (xy 305.001099 -24.66926)
			(xy 305.016612 -24.611367) (xy 305.039548 -24.555994) (xy 305.069515 -24.504088) (xy 305.106002 -24.456538)
			(xy 305.148382 -24.414158) (xy 305.195932 -24.377671) (xy 305.247838 -24.347704) (xy 305.303211 -24.324768)
			(xy 305.361104 -24.309255) (xy 305.420526 -24.301432) (xy 305.480462 -24.301432) (xy 305.539884 -24.309255)
			(xy 305.597777 -24.324768) (xy 305.65315 -24.347704) (xy 305.705056 -24.377671) (xy 305.752606 -24.414158)
			(xy 305.794986 -24.456538) (xy 305.831473 -24.504088) (xy 305.86144 -24.555994) (xy 305.884376 -24.611367)
			(xy 305.899889 -24.66926) (xy 305.907712 -24.728682) (xy 305.908202 -24.75865) (xy 305.907712 -24.788618)
			(xy 305.899889 -24.84804) (xy 305.884376 -24.905933) (xy 305.86144 -24.961306) (xy 305.831473 -25.013212)
			(xy 305.794986 -25.060762) (xy 305.752606 -25.103142) (xy 305.705056 -25.139629) (xy 305.65315 -25.169596)
			(xy 305.597777 -25.192532) (xy 305.539884 -25.208045) (xy 305.480462 -25.215868) (xy 305.420526 -25.215868)
			(xy 305.361104 -25.208045) (xy 305.303211 -25.192532) (xy 305.247838 -25.169596) (xy 305.195932 -25.139629)
			(xy 305.148382 -25.103142) (xy 305.106002 -25.060762) (xy 305.069515 -25.013212) (xy 305.039548 -24.961306)
			(xy 305.016612 -24.905933) (xy 305.001099 -24.84804) (xy 304.993276 -24.788618) (xy 303.063091 -24.788618)
			(xy 303.075581 -24.803033) (xy 303.105047 -24.848883) (xy 303.127689 -24.89846) (xy 303.143044 -24.950755)
			(xy 303.1508 -25.004703) (xy 303.151286 -25.031954) (xy 303.150808 -25.058557) (xy 303.143433 -25.111249)
			(xy 303.128804 -25.162404) (xy 303.107206 -25.21103) (xy 303.079059 -25.25618) (xy 303.044909 -25.29698)
			(xy 303.005418 -25.332637) (xy 302.983646 -25.34793) (xy 302.972158 -25.356257) (xy 302.953946 -25.377999)
			(xy 302.942424 -25.403915) (xy 302.938482 -25.432002) (xy 302.942425 -25.460089) (xy 302.953948 -25.486005)
			(xy 302.972161 -25.507746) (xy 302.983646 -25.516078) (xy 303.005412 -25.531379) (xy 303.044892 -25.567044)
			(xy 303.079036 -25.607846) (xy 303.107182 -25.652995) (xy 303.128785 -25.701615) (xy 303.143426 -25.752765)
			(xy 303.150822 -25.805452) (xy 303.151286 -25.832054) (xy 303.1508 -25.859305) (xy 303.143044 -25.913253)
			(xy 303.127689 -25.965548) (xy 303.105047 -26.015125) (xy 303.075581 -26.060975) (xy 303.03989 -26.102166)
			(xy 302.998699 -26.137857) (xy 302.952849 -26.167323) (xy 302.903272 -26.189965) (xy 302.850977 -26.20532)
			(xy 302.797029 -26.213076) (xy 302.742527 -26.213076) (xy 302.688579 -26.20532) (xy 302.636284 -26.189965)
			(xy 302.586707 -26.167323) (xy 302.540857 -26.137857) (xy 302.499666 -26.102166) (xy 302.463975 -26.060975)
			(xy 302.434509 -26.015125) (xy 302.411867 -25.965548) (xy 302.396512 -25.913253) (xy 302.388756 -25.859305)
			(xy 302.38827 -25.832054) (xy 300.828462 -25.832054) (xy 300.847816 -25.8839) (xy 300.859635 -25.940586)
			(xy 300.86173 -25.969468) (xy 300.862238 -25.981914) (xy 300.874938 -26.00325) (xy 300.966632 -26.060654)
			(xy 300.99127 -26.062432) (xy 301.0027 -26.057606) (xy 301.031061 -26.046145) (xy 301.090057 -26.029987)
			(xy 301.150678 -26.021813) (xy 301.181262 -26.021284) (xy 301.211249 -26.021743) (xy 301.27071 -26.029567)
			(xy 301.32864 -26.045086) (xy 301.384049 -26.068035) (xy 301.435988 -26.09802) (xy 301.483569 -26.13453)
			(xy 301.525976 -26.176937) (xy 301.562484 -26.224518) (xy 301.592469 -26.276458) (xy 301.615417 -26.331867)
			(xy 301.623189 -26.360882) (xy 303.28946 -26.360882) (xy 303.293531 -26.30526) (xy 303.305657 -26.250823)
			(xy 303.32558 -26.198732) (xy 303.352876 -26.150097) (xy 303.386962 -26.105954) (xy 303.427111 -26.067245)
			(xy 303.472469 -26.034794) (xy 303.522069 -26.009293) (xy 303.574853 -25.991286) (xy 303.629696 -25.981156)
			(xy 303.68543 -25.979119) (xy 303.740867 -25.985219) (xy 303.794824 -25.999325) (xy 303.846153 -26.021137)
			(xy 303.893759 -26.050191) (xy 303.936627 -26.085866) (xy 303.973844 -26.127403) (xy 304.004617 -26.173916)
			(xy 304.028289 -26.224413) (xy 304.044357 -26.27782) (xy 304.052477 -26.332996) (xy 304.052986 -26.360882)
			(xy 304.30546 -26.360882) (xy 304.309531 -26.30526) (xy 304.321657 -26.250823) (xy 304.34158 -26.198732)
			(xy 304.368876 -26.150097) (xy 304.402962 -26.105954) (xy 304.443111 -26.067245) (xy 304.488469 -26.034794)
			(xy 304.538069 -26.009293) (xy 304.590853 -25.991286) (xy 304.645696 -25.981156) (xy 304.70143 -25.979119)
			(xy 304.756867 -25.985219) (xy 304.810824 -25.999325) (xy 304.862153 -26.021137) (xy 304.909759 -26.050191)
			(xy 304.952627 -26.085866) (xy 304.989844 -26.127403) (xy 305.020617 -26.173916) (xy 305.044289 -26.224413)
			(xy 305.060357 -26.27782) (xy 305.068477 -26.332996) (xy 305.068986 -26.360882) (xy 305.068477 -26.388768)
			(xy 305.060357 -26.443944) (xy 305.044289 -26.497351) (xy 305.020617 -26.547848) (xy 304.989844 -26.594361)
			(xy 304.952627 -26.635898) (xy 304.909759 -26.671573) (xy 304.862153 -26.700627) (xy 304.810824 -26.722439)
			(xy 304.756867 -26.736545) (xy 304.70143 -26.742645) (xy 304.645696 -26.740608) (xy 304.590853 -26.730478)
			(xy 304.538069 -26.712471) (xy 304.488469 -26.68697) (xy 304.443111 -26.654519) (xy 304.402962 -26.61581)
			(xy 304.368876 -26.571667) (xy 304.34158 -26.523032) (xy 304.321657 -26.470941) (xy 304.309531 -26.416504)
			(xy 304.30546 -26.360882) (xy 304.052986 -26.360882) (xy 304.052477 -26.388768) (xy 304.044357 -26.443944)
			(xy 304.028289 -26.497351) (xy 304.004617 -26.547848) (xy 303.973844 -26.594361) (xy 303.936627 -26.635898)
			(xy 303.893759 -26.671573) (xy 303.846153 -26.700627) (xy 303.794824 -26.722439) (xy 303.740867 -26.736545)
			(xy 303.68543 -26.742645) (xy 303.629696 -26.740608) (xy 303.574853 -26.730478) (xy 303.522069 -26.712471)
			(xy 303.472469 -26.68697) (xy 303.427111 -26.654519) (xy 303.386962 -26.61581) (xy 303.352876 -26.571667)
			(xy 303.32558 -26.523032) (xy 303.305657 -26.470941) (xy 303.293531 -26.416504) (xy 303.28946 -26.360882)
			(xy 301.623189 -26.360882) (xy 301.630935 -26.389798) (xy 301.638758 -26.449259) (xy 301.639224 -26.479246)
			(xy 301.639224 -26.971244) (xy 305.05095 -26.971244) (xy 305.055021 -26.915622) (xy 305.067147 -26.861185)
			(xy 305.08707 -26.809094) (xy 305.114366 -26.760459) (xy 305.148452 -26.716316) (xy 305.188601 -26.677607)
			(xy 305.233959 -26.645156) (xy 305.283559 -26.619655) (xy 305.336343 -26.601648) (xy 305.391186 -26.591518)
			(xy 305.44692 -26.589481) (xy 305.502357 -26.595581) (xy 305.556314 -26.609687) (xy 305.607643 -26.631499)
			(xy 305.655249 -26.660553) (xy 305.698117 -26.696228) (xy 305.735334 -26.737765) (xy 305.766107 -26.784278)
			(xy 305.789779 -26.834775) (xy 305.805847 -26.888182) (xy 305.813967 -26.943358) (xy 305.814476 -26.971244)
			(xy 305.813967 -26.99913) (xy 305.805847 -27.054306) (xy 305.789779 -27.107713) (xy 305.766107 -27.15821)
			(xy 305.735334 -27.204723) (xy 305.698117 -27.24626) (xy 305.655249 -27.281935) (xy 305.607643 -27.310989)
			(xy 305.556314 -27.332801) (xy 305.502357 -27.346907) (xy 305.44692 -27.353007) (xy 305.391186 -27.35097)
			(xy 305.336343 -27.34084) (xy 305.283559 -27.322833) (xy 305.233959 -27.297332) (xy 305.188601 -27.264881)
			(xy 305.148452 -27.226172) (xy 305.114366 -27.182029) (xy 305.08707 -27.133394) (xy 305.067147 -27.081303)
			(xy 305.055021 -27.026866) (xy 305.05095 -26.971244) (xy 301.639224 -26.971244) (xy 301.639224 -27.342846)
			(xy 301.638815 -27.372833) (xy 301.630981 -27.432293) (xy 301.615453 -27.490222) (xy 301.592496 -27.545628)
			(xy 301.562504 -27.597564) (xy 301.52599 -27.645142) (xy 301.483578 -27.687546) (xy 301.435995 -27.724051)
			(xy 301.384053 -27.754034) (xy 301.328642 -27.77698) (xy 301.270711 -27.792497) (xy 301.211249 -27.80032)
			(xy 301.181262 -27.800808) (xy 301.150125 -27.800282) (xy 301.088429 -27.791815) (xy 301.028444 -27.775083)
			(xy 300.999652 -27.763216) (xy 300.988476 -27.75839) (xy 300.964854 -27.75966) (xy 300.873668 -27.810968)
			(xy 300.860206 -27.830526) (xy 300.858682 -27.842464) (xy 300.854498 -27.8695) (xy 300.839316 -27.92206)
			(xy 300.816784 -27.971913) (xy 300.787365 -28.018039) (xy 300.751661 -28.059491) (xy 300.710404 -28.09542)
			(xy 300.664439 -28.12509) (xy 300.614709 -28.147892) (xy 300.562232 -28.16336) (xy 300.508084 -28.171176)
			(xy 300.48073 -28.171648) (xy 300.453479 -28.171107) (xy 300.39953 -28.163354) (xy 300.347234 -28.148002)
			(xy 300.297655 -28.125364) (xy 300.251803 -28.0959) (xy 300.210611 -28.06021) (xy 300.174918 -28.019021)
			(xy 300.145451 -27.973171) (xy 300.122808 -27.923594) (xy 300.107452 -27.871299) (xy 300.099695 -27.817351)
			(xy 298.829741 -27.817351) (xy 298.829729 -27.818026) (xy 298.821609 -27.873202) (xy 298.805541 -27.926609)
			(xy 298.781869 -27.977106) (xy 298.751096 -28.023619) (xy 298.713879 -28.065156) (xy 298.671011 -28.100831)
			(xy 298.623405 -28.129885) (xy 298.572076 -28.151697) (xy 298.518119 -28.165803) (xy 298.462682 -28.171903)
			(xy 298.406948 -28.169866) (xy 298.352105 -28.159736) (xy 298.299321 -28.141729) (xy 298.249721 -28.116228)
			(xy 298.204363 -28.083777) (xy 298.164214 -28.045068) (xy 298.130128 -28.000925) (xy 298.102832 -27.95229)
			(xy 298.082909 -27.900199) (xy 298.070783 -27.845762) (xy 298.066712 -27.79014) (xy 296.326306 -27.79014)
			(xy 296.325797 -27.818026) (xy 296.317677 -27.873202) (xy 296.301609 -27.926609) (xy 296.277937 -27.977106)
			(xy 296.247164 -28.023619) (xy 296.209947 -28.065156) (xy 296.167079 -28.100831) (xy 296.119473 -28.129885)
			(xy 296.068144 -28.151697) (xy 296.014187 -28.165803) (xy 295.95875 -28.171903) (xy 295.903016 -28.169866)
			(xy 295.848173 -28.159736) (xy 295.795389 -28.141729) (xy 295.745789 -28.116228) (xy 295.700431 -28.083777)
			(xy 295.660282 -28.045068) (xy 295.626196 -28.000925) (xy 295.5989 -27.95229) (xy 295.578977 -27.900199)
			(xy 295.566851 -27.845762) (xy 295.56278 -27.79014) (xy 294.229805 -27.79014) (xy 294.229805 -27.81735)
			(xy 294.222048 -27.871297) (xy 294.206693 -27.92359) (xy 294.184053 -27.973165) (xy 294.154587 -28.019014)
			(xy 294.118896 -28.060203) (xy 294.077706 -28.095893) (xy 294.031857 -28.125357) (xy 293.98228 -28.147997)
			(xy 293.929987 -28.16335) (xy 293.87604 -28.171105) (xy 293.84879 -28.171648) (xy 293.845996 -28.171648)
			(xy 293.83603 -28.172124) (xy 293.817594 -28.179701) (xy 293.810182 -28.18638) (xy 293.758874 -28.23718)
			(xy 293.752032 -28.244579) (xy 293.744315 -28.263178) (xy 293.743888 -28.273248) (xy 293.743888 -29.106876)
			(xy 293.744324 -29.11694) (xy 293.752057 -29.135526) (xy 293.758874 -29.142944) (xy 293.810182 -29.193744)
			(xy 293.817593 -29.200426) (xy 293.836028 -29.208008) (xy 293.845996 -29.208476) (xy 293.84879 -29.208476)
			(xy 293.876044 -29.208938) (xy 293.929999 -29.216694) (xy 293.9823 -29.23205) (xy 294.031884 -29.254693)
			(xy 294.07774 -29.284162) (xy 294.118936 -29.319857) (xy 294.154632 -29.361052) (xy 294.184102 -29.406908)
			(xy 294.206746 -29.45649) (xy 294.222104 -29.508791) (xy 294.229861 -29.562746) (xy 294.229861 -29.589984)
			(xy 295.56278 -29.589984) (xy 295.566851 -29.534362) (xy 295.578977 -29.479925) (xy 295.5989 -29.427834)
			(xy 295.626196 -29.379199) (xy 295.660282 -29.335056) (xy 295.700431 -29.296347) (xy 295.745789 -29.263896)
			(xy 295.795389 -29.238395) (xy 295.848173 -29.220388) (xy 295.903016 -29.210258) (xy 295.95875 -29.208221)
			(xy 296.014187 -29.214321) (xy 296.068144 -29.228427) (xy 296.119473 -29.250239) (xy 296.167079 -29.279293)
			(xy 296.209947 -29.314968) (xy 296.247164 -29.356505) (xy 296.277937 -29.403018) (xy 296.301609 -29.453515)
			(xy 296.317677 -29.506922) (xy 296.325797 -29.562098) (xy 296.326306 -29.589984) (xy 298.066712 -29.589984)
			(xy 298.070783 -29.534362) (xy 298.082909 -29.479925) (xy 298.102832 -29.427834) (xy 298.130128 -29.379199)
			(xy 298.164214 -29.335056) (xy 298.204363 -29.296347) (xy 298.249721 -29.263896) (xy 298.299321 -29.238395)
			(xy 298.352105 -29.220388) (xy 298.406948 -29.210258) (xy 298.462682 -29.208221) (xy 298.518119 -29.214321)
			(xy 298.572076 -29.228427) (xy 298.623405 -29.250239) (xy 298.671011 -29.279293) (xy 298.713879 -29.314968)
			(xy 298.751096 -29.356505) (xy 298.781869 -29.403018) (xy 298.805541 -29.453515) (xy 298.821609 -29.506922)
			(xy 298.829729 -29.562098) (xy 298.830238 -29.589984) (xy 300.098712 -29.589984) (xy 300.102783 -29.534362)
			(xy 300.114909 -29.479925) (xy 300.134832 -29.427834) (xy 300.162128 -29.379199) (xy 300.196214 -29.335056)
			(xy 300.236363 -29.296347) (xy 300.281721 -29.263896) (xy 300.331321 -29.238395) (xy 300.384105 -29.220388)
			(xy 300.438948 -29.210258) (xy 300.494682 -29.208221) (xy 300.550119 -29.214321) (xy 300.604076 -29.228427)
			(xy 300.655405 -29.250239) (xy 300.703011 -29.279293) (xy 300.745879 -29.314968) (xy 300.767552 -29.339157)
			(xy 302.490009 -29.339157) (xy 302.490009 -29.284643) (xy 302.497768 -29.230683) (xy 302.513127 -29.178377)
			(xy 302.535774 -29.128789) (xy 302.565248 -29.082929) (xy 302.600948 -29.041731) (xy 302.642149 -29.006033)
			(xy 302.68801 -28.976562) (xy 302.7376 -28.953918) (xy 302.789907 -28.938562) (xy 302.843867 -28.930807)
			(xy 302.871124 -28.930346) (xy 302.885917 -28.930476) (xy 302.915415 -28.932769) (xy 302.930052 -28.934918)
			(xy 302.940974 -28.936696) (xy 302.96231 -28.9306) (xy 303.02962 -28.873196) (xy 303.037646 -28.865627)
			(xy 303.046862 -28.845607) (xy 303.0474 -28.834588) (xy 303.0474 -28.530296) (xy 303.046865 -28.519277)
			(xy 303.037643 -28.49926) (xy 303.02962 -28.491688) (xy 302.96231 -28.434284) (xy 302.940974 -28.428188)
			(xy 302.930052 -28.429966) (xy 302.915414 -28.432107) (xy 302.885917 -28.434395) (xy 302.871124 -28.434538)
			(xy 302.843872 -28.434016) (xy 302.789923 -28.426263) (xy 302.737626 -28.41091) (xy 302.688047 -28.388271)
			(xy 302.642194 -28.358806) (xy 302.601002 -28.323115) (xy 302.565309 -28.281925) (xy 302.535841 -28.236074)
			(xy 302.513198 -28.186496) (xy 302.497842 -28.134201) (xy 302.490085 -28.080252) (xy 302.490085 -28.025748)
			(xy 302.497842 -27.971799) (xy 302.513198 -27.919504) (xy 302.535841 -27.869926) (xy 302.565309 -27.824075)
			(xy 302.601002 -27.782885) (xy 302.642194 -27.747194) (xy 302.688047 -27.717729) (xy 302.737626 -27.69509)
			(xy 302.789923 -27.679737) (xy 302.843872 -27.671984) (xy 302.871124 -27.671522) (xy 302.897051 -27.671928)
			(xy 302.94843 -27.678938) (xy 302.998386 -27.692838) (xy 303.046001 -27.713374) (xy 303.090397 -27.740168)
			(xy 303.130758 -27.772724) (xy 303.166339 -27.810445) (xy 303.181766 -27.831288) (xy 303.187508 -27.838617)
			(xy 303.20301 -27.848903) (xy 303.211992 -27.851354) (xy 303.242218 -27.858212) (xy 303.251496 -27.859946)
			(xy 303.270157 -27.857215) (xy 303.27854 -27.852878) (xy 303.304508 -27.838569) (xy 303.359363 -27.816062)
			(xy 303.416669 -27.800839) (xy 303.475462 -27.793158) (xy 303.505108 -27.79268) (xy 303.534751 -27.793163)
			(xy 303.593534 -27.800888) (xy 303.650832 -27.816119) (xy 303.705692 -27.838602) (xy 303.731676 -27.852878)
			(xy 303.74009 -27.857123) (xy 303.758719 -27.859857) (xy 303.767998 -27.858212) (xy 303.798224 -27.851354)
			(xy 303.807218 -27.848928) (xy 303.822723 -27.838634) (xy 303.82845 -27.831288) (xy 303.84388 -27.810446)
			(xy 303.879449 -27.772711) (xy 303.919804 -27.740144) (xy 303.9642 -27.713348) (xy 304.011818 -27.692816)
			(xy 304.06178 -27.678927) (xy 304.113163 -27.671938) (xy 304.139092 -27.671522) (xy 304.166347 -27.671924)
			(xy 304.220303 -27.679681) (xy 304.272606 -27.695038) (xy 304.322192 -27.717681) (xy 304.368049 -27.747152)
			(xy 304.409246 -27.782848) (xy 304.444944 -27.824044) (xy 304.474415 -27.869901) (xy 304.49706 -27.919486)
			(xy 304.512417 -27.971789) (xy 304.520175 -28.025745) (xy 304.520175 -28.080255) (xy 304.512417 -28.134211)
			(xy 304.49706 -28.186514) (xy 304.474415 -28.236099) (xy 304.444944 -28.281956) (xy 304.409246 -28.323152)
			(xy 304.368049 -28.358848) (xy 304.322192 -28.388319) (xy 304.272606 -28.410962) (xy 304.220303 -28.426319)
			(xy 304.166347 -28.434076) (xy 304.139092 -28.434538) (xy 304.124299 -28.434406) (xy 304.094801 -28.432115)
			(xy 304.080164 -28.429966) (xy 304.069242 -28.428188) (xy 304.047906 -28.434284) (xy 303.980596 -28.491688)
			(xy 303.97258 -28.499266) (xy 303.963358 -28.519279) (xy 303.962816 -28.530296) (xy 303.962816 -28.834588)
			(xy 303.963355 -28.845607) (xy 303.972573 -28.865624) (xy 303.980596 -28.873196) (xy 304.047906 -28.9306)
			(xy 304.069242 -28.936696) (xy 304.080164 -28.934918) (xy 304.094802 -28.932775) (xy 304.124299 -28.930488)
			(xy 304.139092 -28.930346) (xy 304.166342 -28.930901) (xy 304.220287 -28.938656) (xy 304.27258 -28.954009)
			(xy 304.322155 -28.976649) (xy 304.368004 -29.006113) (xy 304.409192 -29.041802) (xy 304.444882 -29.08299)
			(xy 304.474348 -29.128838) (xy 304.496988 -29.178413) (xy 304.512343 -29.230705) (xy 304.520099 -29.28465)
			(xy 304.520099 -29.33915) (xy 304.512343 -29.393095) (xy 304.496988 -29.445387) (xy 304.474348 -29.494962)
			(xy 304.444882 -29.54081) (xy 304.409192 -29.581998) (xy 304.368003 -29.617687) (xy 304.322155 -29.647151)
			(xy 304.27258 -29.669791) (xy 304.220287 -29.685144) (xy 304.166342 -29.692899) (xy 304.139092 -29.693362)
			(xy 304.113165 -29.692951) (xy 304.061786 -29.685943) (xy 304.011829 -29.672043) (xy 303.964214 -29.651508)
			(xy 303.919818 -29.624716) (xy 303.879458 -29.59216) (xy 303.843877 -29.554439) (xy 303.82845 -29.533596)
			(xy 303.822686 -29.526287) (xy 303.807201 -29.515988) (xy 303.798224 -29.51353) (xy 303.767998 -29.506672)
			(xy 303.758719 -29.504949) (xy 303.740059 -29.507673) (xy 303.731676 -29.512006) (xy 303.705704 -29.526308)
			(xy 303.65085 -29.548817) (xy 303.593546 -29.564041) (xy 303.534754 -29.571725) (xy 303.505108 -29.572204)
			(xy 303.475465 -29.571716) (xy 303.416682 -29.563993) (xy 303.359384 -29.548763) (xy 303.304524 -29.526282)
			(xy 303.27854 -29.512006) (xy 303.270123 -29.507769) (xy 303.251497 -29.50503) (xy 303.242218 -29.506672)
			(xy 303.211992 -29.51353) (xy 303.203002 -29.515968) (xy 303.187495 -29.526253) (xy 303.181766 -29.533596)
			(xy 303.166321 -29.554427) (xy 303.130756 -29.592163) (xy 303.090404 -29.624731) (xy 303.04601 -29.651529)
			(xy 302.998393 -29.672063) (xy 302.948434 -29.685954) (xy 302.897052 -29.692945) (xy 302.871124 -29.693362)
			(xy 302.843867 -29.692993) (xy 302.789907 -29.685238) (xy 302.7376 -29.669882) (xy 302.68801 -29.647238)
			(xy 302.642149 -29.617767) (xy 302.600948 -29.582069) (xy 302.565248 -29.540871) (xy 302.535774 -29.495011)
			(xy 302.513127 -29.445423) (xy 302.497768 -29.393117) (xy 302.490009 -29.339157) (xy 300.767552 -29.339157)
			(xy 300.783096 -29.356505) (xy 300.813869 -29.403018) (xy 300.837541 -29.453515) (xy 300.853609 -29.506922)
			(xy 300.861729 -29.562098) (xy 300.862238 -29.589984) (xy 300.861729 -29.61787) (xy 300.853609 -29.673046)
			(xy 300.837541 -29.726453) (xy 300.813869 -29.77695) (xy 300.783096 -29.823463) (xy 300.745879 -29.865)
			(xy 300.703011 -29.900675) (xy 300.655405 -29.929729) (xy 300.604076 -29.951541) (xy 300.550119 -29.965647)
			(xy 300.494682 -29.971747) (xy 300.438948 -29.96971) (xy 300.384105 -29.95958) (xy 300.331321 -29.941573)
			(xy 300.281721 -29.916072) (xy 300.236363 -29.883621) (xy 300.196214 -29.844912) (xy 300.162128 -29.800769)
			(xy 300.134832 -29.752134) (xy 300.114909 -29.700043) (xy 300.102783 -29.645606) (xy 300.098712 -29.589984)
			(xy 298.830238 -29.589984) (xy 298.829729 -29.61787) (xy 298.821609 -29.673046) (xy 298.805541 -29.726453)
			(xy 298.781869 -29.77695) (xy 298.751096 -29.823463) (xy 298.713879 -29.865) (xy 298.671011 -29.900675)
			(xy 298.623405 -29.929729) (xy 298.572076 -29.951541) (xy 298.518119 -29.965647) (xy 298.462682 -29.971747)
			(xy 298.406948 -29.96971) (xy 298.352105 -29.95958) (xy 298.299321 -29.941573) (xy 298.249721 -29.916072)
			(xy 298.204363 -29.883621) (xy 298.164214 -29.844912) (xy 298.130128 -29.800769) (xy 298.102832 -29.752134)
			(xy 298.082909 -29.700043) (xy 298.070783 -29.645606) (xy 298.066712 -29.589984) (xy 296.326306 -29.589984)
			(xy 296.325797 -29.61787) (xy 296.317677 -29.673046) (xy 296.301609 -29.726453) (xy 296.277937 -29.77695)
			(xy 296.247164 -29.823463) (xy 296.209947 -29.865) (xy 296.167079 -29.900675) (xy 296.119473 -29.929729)
			(xy 296.068144 -29.951541) (xy 296.014187 -29.965647) (xy 295.95875 -29.971747) (xy 295.903016 -29.96971)
			(xy 295.848173 -29.95958) (xy 295.795389 -29.941573) (xy 295.745789 -29.916072) (xy 295.700431 -29.883621)
			(xy 295.660282 -29.844912) (xy 295.626196 -29.800769) (xy 295.5989 -29.752134) (xy 295.578977 -29.700043)
			(xy 295.566851 -29.645606) (xy 295.56278 -29.589984) (xy 294.229861 -29.589984) (xy 294.229861 -29.617254)
			(xy 294.222104 -29.671209) (xy 294.206746 -29.72351) (xy 294.184102 -29.773092) (xy 294.154632 -29.818948)
			(xy 294.118936 -29.860143) (xy 294.07774 -29.895838) (xy 294.031884 -29.925307) (xy 293.9823 -29.94795)
			(xy 293.929999 -29.963306) (xy 293.876044 -29.971062) (xy 293.84879 -29.971492) (xy 293.845996 -29.971492)
			(xy 293.836029 -29.971967) (xy 293.817587 -29.979538) (xy 293.810182 -29.986224) (xy 293.758874 -30.037024)
			(xy 293.752023 -30.04442) (xy 293.744286 -30.063019) (xy 293.743888 -30.073092) (xy 293.743888 -30.906974)
			(xy 293.744324 -30.917039) (xy 293.752056 -30.935625) (xy 293.758874 -30.943042) (xy 293.810182 -30.993842)
			(xy 293.817593 -31.000525) (xy 293.836028 -31.008107) (xy 293.845996 -31.008574) (xy 293.84879 -31.008574)
			(xy 293.876045 -31.009036) (xy 293.929999 -31.016792) (xy 293.982301 -31.032148) (xy 294.031885 -31.054791)
			(xy 294.077741 -31.08426) (xy 294.118937 -31.119956) (xy 294.154634 -31.161151) (xy 294.184104 -31.207007)
			(xy 294.206748 -31.25659) (xy 294.222105 -31.308891) (xy 294.229863 -31.362845) (xy 294.229863 -31.417355)
			(xy 294.222105 -31.471309) (xy 294.206748 -31.52361) (xy 294.184104 -31.573193) (xy 294.154634 -31.619049)
			(xy 294.134483 -31.642304) (xy 295.606468 -31.642304) (xy 295.610539 -31.586682) (xy 295.622665 -31.532245)
			(xy 295.642588 -31.480154) (xy 295.669884 -31.431519) (xy 295.70397 -31.387376) (xy 295.744119 -31.348667)
			(xy 295.789477 -31.316216) (xy 295.839077 -31.290715) (xy 295.891861 -31.272708) (xy 295.946704 -31.262578)
			(xy 296.002438 -31.260541) (xy 296.057875 -31.266641) (xy 296.111832 -31.280747) (xy 296.163161 -31.302559)
			(xy 296.210767 -31.331613) (xy 296.253635 -31.367288) (xy 296.274058 -31.390082) (xy 298.066712 -31.390082)
			(xy 298.070783 -31.33446) (xy 298.082909 -31.280023) (xy 298.102832 -31.227932) (xy 298.130128 -31.179297)
			(xy 298.164214 -31.135154) (xy 298.204363 -31.096445) (xy 298.249721 -31.063994) (xy 298.299321 -31.038493)
			(xy 298.352105 -31.020486) (xy 298.406948 -31.010356) (xy 298.462682 -31.008319) (xy 298.518119 -31.014419)
			(xy 298.572076 -31.028525) (xy 298.623405 -31.050337) (xy 298.671011 -31.079391) (xy 298.713879 -31.115066)
			(xy 298.751096 -31.156603) (xy 298.781869 -31.203116) (xy 298.805541 -31.253613) (xy 298.821609 -31.30702)
			(xy 298.829729 -31.362196) (xy 298.830238 -31.390082) (xy 300.098712 -31.390082) (xy 300.102783 -31.33446)
			(xy 300.114909 -31.280023) (xy 300.134832 -31.227932) (xy 300.162128 -31.179297) (xy 300.196214 -31.135154)
			(xy 300.236363 -31.096445) (xy 300.281721 -31.063994) (xy 300.331321 -31.038493) (xy 300.384105 -31.020486)
			(xy 300.438948 -31.010356) (xy 300.494682 -31.008319) (xy 300.550119 -31.014419) (xy 300.604076 -31.028525)
			(xy 300.655405 -31.050337) (xy 300.703011 -31.079391) (xy 300.745879 -31.115066) (xy 300.783096 -31.156603)
			(xy 300.813869 -31.203116) (xy 300.837541 -31.253613) (xy 300.853609 -31.30702) (xy 300.861729 -31.362196)
			(xy 300.862238 -31.390082) (xy 300.861729 -31.417968) (xy 300.853609 -31.473144) (xy 300.837541 -31.526551)
			(xy 300.813869 -31.577048) (xy 300.783096 -31.623561) (xy 300.745879 -31.665098) (xy 300.727665 -31.680256)
			(xy 302.490027 -31.680256) (xy 302.490027 -31.625744) (xy 302.497785 -31.571787) (xy 302.513144 -31.519483)
			(xy 302.535789 -31.469898) (xy 302.565262 -31.42404) (xy 302.600961 -31.382844) (xy 302.642159 -31.347148)
			(xy 302.688019 -31.317678) (xy 302.737606 -31.295035) (xy 302.78991 -31.27968) (xy 302.843868 -31.271925)
			(xy 302.871124 -31.271464) (xy 302.897052 -31.271852) (xy 302.948432 -31.278863) (xy 302.99839 -31.292766)
			(xy 303.046005 -31.313304) (xy 303.090401 -31.3401) (xy 303.130761 -31.37266) (xy 303.16634 -31.410385)
			(xy 303.181766 -31.43123) (xy 303.187519 -31.438549) (xy 303.203012 -31.448842) (xy 303.211992 -31.451296)
			(xy 303.242218 -31.458154) (xy 303.251497 -31.459883) (xy 303.270157 -31.457154) (xy 303.27854 -31.45282)
			(xy 303.304525 -31.438563) (xy 303.359396 -31.416151) (xy 303.416697 -31.400995) (xy 303.475472 -31.393347)
			(xy 303.505108 -31.392876) (xy 303.534746 -31.393313) (xy 303.593529 -31.40094) (xy 303.650833 -31.416105)
			(xy 303.705694 -31.438553) (xy 303.731676 -31.45282) (xy 303.740091 -31.457063) (xy 303.758719 -31.4598)
			(xy 303.767998 -31.458154) (xy 303.798224 -31.451296) (xy 303.807213 -31.448856) (xy 303.82272 -31.438572)
			(xy 303.82845 -31.43123) (xy 303.843863 -31.410376) (xy 303.879437 -31.372643) (xy 303.919795 -31.340079)
			(xy 303.964194 -31.313286) (xy 304.011815 -31.292756) (xy 304.061778 -31.278868) (xy 304.113163 -31.27188)
			(xy 304.139092 -31.271464) (xy 304.166343 -31.271983) (xy 304.220291 -31.279738) (xy 304.272586 -31.295092)
			(xy 304.322164 -31.317733) (xy 304.368014 -31.347198) (xy 304.409205 -31.382889) (xy 304.444897 -31.424079)
			(xy 304.474363 -31.469929) (xy 304.497005 -31.519506) (xy 304.51236 -31.571801) (xy 304.520117 -31.625749)
			(xy 304.520117 -31.680251) (xy 304.51236 -31.734199) (xy 304.497005 -31.786494) (xy 304.474363 -31.836071)
			(xy 304.444897 -31.881921) (xy 304.409205 -31.923111) (xy 304.368014 -31.958802) (xy 304.322164 -31.988267)
			(xy 304.272586 -32.010908) (xy 304.220291 -32.026262) (xy 304.166343 -32.034017) (xy 304.139092 -32.03448)
			(xy 304.124299 -32.034348) (xy 304.094801 -32.032057) (xy 304.080164 -32.029908) (xy 304.069242 -32.02813)
			(xy 304.047906 -32.034226) (xy 303.980596 -32.09163) (xy 303.972561 -32.099191) (xy 303.963349 -32.119216)
			(xy 303.962816 -32.130238) (xy 303.962816 -32.43453) (xy 303.963332 -32.445552) (xy 303.972566 -32.465568)
			(xy 303.980596 -32.473138) (xy 304.047906 -32.530542) (xy 304.069242 -32.536638) (xy 304.080164 -32.53486)
			(xy 304.094802 -32.532717) (xy 304.124299 -32.53043) (xy 304.139092 -32.530288) (xy 304.166345 -32.530759)
			(xy 304.220296 -32.538515) (xy 304.272594 -32.55387) (xy 304.322175 -32.576512) (xy 304.368029 -32.605979)
			(xy 304.409222 -32.641672) (xy 304.444916 -32.682865) (xy 304.474384 -32.728718) (xy 304.497027 -32.778298)
			(xy 304.512384 -32.830596) (xy 304.520141 -32.884547) (xy 304.520141 -32.939053) (xy 304.512384 -32.993004)
			(xy 304.497027 -33.045302) (xy 304.474384 -33.094882) (xy 304.444916 -33.140735) (xy 304.409222 -33.181928)
			(xy 304.368029 -33.217621) (xy 304.322175 -33.247088) (xy 304.272594 -33.26973) (xy 304.220296 -33.285085)
			(xy 304.166345 -33.292841) (xy 304.139092 -33.293304) (xy 304.113166 -33.292876) (xy 304.061788 -33.285868)
			(xy 304.011833 -33.271971) (xy 303.964218 -33.251438) (xy 303.919822 -33.224649) (xy 303.879461 -33.192096)
			(xy 303.843878 -33.154379) (xy 303.82845 -33.133538) (xy 303.822697 -33.126219) (xy 303.807204 -33.115927)
			(xy 303.798224 -33.113472) (xy 303.767998 -33.106614) (xy 303.758719 -33.104885) (xy 303.740058 -33.107612)
			(xy 303.731676 -33.111948) (xy 303.705686 -33.126196) (xy 303.650818 -33.148611) (xy 303.593518 -33.163769)
			(xy 303.534743 -33.171419) (xy 303.505108 -33.171892) (xy 303.47547 -33.171453) (xy 303.416687 -33.163827)
			(xy 303.359383 -33.148663) (xy 303.304522 -33.126215) (xy 303.27854 -33.111948) (xy 303.270123 -33.107712)
			(xy 303.251496 -33.104971) (xy 303.242218 -33.106614) (xy 303.211992 -33.113472) (xy 303.203009 -33.115929)
			(xy 303.1875 -33.126202) (xy 303.181766 -33.133538) (xy 303.166333 -33.154378) (xy 303.130764 -33.192112)
			(xy 303.09041 -33.224678) (xy 303.046014 -33.251474) (xy 302.998396 -33.272007) (xy 302.948435 -33.285896)
			(xy 302.897052 -33.292887) (xy 302.871124 -33.293304) (xy 302.84387 -33.29285) (xy 302.789916 -33.285096)
			(xy 302.737614 -33.269742) (xy 302.688031 -33.247101) (xy 302.642174 -33.217633) (xy 302.600978 -33.181939)
			(xy 302.565282 -33.140745) (xy 302.535811 -33.09489) (xy 302.513167 -33.045308) (xy 302.497809 -32.993008)
			(xy 302.490051 -32.939054) (xy 302.490051 -32.884546) (xy 302.497809 -32.830592) (xy 302.513167 -32.778292)
			(xy 302.535811 -32.72871) (xy 302.565282 -32.682855) (xy 302.600978 -32.641661) (xy 302.642174 -32.605967)
			(xy 302.688031 -32.576499) (xy 302.737614 -32.553858) (xy 302.789916 -32.538504) (xy 302.84387 -32.53075)
			(xy 302.871124 -32.530288) (xy 302.885917 -32.530419) (xy 302.915415 -32.532711) (xy 302.930052 -32.53486)
			(xy 302.940974 -32.536638) (xy 302.96231 -32.530542) (xy 303.02962 -32.473138) (xy 303.037627 -32.465552)
			(xy 303.046853 -32.445545) (xy 303.0474 -32.43453) (xy 303.0474 -32.130238) (xy 303.046841 -32.119222)
			(xy 303.037637 -32.099205) (xy 303.02962 -32.09163) (xy 302.96231 -32.034226) (xy 302.940974 -32.02813)
			(xy 302.930052 -32.029908) (xy 302.915414 -32.032049) (xy 302.885917 -32.034337) (xy 302.871124 -32.03448)
			(xy 302.843868 -32.034075) (xy 302.78991 -32.02632) (xy 302.737606 -32.010965) (xy 302.688019 -31.988322)
			(xy 302.642159 -31.958852) (xy 302.600961 -31.923156) (xy 302.565262 -31.88196) (xy 302.535789 -31.836102)
			(xy 302.513144 -31.786517) (xy 302.497785 -31.734213) (xy 302.490027 -31.680256) (xy 300.727665 -31.680256)
			(xy 300.703011 -31.700773) (xy 300.655405 -31.729827) (xy 300.604076 -31.751639) (xy 300.550119 -31.765745)
			(xy 300.494682 -31.771845) (xy 300.438948 -31.769808) (xy 300.384105 -31.759678) (xy 300.331321 -31.741671)
			(xy 300.281721 -31.71617) (xy 300.236363 -31.683719) (xy 300.196214 -31.64501) (xy 300.162128 -31.600867)
			(xy 300.134832 -31.552232) (xy 300.114909 -31.500141) (xy 300.102783 -31.445704) (xy 300.098712 -31.390082)
			(xy 298.830238 -31.390082) (xy 298.829729 -31.417968) (xy 298.821609 -31.473144) (xy 298.805541 -31.526551)
			(xy 298.781869 -31.577048) (xy 298.751096 -31.623561) (xy 298.713879 -31.665098) (xy 298.671011 -31.700773)
			(xy 298.623405 -31.729827) (xy 298.572076 -31.751639) (xy 298.518119 -31.765745) (xy 298.462682 -31.771845)
			(xy 298.406948 -31.769808) (xy 298.352105 -31.759678) (xy 298.299321 -31.741671) (xy 298.249721 -31.71617)
			(xy 298.204363 -31.683719) (xy 298.164214 -31.64501) (xy 298.130128 -31.600867) (xy 298.102832 -31.552232)
			(xy 298.082909 -31.500141) (xy 298.070783 -31.445704) (xy 298.066712 -31.390082) (xy 296.274058 -31.390082)
			(xy 296.290852 -31.408825) (xy 296.321625 -31.455338) (xy 296.345297 -31.505835) (xy 296.361365 -31.559242)
			(xy 296.369485 -31.614418) (xy 296.369994 -31.642304) (xy 296.369485 -31.67019) (xy 296.361365 -31.725366)
			(xy 296.345297 -31.778773) (xy 296.321625 -31.82927) (xy 296.290852 -31.875783) (xy 296.253635 -31.91732)
			(xy 296.210767 -31.952995) (xy 296.163161 -31.982049) (xy 296.111832 -32.003861) (xy 296.057875 -32.017967)
			(xy 296.002438 -32.024067) (xy 295.946704 -32.02203) (xy 295.891861 -32.0119) (xy 295.839077 -31.993893)
			(xy 295.789477 -31.968392) (xy 295.744119 -31.935941) (xy 295.70397 -31.897232) (xy 295.669884 -31.853089)
			(xy 295.642588 -31.804454) (xy 295.622665 -31.752363) (xy 295.610539 -31.697926) (xy 295.606468 -31.642304)
			(xy 294.134483 -31.642304) (xy 294.118937 -31.660244) (xy 294.077741 -31.69594) (xy 294.031885 -31.725409)
			(xy 293.982301 -31.748052) (xy 293.929999 -31.763408) (xy 293.876045 -31.771164) (xy 293.84879 -31.77159)
			(xy 293.845996 -31.77159) (xy 293.836029 -31.772065) (xy 293.817587 -31.779636) (xy 293.810182 -31.786322)
			(xy 293.758874 -31.837122) (xy 293.752023 -31.844518) (xy 293.744285 -31.863117) (xy 293.743888 -31.87319)
			(xy 293.743888 -32.707072) (xy 293.744324 -32.717137) (xy 293.752055 -32.735723) (xy 293.758874 -32.74314)
			(xy 293.810182 -32.79394) (xy 293.817592 -32.800623) (xy 293.836028 -32.808205) (xy 293.845996 -32.808672)
			(xy 293.84879 -32.808672) (xy 293.876045 -32.809134) (xy 293.93 -32.81689) (xy 293.982302 -32.832246)
			(xy 294.031886 -32.85489) (xy 294.077742 -32.884359) (xy 294.118938 -32.920054) (xy 294.154635 -32.96125)
			(xy 294.184106 -33.007106) (xy 294.20675 -33.056689) (xy 294.222107 -33.108991) (xy 294.229865 -33.162945)
			(xy 294.229865 -33.19018) (xy 295.87393 -33.19018) (xy 295.878001 -33.134558) (xy 295.890127 -33.080121)
			(xy 295.91005 -33.02803) (xy 295.937346 -32.979395) (xy 295.971432 -32.935252) (xy 296.011581 -32.896543)
			(xy 296.056939 -32.864092) (xy 296.106539 -32.838591) (xy 296.159323 -32.820584) (xy 296.214166 -32.810454)
			(xy 296.2699 -32.808417) (xy 296.325337 -32.814517) (xy 296.379294 -32.828623) (xy 296.430623 -32.850435)
			(xy 296.478229 -32.879489) (xy 296.521097 -32.915164) (xy 296.558314 -32.956701) (xy 296.589087 -33.003214)
			(xy 296.612759 -33.053711) (xy 296.628827 -33.107118) (xy 296.636947 -33.162294) (xy 296.637456 -33.19018)
			(xy 298.066712 -33.19018) (xy 298.070783 -33.134558) (xy 298.082909 -33.080121) (xy 298.102832 -33.02803)
			(xy 298.130128 -32.979395) (xy 298.164214 -32.935252) (xy 298.204363 -32.896543) (xy 298.249721 -32.864092)
			(xy 298.299321 -32.838591) (xy 298.352105 -32.820584) (xy 298.406948 -32.810454) (xy 298.462682 -32.808417)
			(xy 298.518119 -32.814517) (xy 298.572076 -32.828623) (xy 298.623405 -32.850435) (xy 298.671011 -32.879489)
			(xy 298.713879 -32.915164) (xy 298.751096 -32.956701) (xy 298.781869 -33.003214) (xy 298.805541 -33.053711)
			(xy 298.821609 -33.107118) (xy 298.829729 -33.162294) (xy 298.830238 -33.19018) (xy 300.098712 -33.19018)
			(xy 300.102783 -33.134558) (xy 300.114909 -33.080121) (xy 300.134832 -33.02803) (xy 300.162128 -32.979395)
			(xy 300.196214 -32.935252) (xy 300.236363 -32.896543) (xy 300.281721 -32.864092) (xy 300.331321 -32.838591)
			(xy 300.384105 -32.820584) (xy 300.438948 -32.810454) (xy 300.494682 -32.808417) (xy 300.550119 -32.814517)
			(xy 300.604076 -32.828623) (xy 300.655405 -32.850435) (xy 300.703011 -32.879489) (xy 300.745879 -32.915164)
			(xy 300.783096 -32.956701) (xy 300.813869 -33.003214) (xy 300.837541 -33.053711) (xy 300.853609 -33.107118)
			(xy 300.861729 -33.162294) (xy 300.862238 -33.19018) (xy 300.861729 -33.218066) (xy 300.853609 -33.273242)
			(xy 300.837541 -33.326649) (xy 300.813869 -33.377146) (xy 300.783096 -33.423659) (xy 300.745879 -33.465196)
			(xy 300.703011 -33.500871) (xy 300.655405 -33.529925) (xy 300.604076 -33.551737) (xy 300.550119 -33.565843)
			(xy 300.494682 -33.571943) (xy 300.438948 -33.569906) (xy 300.384105 -33.559776) (xy 300.331321 -33.541769)
			(xy 300.281721 -33.516268) (xy 300.236363 -33.483817) (xy 300.196214 -33.445108) (xy 300.162128 -33.400965)
			(xy 300.134832 -33.35233) (xy 300.114909 -33.300239) (xy 300.102783 -33.245802) (xy 300.098712 -33.19018)
			(xy 298.830238 -33.19018) (xy 298.829729 -33.218066) (xy 298.821609 -33.273242) (xy 298.805541 -33.326649)
			(xy 298.781869 -33.377146) (xy 298.751096 -33.423659) (xy 298.713879 -33.465196) (xy 298.671011 -33.500871)
			(xy 298.623405 -33.529925) (xy 298.572076 -33.551737) (xy 298.518119 -33.565843) (xy 298.462682 -33.571943)
			(xy 298.406948 -33.569906) (xy 298.352105 -33.559776) (xy 298.299321 -33.541769) (xy 298.249721 -33.516268)
			(xy 298.204363 -33.483817) (xy 298.164214 -33.445108) (xy 298.130128 -33.400965) (xy 298.102832 -33.35233)
			(xy 298.082909 -33.300239) (xy 298.070783 -33.245802) (xy 298.066712 -33.19018) (xy 296.637456 -33.19018)
			(xy 296.636947 -33.218066) (xy 296.628827 -33.273242) (xy 296.612759 -33.326649) (xy 296.589087 -33.377146)
			(xy 296.558314 -33.423659) (xy 296.521097 -33.465196) (xy 296.478229 -33.500871) (xy 296.430623 -33.529925)
			(xy 296.379294 -33.551737) (xy 296.325337 -33.565843) (xy 296.2699 -33.571943) (xy 296.214166 -33.569906)
			(xy 296.159323 -33.559776) (xy 296.106539 -33.541769) (xy 296.056939 -33.516268) (xy 296.011581 -33.483817)
			(xy 295.971432 -33.445108) (xy 295.937346 -33.400965) (xy 295.91005 -33.35233) (xy 295.890127 -33.300239)
			(xy 295.878001 -33.245802) (xy 295.87393 -33.19018) (xy 294.229865 -33.19018) (xy 294.229865 -33.217455)
			(xy 294.222107 -33.271409) (xy 294.20675 -33.323711) (xy 294.184106 -33.373294) (xy 294.154635 -33.41915)
			(xy 294.118938 -33.460346) (xy 294.077742 -33.496041) (xy 294.031886 -33.52551) (xy 293.982302 -33.548154)
			(xy 293.93 -33.56351) (xy 293.876045 -33.571266) (xy 293.84879 -33.571688) (xy 293.845996 -33.571688)
			(xy 293.836029 -33.572163) (xy 293.817587 -33.579733) (xy 293.810182 -33.58642) (xy 293.758874 -33.63722)
			(xy 293.752023 -33.644616) (xy 293.744284 -33.663215) (xy 293.743888 -33.673288) (xy 293.743888 -34.506916)
			(xy 293.744314 -34.516985) (xy 293.752031 -34.535587) (xy 293.758874 -34.542984) (xy 293.810182 -34.593784)
			(xy 293.81759 -34.600473) (xy 293.836026 -34.608064) (xy 293.845996 -34.608516) (xy 293.84879 -34.608516)
			(xy 293.876042 -34.608979) (xy 293.92999 -34.616734) (xy 293.982286 -34.632088) (xy 294.031864 -34.654729)
			(xy 294.077716 -34.684195) (xy 294.118907 -34.719886) (xy 294.154599 -34.761076) (xy 294.184067 -34.806927)
			(xy 294.206708 -34.856505) (xy 294.222064 -34.9088) (xy 294.229821 -34.962748) (xy 294.229821 -34.990024)
			(xy 295.87266 -34.990024) (xy 295.876731 -34.934402) (xy 295.888857 -34.879965) (xy 295.90878 -34.827874)
			(xy 295.936076 -34.779239) (xy 295.970162 -34.735096) (xy 296.010311 -34.696387) (xy 296.055669 -34.663936)
			(xy 296.105269 -34.638435) (xy 296.158053 -34.620428) (xy 296.212896 -34.610298) (xy 296.26863 -34.608261)
			(xy 296.324067 -34.614361) (xy 296.378024 -34.628467) (xy 296.429353 -34.650279) (xy 296.476959 -34.679333)
			(xy 296.519827 -34.715008) (xy 296.557044 -34.756545) (xy 296.587817 -34.803058) (xy 296.611489 -34.853555)
			(xy 296.627557 -34.906962) (xy 296.635677 -34.962138) (xy 296.636186 -34.990024) (xy 297.200826 -34.990024)
			(xy 297.204897 -34.934402) (xy 297.217023 -34.879965) (xy 297.236946 -34.827874) (xy 297.264242 -34.779239)
			(xy 297.298328 -34.735096) (xy 297.338477 -34.696387) (xy 297.383835 -34.663936) (xy 297.433435 -34.638435)
			(xy 297.486219 -34.620428) (xy 297.541062 -34.610298) (xy 297.596796 -34.608261) (xy 297.652233 -34.614361)
			(xy 297.70619 -34.628467) (xy 297.757519 -34.650279) (xy 297.805125 -34.679333) (xy 297.847993 -34.715008)
			(xy 297.88521 -34.756545) (xy 297.915983 -34.803058) (xy 297.939655 -34.853555) (xy 297.955723 -34.906962)
			(xy 297.963843 -34.962138) (xy 297.964352 -34.990024) (xy 300.098712 -34.990024) (xy 300.102783 -34.934402)
			(xy 300.114909 -34.879965) (xy 300.134832 -34.827874) (xy 300.162128 -34.779239) (xy 300.196214 -34.735096)
			(xy 300.236363 -34.696387) (xy 300.281721 -34.663936) (xy 300.331321 -34.638435) (xy 300.384105 -34.620428)
			(xy 300.438948 -34.610298) (xy 300.494682 -34.608261) (xy 300.550119 -34.614361) (xy 300.604076 -34.628467)
			(xy 300.655405 -34.650279) (xy 300.703011 -34.679333) (xy 300.745879 -34.715008) (xy 300.783096 -34.756545)
			(xy 300.813869 -34.803058) (xy 300.837541 -34.853555) (xy 300.853609 -34.906962) (xy 300.861729 -34.962138)
			(xy 300.862238 -34.990024) (xy 300.861729 -35.01791) (xy 300.853609 -35.073086) (xy 300.837541 -35.126493)
			(xy 300.813869 -35.17699) (xy 300.783096 -35.223503) (xy 300.745879 -35.26504) (xy 300.703011 -35.300715)
			(xy 300.655405 -35.329769) (xy 300.604076 -35.351581) (xy 300.550119 -35.365687) (xy 300.494682 -35.371787)
			(xy 300.438948 -35.36975) (xy 300.384105 -35.35962) (xy 300.331321 -35.341613) (xy 300.281721 -35.316112)
			(xy 300.236363 -35.283661) (xy 300.196214 -35.244952) (xy 300.162128 -35.200809) (xy 300.134832 -35.152174)
			(xy 300.114909 -35.100083) (xy 300.102783 -35.045646) (xy 300.098712 -34.990024) (xy 297.964352 -34.990024)
			(xy 297.963843 -35.01791) (xy 297.955723 -35.073086) (xy 297.939655 -35.126493) (xy 297.915983 -35.17699)
			(xy 297.88521 -35.223503) (xy 297.847993 -35.26504) (xy 297.805125 -35.300715) (xy 297.757519 -35.329769)
			(xy 297.70619 -35.351581) (xy 297.652233 -35.365687) (xy 297.596796 -35.371787) (xy 297.541062 -35.36975)
			(xy 297.486219 -35.35962) (xy 297.433435 -35.341613) (xy 297.383835 -35.316112) (xy 297.338477 -35.283661)
			(xy 297.298328 -35.244952) (xy 297.264242 -35.200809) (xy 297.236946 -35.152174) (xy 297.217023 -35.100083)
			(xy 297.204897 -35.045646) (xy 297.200826 -34.990024) (xy 296.636186 -34.990024) (xy 296.635677 -35.01791)
			(xy 296.627557 -35.073086) (xy 296.611489 -35.126493) (xy 296.587817 -35.17699) (xy 296.557044 -35.223503)
			(xy 296.519827 -35.26504) (xy 296.476959 -35.300715) (xy 296.429353 -35.329769) (xy 296.378024 -35.351581)
			(xy 296.324067 -35.365687) (xy 296.26863 -35.371787) (xy 296.212896 -35.36975) (xy 296.158053 -35.35962)
			(xy 296.105269 -35.341613) (xy 296.055669 -35.316112) (xy 296.010311 -35.283661) (xy 295.970162 -35.244952)
			(xy 295.936076 -35.200809) (xy 295.90878 -35.152174) (xy 295.888857 -35.100083) (xy 295.876731 -35.045646)
			(xy 295.87266 -34.990024) (xy 294.229821 -34.990024) (xy 294.229821 -35.017252) (xy 294.222064 -35.0712)
			(xy 294.206708 -35.123495) (xy 294.184067 -35.173073) (xy 294.154599 -35.218924) (xy 294.118907 -35.260114)
			(xy 294.077716 -35.295805) (xy 294.031864 -35.325271) (xy 293.982286 -35.347912) (xy 293.92999 -35.363266)
			(xy 293.876042 -35.371021) (xy 293.84879 -35.371532) (xy 293.845996 -35.371532) (xy 293.836029 -35.372008)
			(xy 293.817592 -35.379583) (xy 293.810182 -35.386264) (xy 293.758874 -35.437064) (xy 293.75203 -35.444463)
			(xy 293.744307 -35.463062) (xy 293.743888 -35.473132) (xy 293.743888 -38.193435) (xy 295.298186 -38.193435)
			(xy 295.298186 -38.106565) (xy 295.306201 -38.020065) (xy 295.322163 -37.934674) (xy 295.345935 -37.851119)
			(xy 295.377316 -37.770115) (xy 295.416036 -37.692351) (xy 295.461766 -37.618492) (xy 295.514116 -37.549167)
			(xy 295.572639 -37.484967) (xy 295.636836 -37.426442) (xy 295.706159 -37.374089) (xy 295.780016 -37.328356)
			(xy 295.857778 -37.289632) (xy 295.938781 -37.258248) (xy 296.022335 -37.234472) (xy 296.107725 -37.218506)
			(xy 296.194225 -37.210487) (xy 296.23766 -37.209984) (xy 296.315638 -37.209984) (xy 296.32565 -37.209543)
			(xy 296.344146 -37.201868) (xy 296.358298 -37.1877) (xy 296.365953 -37.169197) (xy 296.366438 -37.159184)
			(xy 296.366438 -37.151564) (xy 296.36212 -37.137594) (xy 296.358056 -37.131244) (xy 296.334654 -37.094769)
			(xy 296.293662 -37.018408) (xy 296.259677 -36.938682) (xy 296.232972 -36.856231) (xy 296.213761 -36.771719)
			(xy 296.2022 -36.685826) (xy 296.198381 -36.599243) (xy 296.202336 -36.512665) (xy 296.214031 -36.42679)
			(xy 296.233374 -36.342309) (xy 296.260209 -36.2599) (xy 296.294319 -36.180227) (xy 296.335431 -36.103931)
			(xy 296.383213 -36.031625) (xy 296.437281 -35.963891) (xy 296.497201 -35.901274) (xy 296.562491 -35.844278)
			(xy 296.632624 -35.79336) (xy 296.707038 -35.748932) (xy 296.785133 -35.711349) (xy 296.866281 -35.680914)
			(xy 296.949829 -35.657873) (xy 297.035107 -35.64241) (xy 297.121426 -35.63465) (xy 297.16476 -35.634168)
			(xy 297.165014 -35.634168) (xy 297.208346 -35.634635) (xy 297.294661 -35.642409) (xy 297.379932 -35.657884)
			(xy 297.463474 -35.680935) (xy 297.544615 -35.711378) (xy 297.622703 -35.748967) (xy 297.697109 -35.793401)
			(xy 297.767236 -35.844321) (xy 297.804365 -35.876738) (xy 302.917096 -35.876738) (xy 302.921167 -35.821116)
			(xy 302.933293 -35.766679) (xy 302.953216 -35.714588) (xy 302.980512 -35.665953) (xy 303.014598 -35.62181)
			(xy 303.054747 -35.583101) (xy 303.100105 -35.55065) (xy 303.149705 -35.525149) (xy 303.202489 -35.507142)
			(xy 303.257332 -35.497012) (xy 303.313066 -35.494975) (xy 303.368503 -35.501075) (xy 303.42246 -35.515181)
			(xy 303.473789 -35.536993) (xy 303.521395 -35.566047) (xy 303.564263 -35.601722) (xy 303.60148 -35.643259)
			(xy 303.632253 -35.689772) (xy 303.655925 -35.740269) (xy 303.671993 -35.793676) (xy 303.680113 -35.848852)
			(xy 303.680622 -35.876738) (xy 303.680113 -35.904624) (xy 303.671993 -35.9598) (xy 303.655925 -36.013207)
			(xy 303.632253 -36.063704) (xy 303.60148 -36.110217) (xy 303.564263 -36.151754) (xy 303.521395 -36.187429)
			(xy 303.473789 -36.216483) (xy 303.42246 -36.238295) (xy 303.368503 -36.252401) (xy 303.313066 -36.258501)
			(xy 303.257332 -36.256464) (xy 303.202489 -36.246334) (xy 303.149705 -36.228327) (xy 303.100105 -36.202826)
			(xy 303.054747 -36.170375) (xy 303.014598 -36.131666) (xy 302.980512 -36.087523) (xy 302.953216 -36.038888)
			(xy 302.933293 -35.986797) (xy 302.921167 -35.93236) (xy 302.917096 -35.876738) (xy 297.804365 -35.876738)
			(xy 297.832519 -35.901319) (xy 297.892434 -35.963936) (xy 297.946498 -36.031668) (xy 297.994278 -36.103972)
			(xy 298.035388 -36.180265) (xy 298.069498 -36.259934) (xy 298.096334 -36.342338) (xy 298.11568 -36.426815)
			(xy 298.127381 -36.512686) (xy 298.128627 -36.539928) (xy 304.738514 -36.539928) (xy 304.738514 -36.479992)
			(xy 304.746337 -36.42057) (xy 304.76185 -36.362677) (xy 304.784786 -36.307304) (xy 304.814753 -36.255398)
			(xy 304.85124 -36.207848) (xy 304.89362 -36.165468) (xy 304.94117 -36.128981) (xy 304.993076 -36.099014)
			(xy 305.048449 -36.076078) (xy 305.106342 -36.060565) (xy 305.165764 -36.052742) (xy 305.2257 -36.052742)
			(xy 305.285122 -36.060565) (xy 305.343015 -36.076078) (xy 305.398388 -36.099014) (xy 305.450294 -36.128981)
			(xy 305.497844 -36.165468) (xy 305.540224 -36.207848) (xy 305.576711 -36.255398) (xy 305.606678 -36.307304)
			(xy 305.629614 -36.362677) (xy 305.645127 -36.42057) (xy 305.65295 -36.479992) (xy 305.65344 -36.50996)
			(xy 305.65295 -36.539928) (xy 305.645127 -36.59935) (xy 305.629614 -36.657243) (xy 305.606678 -36.712616)
			(xy 305.576711 -36.764522) (xy 305.540224 -36.812072) (xy 305.497844 -36.854452) (xy 305.450294 -36.890939)
			(xy 305.398388 -36.920906) (xy 305.343015 -36.943842) (xy 305.285122 -36.959355) (xy 305.2257 -36.967178)
			(xy 305.165764 -36.967178) (xy 305.106342 -36.959355) (xy 305.048449 -36.943842) (xy 304.993076 -36.920906)
			(xy 304.94117 -36.890939) (xy 304.89362 -36.854452) (xy 304.85124 -36.812072) (xy 304.814753 -36.764522)
			(xy 304.784786 -36.712616) (xy 304.76185 -36.657243) (xy 304.746337 -36.59935) (xy 304.738514 -36.539928)
			(xy 298.128627 -36.539928) (xy 298.131342 -36.599259) (xy 298.127531 -36.685839) (xy 298.11598 -36.77173)
			(xy 298.096781 -36.856241) (xy 298.070088 -36.938692) (xy 298.036117 -37.01842) (xy 297.99514 -37.094784)
			(xy 297.971718 -37.131244) (xy 297.963336 -37.143944) (xy 297.963336 -37.159184) (xy 297.963733 -37.169209)
			(xy 297.971405 -37.187732) (xy 297.985585 -37.201906) (xy 298.004111 -37.209571) (xy 298.014136 -37.209984)
			(xy 298.09186 -37.209984) (xy 298.135302 -37.210393) (xy 298.221815 -37.218406) (xy 298.30722 -37.234368)
			(xy 298.390787 -37.258141) (xy 298.471805 -37.289525) (xy 298.549581 -37.32825) (xy 298.623452 -37.373986)
			(xy 298.692788 -37.426343) (xy 298.74634 -37.47516) (xy 301.959008 -37.47516) (xy 301.963079 -37.419538)
			(xy 301.975205 -37.365101) (xy 301.995128 -37.31301) (xy 302.022424 -37.264375) (xy 302.05651 -37.220232)
			(xy 302.096659 -37.181523) (xy 302.142017 -37.149072) (xy 302.191617 -37.123571) (xy 302.244401 -37.105564)
			(xy 302.299244 -37.095434) (xy 302.354978 -37.093397) (xy 302.410415 -37.099497) (xy 302.464372 -37.113603)
			(xy 302.515701 -37.135415) (xy 302.563307 -37.164469) (xy 302.606175 -37.200144) (xy 302.643392 -37.241681)
			(xy 302.674165 -37.288194) (xy 302.697837 -37.338691) (xy 302.713905 -37.392098) (xy 302.722025 -37.447274)
			(xy 302.722534 -37.47516) (xy 302.722025 -37.503046) (xy 302.713905 -37.558222) (xy 302.697837 -37.611629)
			(xy 302.674165 -37.662126) (xy 302.654185 -37.692326) (xy 304.073034 -37.692326) (xy 304.073034 -37.63239)
			(xy 304.080857 -37.572968) (xy 304.09637 -37.515075) (xy 304.119306 -37.459702) (xy 304.149273 -37.407796)
			(xy 304.18576 -37.360246) (xy 304.22814 -37.317866) (xy 304.27569 -37.281379) (xy 304.327596 -37.251412)
			(xy 304.382969 -37.228476) (xy 304.440862 -37.212963) (xy 304.500284 -37.20514) (xy 304.56022 -37.20514)
			(xy 304.619642 -37.212963) (xy 304.677535 -37.228476) (xy 304.732908 -37.251412) (xy 304.784814 -37.281379)
			(xy 304.832364 -37.317866) (xy 304.874744 -37.360246) (xy 304.911231 -37.407796) (xy 304.941198 -37.459702)
			(xy 304.964134 -37.515075) (xy 304.979647 -37.572968) (xy 304.98747 -37.63239) (xy 304.98796 -37.662358)
			(xy 304.98747 -37.692326) (xy 304.979647 -37.751748) (xy 304.964134 -37.809641) (xy 304.941198 -37.865014)
			(xy 304.911231 -37.91692) (xy 304.874744 -37.96447) (xy 304.832364 -38.00685) (xy 304.784814 -38.043337)
			(xy 304.732908 -38.073304) (xy 304.677535 -38.09624) (xy 304.619642 -38.111753) (xy 304.56022 -38.119576)
			(xy 304.500284 -38.119576) (xy 304.440862 -38.111753) (xy 304.382969 -38.09624) (xy 304.327596 -38.073304)
			(xy 304.27569 -38.043337) (xy 304.22814 -38.00685) (xy 304.18576 -37.96447) (xy 304.149273 -37.91692)
			(xy 304.119306 -37.865014) (xy 304.09637 -37.809641) (xy 304.080857 -37.751748) (xy 304.073034 -37.692326)
			(xy 302.654185 -37.692326) (xy 302.643392 -37.708639) (xy 302.606175 -37.750176) (xy 302.563307 -37.785851)
			(xy 302.515701 -37.814905) (xy 302.464372 -37.836717) (xy 302.410415 -37.850823) (xy 302.354978 -37.856923)
			(xy 302.299244 -37.854886) (xy 302.244401 -37.844756) (xy 302.191617 -37.826749) (xy 302.142017 -37.801248)
			(xy 302.096659 -37.768797) (xy 302.05651 -37.730088) (xy 302.022424 -37.685945) (xy 301.995128 -37.63731)
			(xy 301.975205 -37.585219) (xy 301.963079 -37.530782) (xy 301.959008 -37.47516) (xy 298.74634 -37.47516)
			(xy 298.756997 -37.484875) (xy 298.815531 -37.549081) (xy 298.867891 -37.618415) (xy 298.913631 -37.692284)
			(xy 298.952359 -37.770059) (xy 298.983746 -37.851075) (xy 299.007523 -37.934641) (xy 299.023488 -38.020045)
			(xy 299.031505 -38.106558) (xy 299.031505 -38.193442) (xy 299.023488 -38.279955) (xy 299.007523 -38.365359)
			(xy 298.983746 -38.448925) (xy 298.967383 -38.49116) (xy 301.959008 -38.49116) (xy 301.963079 -38.435538)
			(xy 301.975205 -38.381101) (xy 301.995128 -38.32901) (xy 302.022424 -38.280375) (xy 302.05651 -38.236232)
			(xy 302.096659 -38.197523) (xy 302.142017 -38.165072) (xy 302.191617 -38.139571) (xy 302.244401 -38.121564)
			(xy 302.299244 -38.111434) (xy 302.354978 -38.109397) (xy 302.410415 -38.115497) (xy 302.464372 -38.129603)
			(xy 302.515701 -38.151415) (xy 302.563307 -38.180469) (xy 302.606175 -38.216144) (xy 302.643392 -38.257681)
			(xy 302.674165 -38.304194) (xy 302.697837 -38.354691) (xy 302.713905 -38.408098) (xy 302.722025 -38.463274)
			(xy 302.722534 -38.49116) (xy 302.722025 -38.519046) (xy 302.713905 -38.574222) (xy 302.697837 -38.627629)
			(xy 302.674165 -38.678126) (xy 302.658887 -38.701218) (xy 305.637436 -38.701218) (xy 305.641507 -38.645596)
			(xy 305.653633 -38.591159) (xy 305.673556 -38.539068) (xy 305.700852 -38.490433) (xy 305.734938 -38.44629)
			(xy 305.775087 -38.407581) (xy 305.820445 -38.37513) (xy 305.870045 -38.349629) (xy 305.922829 -38.331622)
			(xy 305.977672 -38.321492) (xy 306.033406 -38.319455) (xy 306.088843 -38.325555) (xy 306.1428 -38.339661)
			(xy 306.194129 -38.361473) (xy 306.241735 -38.390527) (xy 306.284603 -38.426202) (xy 306.32182 -38.467739)
			(xy 306.352593 -38.514252) (xy 306.376265 -38.564749) (xy 306.392333 -38.618156) (xy 306.400453 -38.673332)
			(xy 306.400962 -38.701218) (xy 306.400453 -38.729104) (xy 306.392333 -38.78428) (xy 306.376265 -38.837687)
			(xy 306.352593 -38.888184) (xy 306.32182 -38.934697) (xy 306.284603 -38.976234) (xy 306.241735 -39.011909)
			(xy 306.194129 -39.040963) (xy 306.1428 -39.062775) (xy 306.088843 -39.076881) (xy 306.033406 -39.082981)
			(xy 305.977672 -39.080944) (xy 305.922829 -39.070814) (xy 305.870045 -39.052807) (xy 305.820445 -39.027306)
			(xy 305.775087 -38.994855) (xy 305.734938 -38.956146) (xy 305.700852 -38.912003) (xy 305.673556 -38.863368)
			(xy 305.653633 -38.811277) (xy 305.641507 -38.75684) (xy 305.637436 -38.701218) (xy 302.658887 -38.701218)
			(xy 302.643392 -38.724639) (xy 302.606175 -38.766176) (xy 302.563307 -38.801851) (xy 302.515701 -38.830905)
			(xy 302.464372 -38.852717) (xy 302.410415 -38.866823) (xy 302.354978 -38.872923) (xy 302.299244 -38.870886)
			(xy 302.244401 -38.860756) (xy 302.191617 -38.842749) (xy 302.142017 -38.817248) (xy 302.096659 -38.784797)
			(xy 302.05651 -38.746088) (xy 302.022424 -38.701945) (xy 301.995128 -38.65331) (xy 301.975205 -38.601219)
			(xy 301.963079 -38.546782) (xy 301.959008 -38.49116) (xy 298.967383 -38.49116) (xy 298.952359 -38.529941)
			(xy 298.913631 -38.607716) (xy 298.867891 -38.681585) (xy 298.815531 -38.750919) (xy 298.756997 -38.815125)
			(xy 298.692788 -38.873657) (xy 298.623452 -38.926014) (xy 298.549581 -38.97175) (xy 298.471805 -39.010475)
			(xy 298.390787 -39.041859) (xy 298.30722 -39.065632) (xy 298.221815 -39.081594) (xy 298.135302 -39.089607)
			(xy 298.09186 -39.090092) (xy 296.23766 -39.090092) (xy 296.194225 -39.089513) (xy 296.107725 -39.081494)
			(xy 296.022335 -39.065528) (xy 295.938781 -39.041752) (xy 295.857778 -39.010368) (xy 295.780016 -38.971644)
			(xy 295.706159 -38.925911) (xy 295.636836 -38.873558) (xy 295.572639 -38.815033) (xy 295.514116 -38.750833)
			(xy 295.461766 -38.681508) (xy 295.416036 -38.607649) (xy 295.377316 -38.529885) (xy 295.345935 -38.448881)
			(xy 295.322163 -38.365326) (xy 295.306201 -38.279935) (xy 295.298186 -38.193435) (xy 293.743888 -38.193435)
			(xy 293.743888 -42.849038) (xy 305.091844 -42.849038) (xy 305.095915 -42.793416) (xy 305.108041 -42.738979)
			(xy 305.127964 -42.686888) (xy 305.15526 -42.638253) (xy 305.189346 -42.59411) (xy 305.229495 -42.555401)
			(xy 305.274853 -42.52295) (xy 305.324453 -42.497449) (xy 305.377237 -42.479442) (xy 305.43208 -42.469312)
			(xy 305.487814 -42.467275) (xy 305.543251 -42.473375) (xy 305.597208 -42.487481) (xy 305.648537 -42.509293)
			(xy 305.696143 -42.538347) (xy 305.739011 -42.574022) (xy 305.776228 -42.615559) (xy 305.807001 -42.662072)
			(xy 305.830673 -42.712569) (xy 305.846741 -42.765976) (xy 305.854861 -42.821152) (xy 305.85537 -42.849038)
			(xy 305.854861 -42.876924) (xy 305.846741 -42.9321) (xy 305.830673 -42.985507) (xy 305.807001 -43.036004)
			(xy 305.776228 -43.082517) (xy 305.739011 -43.124054) (xy 305.696143 -43.159729) (xy 305.648537 -43.188783)
			(xy 305.597208 -43.210595) (xy 305.543251 -43.224701) (xy 305.487814 -43.230801) (xy 305.43208 -43.228764)
			(xy 305.377237 -43.218634) (xy 305.324453 -43.200627) (xy 305.274853 -43.175126) (xy 305.229495 -43.142675)
			(xy 305.189346 -43.103966) (xy 305.15526 -43.059823) (xy 305.127964 -43.011188) (xy 305.108041 -42.959097)
			(xy 305.095915 -42.90466) (xy 305.091844 -42.849038) (xy 293.743888 -42.849038) (xy 293.743888 -43.719242)
			(xy 293.744352 -43.729117) (xy 293.7518 -43.747411) (xy 293.758366 -43.754802) (xy 293.75862 -43.755056)
			(xy 294.236648 -44.233084) (xy 294.237156 -44.233592) (xy 294.244539 -44.24017) (xy 294.262838 -44.247613)
			(xy 294.272716 -44.24807)
		)
		(stroke
			(width 0)
			(type solid)
		)
		(fill yes)
		(layer "B.Cu")
		(net "P12V_SSD10")
	)
	(gr_poly
		(pts
			(xy 350.132904 -225.52533) (xy 350.141509 -225.524881) (xy 350.15767 -225.518938) (xy 350.170918 -225.507939)
			(xy 350.175576 -225.500692) (xy 350.176846 -225.49866) (xy 350.219264 -225.41992) (xy 350.21774 -225.391726)
			(xy 350.209612 -225.380042) (xy 350.195595 -225.35857) (xy 350.173394 -225.312349) (xy 350.158304 -225.263343)
			(xy 350.150659 -225.21264) (xy 350.150176 -225.187002) (xy 350.150176 -225.186748) (xy 350.150646 -225.160915)
			(xy 350.158393 -225.109832) (xy 350.173706 -225.060486) (xy 350.196237 -225.013991) (xy 350.225479 -224.971396)
			(xy 350.260772 -224.933662) (xy 350.280732 -224.917254) (xy 350.289411 -224.909729) (xy 350.29947 -224.889102)
			(xy 350.300036 -224.87763) (xy 350.300036 -224.69602) (xy 350.299338 -224.684579) (xy 350.289305 -224.664006)
			(xy 350.280732 -224.656396) (xy 350.260747 -224.640017) (xy 350.225456 -224.602277) (xy 350.196216 -224.559675)
			(xy 350.173689 -224.513175) (xy 350.158382 -224.463824) (xy 350.150641 -224.412737) (xy 350.150176 -224.386902)
			(xy 350.150705 -224.359916) (xy 350.159148 -224.306609) (xy 350.175825 -224.255279) (xy 350.200327 -224.20719)
			(xy 350.232049 -224.163525) (xy 350.270212 -224.125361) (xy 350.313875 -224.093636) (xy 350.361963 -224.069132)
			(xy 350.413292 -224.052452) (xy 350.466598 -224.044007) (xy 350.493584 -224.043494) (xy 350.519828 -224.043991)
			(xy 350.571705 -224.051978) (xy 350.621761 -224.067769) (xy 350.66883 -224.090996) (xy 350.711816 -224.121116)
			(xy 350.749715 -224.157429) (xy 350.781645 -224.199088) (xy 350.806862 -224.245122) (xy 350.824778 -224.294457)
			(xy 350.830388 -224.3201) (xy 350.831912 -224.327466) (xy 350.839024 -224.340674) (xy 350.867218 -224.369122)
			(xy 350.874596 -224.375935) (xy 350.893126 -224.383637) (xy 350.913192 -224.383637) (xy 350.931722 -224.375935)
			(xy 350.9391 -224.369122) (xy 350.944942 -224.363026) (xy 350.952308 -224.348294) (xy 350.953578 -224.339912)
			(xy 350.957857 -224.312845) (xy 350.973881 -224.260446) (xy 350.998024 -224.211257) (xy 351.029673 -224.166526)
			(xy 351.068025 -224.12739) (xy 351.112105 -224.094842) (xy 351.160795 -224.069708) (xy 351.21286 -224.052625)
			(xy 351.239836 -224.047812) (xy 351.258378 -224.044764) (xy 351.282762 -224.016316) (xy 351.282762 -223.957388)
			(xy 351.258378 -223.92894) (xy 351.239836 -223.925892) (xy 351.214675 -223.92142) (xy 351.165952 -223.906011)
			(xy 351.12005 -223.883551) (xy 351.077985 -223.854536) (xy 351.040684 -223.819606) (xy 351.008973 -223.779534)
			(xy 350.983552 -223.735204) (xy 350.964982 -223.687596) (xy 350.953673 -223.637761) (xy 350.949875 -223.5868)
			(xy 350.953673 -223.53584) (xy 350.964981 -223.486005) (xy 350.983552 -223.438397) (xy 351.008973 -223.394067)
			(xy 351.040684 -223.353994) (xy 351.077984 -223.319064) (xy 351.12005 -223.290049) (xy 351.165951 -223.267589)
			(xy 351.214674 -223.25218) (xy 351.239836 -223.247712) (xy 351.258378 -223.244664) (xy 351.282762 -223.216216)
			(xy 351.282762 -223.157542) (xy 351.258378 -223.129094) (xy 351.239836 -223.126046) (xy 351.214678 -223.121574)
			(xy 351.165962 -223.106167) (xy 351.120067 -223.083708) (xy 351.078008 -223.054696) (xy 351.040713 -223.01977)
			(xy 351.009007 -222.979702) (xy 350.98359 -222.935378) (xy 350.965023 -222.887775) (xy 350.953717 -222.837947)
			(xy 350.94992 -222.786993) (xy 350.953719 -222.736039) (xy 350.965027 -222.686211) (xy 350.983596 -222.63861)
			(xy 351.009015 -222.594286) (xy 351.040722 -222.55422) (xy 351.078018 -222.519295) (xy 351.120079 -222.490285)
			(xy 351.165975 -222.467828) (xy 351.214692 -222.452423) (xy 351.239836 -222.447866) (xy 351.258378 -222.444818)
			(xy 351.282762 -222.41637) (xy 351.282762 -222.357442) (xy 351.258378 -222.328994) (xy 351.239836 -222.325946)
			(xy 351.214678 -222.321474) (xy 351.165962 -222.306067) (xy 351.120067 -222.283608) (xy 351.078008 -222.254596)
			(xy 351.040713 -222.21967) (xy 351.009007 -222.179602) (xy 350.98359 -222.135278) (xy 350.965023 -222.087675)
			(xy 350.953717 -222.037847) (xy 350.94992 -221.986893) (xy 350.953719 -221.935939) (xy 350.965027 -221.886111)
			(xy 350.983596 -221.83851) (xy 351.009015 -221.794186) (xy 351.040722 -221.75412) (xy 351.078018 -221.719195)
			(xy 351.120079 -221.690185) (xy 351.165975 -221.667728) (xy 351.214692 -221.652323) (xy 351.239836 -221.647766)
			(xy 351.258378 -221.644718) (xy 351.282762 -221.61627) (xy 351.282762 -221.557342) (xy 351.258378 -221.528894)
			(xy 351.239836 -221.525846) (xy 351.213282 -221.521088) (xy 351.161988 -221.50439) (xy 351.113934 -221.47988)
			(xy 351.070302 -221.44816) (xy 351.032164 -221.410009) (xy 351.000459 -221.366367) (xy 350.975965 -221.318304)
			(xy 350.959285 -221.267004) (xy 350.950829 -221.213728) (xy 350.950276 -221.186756) (xy 350.950782 -221.159743)
			(xy 350.959243 -221.106385) (xy 350.975949 -221.055007) (xy 351.00049 -221.006877) (xy 351.032259 -220.96318)
			(xy 351.070475 -220.924992) (xy 351.114196 -220.893256) (xy 351.162344 -220.868751) (xy 351.213734 -220.852083)
			(xy 351.240344 -220.847412) (xy 351.248472 -220.846142) (xy 351.262696 -220.83903) (xy 351.573592 -220.528134)
			(xy 351.580989 -220.521283) (xy 351.599587 -220.51354) (xy 351.60966 -220.513148) (xy 353.31654 -220.513148)
			(xy 353.326416 -220.512685) (xy 353.344714 -220.505242) (xy 353.3521 -220.49867) (xy 353.464114 -220.386656)
			(xy 353.464622 -220.386148) (xy 353.471208 -220.378768) (xy 353.478663 -220.360469) (xy 353.4791 -220.350588)
			(xy 353.4791 -220.214444) (xy 353.47148 -220.209364) (xy 353.47148 -220.033342) (xy 353.4791 -220.028262)
			(xy 353.4791 -219.24772) (xy 353.477068 -219.24645) (xy 353.477068 -219.070428) (xy 353.4791 -219.069158)
			(xy 353.4791 -218.948) (xy 353.479523 -218.93793) (xy 353.487238 -218.919325) (xy 353.494086 -218.911932)
			(xy 353.735894 -218.670124) (xy 353.736402 -218.669616) (xy 353.742985 -218.662236) (xy 353.750432 -218.643936)
			(xy 353.75088 -218.634056) (xy 353.75088 -216.135458) (xy 353.751243 -216.127422) (xy 353.756289 -216.112157)
			(xy 353.760786 -216.105486) (xy 353.765612 -216.098882) (xy 353.770438 -216.083642) (xy 353.770438 -214.117174)
			(xy 353.770008 -214.107107) (xy 353.762281 -214.088516) (xy 353.755452 -214.081106) (xy 352.961956 -213.28761)
			(xy 352.954844 -213.280244) (xy 352.936048 -213.272624) (xy 351.647506 -213.272624) (xy 351.621598 -213.290658)
			(xy 351.61601 -213.305898) (xy 351.606514 -213.330281) (xy 351.581203 -213.376078) (xy 351.549239 -213.417505)
			(xy 351.51136 -213.453605) (xy 351.468444 -213.483541) (xy 351.421484 -213.506621) (xy 351.371567 -213.522311)
			(xy 351.319847 -213.530248) (xy 351.267521 -213.530248) (xy 351.215801 -213.522311) (xy 351.165884 -213.506621)
			(xy 351.118924 -213.483541) (xy 351.076008 -213.453605) (xy 351.038129 -213.417505) (xy 351.006165 -213.376078)
			(xy 350.980854 -213.330281) (xy 350.971358 -213.305898) (xy 350.96577 -213.290658) (xy 350.939862 -213.272624)
			(xy 350.847406 -213.272624) (xy 350.821498 -213.290658) (xy 350.81591 -213.305898) (xy 350.806414 -213.330281)
			(xy 350.781103 -213.376078) (xy 350.749139 -213.417505) (xy 350.71126 -213.453605) (xy 350.668344 -213.483541)
			(xy 350.621384 -213.506621) (xy 350.571467 -213.522311) (xy 350.519747 -213.530248) (xy 350.467421 -213.530248)
			(xy 350.415701 -213.522311) (xy 350.365784 -213.506621) (xy 350.318824 -213.483541) (xy 350.275908 -213.453605)
			(xy 350.238029 -213.417505) (xy 350.206065 -213.376078) (xy 350.180754 -213.330281) (xy 350.171258 -213.305898)
			(xy 350.16567 -213.290658) (xy 350.139762 -213.272624) (xy 350.082612 -213.272624) (xy 350.072541 -213.273045)
			(xy 350.053936 -213.280759) (xy 350.046544 -213.28761) (xy 350.007936 -213.326218) (xy 350.004126 -213.334346)
			(xy 349.991791 -213.35915) (xy 349.960347 -213.404755) (xy 349.921988 -213.444719) (xy 349.87771 -213.478005)
			(xy 349.828661 -213.503749) (xy 349.776115 -213.521283) (xy 349.721435 -213.530152) (xy 349.693738 -213.530688)
			(xy 349.667482 -213.530185) (xy 349.615583 -213.52218) (xy 349.565508 -213.506367) (xy 349.518425 -213.483115)
			(xy 349.496634 -213.468458) (xy 349.487998 -213.462362) (xy 349.467424 -213.458298) (xy 349.40367 -213.472014)
			(xy 349.393974 -213.474456) (xy 349.377467 -213.485715) (xy 349.371666 -213.493858) (xy 349.371666 -213.494112)
			(xy 349.354851 -213.519568) (xy 349.316585 -213.567087) (xy 349.273447 -213.610232) (xy 349.225933 -213.648504)
			(xy 349.20047 -213.665308) (xy 349.200216 -213.665308) (xy 349.192156 -213.671194) (xy 349.180907 -213.687659)
			(xy 349.178372 -213.697312) (xy 349.164656 -213.761066) (xy 349.16872 -213.78164) (xy 349.174816 -213.790276)
			(xy 349.189491 -213.812056) (xy 349.212755 -213.859139) (xy 349.228569 -213.909217) (xy 349.236563 -213.961122)
			(xy 349.237046 -213.98738) (xy 349.236566 -214.013079) (xy 349.228905 -214.063903) (xy 349.213756 -214.113017)
			(xy 349.191455 -214.159325) (xy 349.162502 -214.201792) (xy 349.127542 -214.239469) (xy 349.087358 -214.271515)
			(xy 349.042846 -214.297214) (xy 348.995001 -214.315991) (xy 348.944892 -214.327429) (xy 348.893638 -214.33127)
			(xy 348.842384 -214.327429) (xy 348.792275 -214.315991) (xy 348.74443 -214.297214) (xy 348.699918 -214.271515)
			(xy 348.659734 -214.239469) (xy 348.624774 -214.201792) (xy 348.595821 -214.159325) (xy 348.57352 -214.113017)
			(xy 348.558371 -214.063903) (xy 348.55071 -214.013079) (xy 348.55023 -213.98738) (xy 348.55023 -213.987126)
			(xy 348.550728 -213.960869) (xy 348.558724 -213.908967) (xy 348.574535 -213.85889) (xy 348.597792 -213.811806)
			(xy 348.61246 -213.790022) (xy 348.61881 -213.781386) (xy 348.622874 -213.760812) (xy 348.607126 -213.687152)
			(xy 348.595442 -213.670642) (xy 348.586806 -213.665054) (xy 348.56144 -213.648201) (xy 348.514095 -213.609889)
			(xy 348.492318 -213.5886) (xy 348.387162 -213.483444) (xy 348.37975 -213.47676) (xy 348.361317 -213.469163)
			(xy 348.341379 -213.469163) (xy 348.322946 -213.47676) (xy 348.315534 -213.483444) (xy 348.250256 -213.548722)
			(xy 348.242644 -213.557298) (xy 348.235125 -213.578929) (xy 348.235778 -213.590378) (xy 348.244414 -213.665562)
			(xy 348.257368 -213.685374) (xy 348.267782 -213.69147) (xy 348.289509 -213.704804) (xy 348.329127 -213.736881)
			(xy 348.363569 -213.774462) (xy 348.392077 -213.816721) (xy 348.414026 -213.862729) (xy 348.428933 -213.911477)
			(xy 348.436471 -213.961892) (xy 348.436946 -213.98738) (xy 348.436418 -214.014367) (xy 348.427978 -214.067678)
			(xy 348.411303 -214.119012) (xy 348.386802 -214.167105) (xy 348.35508 -214.210774) (xy 348.316918 -214.248943)
			(xy 348.273255 -214.280672) (xy 348.225165 -214.30518) (xy 348.173834 -214.321865) (xy 348.120525 -214.330314)
			(xy 348.093538 -214.330788) (xy 348.068048 -214.330326) (xy 348.017628 -214.322795) (xy 347.968875 -214.307891)
			(xy 347.922861 -214.285944) (xy 347.880598 -214.257435) (xy 347.843014 -214.222991) (xy 347.810936 -214.183369)
			(xy 347.797628 -214.161624) (xy 347.791532 -214.15121) (xy 347.77172 -214.138256) (xy 347.696536 -214.12962)
			(xy 347.685073 -214.128834) (xy 347.663395 -214.136382) (xy 347.65488 -214.144098) (xy 347.45041 -214.348568)
			(xy 347.4428 -214.357144) (xy 347.435292 -214.378775) (xy 347.435932 -214.390224) (xy 347.444568 -214.465408)
			(xy 347.457522 -214.48522) (xy 347.467936 -214.491316) (xy 347.489663 -214.504649) (xy 347.529282 -214.536725)
			(xy 347.563723 -214.574306) (xy 347.59223 -214.616565) (xy 347.614176 -214.662574) (xy 347.629079 -214.711322)
			(xy 347.636611 -214.761738) (xy 347.6371 -214.787226) (xy 347.749625 -214.787226) (xy 347.753655 -214.734728)
			(xy 347.765652 -214.68346) (xy 347.785335 -214.634625) (xy 347.812241 -214.589366) (xy 347.845741 -214.548745)
			(xy 347.885049 -214.513714) (xy 347.929244 -214.485094) (xy 347.977289 -214.463555) (xy 348.02806 -214.449603)
			(xy 348.080365 -214.443565) (xy 348.132979 -214.445582) (xy 348.184669 -214.455606) (xy 348.234222 -214.473404)
			(xy 348.280478 -214.498557) (xy 348.322352 -214.530476) (xy 348.358864 -214.568414) (xy 348.389156 -214.61148)
			(xy 348.412519 -214.658665) (xy 348.428405 -214.708864) (xy 348.436442 -214.7609) (xy 348.436946 -214.787226)
			(xy 348.549725 -214.787226) (xy 348.553755 -214.734728) (xy 348.565752 -214.68346) (xy 348.585435 -214.634625)
			(xy 348.612341 -214.589366) (xy 348.645841 -214.548745) (xy 348.685149 -214.513714) (xy 348.729344 -214.485094)
			(xy 348.777389 -214.463555) (xy 348.82816 -214.449603) (xy 348.880465 -214.443565) (xy 348.933079 -214.445582)
			(xy 348.984769 -214.455606) (xy 349.034322 -214.473404) (xy 349.080578 -214.498557) (xy 349.122452 -214.530476)
			(xy 349.158964 -214.568414) (xy 349.189256 -214.61148) (xy 349.212619 -214.658665) (xy 349.228505 -214.708864)
			(xy 349.236542 -214.7609) (xy 349.237046 -214.787226) (xy 349.35033 -214.787226) (xy 349.35033 -214.786972)
			(xy 349.350812 -214.762271) (xy 349.357905 -214.713382) (xy 349.371925 -214.666012) (xy 349.392585 -214.621138)
			(xy 349.419458 -214.579685) (xy 349.45199 -214.542507) (xy 349.470472 -214.526114) (xy 349.478498 -214.518545)
			(xy 349.487712 -214.498525) (xy 349.488252 -214.487506) (xy 349.488252 -214.469472) (xy 349.488252 -214.292942)
			(xy 349.5802 -214.234268) (xy 349.754698 -214.234268) (xy 349.763026 -214.232892) (xy 349.778187 -214.225488)
			(xy 349.784416 -214.21979) (xy 349.93072 -214.073232) (xy 349.938201 -214.066538) (xy 349.956761 -214.058949)
			(xy 349.966788 -214.0585) (xy 350.059752 -214.0585) (xy 350.06976 -214.058062) (xy 350.088223 -214.050329)
			(xy 350.095566 -214.043514) (xy 350.142556 -213.996524) (xy 350.150176 -213.97976) (xy 350.150684 -213.970108)
			(xy 350.152487 -213.944046) (xy 350.162964 -213.892868) (xy 350.181076 -213.843869) (xy 350.206404 -213.798181)
			(xy 350.238363 -213.756858) (xy 350.276214 -213.720856) (xy 350.319084 -213.691005) (xy 350.365983 -213.667995)
			(xy 350.415827 -213.652358) (xy 350.467464 -213.644454) (xy 350.493584 -213.643972) (xy 350.520568 -213.644536)
			(xy 350.573871 -213.652976) (xy 350.625198 -213.66965) (xy 350.673284 -213.694148) (xy 350.716947 -213.725867)
			(xy 350.755109 -213.764026) (xy 350.786833 -213.807685) (xy 350.811336 -213.855769) (xy 350.828016 -213.907094)
			(xy 350.836461 -213.960396) (xy 350.836992 -213.98738) (xy 350.949771 -213.98738) (xy 350.953801 -213.934882)
			(xy 350.965798 -213.883614) (xy 350.985481 -213.834779) (xy 351.012387 -213.78952) (xy 351.045887 -213.748899)
			(xy 351.085195 -213.713868) (xy 351.12939 -213.685248) (xy 351.177435 -213.663709) (xy 351.228206 -213.649757)
			(xy 351.280511 -213.643719) (xy 351.333125 -213.645736) (xy 351.384815 -213.65576) (xy 351.434368 -213.673558)
			(xy 351.480624 -213.698711) (xy 351.522498 -213.73063) (xy 351.55901 -213.768568) (xy 351.589302 -213.811634)
			(xy 351.612665 -213.858819) (xy 351.628551 -213.909018) (xy 351.636588 -213.961054) (xy 351.637092 -213.98738)
			(xy 351.636588 -214.013706) (xy 351.628551 -214.065742) (xy 351.612665 -214.115941) (xy 351.589302 -214.163126)
			(xy 351.55901 -214.206192) (xy 351.522498 -214.24413) (xy 351.480624 -214.276049) (xy 351.434368 -214.301202)
			(xy 351.384815 -214.319) (xy 351.333125 -214.329024) (xy 351.280511 -214.331041) (xy 351.228206 -214.325003)
			(xy 351.177435 -214.311051) (xy 351.12939 -214.289512) (xy 351.085195 -214.260892) (xy 351.045887 -214.225861)
			(xy 351.012387 -214.18524) (xy 350.985481 -214.139981) (xy 350.965798 -214.091146) (xy 350.953801 -214.039878)
			(xy 350.949771 -213.98738) (xy 350.836992 -213.98738) (xy 350.836518 -214.013496) (xy 350.828583 -214.065122)
			(xy 350.812925 -214.114951) (xy 350.789903 -214.161836) (xy 350.760049 -214.204695) (xy 350.724051 -214.242541)
			(xy 350.682738 -214.274501) (xy 350.637063 -214.299838) (xy 350.588079 -214.317968) (xy 350.536914 -214.328474)
			(xy 350.510856 -214.33028) (xy 350.501204 -214.330788) (xy 350.48444 -214.338408) (xy 350.465644 -214.357204)
			(xy 350.458888 -214.364604) (xy 350.451264 -214.38312) (xy 350.451277 -214.403143) (xy 350.458924 -214.421649)
			(xy 350.465644 -214.429086) (xy 350.472756 -214.436198) (xy 350.490536 -214.443564) (xy 350.500442 -214.443818)
			(xy 350.527067 -214.444918) (xy 350.579534 -214.454208) (xy 350.629937 -214.471489) (xy 350.677067 -214.496345)
			(xy 350.719794 -214.52818) (xy 350.757092 -214.566232) (xy 350.788067 -214.609586) (xy 350.811976 -214.657204)
			(xy 350.828245 -214.707942) (xy 350.836484 -214.760585) (xy 350.836992 -214.787226) (xy 350.949771 -214.787226)
			(xy 350.953801 -214.734728) (xy 350.965798 -214.68346) (xy 350.985481 -214.634625) (xy 351.012387 -214.589366)
			(xy 351.045887 -214.548745) (xy 351.085195 -214.513714) (xy 351.12939 -214.485094) (xy 351.177435 -214.463555)
			(xy 351.228206 -214.449603) (xy 351.280511 -214.443565) (xy 351.333125 -214.445582) (xy 351.384815 -214.455606)
			(xy 351.434368 -214.473404) (xy 351.480624 -214.498557) (xy 351.522498 -214.530476) (xy 351.55901 -214.568414)
			(xy 351.589302 -214.61148) (xy 351.612665 -214.658665) (xy 351.628551 -214.708864) (xy 351.636588 -214.7609)
			(xy 351.637092 -214.787226) (xy 351.636588 -214.813552) (xy 351.628551 -214.865588) (xy 351.612665 -214.915787)
			(xy 351.589302 -214.962972) (xy 351.55901 -215.006038) (xy 351.522498 -215.043976) (xy 351.480624 -215.075895)
			(xy 351.434368 -215.101048) (xy 351.384815 -215.118846) (xy 351.333125 -215.12887) (xy 351.280511 -215.130887)
			(xy 351.228206 -215.124849) (xy 351.177435 -215.110897) (xy 351.12939 -215.089358) (xy 351.085195 -215.060738)
			(xy 351.045887 -215.025707) (xy 351.012387 -214.985086) (xy 350.985481 -214.939827) (xy 350.965798 -214.890992)
			(xy 350.953801 -214.839724) (xy 350.949771 -214.787226) (xy 350.836992 -214.787226) (xy 350.836512 -214.812925)
			(xy 350.828851 -214.863749) (xy 350.813702 -214.912863) (xy 350.791401 -214.959171) (xy 350.762448 -215.001638)
			(xy 350.727488 -215.039315) (xy 350.687304 -215.071361) (xy 350.642792 -215.09706) (xy 350.594947 -215.115837)
			(xy 350.544838 -215.127275) (xy 350.493584 -215.131116) (xy 350.44233 -215.127275) (xy 350.392221 -215.115837)
			(xy 350.344376 -215.09706) (xy 350.299864 -215.071361) (xy 350.25968 -215.039315) (xy 350.22472 -215.001638)
			(xy 350.195767 -214.959171) (xy 350.173466 -214.912863) (xy 350.158317 -214.863749) (xy 350.150656 -214.812925)
			(xy 350.150176 -214.787226) (xy 350.151192 -214.759286) (xy 350.151446 -214.757254) (xy 350.151446 -214.754968)
			(xy 350.150939 -214.744964) (xy 350.143278 -214.72648) (xy 350.129131 -214.71233) (xy 350.11065 -214.704663)
			(xy 350.100646 -214.704168) (xy 350.086676 -214.704168) (xy 350.076671 -214.704667) (xy 350.058185 -214.712329)
			(xy 350.044033 -214.726478) (xy 350.036369 -214.744963) (xy 350.035876 -214.754968) (xy 350.035876 -214.757254)
			(xy 350.03613 -214.759286) (xy 350.037146 -214.787226) (xy 350.036666 -214.812925) (xy 350.029005 -214.863749)
			(xy 350.013856 -214.912863) (xy 349.991555 -214.959171) (xy 349.962602 -215.001638) (xy 349.927642 -215.039315)
			(xy 349.887458 -215.071361) (xy 349.842946 -215.09706) (xy 349.795101 -215.115837) (xy 349.744992 -215.127275)
			(xy 349.693738 -215.131116) (xy 349.642484 -215.127275) (xy 349.592375 -215.115837) (xy 349.54453 -215.09706)
			(xy 349.500018 -215.071361) (xy 349.459834 -215.039315) (xy 349.424874 -215.001638) (xy 349.395921 -214.959171)
			(xy 349.37362 -214.912863) (xy 349.358471 -214.863749) (xy 349.35081 -214.812925) (xy 349.35033 -214.787226)
			(xy 349.237046 -214.787226) (xy 349.236542 -214.813552) (xy 349.228505 -214.865588) (xy 349.212619 -214.915787)
			(xy 349.189256 -214.962972) (xy 349.158964 -215.006038) (xy 349.122452 -215.043976) (xy 349.080578 -215.075895)
			(xy 349.034322 -215.101048) (xy 348.984769 -215.118846) (xy 348.933079 -215.12887) (xy 348.880465 -215.130887)
			(xy 348.82816 -215.124849) (xy 348.777389 -215.110897) (xy 348.729344 -215.089358) (xy 348.685149 -215.060738)
			(xy 348.645841 -215.025707) (xy 348.612341 -214.985086) (xy 348.585435 -214.939827) (xy 348.565752 -214.890992)
			(xy 348.553755 -214.839724) (xy 348.549725 -214.787226) (xy 348.436946 -214.787226) (xy 348.436442 -214.813552)
			(xy 348.428405 -214.865588) (xy 348.412519 -214.915787) (xy 348.389156 -214.962972) (xy 348.358864 -215.006038)
			(xy 348.322352 -215.043976) (xy 348.280478 -215.075895) (xy 348.234222 -215.101048) (xy 348.184669 -215.118846)
			(xy 348.132979 -215.12887) (xy 348.080365 -215.130887) (xy 348.02806 -215.124849) (xy 347.977289 -215.110897)
			(xy 347.929244 -215.089358) (xy 347.885049 -215.060738) (xy 347.845741 -215.025707) (xy 347.812241 -214.985086)
			(xy 347.785335 -214.939827) (xy 347.765652 -214.890992) (xy 347.753655 -214.839724) (xy 347.749625 -214.787226)
			(xy 347.6371 -214.787226) (xy 347.636569 -214.81421) (xy 347.628123 -214.867512) (xy 347.611443 -214.918837)
			(xy 347.586939 -214.96692) (xy 347.555216 -215.010579) (xy 347.517053 -215.048738) (xy 347.473391 -215.080457)
			(xy 347.425305 -215.104956) (xy 347.373979 -215.121631) (xy 347.320676 -215.130071) (xy 347.293692 -215.130634)
			(xy 347.268204 -215.130169) (xy 347.21779 -215.122631) (xy 347.169043 -215.107721) (xy 347.123038 -215.085768)
			(xy 347.080783 -215.057255) (xy 347.043209 -215.022807) (xy 347.011141 -214.983182) (xy 346.997782 -214.96147)
			(xy 346.991686 -214.951056) (xy 346.971874 -214.938102) (xy 346.89669 -214.929466) (xy 346.885223 -214.928669)
			(xy 346.863533 -214.936205) (xy 346.855034 -214.943944) (xy 346.625164 -215.173814) (xy 346.617798 -215.180926)
			(xy 346.610178 -215.199722) (xy 346.610178 -215.245442) (xy 346.625926 -215.27008) (xy 346.639388 -215.27643)
			(xy 346.664319 -215.288717) (xy 346.710178 -215.320116) (xy 346.750384 -215.358488) (xy 346.783888 -215.402832)
			(xy 346.809815 -215.451993) (xy 346.827489 -215.504686) (xy 346.836449 -215.559537) (xy 346.837 -215.587326)
			(xy 346.949779 -215.587326) (xy 346.953809 -215.534828) (xy 346.965806 -215.48356) (xy 346.985489 -215.434725)
			(xy 347.012395 -215.389466) (xy 347.045895 -215.348845) (xy 347.085203 -215.313814) (xy 347.129398 -215.285194)
			(xy 347.177443 -215.263655) (xy 347.228214 -215.249703) (xy 347.280519 -215.243665) (xy 347.333133 -215.245682)
			(xy 347.384823 -215.255706) (xy 347.434376 -215.273504) (xy 347.480632 -215.298657) (xy 347.522506 -215.330576)
			(xy 347.559018 -215.368514) (xy 347.58931 -215.41158) (xy 347.612673 -215.458765) (xy 347.628559 -215.508964)
			(xy 347.636596 -215.561) (xy 347.6371 -215.587326) (xy 347.749625 -215.587326) (xy 347.753655 -215.534828)
			(xy 347.765652 -215.48356) (xy 347.785335 -215.434725) (xy 347.812241 -215.389466) (xy 347.845741 -215.348845)
			(xy 347.885049 -215.313814) (xy 347.929244 -215.285194) (xy 347.977289 -215.263655) (xy 348.02806 -215.249703)
			(xy 348.080365 -215.243665) (xy 348.132979 -215.245682) (xy 348.184669 -215.255706) (xy 348.234222 -215.273504)
			(xy 348.280478 -215.298657) (xy 348.322352 -215.330576) (xy 348.358864 -215.368514) (xy 348.389156 -215.41158)
			(xy 348.412519 -215.458765) (xy 348.428405 -215.508964) (xy 348.436442 -215.561) (xy 348.436946 -215.587326)
			(xy 348.549725 -215.587326) (xy 348.553755 -215.534828) (xy 348.565752 -215.48356) (xy 348.585435 -215.434725)
			(xy 348.612341 -215.389466) (xy 348.645841 -215.348845) (xy 348.685149 -215.313814) (xy 348.729344 -215.285194)
			(xy 348.777389 -215.263655) (xy 348.82816 -215.249703) (xy 348.880465 -215.243665) (xy 348.933079 -215.245682)
			(xy 348.984769 -215.255706) (xy 349.034322 -215.273504) (xy 349.080578 -215.298657) (xy 349.122452 -215.330576)
			(xy 349.158964 -215.368514) (xy 349.189256 -215.41158) (xy 349.212619 -215.458765) (xy 349.228505 -215.508964)
			(xy 349.236542 -215.561) (xy 349.237046 -215.587326) (xy 349.349825 -215.587326) (xy 349.353855 -215.534828)
			(xy 349.365852 -215.48356) (xy 349.385535 -215.434725) (xy 349.412441 -215.389466) (xy 349.445941 -215.348845)
			(xy 349.485249 -215.313814) (xy 349.529444 -215.285194) (xy 349.577489 -215.263655) (xy 349.62826 -215.249703)
			(xy 349.680565 -215.243665) (xy 349.733179 -215.245682) (xy 349.784869 -215.255706) (xy 349.834422 -215.273504)
			(xy 349.880678 -215.298657) (xy 349.922552 -215.330576) (xy 349.959064 -215.368514) (xy 349.989356 -215.41158)
			(xy 350.012719 -215.458765) (xy 350.028605 -215.508964) (xy 350.036642 -215.561) (xy 350.037146 -215.587326)
			(xy 350.149671 -215.587326) (xy 350.153701 -215.534828) (xy 350.165698 -215.48356) (xy 350.185381 -215.434725)
			(xy 350.212287 -215.389466) (xy 350.245787 -215.348845) (xy 350.285095 -215.313814) (xy 350.32929 -215.285194)
			(xy 350.377335 -215.263655) (xy 350.428106 -215.249703) (xy 350.480411 -215.243665) (xy 350.533025 -215.245682)
			(xy 350.584715 -215.255706) (xy 350.634268 -215.273504) (xy 350.680524 -215.298657) (xy 350.722398 -215.330576)
			(xy 350.75891 -215.368514) (xy 350.789202 -215.41158) (xy 350.812565 -215.458765) (xy 350.828451 -215.508964)
			(xy 350.836488 -215.561) (xy 350.836992 -215.587326) (xy 350.836488 -215.613652) (xy 350.828451 -215.665688)
			(xy 350.812565 -215.715887) (xy 350.789202 -215.763072) (xy 350.75891 -215.806138) (xy 350.722398 -215.844076)
			(xy 350.680524 -215.875995) (xy 350.634268 -215.901148) (xy 350.584715 -215.918946) (xy 350.533025 -215.92897)
			(xy 350.480411 -215.930987) (xy 350.428106 -215.924949) (xy 350.377335 -215.910997) (xy 350.32929 -215.889458)
			(xy 350.285095 -215.860838) (xy 350.245787 -215.825807) (xy 350.212287 -215.785186) (xy 350.185381 -215.739927)
			(xy 350.165698 -215.691092) (xy 350.153701 -215.639824) (xy 350.149671 -215.587326) (xy 350.037146 -215.587326)
			(xy 350.036642 -215.613652) (xy 350.028605 -215.665688) (xy 350.012719 -215.715887) (xy 349.989356 -215.763072)
			(xy 349.959064 -215.806138) (xy 349.922552 -215.844076) (xy 349.880678 -215.875995) (xy 349.834422 -215.901148)
			(xy 349.784869 -215.918946) (xy 349.733179 -215.92897) (xy 349.680565 -215.930987) (xy 349.62826 -215.924949)
			(xy 349.577489 -215.910997) (xy 349.529444 -215.889458) (xy 349.485249 -215.860838) (xy 349.445941 -215.825807)
			(xy 349.412441 -215.785186) (xy 349.385535 -215.739927) (xy 349.365852 -215.691092) (xy 349.353855 -215.639824)
			(xy 349.349825 -215.587326) (xy 349.237046 -215.587326) (xy 349.236542 -215.613652) (xy 349.228505 -215.665688)
			(xy 349.212619 -215.715887) (xy 349.189256 -215.763072) (xy 349.158964 -215.806138) (xy 349.122452 -215.844076)
			(xy 349.080578 -215.875995) (xy 349.034322 -215.901148) (xy 348.984769 -215.918946) (xy 348.933079 -215.92897)
			(xy 348.880465 -215.930987) (xy 348.82816 -215.924949) (xy 348.777389 -215.910997) (xy 348.729344 -215.889458)
			(xy 348.685149 -215.860838) (xy 348.645841 -215.825807) (xy 348.612341 -215.785186) (xy 348.585435 -215.739927)
			(xy 348.565752 -215.691092) (xy 348.553755 -215.639824) (xy 348.549725 -215.587326) (xy 348.436946 -215.587326)
			(xy 348.436442 -215.613652) (xy 348.428405 -215.665688) (xy 348.412519 -215.715887) (xy 348.389156 -215.763072)
			(xy 348.358864 -215.806138) (xy 348.322352 -215.844076) (xy 348.280478 -215.875995) (xy 348.234222 -215.901148)
			(xy 348.184669 -215.918946) (xy 348.132979 -215.92897) (xy 348.080365 -215.930987) (xy 348.02806 -215.924949)
			(xy 347.977289 -215.910997) (xy 347.929244 -215.889458) (xy 347.885049 -215.860838) (xy 347.845741 -215.825807)
			(xy 347.812241 -215.785186) (xy 347.785335 -215.739927) (xy 347.765652 -215.691092) (xy 347.753655 -215.639824)
			(xy 347.749625 -215.587326) (xy 347.6371 -215.587326) (xy 347.636596 -215.613652) (xy 347.628559 -215.665688)
			(xy 347.612673 -215.715887) (xy 347.58931 -215.763072) (xy 347.559018 -215.806138) (xy 347.522506 -215.844076)
			(xy 347.480632 -215.875995) (xy 347.434376 -215.901148) (xy 347.384823 -215.918946) (xy 347.333133 -215.92897)
			(xy 347.280519 -215.930987) (xy 347.228214 -215.924949) (xy 347.177443 -215.910997) (xy 347.129398 -215.889458)
			(xy 347.085203 -215.860838) (xy 347.045895 -215.825807) (xy 347.012395 -215.785186) (xy 346.985489 -215.739927)
			(xy 346.965806 -215.691092) (xy 346.953809 -215.639824) (xy 346.949779 -215.587326) (xy 346.837 -215.587326)
			(xy 346.83652 -215.613025) (xy 346.828859 -215.663849) (xy 346.81371 -215.712963) (xy 346.791409 -215.759271)
			(xy 346.762456 -215.801738) (xy 346.727496 -215.839415) (xy 346.687312 -215.871461) (xy 346.6428 -215.89716)
			(xy 346.594955 -215.915937) (xy 346.544846 -215.927375) (xy 346.493592 -215.931216) (xy 346.442338 -215.927375)
			(xy 346.392229 -215.915937) (xy 346.344384 -215.89716) (xy 346.299872 -215.871461) (xy 346.259688 -215.839415)
			(xy 346.224728 -215.801738) (xy 346.195775 -215.759271) (xy 346.173474 -215.712963) (xy 346.158325 -215.663849)
			(xy 346.150664 -215.613025) (xy 346.150184 -215.587326) (xy 346.150184 -215.587072) (xy 346.150684 -215.561497)
			(xy 346.158318 -215.51092) (xy 346.173355 -215.462029) (xy 346.195464 -215.415903) (xy 346.224157 -215.373558)
			(xy 346.241116 -215.354408) (xy 346.251784 -215.342978) (xy 346.25661 -215.31326) (xy 346.218002 -215.227154)
			(xy 346.213597 -215.218459) (xy 346.199556 -215.204962) (xy 346.18151 -215.197638) (xy 346.171774 -215.197182)
			(xy 345.90863 -215.197182) (xy 345.898565 -215.197617) (xy 345.879977 -215.205348) (xy 345.872562 -215.212168)
			(xy 345.867228 -215.217502) (xy 345.860425 -215.22488) (xy 345.85274 -215.243403) (xy 345.852752 -215.263457)
			(xy 345.860459 -215.281971) (xy 345.867228 -215.289384) (xy 345.871292 -215.293448) (xy 345.876118 -215.296496)
			(xy 345.896904 -215.310029) (xy 345.934711 -215.342132) (xy 345.967502 -215.379344) (xy 345.994594 -215.420889)
			(xy 346.015421 -215.465902) (xy 346.029551 -215.513445) (xy 346.036689 -215.562527) (xy 346.037154 -215.587326)
			(xy 346.036623 -215.614311) (xy 346.028177 -215.667617) (xy 346.011498 -215.718945) (xy 345.986995 -215.767032)
			(xy 345.955272 -215.810696) (xy 345.917111 -215.848859) (xy 345.873449 -215.880585) (xy 345.825363 -215.90509)
			(xy 345.774036 -215.921772) (xy 345.720731 -215.930221) (xy 345.693746 -215.930734) (xy 345.667955 -215.930269)
			(xy 345.616953 -215.922555) (xy 345.567675 -215.90731) (xy 345.521227 -215.884874) (xy 345.478652 -215.855752)
			(xy 345.440905 -215.820597) (xy 345.424506 -215.800686) (xy 345.417648 -215.791796) (xy 345.398344 -215.78189)
			(xy 345.329256 -215.778842) (xy 345.318687 -215.778883) (xy 345.29899 -215.786482) (xy 345.291156 -215.793574)
			(xy 345.220036 -215.864694) (xy 345.21267 -215.871806) (xy 345.20505 -215.890602) (xy 345.20505 -216.208102)
			(xy 345.207844 -216.219532) (xy 345.210638 -216.224866) (xy 345.217242 -216.23909) (xy 345.21775 -216.239852)
			(xy 345.218004 -216.240614) (xy 345.230704 -216.269824) (xy 345.238269 -216.28826) (xy 345.249102 -216.326608)
			(xy 345.252294 -216.346278) (xy 345.258216 -216.36355) (xy 345.346782 -216.36355) (xy 345.349081 -216.359206)
			(xy 345.352143 -216.349868) (xy 345.352878 -216.345008) (xy 345.356828 -216.31765) (xy 345.372327 -216.264596)
			(xy 345.39612 -216.214708) (xy 345.427594 -216.169273) (xy 345.465936 -216.129464) (xy 345.510158 -216.096307)
			(xy 345.559118 -216.070658) (xy 345.611553 -216.053179) (xy 345.66611 -216.044321) (xy 345.693746 -216.043764)
			(xy 345.72081 -216.044216) (xy 345.774265 -216.052728) (xy 345.825724 -216.069519) (xy 345.873913 -216.094172)
			(xy 345.917638 -216.126077) (xy 345.955819 -216.164446) (xy 345.98751 -216.208328) (xy 346.011926 -216.256637)
			(xy 346.028464 -216.308177) (xy 346.03309 -216.334848) (xy 346.03436 -216.34323) (xy 346.041726 -216.357454)
			(xy 346.065602 -216.38133) (xy 346.073036 -216.388046) (xy 346.091536 -216.395682) (xy 346.11155 -216.395682)
			(xy 346.13005 -216.388046) (xy 346.137484 -216.38133) (xy 346.143834 -216.375234) (xy 346.1512 -216.359486)
			(xy 346.152216 -216.35085) (xy 346.155263 -216.325868) (xy 346.167816 -216.277131) (xy 346.187351 -216.230749)
			(xy 346.21345 -216.187717) (xy 346.245553 -216.148958) (xy 346.282973 -216.115302) (xy 346.324905 -216.087472)
			(xy 346.370452 -216.066063) (xy 346.418638 -216.051535) (xy 346.468428 -216.044199) (xy 346.493592 -216.043764)
			(xy 346.519291 -216.044276) (xy 346.570115 -216.051935) (xy 346.61923 -216.067084) (xy 346.665538 -216.089384)
			(xy 346.708006 -216.118337) (xy 346.745683 -216.153296) (xy 346.77773 -216.19348) (xy 346.803429 -216.237992)
			(xy 346.822207 -216.285837) (xy 346.833644 -216.335946) (xy 346.837484 -216.387172) (xy 346.949779 -216.387172)
			(xy 346.953809 -216.334674) (xy 346.965806 -216.283406) (xy 346.985489 -216.234571) (xy 347.012395 -216.189312)
			(xy 347.045895 -216.148691) (xy 347.085203 -216.11366) (xy 347.129398 -216.08504) (xy 347.177443 -216.063501)
			(xy 347.228214 -216.049549) (xy 347.280519 -216.043511) (xy 347.333133 -216.045528) (xy 347.384823 -216.055552)
			(xy 347.434376 -216.07335) (xy 347.480632 -216.098503) (xy 347.522506 -216.130422) (xy 347.559018 -216.16836)
			(xy 347.58931 -216.211426) (xy 347.612673 -216.258611) (xy 347.628559 -216.30881) (xy 347.636596 -216.360846)
			(xy 347.6371 -216.387172) (xy 347.749625 -216.387172) (xy 347.753655 -216.334674) (xy 347.765652 -216.283406)
			(xy 347.785335 -216.234571) (xy 347.812241 -216.189312) (xy 347.845741 -216.148691) (xy 347.885049 -216.11366)
			(xy 347.929244 -216.08504) (xy 347.977289 -216.063501) (xy 348.02806 -216.049549) (xy 348.080365 -216.043511)
			(xy 348.132979 -216.045528) (xy 348.184669 -216.055552) (xy 348.234222 -216.07335) (xy 348.280478 -216.098503)
			(xy 348.322352 -216.130422) (xy 348.358864 -216.16836) (xy 348.389156 -216.211426) (xy 348.412519 -216.258611)
			(xy 348.428405 -216.30881) (xy 348.436442 -216.360846) (xy 348.436946 -216.387172) (xy 348.549725 -216.387172)
			(xy 348.553755 -216.334674) (xy 348.565752 -216.283406) (xy 348.585435 -216.234571) (xy 348.612341 -216.189312)
			(xy 348.645841 -216.148691) (xy 348.685149 -216.11366) (xy 348.729344 -216.08504) (xy 348.777389 -216.063501)
			(xy 348.82816 -216.049549) (xy 348.880465 -216.043511) (xy 348.933079 -216.045528) (xy 348.984769 -216.055552)
			(xy 349.034322 -216.07335) (xy 349.080578 -216.098503) (xy 349.122452 -216.130422) (xy 349.158964 -216.16836)
			(xy 349.189256 -216.211426) (xy 349.212619 -216.258611) (xy 349.228505 -216.30881) (xy 349.236542 -216.360846)
			(xy 349.237046 -216.387172) (xy 349.349825 -216.387172) (xy 349.353855 -216.334674) (xy 349.365852 -216.283406)
			(xy 349.385535 -216.234571) (xy 349.412441 -216.189312) (xy 349.445941 -216.148691) (xy 349.485249 -216.11366)
			(xy 349.529444 -216.08504) (xy 349.577489 -216.063501) (xy 349.62826 -216.049549) (xy 349.680565 -216.043511)
			(xy 349.733179 -216.045528) (xy 349.784869 -216.055552) (xy 349.834422 -216.07335) (xy 349.880678 -216.098503)
			(xy 349.922552 -216.130422) (xy 349.959064 -216.16836) (xy 349.989356 -216.211426) (xy 350.012719 -216.258611)
			(xy 350.028605 -216.30881) (xy 350.036642 -216.360846) (xy 350.037146 -216.387172) (xy 350.149671 -216.387172)
			(xy 350.153701 -216.334674) (xy 350.165698 -216.283406) (xy 350.185381 -216.234571) (xy 350.212287 -216.189312)
			(xy 350.245787 -216.148691) (xy 350.285095 -216.11366) (xy 350.32929 -216.08504) (xy 350.377335 -216.063501)
			(xy 350.428106 -216.049549) (xy 350.480411 -216.043511) (xy 350.533025 -216.045528) (xy 350.584715 -216.055552)
			(xy 350.634268 -216.07335) (xy 350.680524 -216.098503) (xy 350.722398 -216.130422) (xy 350.75891 -216.16836)
			(xy 350.789202 -216.211426) (xy 350.812565 -216.258611) (xy 350.828451 -216.30881) (xy 350.836488 -216.360846)
			(xy 350.836992 -216.387172) (xy 350.949771 -216.387172) (xy 350.953801 -216.334674) (xy 350.965798 -216.283406)
			(xy 350.985481 -216.234571) (xy 351.012387 -216.189312) (xy 351.045887 -216.148691) (xy 351.085195 -216.11366)
			(xy 351.12939 -216.08504) (xy 351.177435 -216.063501) (xy 351.228206 -216.049549) (xy 351.280511 -216.043511)
			(xy 351.333125 -216.045528) (xy 351.384815 -216.055552) (xy 351.434368 -216.07335) (xy 351.480624 -216.098503)
			(xy 351.522498 -216.130422) (xy 351.55901 -216.16836) (xy 351.589302 -216.211426) (xy 351.612665 -216.258611)
			(xy 351.628551 -216.30881) (xy 351.636588 -216.360846) (xy 351.637092 -216.387172) (xy 351.636588 -216.413498)
			(xy 351.628551 -216.465534) (xy 351.612665 -216.515733) (xy 351.589302 -216.562918) (xy 351.55901 -216.605984)
			(xy 351.522498 -216.643922) (xy 351.480624 -216.675841) (xy 351.434368 -216.700994) (xy 351.384815 -216.718792)
			(xy 351.333125 -216.728816) (xy 351.280511 -216.730833) (xy 351.228206 -216.724795) (xy 351.177435 -216.710843)
			(xy 351.12939 -216.689304) (xy 351.085195 -216.660684) (xy 351.045887 -216.625653) (xy 351.012387 -216.585032)
			(xy 350.985481 -216.539773) (xy 350.965798 -216.490938) (xy 350.953801 -216.43967) (xy 350.949771 -216.387172)
			(xy 350.836992 -216.387172) (xy 350.836488 -216.413498) (xy 350.828451 -216.465534) (xy 350.812565 -216.515733)
			(xy 350.789202 -216.562918) (xy 350.75891 -216.605984) (xy 350.722398 -216.643922) (xy 350.680524 -216.675841)
			(xy 350.634268 -216.700994) (xy 350.584715 -216.718792) (xy 350.533025 -216.728816) (xy 350.480411 -216.730833)
			(xy 350.428106 -216.724795) (xy 350.377335 -216.710843) (xy 350.32929 -216.689304) (xy 350.285095 -216.660684)
			(xy 350.245787 -216.625653) (xy 350.212287 -216.585032) (xy 350.185381 -216.539773) (xy 350.165698 -216.490938)
			(xy 350.153701 -216.43967) (xy 350.149671 -216.387172) (xy 350.037146 -216.387172) (xy 350.036642 -216.413498)
			(xy 350.028605 -216.465534) (xy 350.012719 -216.515733) (xy 349.989356 -216.562918) (xy 349.959064 -216.605984)
			(xy 349.922552 -216.643922) (xy 349.880678 -216.675841) (xy 349.834422 -216.700994) (xy 349.784869 -216.718792)
			(xy 349.733179 -216.728816) (xy 349.680565 -216.730833) (xy 349.62826 -216.724795) (xy 349.577489 -216.710843)
			(xy 349.529444 -216.689304) (xy 349.485249 -216.660684) (xy 349.445941 -216.625653) (xy 349.412441 -216.585032)
			(xy 349.385535 -216.539773) (xy 349.365852 -216.490938) (xy 349.353855 -216.43967) (xy 349.349825 -216.387172)
			(xy 349.237046 -216.387172) (xy 349.236542 -216.413498) (xy 349.228505 -216.465534) (xy 349.212619 -216.515733)
			(xy 349.189256 -216.562918) (xy 349.158964 -216.605984) (xy 349.122452 -216.643922) (xy 349.080578 -216.675841)
			(xy 349.034322 -216.700994) (xy 348.984769 -216.718792) (xy 348.933079 -216.728816) (xy 348.880465 -216.730833)
			(xy 348.82816 -216.724795) (xy 348.777389 -216.710843) (xy 348.729344 -216.689304) (xy 348.685149 -216.660684)
			(xy 348.645841 -216.625653) (xy 348.612341 -216.585032) (xy 348.585435 -216.539773) (xy 348.565752 -216.490938)
			(xy 348.553755 -216.43967) (xy 348.549725 -216.387172) (xy 348.436946 -216.387172) (xy 348.436442 -216.413498)
			(xy 348.428405 -216.465534) (xy 348.412519 -216.515733) (xy 348.389156 -216.562918) (xy 348.358864 -216.605984)
			(xy 348.322352 -216.643922) (xy 348.280478 -216.675841) (xy 348.234222 -216.700994) (xy 348.184669 -216.718792)
			(xy 348.132979 -216.728816) (xy 348.080365 -216.730833) (xy 348.02806 -216.724795) (xy 347.977289 -216.710843)
			(xy 347.929244 -216.689304) (xy 347.885049 -216.660684) (xy 347.845741 -216.625653) (xy 347.812241 -216.585032)
			(xy 347.785335 -216.539773) (xy 347.765652 -216.490938) (xy 347.753655 -216.43967) (xy 347.749625 -216.387172)
			(xy 347.6371 -216.387172) (xy 347.636596 -216.413498) (xy 347.628559 -216.465534) (xy 347.612673 -216.515733)
			(xy 347.58931 -216.562918) (xy 347.559018 -216.605984) (xy 347.522506 -216.643922) (xy 347.480632 -216.675841)
			(xy 347.434376 -216.700994) (xy 347.384823 -216.718792) (xy 347.333133 -216.728816) (xy 347.280519 -216.730833)
			(xy 347.228214 -216.724795) (xy 347.177443 -216.710843) (xy 347.129398 -216.689304) (xy 347.085203 -216.660684)
			(xy 347.045895 -216.625653) (xy 347.012395 -216.585032) (xy 346.985489 -216.539773) (xy 346.965806 -216.490938)
			(xy 346.953809 -216.43967) (xy 346.949779 -216.387172) (xy 346.837484 -216.387172) (xy 346.837486 -216.3872)
			(xy 346.833644 -216.438454) (xy 346.822207 -216.488563) (xy 346.803429 -216.536408) (xy 346.77773 -216.58092)
			(xy 346.745683 -216.621104) (xy 346.708006 -216.656063) (xy 346.665538 -216.685016) (xy 346.61923 -216.707316)
			(xy 346.570115 -216.722465) (xy 346.519291 -216.730124) (xy 346.493592 -216.73058) (xy 346.490544 -216.73058)
			(xy 346.480863 -216.730928) (xy 346.462838 -216.737981) (xy 346.455492 -216.744296) (xy 346.416884 -216.780618)
			(xy 346.416884 -216.793826) (xy 346.455492 -216.830148) (xy 346.462867 -216.836418) (xy 346.480873 -216.843479)
			(xy 346.490544 -216.843864) (xy 346.493592 -216.843864) (xy 346.519291 -216.844376) (xy 346.570115 -216.852035)
			(xy 346.61923 -216.867184) (xy 346.665538 -216.889484) (xy 346.708006 -216.918437) (xy 346.745683 -216.953396)
			(xy 346.77773 -216.99358) (xy 346.803429 -217.038092) (xy 346.822207 -217.085937) (xy 346.833644 -217.136046)
			(xy 346.837484 -217.187272) (xy 346.949779 -217.187272) (xy 346.953809 -217.134774) (xy 346.965806 -217.083506)
			(xy 346.985489 -217.034671) (xy 347.012395 -216.989412) (xy 347.045895 -216.948791) (xy 347.085203 -216.91376)
			(xy 347.129398 -216.88514) (xy 347.177443 -216.863601) (xy 347.228214 -216.849649) (xy 347.280519 -216.843611)
			(xy 347.333133 -216.845628) (xy 347.384823 -216.855652) (xy 347.434376 -216.87345) (xy 347.480632 -216.898603)
			(xy 347.522506 -216.930522) (xy 347.559018 -216.96846) (xy 347.58931 -217.011526) (xy 347.612673 -217.058711)
			(xy 347.628559 -217.10891) (xy 347.636596 -217.160946) (xy 347.6371 -217.187272) (xy 347.749625 -217.187272)
			(xy 347.753655 -217.134774) (xy 347.765652 -217.083506) (xy 347.785335 -217.034671) (xy 347.812241 -216.989412)
			(xy 347.845741 -216.948791) (xy 347.885049 -216.91376) (xy 347.929244 -216.88514) (xy 347.977289 -216.863601)
			(xy 348.02806 -216.849649) (xy 348.080365 -216.843611) (xy 348.132979 -216.845628) (xy 348.184669 -216.855652)
			(xy 348.234222 -216.87345) (xy 348.280478 -216.898603) (xy 348.322352 -216.930522) (xy 348.358864 -216.96846)
			(xy 348.389156 -217.011526) (xy 348.412519 -217.058711) (xy 348.428405 -217.10891) (xy 348.436442 -217.160946)
			(xy 348.436941 -217.187018) (xy 348.549979 -217.187018) (xy 348.554009 -217.13452) (xy 348.566006 -217.083252)
			(xy 348.585689 -217.034417) (xy 348.612595 -216.989158) (xy 348.646095 -216.948537) (xy 348.685403 -216.913506)
			(xy 348.729598 -216.884886) (xy 348.777643 -216.863347) (xy 348.828414 -216.849395) (xy 348.880719 -216.843357)
			(xy 348.933333 -216.845374) (xy 348.985023 -216.855398) (xy 349.034576 -216.873196) (xy 349.080832 -216.898349)
			(xy 349.122706 -216.930268) (xy 349.159218 -216.968206) (xy 349.18951 -217.011272) (xy 349.212873 -217.058457)
			(xy 349.228759 -217.108656) (xy 349.236796 -217.160692) (xy 349.2373 -217.187018) (xy 349.237295 -217.187272)
			(xy 349.349825 -217.187272) (xy 349.353855 -217.134774) (xy 349.365852 -217.083506) (xy 349.385535 -217.034671)
			(xy 349.412441 -216.989412) (xy 349.445941 -216.948791) (xy 349.485249 -216.91376) (xy 349.529444 -216.88514)
			(xy 349.577489 -216.863601) (xy 349.62826 -216.849649) (xy 349.680565 -216.843611) (xy 349.733179 -216.845628)
			(xy 349.784869 -216.855652) (xy 349.834422 -216.87345) (xy 349.880678 -216.898603) (xy 349.922552 -216.930522)
			(xy 349.959064 -216.96846) (xy 349.989356 -217.011526) (xy 350.012719 -217.058711) (xy 350.028605 -217.10891)
			(xy 350.036642 -217.160946) (xy 350.037146 -217.187272) (xy 350.149671 -217.187272) (xy 350.153701 -217.134774)
			(xy 350.165698 -217.083506) (xy 350.185381 -217.034671) (xy 350.212287 -216.989412) (xy 350.245787 -216.948791)
			(xy 350.285095 -216.91376) (xy 350.32929 -216.88514) (xy 350.377335 -216.863601) (xy 350.428106 -216.849649)
			(xy 350.480411 -216.843611) (xy 350.533025 -216.845628) (xy 350.584715 -216.855652) (xy 350.634268 -216.87345)
			(xy 350.680524 -216.898603) (xy 350.722398 -216.930522) (xy 350.75891 -216.96846) (xy 350.789202 -217.011526)
			(xy 350.812565 -217.058711) (xy 350.828451 -217.10891) (xy 350.836488 -217.160946) (xy 350.836992 -217.187272)
			(xy 350.836488 -217.213598) (xy 350.828451 -217.265634) (xy 350.812565 -217.315833) (xy 350.789202 -217.363018)
			(xy 350.75891 -217.406084) (xy 350.722398 -217.444022) (xy 350.680524 -217.475941) (xy 350.634268 -217.501094)
			(xy 350.584715 -217.518892) (xy 350.533025 -217.528916) (xy 350.480411 -217.530933) (xy 350.428106 -217.524895)
			(xy 350.377335 -217.510943) (xy 350.32929 -217.489404) (xy 350.285095 -217.460784) (xy 350.245787 -217.425753)
			(xy 350.212287 -217.385132) (xy 350.185381 -217.339873) (xy 350.165698 -217.291038) (xy 350.153701 -217.23977)
			(xy 350.149671 -217.187272) (xy 350.037146 -217.187272) (xy 350.036642 -217.213598) (xy 350.028605 -217.265634)
			(xy 350.012719 -217.315833) (xy 349.989356 -217.363018) (xy 349.959064 -217.406084) (xy 349.922552 -217.444022)
			(xy 349.880678 -217.475941) (xy 349.834422 -217.501094) (xy 349.784869 -217.518892) (xy 349.733179 -217.528916)
			(xy 349.680565 -217.530933) (xy 349.62826 -217.524895) (xy 349.577489 -217.510943) (xy 349.529444 -217.489404)
			(xy 349.485249 -217.460784) (xy 349.445941 -217.425753) (xy 349.412441 -217.385132) (xy 349.385535 -217.339873)
			(xy 349.365852 -217.291038) (xy 349.353855 -217.23977) (xy 349.349825 -217.187272) (xy 349.237295 -217.187272)
			(xy 349.236796 -217.213344) (xy 349.228759 -217.26538) (xy 349.212873 -217.315579) (xy 349.18951 -217.362764)
			(xy 349.159218 -217.40583) (xy 349.122706 -217.443768) (xy 349.080832 -217.475687) (xy 349.034576 -217.50084)
			(xy 348.985023 -217.518638) (xy 348.933333 -217.528662) (xy 348.880719 -217.530679) (xy 348.828414 -217.524641)
			(xy 348.777643 -217.510689) (xy 348.729598 -217.48915) (xy 348.685403 -217.46053) (xy 348.646095 -217.425499)
			(xy 348.612595 -217.384878) (xy 348.585689 -217.339619) (xy 348.566006 -217.290784) (xy 348.554009 -217.239516)
			(xy 348.549979 -217.187018) (xy 348.436941 -217.187018) (xy 348.436946 -217.187272) (xy 348.436442 -217.213598)
			(xy 348.428405 -217.265634) (xy 348.412519 -217.315833) (xy 348.389156 -217.363018) (xy 348.358864 -217.406084)
			(xy 348.322352 -217.444022) (xy 348.280478 -217.475941) (xy 348.234222 -217.501094) (xy 348.184669 -217.518892)
			(xy 348.132979 -217.528916) (xy 348.080365 -217.530933) (xy 348.02806 -217.524895) (xy 347.977289 -217.510943)
			(xy 347.929244 -217.489404) (xy 347.885049 -217.460784) (xy 347.845741 -217.425753) (xy 347.812241 -217.385132)
			(xy 347.785335 -217.339873) (xy 347.765652 -217.291038) (xy 347.753655 -217.23977) (xy 347.749625 -217.187272)
			(xy 347.6371 -217.187272) (xy 347.636596 -217.213598) (xy 347.628559 -217.265634) (xy 347.612673 -217.315833)
			(xy 347.58931 -217.363018) (xy 347.559018 -217.406084) (xy 347.522506 -217.444022) (xy 347.480632 -217.475941)
			(xy 347.434376 -217.501094) (xy 347.384823 -217.518892) (xy 347.333133 -217.528916) (xy 347.280519 -217.530933)
			(xy 347.228214 -217.524895) (xy 347.177443 -217.510943) (xy 347.129398 -217.489404) (xy 347.085203 -217.460784)
			(xy 347.045895 -217.425753) (xy 347.012395 -217.385132) (xy 346.985489 -217.339873) (xy 346.965806 -217.291038)
			(xy 346.953809 -217.23977) (xy 346.949779 -217.187272) (xy 346.837484 -217.187272) (xy 346.837486 -217.1873)
			(xy 346.833644 -217.238554) (xy 346.822207 -217.288663) (xy 346.803429 -217.336508) (xy 346.77773 -217.38102)
			(xy 346.745683 -217.421204) (xy 346.708006 -217.456163) (xy 346.665538 -217.485116) (xy 346.61923 -217.507416)
			(xy 346.570115 -217.522565) (xy 346.519291 -217.530224) (xy 346.493592 -217.53068) (xy 346.467516 -217.530208)
			(xy 346.415963 -217.522321) (xy 346.366196 -217.506729) (xy 346.319358 -217.48379) (xy 346.276528 -217.454033)
			(xy 346.23869 -217.418141) (xy 346.22232 -217.397838) (xy 346.214756 -217.389079) (xy 346.193998 -217.378897)
			(xy 346.182442 -217.37828) (xy 346.181934 -217.37828) (xy 346.005404 -217.37828) (xy 345.946984 -217.286332)
			(xy 345.946984 -217.114374) (xy 345.945931 -217.105347) (xy 345.938383 -217.088825) (xy 345.932252 -217.082116)
			(xy 345.785694 -216.935812) (xy 345.778866 -216.928403) (xy 345.771139 -216.90981) (xy 345.770708 -216.899744)
			(xy 345.770708 -216.862914) (xy 345.770249 -216.852945) (xy 345.762663 -216.834508) (xy 345.755976 -216.8271)
			(xy 345.664028 -216.735152) (xy 345.649804 -216.727786) (xy 345.641422 -216.726516) (xy 345.61422 -216.721705)
			(xy 345.561683 -216.70465) (xy 345.512553 -216.679406) (xy 345.468098 -216.646623) (xy 345.429465 -216.607146)
			(xy 345.397649 -216.561993) (xy 345.373471 -216.51233) (xy 345.357555 -216.459437) (xy 345.353386 -216.43213)
			(xy 345.352594 -216.427258) (xy 345.349401 -216.41792) (xy 345.347036 -216.413588) (xy 345.346782 -216.36355)
			(xy 345.258216 -216.36355) (xy 345.25839 -216.364058) (xy 345.258644 -216.414096) (xy 345.252548 -216.431876)
			(xy 345.248064 -216.459675) (xy 345.2303 -216.513101) (xy 345.217242 -216.538048) (xy 345.215972 -216.540334)
			(xy 345.205812 -216.55913) (xy 345.191177 -216.584482) (xy 345.154927 -216.630438) (xy 345.133676 -216.65057)
			(xy 345.126056 -216.657428) (xy 345.112848 -216.685876) (xy 345.110689 -216.690941) (xy 345.108382 -216.701707)
			(xy 345.108276 -216.707212) (xy 345.108276 -216.86774) (xy 345.108739 -216.877616) (xy 345.116185 -216.895911)
			(xy 345.122754 -216.9033) (xy 345.200224 -216.98077) (xy 345.206967 -216.986994) (xy 345.223625 -216.994657)
			(xy 345.232736 -216.995756) (xy 345.382342 -216.995756) (xy 345.390216 -217.007948) (xy 345.393518 -217.013028)
			(xy 345.396058 -217.017092) (xy 345.39682 -217.018108) (xy 345.397328 -217.019124) (xy 345.433142 -217.075258)
			(xy 345.433142 -217.075512) (xy 345.434412 -217.07729) (xy 345.435174 -217.07856) (xy 345.441016 -217.087704)
			(xy 345.441016 -217.238072) (xy 345.441504 -217.248033) (xy 345.449095 -217.266455) (xy 345.455748 -217.273886)
			(xy 345.614752 -217.433144) (xy 345.621864 -217.440256) (xy 345.625674 -217.4494) (xy 345.627447 -217.454028)
			(xy 345.629366 -217.463749) (xy 345.629484 -217.468704) (xy 345.629484 -217.705686) (xy 345.628994 -217.715646)
			(xy 345.621399 -217.734064) (xy 345.614752 -217.7415) (xy 345.448382 -217.90787) (xy 345.440984 -217.914717)
			(xy 345.422386 -217.92245) (xy 345.412314 -217.922856) (xy 345.34983 -217.922856) (xy 345.340387 -217.923351)
			(xy 345.322807 -217.930266) (xy 345.31554 -217.936318) (xy 345.26474 -217.9828) (xy 345.261232 -217.986223)
			(xy 345.260397 -217.987372) (xy 346.149679 -217.987372) (xy 346.153709 -217.934874) (xy 346.165706 -217.883606)
			(xy 346.185389 -217.834771) (xy 346.212295 -217.789512) (xy 346.245795 -217.748891) (xy 346.285103 -217.71386)
			(xy 346.329298 -217.68524) (xy 346.377343 -217.663701) (xy 346.428114 -217.649749) (xy 346.480419 -217.643711)
			(xy 346.533033 -217.645728) (xy 346.584723 -217.655752) (xy 346.634276 -217.67355) (xy 346.680532 -217.698703)
			(xy 346.722406 -217.730622) (xy 346.758918 -217.76856) (xy 346.78921 -217.811626) (xy 346.812573 -217.858811)
			(xy 346.828459 -217.90901) (xy 346.836496 -217.961046) (xy 346.837 -217.987372) (xy 346.949779 -217.987372)
			(xy 346.953809 -217.934874) (xy 346.965806 -217.883606) (xy 346.985489 -217.834771) (xy 347.012395 -217.789512)
			(xy 347.045895 -217.748891) (xy 347.085203 -217.71386) (xy 347.129398 -217.68524) (xy 347.177443 -217.663701)
			(xy 347.228214 -217.649749) (xy 347.280519 -217.643711) (xy 347.333133 -217.645728) (xy 347.384823 -217.655752)
			(xy 347.434376 -217.67355) (xy 347.480632 -217.698703) (xy 347.522506 -217.730622) (xy 347.559018 -217.76856)
			(xy 347.58931 -217.811626) (xy 347.612673 -217.858811) (xy 347.628559 -217.90901) (xy 347.636596 -217.961046)
			(xy 347.6371 -217.987372) (xy 347.749625 -217.987372) (xy 347.753655 -217.934874) (xy 347.765652 -217.883606)
			(xy 347.785335 -217.834771) (xy 347.812241 -217.789512) (xy 347.845741 -217.748891) (xy 347.885049 -217.71386)
			(xy 347.929244 -217.68524) (xy 347.977289 -217.663701) (xy 348.02806 -217.649749) (xy 348.080365 -217.643711)
			(xy 348.132979 -217.645728) (xy 348.184669 -217.655752) (xy 348.234222 -217.67355) (xy 348.280478 -217.698703)
			(xy 348.322352 -217.730622) (xy 348.358864 -217.76856) (xy 348.389156 -217.811626) (xy 348.412519 -217.858811)
			(xy 348.428405 -217.90901) (xy 348.436442 -217.961046) (xy 348.436946 -217.987372) (xy 348.549725 -217.987372)
			(xy 348.553755 -217.934874) (xy 348.565752 -217.883606) (xy 348.585435 -217.834771) (xy 348.612341 -217.789512)
			(xy 348.645841 -217.748891) (xy 348.685149 -217.71386) (xy 348.729344 -217.68524) (xy 348.777389 -217.663701)
			(xy 348.82816 -217.649749) (xy 348.880465 -217.643711) (xy 348.933079 -217.645728) (xy 348.984769 -217.655752)
			(xy 349.034322 -217.67355) (xy 349.080578 -217.698703) (xy 349.122452 -217.730622) (xy 349.158964 -217.76856)
			(xy 349.189256 -217.811626) (xy 349.212619 -217.858811) (xy 349.228505 -217.90901) (xy 349.236542 -217.961046)
			(xy 349.237046 -217.987372) (xy 349.349825 -217.987372) (xy 349.353855 -217.934874) (xy 349.365852 -217.883606)
			(xy 349.385535 -217.834771) (xy 349.412441 -217.789512) (xy 349.445941 -217.748891) (xy 349.485249 -217.71386)
			(xy 349.529444 -217.68524) (xy 349.577489 -217.663701) (xy 349.62826 -217.649749) (xy 349.680565 -217.643711)
			(xy 349.733179 -217.645728) (xy 349.784869 -217.655752) (xy 349.834422 -217.67355) (xy 349.880678 -217.698703)
			(xy 349.922552 -217.730622) (xy 349.959064 -217.76856) (xy 349.989356 -217.811626) (xy 350.012719 -217.858811)
			(xy 350.028605 -217.90901) (xy 350.036642 -217.961046) (xy 350.037146 -217.987372) (xy 350.149671 -217.987372)
			(xy 350.153701 -217.934874) (xy 350.165698 -217.883606) (xy 350.185381 -217.834771) (xy 350.212287 -217.789512)
			(xy 350.245787 -217.748891) (xy 350.285095 -217.71386) (xy 350.32929 -217.68524) (xy 350.377335 -217.663701)
			(xy 350.428106 -217.649749) (xy 350.480411 -217.643711) (xy 350.533025 -217.645728) (xy 350.584715 -217.655752)
			(xy 350.634268 -217.67355) (xy 350.680524 -217.698703) (xy 350.722398 -217.730622) (xy 350.75891 -217.76856)
			(xy 350.789202 -217.811626) (xy 350.812565 -217.858811) (xy 350.828451 -217.90901) (xy 350.836488 -217.961046)
			(xy 350.836992 -217.987372) (xy 350.949771 -217.987372) (xy 350.953801 -217.934874) (xy 350.965798 -217.883606)
			(xy 350.985481 -217.834771) (xy 351.012387 -217.789512) (xy 351.045887 -217.748891) (xy 351.085195 -217.71386)
			(xy 351.12939 -217.68524) (xy 351.177435 -217.663701) (xy 351.228206 -217.649749) (xy 351.280511 -217.643711)
			(xy 351.333125 -217.645728) (xy 351.384815 -217.655752) (xy 351.434368 -217.67355) (xy 351.480624 -217.698703)
			(xy 351.522498 -217.730622) (xy 351.55901 -217.76856) (xy 351.589302 -217.811626) (xy 351.612665 -217.858811)
			(xy 351.628551 -217.90901) (xy 351.636588 -217.961046) (xy 351.637092 -217.987372) (xy 351.636588 -218.013698)
			(xy 351.628551 -218.065734) (xy 351.612665 -218.115933) (xy 351.589302 -218.163118) (xy 351.55901 -218.206184)
			(xy 351.522498 -218.244122) (xy 351.480624 -218.276041) (xy 351.434368 -218.301194) (xy 351.384815 -218.318992)
			(xy 351.333125 -218.329016) (xy 351.280511 -218.331033) (xy 351.228206 -218.324995) (xy 351.177435 -218.311043)
			(xy 351.12939 -218.289504) (xy 351.085195 -218.260884) (xy 351.045887 -218.225853) (xy 351.012387 -218.185232)
			(xy 350.985481 -218.139973) (xy 350.965798 -218.091138) (xy 350.953801 -218.03987) (xy 350.949771 -217.987372)
			(xy 350.836992 -217.987372) (xy 350.836488 -218.013698) (xy 350.828451 -218.065734) (xy 350.812565 -218.115933)
			(xy 350.789202 -218.163118) (xy 350.75891 -218.206184) (xy 350.722398 -218.244122) (xy 350.680524 -218.276041)
			(xy 350.634268 -218.301194) (xy 350.584715 -218.318992) (xy 350.533025 -218.329016) (xy 350.480411 -218.331033)
			(xy 350.428106 -218.324995) (xy 350.377335 -218.311043) (xy 350.32929 -218.289504) (xy 350.285095 -218.260884)
			(xy 350.245787 -218.225853) (xy 350.212287 -218.185232) (xy 350.185381 -218.139973) (xy 350.165698 -218.091138)
			(xy 350.153701 -218.03987) (xy 350.149671 -217.987372) (xy 350.037146 -217.987372) (xy 350.036642 -218.013698)
			(xy 350.028605 -218.065734) (xy 350.012719 -218.115933) (xy 349.989356 -218.163118) (xy 349.959064 -218.206184)
			(xy 349.922552 -218.244122) (xy 349.880678 -218.276041) (xy 349.834422 -218.301194) (xy 349.784869 -218.318992)
			(xy 349.733179 -218.329016) (xy 349.680565 -218.331033) (xy 349.62826 -218.324995) (xy 349.577489 -218.311043)
			(xy 349.529444 -218.289504) (xy 349.485249 -218.260884) (xy 349.445941 -218.225853) (xy 349.412441 -218.185232)
			(xy 349.385535 -218.139973) (xy 349.365852 -218.091138) (xy 349.353855 -218.03987) (xy 349.349825 -217.987372)
			(xy 349.237046 -217.987372) (xy 349.236542 -218.013698) (xy 349.228505 -218.065734) (xy 349.212619 -218.115933)
			(xy 349.189256 -218.163118) (xy 349.158964 -218.206184) (xy 349.122452 -218.244122) (xy 349.080578 -218.276041)
			(xy 349.034322 -218.301194) (xy 348.984769 -218.318992) (xy 348.933079 -218.329016) (xy 348.880465 -218.331033)
			(xy 348.82816 -218.324995) (xy 348.777389 -218.311043) (xy 348.729344 -218.289504) (xy 348.685149 -218.260884)
			(xy 348.645841 -218.225853) (xy 348.612341 -218.185232) (xy 348.585435 -218.139973) (xy 348.565752 -218.091138)
			(xy 348.553755 -218.03987) (xy 348.549725 -217.987372) (xy 348.436946 -217.987372) (xy 348.436442 -218.013698)
			(xy 348.428405 -218.065734) (xy 348.412519 -218.115933) (xy 348.389156 -218.163118) (xy 348.358864 -218.206184)
			(xy 348.322352 -218.244122) (xy 348.280478 -218.276041) (xy 348.234222 -218.301194) (xy 348.184669 -218.318992)
			(xy 348.132979 -218.329016) (xy 348.080365 -218.331033) (xy 348.02806 -218.324995) (xy 347.977289 -218.311043)
			(xy 347.929244 -218.289504) (xy 347.885049 -218.260884) (xy 347.845741 -218.225853) (xy 347.812241 -218.185232)
			(xy 347.785335 -218.139973) (xy 347.765652 -218.091138) (xy 347.753655 -218.03987) (xy 347.749625 -217.987372)
			(xy 347.6371 -217.987372) (xy 347.636596 -218.013698) (xy 347.628559 -218.065734) (xy 347.612673 -218.115933)
			(xy 347.58931 -218.163118) (xy 347.559018 -218.206184) (xy 347.522506 -218.244122) (xy 347.480632 -218.276041)
			(xy 347.434376 -218.301194) (xy 347.384823 -218.318992) (xy 347.333133 -218.329016) (xy 347.280519 -218.331033)
			(xy 347.228214 -218.324995) (xy 347.177443 -218.311043) (xy 347.129398 -218.289504) (xy 347.085203 -218.260884)
			(xy 347.045895 -218.225853) (xy 347.012395 -218.185232) (xy 346.985489 -218.139973) (xy 346.965806 -218.091138)
			(xy 346.953809 -218.03987) (xy 346.949779 -217.987372) (xy 346.837 -217.987372) (xy 346.836496 -218.013698)
			(xy 346.828459 -218.065734) (xy 346.812573 -218.115933) (xy 346.78921 -218.163118) (xy 346.758918 -218.206184)
			(xy 346.722406 -218.244122) (xy 346.680532 -218.276041) (xy 346.634276 -218.301194) (xy 346.584723 -218.318992)
			(xy 346.533033 -218.329016) (xy 346.480419 -218.331033) (xy 346.428114 -218.324995) (xy 346.377343 -218.311043)
			(xy 346.329298 -218.289504) (xy 346.285103 -218.260884) (xy 346.245795 -218.225853) (xy 346.212295 -218.185232)
			(xy 346.185389 -218.139973) (xy 346.165706 -218.091138) (xy 346.153709 -218.03987) (xy 346.149679 -217.987372)
			(xy 345.260397 -217.987372) (xy 345.255474 -217.994151) (xy 345.25331 -217.998548) (xy 345.249246 -218.00693)
			(xy 345.248484 -218.016074) (xy 345.246015 -218.041298) (xy 345.234851 -218.090733) (xy 345.216797 -218.138089)
			(xy 345.192217 -218.182409) (xy 345.161607 -218.222801) (xy 345.125584 -218.25845) (xy 345.105482 -218.273884)
			(xy 345.100656 -218.277186) (xy 345.09329 -218.285822) (xy 345.080336 -218.310714) (xy 345.077642 -218.316245)
			(xy 345.074693 -218.328186) (xy 345.074494 -218.334336) (xy 345.074494 -218.440254) (xy 345.074678 -218.446201)
			(xy 345.077491 -218.457759) (xy 345.080082 -218.463114) (xy 345.080082 -218.463622) (xy 345.088718 -218.479624)
			(xy 345.095576 -218.489784) (xy 345.099386 -218.494102) (xy 345.103958 -218.497404) (xy 345.113102 -218.504262)
			(xy 345.125548 -218.514168) (xy 345.131644 -218.519502) (xy 345.132152 -218.52001) (xy 345.140026 -218.527122)
			(xy 345.14028 -218.527376) (xy 345.140788 -218.527884) (xy 345.149424 -218.53652) (xy 345.169744 -218.559126)
			(xy 345.169998 -218.559634) (xy 345.175332 -218.565984) (xy 345.178807 -218.57003) (xy 345.187127 -218.5767)
			(xy 345.191842 -218.579192) (xy 345.21394 -218.590114) (xy 345.218258 -218.592146) (xy 345.227402 -218.595702)
			(xy 345.2622 -218.595956) (xy 345.382342 -218.595956) (xy 345.390216 -218.608148) (xy 345.393518 -218.613228)
			(xy 345.396058 -218.617292) (xy 345.39682 -218.618308) (xy 345.397328 -218.619324) (xy 345.433142 -218.675458)
			(xy 345.433142 -218.675712) (xy 345.434412 -218.67749) (xy 345.435174 -218.67876) (xy 345.441016 -218.687904)
			(xy 345.441016 -218.787218) (xy 346.149679 -218.787218) (xy 346.153709 -218.73472) (xy 346.165706 -218.683452)
			(xy 346.185389 -218.634617) (xy 346.212295 -218.589358) (xy 346.245795 -218.548737) (xy 346.285103 -218.513706)
			(xy 346.329298 -218.485086) (xy 346.377343 -218.463547) (xy 346.428114 -218.449595) (xy 346.480419 -218.443557)
			(xy 346.533033 -218.445574) (xy 346.584723 -218.455598) (xy 346.634276 -218.473396) (xy 346.680532 -218.498549)
			(xy 346.722406 -218.530468) (xy 346.758918 -218.568406) (xy 346.78921 -218.611472) (xy 346.812573 -218.658657)
			(xy 346.828459 -218.708856) (xy 346.836496 -218.760892) (xy 346.837 -218.787218) (xy 346.949779 -218.787218)
			(xy 346.953809 -218.73472) (xy 346.965806 -218.683452) (xy 346.985489 -218.634617) (xy 347.012395 -218.589358)
			(xy 347.045895 -218.548737) (xy 347.085203 -218.513706) (xy 347.129398 -218.485086) (xy 347.177443 -218.463547)
			(xy 347.228214 -218.449595) (xy 347.280519 -218.443557) (xy 347.333133 -218.445574) (xy 347.384823 -218.455598)
			(xy 347.434376 -218.473396) (xy 347.480632 -218.498549) (xy 347.522506 -218.530468) (xy 347.559018 -218.568406)
			(xy 347.58931 -218.611472) (xy 347.612673 -218.658657) (xy 347.628559 -218.708856) (xy 347.636596 -218.760892)
			(xy 347.6371 -218.787218) (xy 348.549725 -218.787218) (xy 348.553755 -218.73472) (xy 348.565752 -218.683452)
			(xy 348.585435 -218.634617) (xy 348.612341 -218.589358) (xy 348.645841 -218.548737) (xy 348.685149 -218.513706)
			(xy 348.729344 -218.485086) (xy 348.777389 -218.463547) (xy 348.82816 -218.449595) (xy 348.880465 -218.443557)
			(xy 348.933079 -218.445574) (xy 348.984769 -218.455598) (xy 349.034322 -218.473396) (xy 349.080578 -218.498549)
			(xy 349.122452 -218.530468) (xy 349.158964 -218.568406) (xy 349.189256 -218.611472) (xy 349.212619 -218.658657)
			(xy 349.228505 -218.708856) (xy 349.236542 -218.760892) (xy 349.237046 -218.787218) (xy 349.349825 -218.787218)
			(xy 349.353855 -218.73472) (xy 349.365852 -218.683452) (xy 349.385535 -218.634617) (xy 349.412441 -218.589358)
			(xy 349.445941 -218.548737) (xy 349.485249 -218.513706) (xy 349.529444 -218.485086) (xy 349.577489 -218.463547)
			(xy 349.62826 -218.449595) (xy 349.680565 -218.443557) (xy 349.733179 -218.445574) (xy 349.784869 -218.455598)
			(xy 349.834422 -218.473396) (xy 349.880678 -218.498549) (xy 349.922552 -218.530468) (xy 349.959064 -218.568406)
			(xy 349.989356 -218.611472) (xy 350.012719 -218.658657) (xy 350.028605 -218.708856) (xy 350.036642 -218.760892)
			(xy 350.037146 -218.787218) (xy 350.149671 -218.787218) (xy 350.153701 -218.73472) (xy 350.165698 -218.683452)
			(xy 350.185381 -218.634617) (xy 350.212287 -218.589358) (xy 350.245787 -218.548737) (xy 350.285095 -218.513706)
			(xy 350.32929 -218.485086) (xy 350.377335 -218.463547) (xy 350.428106 -218.449595) (xy 350.480411 -218.443557)
			(xy 350.533025 -218.445574) (xy 350.584715 -218.455598) (xy 350.634268 -218.473396) (xy 350.680524 -218.498549)
			(xy 350.722398 -218.530468) (xy 350.75891 -218.568406) (xy 350.789202 -218.611472) (xy 350.812565 -218.658657)
			(xy 350.828451 -218.708856) (xy 350.836488 -218.760892) (xy 350.836992 -218.787218) (xy 350.949771 -218.787218)
			(xy 350.953801 -218.73472) (xy 350.965798 -218.683452) (xy 350.985481 -218.634617) (xy 351.012387 -218.589358)
			(xy 351.045887 -218.548737) (xy 351.085195 -218.513706) (xy 351.12939 -218.485086) (xy 351.177435 -218.463547)
			(xy 351.228206 -218.449595) (xy 351.280511 -218.443557) (xy 351.333125 -218.445574) (xy 351.384815 -218.455598)
			(xy 351.434368 -218.473396) (xy 351.480624 -218.498549) (xy 351.522498 -218.530468) (xy 351.55901 -218.568406)
			(xy 351.589302 -218.611472) (xy 351.612665 -218.658657) (xy 351.628551 -218.708856) (xy 351.636588 -218.760892)
			(xy 351.637092 -218.787218) (xy 351.636588 -218.813544) (xy 351.628551 -218.86558) (xy 351.612665 -218.915779)
			(xy 351.589302 -218.962964) (xy 351.55901 -219.00603) (xy 351.522498 -219.043968) (xy 351.480624 -219.075887)
			(xy 351.434368 -219.10104) (xy 351.384815 -219.118838) (xy 351.333125 -219.128862) (xy 351.280511 -219.130879)
			(xy 351.228206 -219.124841) (xy 351.177435 -219.110889) (xy 351.12939 -219.08935) (xy 351.085195 -219.06073)
			(xy 351.045887 -219.025699) (xy 351.012387 -218.985078) (xy 350.985481 -218.939819) (xy 350.965798 -218.890984)
			(xy 350.953801 -218.839716) (xy 350.949771 -218.787218) (xy 350.836992 -218.787218) (xy 350.836488 -218.813544)
			(xy 350.828451 -218.86558) (xy 350.812565 -218.915779) (xy 350.789202 -218.962964) (xy 350.75891 -219.00603)
			(xy 350.722398 -219.043968) (xy 350.680524 -219.075887) (xy 350.634268 -219.10104) (xy 350.584715 -219.118838)
			(xy 350.533025 -219.128862) (xy 350.480411 -219.130879) (xy 350.428106 -219.124841) (xy 350.377335 -219.110889)
			(xy 350.32929 -219.08935) (xy 350.285095 -219.06073) (xy 350.245787 -219.025699) (xy 350.212287 -218.985078)
			(xy 350.185381 -218.939819) (xy 350.165698 -218.890984) (xy 350.153701 -218.839716) (xy 350.149671 -218.787218)
			(xy 350.037146 -218.787218) (xy 350.036642 -218.813544) (xy 350.028605 -218.86558) (xy 350.012719 -218.915779)
			(xy 349.989356 -218.962964) (xy 349.959064 -219.00603) (xy 349.922552 -219.043968) (xy 349.880678 -219.075887)
			(xy 349.834422 -219.10104) (xy 349.784869 -219.118838) (xy 349.733179 -219.128862) (xy 349.680565 -219.130879)
			(xy 349.62826 -219.124841) (xy 349.577489 -219.110889) (xy 349.529444 -219.08935) (xy 349.485249 -219.06073)
			(xy 349.445941 -219.025699) (xy 349.412441 -218.985078) (xy 349.385535 -218.939819) (xy 349.365852 -218.890984)
			(xy 349.353855 -218.839716) (xy 349.349825 -218.787218) (xy 349.237046 -218.787218) (xy 349.236542 -218.813544)
			(xy 349.228505 -218.86558) (xy 349.212619 -218.915779) (xy 349.189256 -218.962964) (xy 349.158964 -219.00603)
			(xy 349.122452 -219.043968) (xy 349.080578 -219.075887) (xy 349.034322 -219.10104) (xy 348.984769 -219.118838)
			(xy 348.933079 -219.128862) (xy 348.880465 -219.130879) (xy 348.82816 -219.124841) (xy 348.777389 -219.110889)
			(xy 348.729344 -219.08935) (xy 348.685149 -219.06073) (xy 348.645841 -219.025699) (xy 348.612341 -218.985078)
			(xy 348.585435 -218.939819) (xy 348.565752 -218.890984) (xy 348.553755 -218.839716) (xy 348.549725 -218.787218)
			(xy 347.6371 -218.787218) (xy 347.636596 -218.813544) (xy 347.628559 -218.86558) (xy 347.612673 -218.915779)
			(xy 347.58931 -218.962964) (xy 347.559018 -219.00603) (xy 347.522506 -219.043968) (xy 347.480632 -219.075887)
			(xy 347.434376 -219.10104) (xy 347.384823 -219.118838) (xy 347.333133 -219.128862) (xy 347.280519 -219.130879)
			(xy 347.228214 -219.124841) (xy 347.177443 -219.110889) (xy 347.129398 -219.08935) (xy 347.085203 -219.06073)
			(xy 347.045895 -219.025699) (xy 347.012395 -218.985078) (xy 346.985489 -218.939819) (xy 346.965806 -218.890984)
			(xy 346.953809 -218.839716) (xy 346.949779 -218.787218) (xy 346.837 -218.787218) (xy 346.836496 -218.813544)
			(xy 346.828459 -218.86558) (xy 346.812573 -218.915779) (xy 346.78921 -218.962964) (xy 346.758918 -219.00603)
			(xy 346.722406 -219.043968) (xy 346.680532 -219.075887) (xy 346.634276 -219.10104) (xy 346.584723 -219.118838)
			(xy 346.533033 -219.128862) (xy 346.480419 -219.130879) (xy 346.428114 -219.124841) (xy 346.377343 -219.110889)
			(xy 346.329298 -219.08935) (xy 346.285103 -219.06073) (xy 346.245795 -219.025699) (xy 346.212295 -218.985078)
			(xy 346.185389 -218.939819) (xy 346.165706 -218.890984) (xy 346.153709 -218.839716) (xy 346.149679 -218.787218)
			(xy 345.441016 -218.787218) (xy 345.441016 -218.834208) (xy 345.44119 -218.84036) (xy 345.444151 -218.852302)
			(xy 345.446858 -218.85783) (xy 345.45143 -218.86672) (xy 345.541854 -218.957144) (xy 345.563444 -218.981274)
			(xy 345.564206 -218.98229) (xy 345.568016 -218.986608) (xy 345.614498 -219.03309) (xy 345.621346 -219.040488)
			(xy 345.629085 -219.059086) (xy 345.629484 -219.069158) (xy 345.629484 -219.13977) (xy 345.629738 -219.142564)
			(xy 345.631516 -219.174822) (xy 345.631516 -219.256864) (xy 345.629484 -219.263468) (xy 345.629484 -219.305632)
			(xy 345.629055 -219.315699) (xy 345.62133 -219.334294) (xy 345.614498 -219.3417) (xy 345.591384 -219.364814)
			(xy 345.583002 -219.378276) (xy 345.579399 -219.384419) (xy 345.575413 -219.398084) (xy 345.575128 -219.4052)
			(xy 345.575128 -219.76969) (xy 345.575372 -219.776872) (xy 345.579365 -219.790671) (xy 345.583002 -219.796868)
			(xy 345.586304 -219.801948) (xy 345.58986 -219.80779) (xy 345.609418 -219.82811) (xy 345.61399 -219.832682)
			(xy 345.620825 -219.840085) (xy 345.628531 -219.858683) (xy 345.628976 -219.86875) (xy 345.628976 -219.927678)
			(xy 345.629484 -219.931234) (xy 345.629738 -219.933266) (xy 345.629738 -219.93479) (xy 345.629992 -219.936822)
			(xy 345.6305 -219.944188) (xy 345.6305 -219.944696) (xy 345.631008 -219.961714) (xy 345.631008 -219.999052)
			(xy 345.62923 -220.03131) (xy 345.628976 -220.034104) (xy 345.628976 -220.10497) (xy 345.62854 -220.115034)
			(xy 345.620805 -220.133618) (xy 345.61399 -220.141038) (xy 345.565476 -220.189552) (xy 345.563698 -220.191584)
			(xy 345.541346 -220.21673) (xy 345.469972 -220.288104) (xy 345.463119 -220.295499) (xy 345.455374 -220.314098)
			(xy 345.454986 -220.324172) (xy 345.454986 -220.38691) (xy 346.149679 -220.38691) (xy 346.153709 -220.334412)
			(xy 346.165706 -220.283144) (xy 346.185389 -220.234309) (xy 346.212295 -220.18905) (xy 346.245795 -220.148429)
			(xy 346.285103 -220.113398) (xy 346.329298 -220.084778) (xy 346.377343 -220.063239) (xy 346.428114 -220.049287)
			(xy 346.480419 -220.043249) (xy 346.533033 -220.045266) (xy 346.584723 -220.05529) (xy 346.634276 -220.073088)
			(xy 346.680532 -220.098241) (xy 346.722406 -220.13016) (xy 346.758918 -220.168098) (xy 346.78921 -220.211164)
			(xy 346.812573 -220.258349) (xy 346.828459 -220.308548) (xy 346.836496 -220.360584) (xy 346.837 -220.38691)
			(xy 346.949779 -220.38691) (xy 346.953809 -220.334412) (xy 346.965806 -220.283144) (xy 346.985489 -220.234309)
			(xy 347.012395 -220.18905) (xy 347.045895 -220.148429) (xy 347.085203 -220.113398) (xy 347.129398 -220.084778)
			(xy 347.177443 -220.063239) (xy 347.228214 -220.049287) (xy 347.280519 -220.043249) (xy 347.333133 -220.045266)
			(xy 347.384823 -220.05529) (xy 347.434376 -220.073088) (xy 347.480632 -220.098241) (xy 347.522506 -220.13016)
			(xy 347.559018 -220.168098) (xy 347.58931 -220.211164) (xy 347.612673 -220.258349) (xy 347.628559 -220.308548)
			(xy 347.636596 -220.360584) (xy 347.6371 -220.38691) (xy 347.636596 -220.413236) (xy 347.628559 -220.465272)
			(xy 347.612673 -220.515471) (xy 347.58931 -220.562656) (xy 347.559018 -220.605722) (xy 347.522506 -220.64366)
			(xy 347.480632 -220.675579) (xy 347.434376 -220.700732) (xy 347.384823 -220.71853) (xy 347.333133 -220.728554)
			(xy 347.280519 -220.730571) (xy 347.228214 -220.724533) (xy 347.177443 -220.710581) (xy 347.129398 -220.689042)
			(xy 347.085203 -220.660422) (xy 347.045895 -220.625391) (xy 347.012395 -220.58477) (xy 346.985489 -220.539511)
			(xy 346.965806 -220.490676) (xy 346.953809 -220.439408) (xy 346.949779 -220.38691) (xy 346.837 -220.38691)
			(xy 346.836496 -220.413236) (xy 346.828459 -220.465272) (xy 346.812573 -220.515471) (xy 346.78921 -220.562656)
			(xy 346.758918 -220.605722) (xy 346.722406 -220.64366) (xy 346.680532 -220.675579) (xy 346.634276 -220.700732)
			(xy 346.584723 -220.71853) (xy 346.533033 -220.728554) (xy 346.480419 -220.730571) (xy 346.428114 -220.724533)
			(xy 346.377343 -220.710581) (xy 346.329298 -220.689042) (xy 346.285103 -220.660422) (xy 346.245795 -220.625391)
			(xy 346.212295 -220.58477) (xy 346.185389 -220.539511) (xy 346.165706 -220.490676) (xy 346.153709 -220.439408)
			(xy 346.149679 -220.38691) (xy 345.454986 -220.38691) (xy 345.454986 -220.51137) (xy 345.45455 -220.521434)
			(xy 345.446816 -220.540019) (xy 345.44 -220.547438) (xy 345.413838 -220.5736) (xy 345.406436 -220.580437)
			(xy 345.387838 -220.588149) (xy 345.37777 -220.588586) (xy 345.216734 -220.588586) (xy 345.210867 -220.588739)
			(xy 345.199448 -220.591439) (xy 345.194128 -220.59392) (xy 345.186508 -220.59773) (xy 345.178126 -220.604588)
			(xy 345.174316 -220.60916) (xy 345.159584 -220.626686) (xy 345.159584 -220.627194) (xy 345.151964 -220.635322)
			(xy 345.15171 -220.635576) (xy 345.151202 -220.636084) (xy 345.123516 -220.661992) (xy 345.119198 -220.665548)
			(xy 345.112848 -220.673676) (xy 345.103196 -220.693488) (xy 345.100855 -220.698711) (xy 345.098295 -220.709865)
			(xy 345.098116 -220.715586) (xy 345.098116 -220.85808) (xy 345.098283 -220.863741) (xy 345.100843 -220.874772)
			(xy 345.103196 -220.879924) (xy 345.116912 -220.909134) (xy 345.12504 -220.915992) (xy 345.145864 -220.93452)
			(xy 345.182052 -220.976911) (xy 345.211195 -221.024422) (xy 345.232581 -221.075893) (xy 345.245687 -221.130067)
			(xy 345.248484 -221.1578) (xy 345.249246 -221.167452) (xy 345.257628 -221.18447) (xy 345.260099 -221.186756)
			(xy 346.149679 -221.186756) (xy 346.153709 -221.134258) (xy 346.165706 -221.08299) (xy 346.185389 -221.034155)
			(xy 346.212295 -220.988896) (xy 346.245795 -220.948275) (xy 346.285103 -220.913244) (xy 346.329298 -220.884624)
			(xy 346.377343 -220.863085) (xy 346.428114 -220.849133) (xy 346.480419 -220.843095) (xy 346.533033 -220.845112)
			(xy 346.584723 -220.855136) (xy 346.634276 -220.872934) (xy 346.680532 -220.898087) (xy 346.722406 -220.930006)
			(xy 346.758918 -220.967944) (xy 346.78921 -221.01101) (xy 346.812573 -221.058195) (xy 346.828459 -221.108394)
			(xy 346.836496 -221.16043) (xy 346.837 -221.186756) (xy 346.949779 -221.186756) (xy 346.953809 -221.134258)
			(xy 346.965806 -221.08299) (xy 346.985489 -221.034155) (xy 347.012395 -220.988896) (xy 347.045895 -220.948275)
			(xy 347.085203 -220.913244) (xy 347.129398 -220.884624) (xy 347.177443 -220.863085) (xy 347.228214 -220.849133)
			(xy 347.280519 -220.843095) (xy 347.333133 -220.845112) (xy 347.384823 -220.855136) (xy 347.434376 -220.872934)
			(xy 347.480632 -220.898087) (xy 347.522506 -220.930006) (xy 347.559018 -220.967944) (xy 347.58931 -221.01101)
			(xy 347.612673 -221.058195) (xy 347.628559 -221.108394) (xy 347.636596 -221.16043) (xy 347.6371 -221.186756)
			(xy 347.75013 -221.186756) (xy 347.750633 -221.160198) (xy 347.758832 -221.107719) (xy 347.775011 -221.057128)
			(xy 347.798786 -221.009631) (xy 347.82959 -220.966359) (xy 347.866688 -220.928346) (xy 347.909195 -220.896496)
			(xy 347.956099 -220.87157) (xy 348.006281 -220.854162) (xy 348.032324 -220.848936) (xy 348.039944 -220.847412)
			(xy 348.05366 -220.8403) (xy 348.059248 -220.834712) (xy 348.066091 -220.827358) (xy 348.073791 -220.808818)
			(xy 348.073783 -220.788742) (xy 348.066068 -220.770208) (xy 348.059248 -220.76283) (xy 348.023434 -220.72727)
			(xy 348.012004 -220.720666) (xy 348.0054 -220.718888) (xy 347.981316 -220.712056) (xy 347.935316 -220.692302)
			(xy 347.892669 -220.666082) (xy 347.854279 -220.633951) (xy 347.820959 -220.596587) (xy 347.793415 -220.554784)
			(xy 347.772229 -220.509426) (xy 347.75785 -220.461473) (xy 347.750583 -220.411941) (xy 347.75013 -220.38691)
			(xy 347.750603 -220.359921) (xy 347.759046 -220.306608) (xy 347.775726 -220.255272) (xy 347.800232 -220.207177)
			(xy 347.831961 -220.163509) (xy 347.870131 -220.125343) (xy 347.913801 -220.093618) (xy 347.961898 -220.069116)
			(xy 348.013235 -220.05244) (xy 348.066549 -220.044001) (xy 348.093538 -220.043502) (xy 348.119615 -220.043959)
			(xy 348.171168 -220.051851) (xy 348.220935 -220.067446) (xy 348.267772 -220.090388) (xy 348.310602 -220.120147)
			(xy 348.34844 -220.15604) (xy 348.36481 -220.176344) (xy 348.372384 -220.185218) (xy 348.393291 -220.195524)
			(xy 348.404942 -220.196156) (xy 348.582234 -220.196156) (xy 348.593902 -220.195601) (xy 348.61482 -220.185262)
			(xy 348.622366 -220.176344) (xy 348.638716 -220.156024) (xy 348.676559 -220.120136) (xy 348.719394 -220.090384)
			(xy 348.766235 -220.067451) (xy 348.816006 -220.051865) (xy 348.867561 -220.043984) (xy 348.893638 -220.043502)
			(xy 348.919336 -220.043965) (xy 348.970157 -220.05163) (xy 349.019268 -220.066784) (xy 349.065572 -220.089087)
			(xy 349.108035 -220.118042) (xy 349.145708 -220.153002) (xy 349.177751 -220.193186) (xy 349.203447 -220.237697)
			(xy 349.222223 -220.285541) (xy 349.233659 -220.335648) (xy 349.2375 -220.3869) (xy 349.237499 -220.38691)
			(xy 349.349825 -220.38691) (xy 349.353855 -220.334412) (xy 349.365852 -220.283144) (xy 349.385535 -220.234309)
			(xy 349.412441 -220.18905) (xy 349.445941 -220.148429) (xy 349.485249 -220.113398) (xy 349.529444 -220.084778)
			(xy 349.577489 -220.063239) (xy 349.62826 -220.049287) (xy 349.680565 -220.043249) (xy 349.733179 -220.045266)
			(xy 349.784869 -220.05529) (xy 349.834422 -220.073088) (xy 349.880678 -220.098241) (xy 349.922552 -220.13016)
			(xy 349.959064 -220.168098) (xy 349.989356 -220.211164) (xy 350.012719 -220.258349) (xy 350.028605 -220.308548)
			(xy 350.036642 -220.360584) (xy 350.037146 -220.38691) (xy 350.149671 -220.38691) (xy 350.153701 -220.334412)
			(xy 350.165698 -220.283144) (xy 350.185381 -220.234309) (xy 350.212287 -220.18905) (xy 350.245787 -220.148429)
			(xy 350.285095 -220.113398) (xy 350.32929 -220.084778) (xy 350.377335 -220.063239) (xy 350.428106 -220.049287)
			(xy 350.480411 -220.043249) (xy 350.533025 -220.045266) (xy 350.584715 -220.05529) (xy 350.634268 -220.073088)
			(xy 350.680524 -220.098241) (xy 350.722398 -220.13016) (xy 350.75891 -220.168098) (xy 350.789202 -220.211164)
			(xy 350.812565 -220.258349) (xy 350.828451 -220.308548) (xy 350.836488 -220.360584) (xy 350.836992 -220.38691)
			(xy 350.836488 -220.413236) (xy 350.828451 -220.465272) (xy 350.812565 -220.515471) (xy 350.789202 -220.562656)
			(xy 350.75891 -220.605722) (xy 350.722398 -220.64366) (xy 350.680524 -220.675579) (xy 350.634268 -220.700732)
			(xy 350.584715 -220.71853) (xy 350.533025 -220.728554) (xy 350.480411 -220.730571) (xy 350.428106 -220.724533)
			(xy 350.377335 -220.710581) (xy 350.32929 -220.689042) (xy 350.285095 -220.660422) (xy 350.245787 -220.625391)
			(xy 350.212287 -220.58477) (xy 350.185381 -220.539511) (xy 350.165698 -220.490676) (xy 350.153701 -220.439408)
			(xy 350.149671 -220.38691) (xy 350.037146 -220.38691) (xy 350.036642 -220.413236) (xy 350.028605 -220.465272)
			(xy 350.012719 -220.515471) (xy 349.989356 -220.562656) (xy 349.959064 -220.605722) (xy 349.922552 -220.64366)
			(xy 349.880678 -220.675579) (xy 349.834422 -220.700732) (xy 349.784869 -220.71853) (xy 349.733179 -220.728554)
			(xy 349.680565 -220.730571) (xy 349.62826 -220.724533) (xy 349.577489 -220.710581) (xy 349.529444 -220.689042)
			(xy 349.485249 -220.660422) (xy 349.445941 -220.625391) (xy 349.412441 -220.58477) (xy 349.385535 -220.539511)
			(xy 349.365852 -220.490676) (xy 349.353855 -220.439408) (xy 349.349825 -220.38691) (xy 349.237499 -220.38691)
			(xy 349.233659 -220.438152) (xy 349.222223 -220.488259) (xy 349.203447 -220.536103) (xy 349.177751 -220.580614)
			(xy 349.145708 -220.620798) (xy 349.108035 -220.655758) (xy 349.065572 -220.684713) (xy 349.019268 -220.707016)
			(xy 348.970157 -220.72217) (xy 348.919336 -220.729835) (xy 348.893638 -220.730318) (xy 348.89059 -220.730318)
			(xy 348.88091 -220.73068) (xy 348.862884 -220.737722) (xy 348.855538 -220.744034) (xy 348.816676 -220.780356)
			(xy 348.816676 -220.79331) (xy 348.855538 -220.829632) (xy 348.8629 -220.83592) (xy 348.880916 -220.842971)
			(xy 348.89059 -220.843348) (xy 348.893638 -220.843348) (xy 348.91975 -220.843921) (xy 348.97137 -220.851834)
			(xy 349.021196 -220.867474) (xy 349.06808 -220.890478) (xy 349.110939 -220.920316) (xy 349.148786 -220.9563)
			(xy 349.180748 -220.997601) (xy 349.206086 -221.043265) (xy 349.224218 -221.092239) (xy 349.234725 -221.143395)
			(xy 349.236919 -221.186756) (xy 349.349825 -221.186756) (xy 349.353855 -221.134258) (xy 349.365852 -221.08299)
			(xy 349.385535 -221.034155) (xy 349.412441 -220.988896) (xy 349.445941 -220.948275) (xy 349.485249 -220.913244)
			(xy 349.529444 -220.884624) (xy 349.577489 -220.863085) (xy 349.62826 -220.849133) (xy 349.680565 -220.843095)
			(xy 349.733179 -220.845112) (xy 349.784869 -220.855136) (xy 349.834422 -220.872934) (xy 349.880678 -220.898087)
			(xy 349.922552 -220.930006) (xy 349.959064 -220.967944) (xy 349.989356 -221.01101) (xy 350.012719 -221.058195)
			(xy 350.028605 -221.108394) (xy 350.036642 -221.16043) (xy 350.037146 -221.186756) (xy 350.149671 -221.186756)
			(xy 350.153701 -221.134258) (xy 350.165698 -221.08299) (xy 350.185381 -221.034155) (xy 350.212287 -220.988896)
			(xy 350.245787 -220.948275) (xy 350.285095 -220.913244) (xy 350.32929 -220.884624) (xy 350.377335 -220.863085)
			(xy 350.428106 -220.849133) (xy 350.480411 -220.843095) (xy 350.533025 -220.845112) (xy 350.584715 -220.855136)
			(xy 350.634268 -220.872934) (xy 350.680524 -220.898087) (xy 350.722398 -220.930006) (xy 350.75891 -220.967944)
			(xy 350.789202 -221.01101) (xy 350.812565 -221.058195) (xy 350.828451 -221.108394) (xy 350.836488 -221.16043)
			(xy 350.836992 -221.186756) (xy 350.836488 -221.213082) (xy 350.828451 -221.265118) (xy 350.812565 -221.315317)
			(xy 350.789202 -221.362502) (xy 350.75891 -221.405568) (xy 350.722398 -221.443506) (xy 350.680524 -221.475425)
			(xy 350.634268 -221.500578) (xy 350.584715 -221.518376) (xy 350.533025 -221.5284) (xy 350.480411 -221.530417)
			(xy 350.428106 -221.524379) (xy 350.377335 -221.510427) (xy 350.32929 -221.488888) (xy 350.285095 -221.460268)
			(xy 350.245787 -221.425237) (xy 350.212287 -221.384616) (xy 350.185381 -221.339357) (xy 350.165698 -221.290522)
			(xy 350.153701 -221.239254) (xy 350.149671 -221.186756) (xy 350.037146 -221.186756) (xy 350.036642 -221.213082)
			(xy 350.028605 -221.265118) (xy 350.012719 -221.315317) (xy 349.989356 -221.362502) (xy 349.959064 -221.405568)
			(xy 349.922552 -221.443506) (xy 349.880678 -221.475425) (xy 349.834422 -221.500578) (xy 349.784869 -221.518376)
			(xy 349.733179 -221.5284) (xy 349.680565 -221.530417) (xy 349.62826 -221.524379) (xy 349.577489 -221.510427)
			(xy 349.529444 -221.488888) (xy 349.485249 -221.460268) (xy 349.445941 -221.425237) (xy 349.412441 -221.384616)
			(xy 349.385535 -221.339357) (xy 349.365852 -221.290522) (xy 349.353855 -221.239254) (xy 349.349825 -221.186756)
			(xy 349.236919 -221.186756) (xy 349.237364 -221.195551) (xy 349.232074 -221.247506) (xy 349.218978 -221.298061)
			(xy 349.198378 -221.346049) (xy 349.170749 -221.390365) (xy 349.136727 -221.429985) (xy 349.097098 -221.463997)
			(xy 349.052776 -221.491616) (xy 349.004783 -221.512205) (xy 348.954225 -221.525289) (xy 348.902269 -221.530566)
			(xy 348.850113 -221.527914) (xy 348.798961 -221.517396) (xy 348.74999 -221.499252) (xy 348.704332 -221.473902)
			(xy 348.66304 -221.441931) (xy 348.627064 -221.404076) (xy 348.597236 -221.361209) (xy 348.574243 -221.31432)
			(xy 348.558616 -221.26449) (xy 348.550714 -221.212868) (xy 348.55023 -221.186756) (xy 348.550992 -221.164404)
			(xy 348.550992 -221.160848) (xy 348.550541 -221.150829) (xy 348.542885 -221.132311) (xy 348.528722 -221.118137)
			(xy 348.510211 -221.110467) (xy 348.500192 -221.110048) (xy 348.486984 -221.110048) (xy 348.476956 -221.110408)
			(xy 348.458429 -221.118092) (xy 348.444256 -221.132283) (xy 348.436595 -221.150819) (xy 348.436184 -221.160848)
			(xy 348.436184 -221.164404) (xy 348.436946 -221.186756) (xy 348.436466 -221.212455) (xy 348.428805 -221.263279)
			(xy 348.413656 -221.312393) (xy 348.391355 -221.358701) (xy 348.362402 -221.401168) (xy 348.327442 -221.438845)
			(xy 348.287258 -221.470891) (xy 348.242746 -221.49659) (xy 348.194901 -221.515367) (xy 348.144792 -221.526805)
			(xy 348.093538 -221.530646) (xy 348.042284 -221.526805) (xy 347.992175 -221.515367) (xy 347.94433 -221.49659)
			(xy 347.899818 -221.470891) (xy 347.859634 -221.438845) (xy 347.824674 -221.401168) (xy 347.795721 -221.358701)
			(xy 347.77342 -221.312393) (xy 347.758271 -221.263279) (xy 347.75061 -221.212455) (xy 347.75013 -221.186756)
			(xy 347.6371 -221.186756) (xy 347.636596 -221.213082) (xy 347.628559 -221.265118) (xy 347.612673 -221.315317)
			(xy 347.58931 -221.362502) (xy 347.559018 -221.405568) (xy 347.522506 -221.443506) (xy 347.480632 -221.475425)
			(xy 347.434376 -221.500578) (xy 347.384823 -221.518376) (xy 347.333133 -221.5284) (xy 347.280519 -221.530417)
			(xy 347.228214 -221.524379) (xy 347.177443 -221.510427) (xy 347.129398 -221.488888) (xy 347.085203 -221.460268)
			(xy 347.045895 -221.425237) (xy 347.012395 -221.384616) (xy 346.985489 -221.339357) (xy 346.965806 -221.290522)
			(xy 346.953809 -221.239254) (xy 346.949779 -221.186756) (xy 346.837 -221.186756) (xy 346.836496 -221.213082)
			(xy 346.828459 -221.265118) (xy 346.812573 -221.315317) (xy 346.78921 -221.362502) (xy 346.758918 -221.405568)
			(xy 346.722406 -221.443506) (xy 346.680532 -221.475425) (xy 346.634276 -221.500578) (xy 346.584723 -221.518376)
			(xy 346.533033 -221.5284) (xy 346.480419 -221.530417) (xy 346.428114 -221.524379) (xy 346.377343 -221.510427)
			(xy 346.329298 -221.488888) (xy 346.285103 -221.460268) (xy 346.245795 -221.425237) (xy 346.212295 -221.384616)
			(xy 346.185389 -221.339357) (xy 346.165706 -221.290522) (xy 346.153709 -221.239254) (xy 346.149679 -221.186756)
			(xy 345.260099 -221.186756) (xy 345.315286 -221.23781) (xy 345.319941 -221.241831) (xy 345.330727 -221.247738)
			(xy 345.336622 -221.249494) (xy 345.343226 -221.251272) (xy 345.411552 -221.251272) (xy 345.421619 -221.251704)
			(xy 345.440212 -221.259428) (xy 345.44762 -221.266258) (xy 345.61399 -221.432628) (xy 345.620833 -221.440028)
			(xy 345.628559 -221.458626) (xy 345.628976 -221.468696) (xy 345.628976 -221.704916) (xy 345.628549 -221.714984)
			(xy 345.620828 -221.733582) (xy 345.61399 -221.740984) (xy 345.453462 -221.901512) (xy 345.447244 -221.908826)
			(xy 345.440325 -221.926716) (xy 345.44 -221.93631) (xy 345.44 -222.071184) (xy 345.444064 -222.075248)
			(xy 345.444064 -222.113348) (xy 345.443631 -222.123414) (xy 345.435901 -222.142002) (xy 345.429078 -222.149416)
			(xy 345.409774 -222.16872) (xy 345.402378 -222.175571) (xy 345.383779 -222.183309) (xy 345.373706 -222.183706)
			(xy 345.219782 -222.183706) (xy 345.212974 -222.183927) (xy 345.199845 -222.187539) (xy 345.193874 -222.190818)
			(xy 345.180666 -222.198438) (xy 345.174824 -222.206058) (xy 345.155705 -222.229554) (xy 345.110883 -222.270294)
			(xy 345.08567 -222.287084) (xy 345.078619 -222.291929) (xy 345.067984 -222.305317) (xy 345.062354 -222.321461)
			(xy 345.062048 -222.33001) (xy 345.062048 -222.365824) (xy 345.062477 -222.375891) (xy 345.070203 -222.394485)
			(xy 345.077034 -222.401892) (xy 345.100148 -222.425006) (xy 345.100402 -222.425006) (xy 345.29141 -222.616014)
			(xy 345.298805 -222.622868) (xy 345.317404 -222.630613) (xy 345.327478 -222.631) (xy 345.330018 -222.631)
			(xy 345.336664 -222.630817) (xy 345.349527 -222.627476) (xy 345.355418 -222.624396) (xy 345.375484 -222.612712)
			(xy 345.380696 -222.609483) (xy 345.389553 -222.601011) (xy 345.39301 -222.595948) (xy 345.393264 -222.595694)
			(xy 345.408385 -222.572899) (xy 345.444491 -222.53181) (xy 345.486453 -222.496721) (xy 345.533285 -222.468458)
			(xy 345.583887 -222.447685) (xy 345.637068 -222.43489) (xy 345.664282 -222.432118) (xy 345.673934 -222.431356)
			(xy 345.690952 -222.422974) (xy 345.712542 -222.399606) (xy 345.71305 -222.399098) (xy 345.728544 -222.38208)
			(xy 345.734603 -222.37491) (xy 345.741397 -222.357424) (xy 345.741752 -222.348044) (xy 345.741752 -222.262446)
			(xy 345.742186 -222.252381) (xy 345.74992 -222.233796) (xy 345.756738 -222.226378) (xy 345.917012 -222.066104)
			(xy 345.923868 -222.05871) (xy 345.931618 -222.040111) (xy 345.931998 -222.030036) (xy 345.931998 -221.861634)
			(xy 345.932433 -221.851569) (xy 345.940164 -221.832982) (xy 345.946984 -221.825566) (xy 345.970098 -221.802452)
			(xy 345.977494 -221.7956) (xy 345.996092 -221.787856) (xy 346.006166 -221.787466) (xy 346.189046 -221.787466)
			(xy 346.228162 -221.768924) (xy 346.244557 -221.749658) (xy 346.282043 -221.715688) (xy 346.324109 -221.687588)
			(xy 346.369843 -221.665966) (xy 346.418256 -221.65129) (xy 346.468298 -221.643879) (xy 346.493592 -221.643448)
			(xy 346.520579 -221.643977) (xy 346.573888 -221.652418) (xy 346.625221 -221.669095) (xy 346.673313 -221.693595)
			(xy 346.716981 -221.725318) (xy 346.755149 -221.76348) (xy 346.786877 -221.807143) (xy 346.811385 -221.855231)
			(xy 346.82807 -221.906561) (xy 346.836519 -221.959869) (xy 346.837 -221.986856) (xy 346.949779 -221.986856)
			(xy 346.953809 -221.934358) (xy 346.965806 -221.88309) (xy 346.985489 -221.834255) (xy 347.012395 -221.788996)
			(xy 347.045895 -221.748375) (xy 347.085203 -221.713344) (xy 347.129398 -221.684724) (xy 347.177443 -221.663185)
			(xy 347.228214 -221.649233) (xy 347.280519 -221.643195) (xy 347.333133 -221.645212) (xy 347.384823 -221.655236)
			(xy 347.434376 -221.673034) (xy 347.480632 -221.698187) (xy 347.522506 -221.730106) (xy 347.559018 -221.768044)
			(xy 347.58931 -221.81111) (xy 347.612673 -221.858295) (xy 347.628559 -221.908494) (xy 347.636596 -221.96053)
			(xy 347.6371 -221.986856) (xy 347.749625 -221.986856) (xy 347.753655 -221.934358) (xy 347.765652 -221.88309)
			(xy 347.785335 -221.834255) (xy 347.812241 -221.788996) (xy 347.845741 -221.748375) (xy 347.885049 -221.713344)
			(xy 347.929244 -221.684724) (xy 347.977289 -221.663185) (xy 348.02806 -221.649233) (xy 348.080365 -221.643195)
			(xy 348.132979 -221.645212) (xy 348.184669 -221.655236) (xy 348.234222 -221.673034) (xy 348.280478 -221.698187)
			(xy 348.322352 -221.730106) (xy 348.358864 -221.768044) (xy 348.389156 -221.81111) (xy 348.412519 -221.858295)
			(xy 348.428405 -221.908494) (xy 348.436442 -221.96053) (xy 348.436946 -221.986856) (xy 348.436941 -221.98711)
			(xy 348.549979 -221.98711) (xy 348.554009 -221.934612) (xy 348.566006 -221.883344) (xy 348.585689 -221.834509)
			(xy 348.612595 -221.78925) (xy 348.646095 -221.748629) (xy 348.685403 -221.713598) (xy 348.729598 -221.684978)
			(xy 348.777643 -221.663439) (xy 348.828414 -221.649487) (xy 348.880719 -221.643449) (xy 348.933333 -221.645466)
			(xy 348.985023 -221.65549) (xy 349.034576 -221.673288) (xy 349.080832 -221.698441) (xy 349.122706 -221.73036)
			(xy 349.159218 -221.768298) (xy 349.18951 -221.811364) (xy 349.212873 -221.858549) (xy 349.228759 -221.908748)
			(xy 349.236796 -221.960784) (xy 349.237295 -221.986856) (xy 349.349825 -221.986856) (xy 349.353855 -221.934358)
			(xy 349.365852 -221.88309) (xy 349.385535 -221.834255) (xy 349.412441 -221.788996) (xy 349.445941 -221.748375)
			(xy 349.485249 -221.713344) (xy 349.529444 -221.684724) (xy 349.577489 -221.663185) (xy 349.62826 -221.649233)
			(xy 349.680565 -221.643195) (xy 349.733179 -221.645212) (xy 349.784869 -221.655236) (xy 349.834422 -221.673034)
			(xy 349.880678 -221.698187) (xy 349.922552 -221.730106) (xy 349.959064 -221.768044) (xy 349.989356 -221.81111)
			(xy 350.012719 -221.858295) (xy 350.028605 -221.908494) (xy 350.036642 -221.96053) (xy 350.037146 -221.986856)
			(xy 350.149671 -221.986856) (xy 350.153701 -221.934358) (xy 350.165698 -221.88309) (xy 350.185381 -221.834255)
			(xy 350.212287 -221.788996) (xy 350.245787 -221.748375) (xy 350.285095 -221.713344) (xy 350.32929 -221.684724)
			(xy 350.377335 -221.663185) (xy 350.428106 -221.649233) (xy 350.480411 -221.643195) (xy 350.533025 -221.645212)
			(xy 350.584715 -221.655236) (xy 350.634268 -221.673034) (xy 350.680524 -221.698187) (xy 350.722398 -221.730106)
			(xy 350.75891 -221.768044) (xy 350.789202 -221.81111) (xy 350.812565 -221.858295) (xy 350.828451 -221.908494)
			(xy 350.836488 -221.96053) (xy 350.836992 -221.986856) (xy 350.836488 -222.013182) (xy 350.828451 -222.065218)
			(xy 350.812565 -222.115417) (xy 350.789202 -222.162602) (xy 350.75891 -222.205668) (xy 350.722398 -222.243606)
			(xy 350.680524 -222.275525) (xy 350.634268 -222.300678) (xy 350.584715 -222.318476) (xy 350.533025 -222.3285)
			(xy 350.480411 -222.330517) (xy 350.428106 -222.324479) (xy 350.377335 -222.310527) (xy 350.32929 -222.288988)
			(xy 350.285095 -222.260368) (xy 350.245787 -222.225337) (xy 350.212287 -222.184716) (xy 350.185381 -222.139457)
			(xy 350.165698 -222.090622) (xy 350.153701 -222.039354) (xy 350.149671 -221.986856) (xy 350.037146 -221.986856)
			(xy 350.036642 -222.013182) (xy 350.028605 -222.065218) (xy 350.012719 -222.115417) (xy 349.989356 -222.162602)
			(xy 349.959064 -222.205668) (xy 349.922552 -222.243606) (xy 349.880678 -222.275525) (xy 349.834422 -222.300678)
			(xy 349.784869 -222.318476) (xy 349.733179 -222.3285) (xy 349.680565 -222.330517) (xy 349.62826 -222.324479)
			(xy 349.577489 -222.310527) (xy 349.529444 -222.288988) (xy 349.485249 -222.260368) (xy 349.445941 -222.225337)
			(xy 349.412441 -222.184716) (xy 349.385535 -222.139457) (xy 349.365852 -222.090622) (xy 349.353855 -222.039354)
			(xy 349.349825 -221.986856) (xy 349.237295 -221.986856) (xy 349.2373 -221.98711) (xy 349.236796 -222.013436)
			(xy 349.228759 -222.065472) (xy 349.212873 -222.115671) (xy 349.18951 -222.162856) (xy 349.159218 -222.205922)
			(xy 349.122706 -222.24386) (xy 349.080832 -222.275779) (xy 349.034576 -222.300932) (xy 348.985023 -222.31873)
			(xy 348.933333 -222.328754) (xy 348.880719 -222.330771) (xy 348.828414 -222.324733) (xy 348.777643 -222.310781)
			(xy 348.729598 -222.289242) (xy 348.685403 -222.260622) (xy 348.646095 -222.225591) (xy 348.612595 -222.18497)
			(xy 348.585689 -222.139711) (xy 348.566006 -222.090876) (xy 348.554009 -222.039608) (xy 348.549979 -221.98711)
			(xy 348.436941 -221.98711) (xy 348.436442 -222.013182) (xy 348.428405 -222.065218) (xy 348.412519 -222.115417)
			(xy 348.389156 -222.162602) (xy 348.358864 -222.205668) (xy 348.322352 -222.243606) (xy 348.280478 -222.275525)
			(xy 348.234222 -222.300678) (xy 348.184669 -222.318476) (xy 348.132979 -222.3285) (xy 348.080365 -222.330517)
			(xy 348.02806 -222.324479) (xy 347.977289 -222.310527) (xy 347.929244 -222.288988) (xy 347.885049 -222.260368)
			(xy 347.845741 -222.225337) (xy 347.812241 -222.184716) (xy 347.785335 -222.139457) (xy 347.765652 -222.090622)
			(xy 347.753655 -222.039354) (xy 347.749625 -221.986856) (xy 347.6371 -221.986856) (xy 347.636596 -222.013182)
			(xy 347.628559 -222.065218) (xy 347.612673 -222.115417) (xy 347.58931 -222.162602) (xy 347.559018 -222.205668)
			(xy 347.522506 -222.243606) (xy 347.480632 -222.275525) (xy 347.434376 -222.300678) (xy 347.384823 -222.318476)
			(xy 347.333133 -222.3285) (xy 347.280519 -222.330517) (xy 347.228214 -222.324479) (xy 347.177443 -222.310527)
			(xy 347.129398 -222.288988) (xy 347.085203 -222.260368) (xy 347.045895 -222.225337) (xy 347.012395 -222.184716)
			(xy 346.985489 -222.139457) (xy 346.965806 -222.090622) (xy 346.953809 -222.039354) (xy 346.949779 -221.986856)
			(xy 346.837 -221.986856) (xy 346.836481 -222.013661) (xy 346.828141 -222.066617) (xy 346.811674 -222.117635)
			(xy 346.787478 -222.165473) (xy 346.756143 -222.208971) (xy 346.718428 -222.24707) (xy 346.675252 -222.278847)
			(xy 346.627662 -222.303527) (xy 346.576814 -222.320512) (xy 346.523945 -222.32939) (xy 346.497148 -222.330264)
			(xy 346.486988 -222.330264) (xy 346.4687 -222.337884) (xy 346.461588 -222.344996) (xy 346.454778 -222.352371)
			(xy 346.447081 -222.370896) (xy 346.447091 -222.390956) (xy 346.454807 -222.409472) (xy 346.461588 -222.416878)
			(xy 346.480638 -222.435928) (xy 346.49791 -222.443548) (xy 346.507562 -222.443802) (xy 346.533112 -222.445314)
			(xy 346.583374 -222.454959) (xy 346.631649 -222.471955) (xy 346.676868 -222.495927) (xy 346.718029 -222.526343)
			(xy 346.754222 -222.562529) (xy 346.784644 -222.603686) (xy 346.808623 -222.648901) (xy 346.825627 -222.697173)
			(xy 346.83528 -222.747435) (xy 346.836746 -222.772986) (xy 346.837 -222.782638) (xy 346.84462 -222.79991)
			(xy 346.86367 -222.81896) (xy 346.871048 -222.825773) (xy 346.889578 -222.833475) (xy 346.909644 -222.833475)
			(xy 346.928174 -222.825773) (xy 346.935552 -222.81896) (xy 346.942664 -222.811848) (xy 346.950284 -222.79356)
			(xy 346.950284 -222.7834) (xy 346.951073 -222.756595) (xy 346.959947 -222.70371) (xy 346.976933 -222.652847)
			(xy 347.001617 -222.605242) (xy 347.033401 -222.562053) (xy 347.071511 -222.524328) (xy 347.115022 -222.492985)
			(xy 347.162875 -222.468786) (xy 347.213908 -222.452318) (xy 347.26688 -222.443982) (xy 347.293692 -222.443548)
			(xy 347.320679 -222.444077) (xy 347.373988 -222.452518) (xy 347.425321 -222.469195) (xy 347.473413 -222.493695)
			(xy 347.517081 -222.525418) (xy 347.555249 -222.56358) (xy 347.586977 -222.607243) (xy 347.611485 -222.655331)
			(xy 347.62817 -222.706661) (xy 347.636619 -222.759969) (xy 347.6371 -222.786956) (xy 347.749625 -222.786956)
			(xy 347.753655 -222.734458) (xy 347.765652 -222.68319) (xy 347.785335 -222.634355) (xy 347.812241 -222.589096)
			(xy 347.845741 -222.548475) (xy 347.885049 -222.513444) (xy 347.929244 -222.484824) (xy 347.977289 -222.463285)
			(xy 348.02806 -222.449333) (xy 348.080365 -222.443295) (xy 348.132979 -222.445312) (xy 348.184669 -222.455336)
			(xy 348.234222 -222.473134) (xy 348.280478 -222.498287) (xy 348.322352 -222.530206) (xy 348.358864 -222.568144)
			(xy 348.389156 -222.61121) (xy 348.412519 -222.658395) (xy 348.428405 -222.708594) (xy 348.436442 -222.76063)
			(xy 348.436946 -222.786956) (xy 348.549725 -222.786956) (xy 348.553755 -222.734458) (xy 348.565752 -222.68319)
			(xy 348.585435 -222.634355) (xy 348.612341 -222.589096) (xy 348.645841 -222.548475) (xy 348.685149 -222.513444)
			(xy 348.729344 -222.484824) (xy 348.777389 -222.463285) (xy 348.82816 -222.449333) (xy 348.880465 -222.443295)
			(xy 348.933079 -222.445312) (xy 348.984769 -222.455336) (xy 349.034322 -222.473134) (xy 349.080578 -222.498287)
			(xy 349.122452 -222.530206) (xy 349.158964 -222.568144) (xy 349.189256 -222.61121) (xy 349.212619 -222.658395)
			(xy 349.228505 -222.708594) (xy 349.236542 -222.76063) (xy 349.237046 -222.786956) (xy 349.349825 -222.786956)
			(xy 349.353855 -222.734458) (xy 349.365852 -222.68319) (xy 349.385535 -222.634355) (xy 349.412441 -222.589096)
			(xy 349.445941 -222.548475) (xy 349.485249 -222.513444) (xy 349.529444 -222.484824) (xy 349.577489 -222.463285)
			(xy 349.62826 -222.449333) (xy 349.680565 -222.443295) (xy 349.733179 -222.445312) (xy 349.784869 -222.455336)
			(xy 349.834422 -222.473134) (xy 349.880678 -222.498287) (xy 349.922552 -222.530206) (xy 349.959064 -222.568144)
			(xy 349.989356 -222.61121) (xy 350.012719 -222.658395) (xy 350.028605 -222.708594) (xy 350.036642 -222.76063)
			(xy 350.037146 -222.786956) (xy 350.149671 -222.786956) (xy 350.153701 -222.734458) (xy 350.165698 -222.68319)
			(xy 350.185381 -222.634355) (xy 350.212287 -222.589096) (xy 350.245787 -222.548475) (xy 350.285095 -222.513444)
			(xy 350.32929 -222.484824) (xy 350.377335 -222.463285) (xy 350.428106 -222.449333) (xy 350.480411 -222.443295)
			(xy 350.533025 -222.445312) (xy 350.584715 -222.455336) (xy 350.634268 -222.473134) (xy 350.680524 -222.498287)
			(xy 350.722398 -222.530206) (xy 350.75891 -222.568144) (xy 350.789202 -222.61121) (xy 350.812565 -222.658395)
			(xy 350.828451 -222.708594) (xy 350.836488 -222.76063) (xy 350.836992 -222.786956) (xy 350.836488 -222.813282)
			(xy 350.828451 -222.865318) (xy 350.812565 -222.915517) (xy 350.789202 -222.962702) (xy 350.75891 -223.005768)
			(xy 350.722398 -223.043706) (xy 350.680524 -223.075625) (xy 350.634268 -223.100778) (xy 350.584715 -223.118576)
			(xy 350.533025 -223.1286) (xy 350.480411 -223.130617) (xy 350.428106 -223.124579) (xy 350.377335 -223.110627)
			(xy 350.32929 -223.089088) (xy 350.285095 -223.060468) (xy 350.245787 -223.025437) (xy 350.212287 -222.984816)
			(xy 350.185381 -222.939557) (xy 350.165698 -222.890722) (xy 350.153701 -222.839454) (xy 350.149671 -222.786956)
			(xy 350.037146 -222.786956) (xy 350.036642 -222.813282) (xy 350.028605 -222.865318) (xy 350.012719 -222.915517)
			(xy 349.989356 -222.962702) (xy 349.959064 -223.005768) (xy 349.922552 -223.043706) (xy 349.880678 -223.075625)
			(xy 349.834422 -223.100778) (xy 349.784869 -223.118576) (xy 349.733179 -223.1286) (xy 349.680565 -223.130617)
			(xy 349.62826 -223.124579) (xy 349.577489 -223.110627) (xy 349.529444 -223.089088) (xy 349.485249 -223.060468)
			(xy 349.445941 -223.025437) (xy 349.412441 -222.984816) (xy 349.385535 -222.939557) (xy 349.365852 -222.890722)
			(xy 349.353855 -222.839454) (xy 349.349825 -222.786956) (xy 349.237046 -222.786956) (xy 349.236542 -222.813282)
			(xy 349.228505 -222.865318) (xy 349.212619 -222.915517) (xy 349.189256 -222.962702) (xy 349.158964 -223.005768)
			(xy 349.122452 -223.043706) (xy 349.080578 -223.075625) (xy 349.034322 -223.100778) (xy 348.984769 -223.118576)
			(xy 348.933079 -223.1286) (xy 348.880465 -223.130617) (xy 348.82816 -223.124579) (xy 348.777389 -223.110627)
			(xy 348.729344 -223.089088) (xy 348.685149 -223.060468) (xy 348.645841 -223.025437) (xy 348.612341 -222.984816)
			(xy 348.585435 -222.939557) (xy 348.565752 -222.890722) (xy 348.553755 -222.839454) (xy 348.549725 -222.786956)
			(xy 348.436946 -222.786956) (xy 348.436442 -222.813282) (xy 348.428405 -222.865318) (xy 348.412519 -222.915517)
			(xy 348.389156 -222.962702) (xy 348.358864 -223.005768) (xy 348.322352 -223.043706) (xy 348.280478 -223.075625)
			(xy 348.234222 -223.100778) (xy 348.184669 -223.118576) (xy 348.132979 -223.1286) (xy 348.080365 -223.130617)
			(xy 348.02806 -223.124579) (xy 347.977289 -223.110627) (xy 347.929244 -223.089088) (xy 347.885049 -223.060468)
			(xy 347.845741 -223.025437) (xy 347.812241 -222.984816) (xy 347.785335 -222.939557) (xy 347.765652 -222.890722)
			(xy 347.753655 -222.839454) (xy 347.749625 -222.786956) (xy 347.6371 -222.786956) (xy 347.636581 -222.813761)
			(xy 347.628241 -222.866717) (xy 347.611774 -222.917735) (xy 347.587578 -222.965573) (xy 347.556243 -223.009071)
			(xy 347.518528 -223.04717) (xy 347.475352 -223.078947) (xy 347.427762 -223.103627) (xy 347.376914 -223.120612)
			(xy 347.324045 -223.12949) (xy 347.297248 -223.130364) (xy 347.287088 -223.130364) (xy 347.2688 -223.137984)
			(xy 347.261688 -223.145096) (xy 347.254878 -223.152471) (xy 347.247181 -223.170996) (xy 347.247191 -223.191056)
			(xy 347.254907 -223.209572) (xy 347.261688 -223.216978) (xy 347.280484 -223.235774) (xy 347.297756 -223.243394)
			(xy 347.307408 -223.243648) (xy 347.332982 -223.245144) (xy 347.383296 -223.254769) (xy 347.431622 -223.271761)
			(xy 347.476888 -223.295743) (xy 347.51809 -223.326183) (xy 347.554313 -223.362405) (xy 347.584754 -223.403606)
			(xy 347.608737 -223.448872) (xy 347.62573 -223.497198) (xy 347.635356 -223.547512) (xy 347.636846 -223.573086)
			(xy 347.6371 -223.582738) (xy 347.64472 -223.60001) (xy 347.663516 -223.618806) (xy 347.670894 -223.625619)
			(xy 347.689424 -223.633321) (xy 347.70949 -223.633321) (xy 347.72802 -223.625619) (xy 347.735398 -223.618806)
			(xy 347.74251 -223.611694) (xy 347.75013 -223.593406) (xy 347.75013 -223.583246) (xy 347.750923 -223.556445)
			(xy 347.759804 -223.503569) (xy 347.776795 -223.452717) (xy 347.801483 -223.405123) (xy 347.833269 -223.361944)
			(xy 347.871379 -223.324231) (xy 347.914887 -223.292899) (xy 347.962737 -223.26871) (xy 348.013764 -223.252251)
			(xy 348.06673 -223.243924) (xy 348.093538 -223.243394) (xy 348.120521 -223.243926) (xy 348.173822 -223.252374)
			(xy 348.225146 -223.269055) (xy 348.273228 -223.293559) (xy 348.316886 -223.325282) (xy 348.355044 -223.363445)
			(xy 348.386762 -223.407106) (xy 348.411261 -223.455191) (xy 348.427936 -223.506517) (xy 348.436377 -223.559819)
			(xy 348.436946 -223.586802) (xy 348.549725 -223.586802) (xy 348.553755 -223.534304) (xy 348.565752 -223.483036)
			(xy 348.585435 -223.434201) (xy 348.612341 -223.388942) (xy 348.645841 -223.348321) (xy 348.685149 -223.31329)
			(xy 348.729344 -223.28467) (xy 348.777389 -223.263131) (xy 348.82816 -223.249179) (xy 348.880465 -223.243141)
			(xy 348.933079 -223.245158) (xy 348.984769 -223.255182) (xy 349.034322 -223.27298) (xy 349.080578 -223.298133)
			(xy 349.122452 -223.330052) (xy 349.158964 -223.36799) (xy 349.189256 -223.411056) (xy 349.212619 -223.458241)
			(xy 349.228505 -223.50844) (xy 349.236542 -223.560476) (xy 349.237046 -223.586802) (xy 349.349825 -223.586802)
			(xy 349.353855 -223.534304) (xy 349.365852 -223.483036) (xy 349.385535 -223.434201) (xy 349.412441 -223.388942)
			(xy 349.445941 -223.348321) (xy 349.485249 -223.31329) (xy 349.529444 -223.28467) (xy 349.577489 -223.263131)
			(xy 349.62826 -223.249179) (xy 349.680565 -223.243141) (xy 349.733179 -223.245158) (xy 349.784869 -223.255182)
			(xy 349.834422 -223.27298) (xy 349.880678 -223.298133) (xy 349.922552 -223.330052) (xy 349.959064 -223.36799)
			(xy 349.989356 -223.411056) (xy 350.012719 -223.458241) (xy 350.028605 -223.50844) (xy 350.036642 -223.560476)
			(xy 350.037146 -223.586802) (xy 350.149671 -223.586802) (xy 350.153701 -223.534304) (xy 350.165698 -223.483036)
			(xy 350.185381 -223.434201) (xy 350.212287 -223.388942) (xy 350.245787 -223.348321) (xy 350.285095 -223.31329)
			(xy 350.32929 -223.28467) (xy 350.377335 -223.263131) (xy 350.428106 -223.249179) (xy 350.480411 -223.243141)
			(xy 350.533025 -223.245158) (xy 350.584715 -223.255182) (xy 350.634268 -223.27298) (xy 350.680524 -223.298133)
			(xy 350.722398 -223.330052) (xy 350.75891 -223.36799) (xy 350.789202 -223.411056) (xy 350.812565 -223.458241)
			(xy 350.828451 -223.50844) (xy 350.836488 -223.560476) (xy 350.836992 -223.586802) (xy 350.836488 -223.613128)
			(xy 350.828451 -223.665164) (xy 350.812565 -223.715363) (xy 350.789202 -223.762548) (xy 350.75891 -223.805614)
			(xy 350.722398 -223.843552) (xy 350.680524 -223.875471) (xy 350.634268 -223.900624) (xy 350.584715 -223.918422)
			(xy 350.533025 -223.928446) (xy 350.480411 -223.930463) (xy 350.428106 -223.924425) (xy 350.377335 -223.910473)
			(xy 350.32929 -223.888934) (xy 350.285095 -223.860314) (xy 350.245787 -223.825283) (xy 350.212287 -223.784662)
			(xy 350.185381 -223.739403) (xy 350.165698 -223.690568) (xy 350.153701 -223.6393) (xy 350.149671 -223.586802)
			(xy 350.037146 -223.586802) (xy 350.036642 -223.613128) (xy 350.028605 -223.665164) (xy 350.012719 -223.715363)
			(xy 349.989356 -223.762548) (xy 349.959064 -223.805614) (xy 349.922552 -223.843552) (xy 349.880678 -223.875471)
			(xy 349.834422 -223.900624) (xy 349.784869 -223.918422) (xy 349.733179 -223.928446) (xy 349.680565 -223.930463)
			(xy 349.62826 -223.924425) (xy 349.577489 -223.910473) (xy 349.529444 -223.888934) (xy 349.485249 -223.860314)
			(xy 349.445941 -223.825283) (xy 349.412441 -223.784662) (xy 349.385535 -223.739403) (xy 349.365852 -223.690568)
			(xy 349.353855 -223.6393) (xy 349.349825 -223.586802) (xy 349.237046 -223.586802) (xy 349.236542 -223.613128)
			(xy 349.228505 -223.665164) (xy 349.212619 -223.715363) (xy 349.189256 -223.762548) (xy 349.158964 -223.805614)
			(xy 349.122452 -223.843552) (xy 349.080578 -223.875471) (xy 349.034322 -223.900624) (xy 348.984769 -223.918422)
			(xy 348.933079 -223.928446) (xy 348.880465 -223.930463) (xy 348.82816 -223.924425) (xy 348.777389 -223.910473)
			(xy 348.729344 -223.888934) (xy 348.685149 -223.860314) (xy 348.645841 -223.825283) (xy 348.612341 -223.784662)
			(xy 348.585435 -223.739403) (xy 348.565752 -223.690568) (xy 348.553755 -223.6393) (xy 348.549725 -223.586802)
			(xy 348.436946 -223.586802) (xy 348.436431 -223.613611) (xy 348.428098 -223.666576) (xy 348.411636 -223.717604)
			(xy 348.387444 -223.765453) (xy 348.356111 -223.808962) (xy 348.318396 -223.847073) (xy 348.275218 -223.87886)
			(xy 348.227624 -223.903551) (xy 348.176772 -223.920545) (xy 348.123896 -223.929431) (xy 348.097094 -223.93021)
			(xy 348.086934 -223.93021) (xy 348.068646 -223.93783) (xy 348.061534 -223.944942) (xy 348.054719 -223.952321)
			(xy 348.047011 -223.970853) (xy 348.047006 -223.990924) (xy 348.054705 -224.009459) (xy 348.061534 -224.016824)
			(xy 348.080584 -224.035874) (xy 348.097856 -224.043494) (xy 348.107508 -224.043748) (xy 348.133054 -224.045263)
			(xy 348.183309 -224.054914) (xy 348.231576 -224.071915) (xy 348.276785 -224.09589) (xy 348.317937 -224.126307)
			(xy 348.35412 -224.162495) (xy 348.384532 -224.20365) (xy 348.408502 -224.248863) (xy 348.425497 -224.297131)
			(xy 348.435142 -224.347387) (xy 348.436692 -224.372932) (xy 348.436946 -224.382584) (xy 348.444566 -224.399856)
			(xy 348.463616 -224.418906) (xy 348.470994 -224.425719) (xy 348.489524 -224.433421) (xy 348.50959 -224.433421)
			(xy 348.52812 -224.425719) (xy 348.535498 -224.418906) (xy 348.54261 -224.411794) (xy 348.55023 -224.393506)
			(xy 348.55023 -224.383346) (xy 348.551023 -224.356545) (xy 348.559904 -224.303669) (xy 348.576895 -224.252817)
			(xy 348.601583 -224.205223) (xy 348.633369 -224.162044) (xy 348.671479 -224.124331) (xy 348.714987 -224.092999)
			(xy 348.762837 -224.06881) (xy 348.813864 -224.052351) (xy 348.86683 -224.044024) (xy 348.893638 -224.043494)
			(xy 348.920621 -224.044026) (xy 348.973922 -224.052474) (xy 349.025246 -224.069155) (xy 349.073328 -224.093659)
			(xy 349.116986 -224.125382) (xy 349.155144 -224.163545) (xy 349.186862 -224.207206) (xy 349.211361 -224.255291)
			(xy 349.228036 -224.306617) (xy 349.236477 -224.359919) (xy 349.237046 -224.386902) (xy 349.236531 -224.413711)
			(xy 349.228198 -224.466676) (xy 349.211736 -224.517704) (xy 349.187544 -224.565553) (xy 349.156211 -224.609062)
			(xy 349.118496 -224.647173) (xy 349.075318 -224.67896) (xy 349.027724 -224.703651) (xy 348.976872 -224.720645)
			(xy 348.923996 -224.729531) (xy 348.897194 -224.73031) (xy 348.887034 -224.73031) (xy 348.868746 -224.73793)
			(xy 348.861634 -224.745042) (xy 348.854819 -224.752421) (xy 348.847111 -224.770953) (xy 348.847106 -224.791024)
			(xy 348.854805 -224.809559) (xy 348.861634 -224.816924) (xy 348.88043 -224.83572) (xy 348.897702 -224.84334)
			(xy 348.907354 -224.843594) (xy 348.932924 -224.845093) (xy 348.983231 -224.854724) (xy 349.031548 -224.871721)
			(xy 349.076805 -224.895706) (xy 349.117998 -224.926148) (xy 349.154211 -224.96237) (xy 349.184642 -225.00357)
			(xy 349.208615 -225.048833) (xy 349.225599 -225.097156) (xy 349.235217 -225.147464) (xy 349.236792 -225.173032)
			(xy 349.237046 -225.182684) (xy 349.244666 -225.199956) (xy 349.263716 -225.219006) (xy 349.271094 -225.225819)
			(xy 349.289624 -225.233521) (xy 349.30969 -225.233521) (xy 349.32822 -225.225819) (xy 349.335598 -225.219006)
			(xy 349.34271 -225.211894) (xy 349.35033 -225.193606) (xy 349.35033 -225.183446) (xy 349.351101 -225.156629)
			(xy 349.359945 -225.103718) (xy 349.37691 -225.052825) (xy 349.401582 -225.00519) (xy 349.433363 -224.961971)
			(xy 349.471477 -224.92422) (xy 349.514999 -224.892856) (xy 349.562868 -224.868641) (xy 349.613921 -224.852165)
			(xy 349.666915 -224.843828) (xy 349.693738 -224.84334) (xy 349.720722 -224.843845) (xy 349.774025 -224.852293)
			(xy 349.825349 -224.868976) (xy 349.873432 -224.893483) (xy 349.91709 -224.92521) (xy 349.955246 -224.963376)
			(xy 349.986962 -225.007041) (xy 350.011457 -225.05513) (xy 350.028127 -225.106459) (xy 350.036562 -225.159764)
			(xy 350.037146 -225.186748) (xy 350.037146 -225.187002) (xy 350.036676 -225.212642) (xy 350.029054 -225.263353)
			(xy 350.013967 -225.312364) (xy 349.99175 -225.358582) (xy 349.97771 -225.380042) (xy 349.969582 -225.391726)
			(xy 349.968058 -225.41992) (xy 350.010476 -225.49866) (xy 350.011746 -225.500692) (xy 350.016477 -225.507875)
			(xy 350.029721 -225.518834) (xy 350.045832 -225.524829) (xy 350.054418 -225.52533)
		)
		(stroke
			(width 0)
			(type solid)
		)
		(fill yes)
		(layer "B.Cu")
		(net "P3V3_FPGA_VCCIO1")
	)
	(gr_poly
		(pts
			(xy 456.86472 -250.10364) (xy 456.874787 -250.103212) (xy 456.893381 -250.095485) (xy 456.900788 -250.088654)
			(xy 456.972416 -250.017026) (xy 456.97926 -250.009628) (xy 456.986981 -249.991028) (xy 456.987402 -249.980958)
			(xy 456.987402 -246.846344) (xy 456.987836 -246.836278) (xy 456.995564 -246.817689) (xy 457.002388 -246.810276)
			(xy 457.004674 -246.80799) (xy 457.012548 -246.789194) (xy 457.012548 -244.329712) (xy 457.013039 -244.319753)
			(xy 457.020638 -244.301338) (xy 457.02728 -244.293898) (xy 457.29906 -244.022118) (xy 457.306408 -244.015315)
			(xy 457.324871 -244.007602) (xy 457.334874 -244.007132) (xy 459.78445 -244.007132) (xy 459.794414 -244.00665)
			(xy 459.812846 -243.99907) (xy 459.820264 -243.9924) (xy 461.664304 -242.14836) (xy 461.671144 -242.140959)
			(xy 461.678863 -242.122361) (xy 461.67929 -242.112292) (xy 461.67929 -136.202166) (xy 461.67167 -136.18337)
			(xy 461.664304 -136.176258) (xy 456.586844 -131.098798) (xy 456.579442 -131.091961) (xy 456.560844 -131.084247)
			(xy 456.550776 -131.083812) (xy 430.849278 -131.083812) (xy 430.823878 -131.100576) (xy 430.817782 -131.1148)
			(xy 430.806474 -131.140375) (xy 430.777472 -131.188184) (xy 430.741804 -131.23125) (xy 430.700233 -131.268649)
			(xy 430.65365 -131.299582) (xy 430.603052 -131.323386) (xy 430.549521 -131.339552) (xy 430.494205 -131.347733)
			(xy 430.466246 -131.348226) (xy 430.436695 -131.347674) (xy 430.378301 -131.33856) (xy 430.322013 -131.320544)
			(xy 430.26918 -131.294057) (xy 430.221067 -131.259733) (xy 430.178827 -131.218396) (xy 430.160684 -131.195064)
			(xy 430.15535 -131.187952) (xy 430.134014 -131.173728) (xy 430.130515 -131.171563) (xy 430.122985 -131.168252)
			(xy 430.119028 -131.167124) (xy 430.116488 -131.166362) (xy 430.098708 -131.162298) (xy 430.092714 -131.161164)
			(xy 430.080519 -131.161421) (xy 430.074578 -131.162806) (xy 430.059084 -131.16687) (xy 430.053496 -131.169918)
			(xy 430.028008 -131.183498) (xy 429.974347 -131.204852) (xy 429.918429 -131.219295) (xy 429.861138 -131.226597)
			(xy 429.832262 -131.227068) (xy 429.803385 -131.226613) (xy 429.746093 -131.219315) (xy 429.690175 -131.204866)
			(xy 429.636519 -131.183494) (xy 429.611028 -131.169918) (xy 429.60544 -131.16687) (xy 429.589946 -131.162806)
			(xy 429.58401 -131.16138) (xy 429.571809 -131.161132) (xy 429.565816 -131.162298) (xy 429.548036 -131.166362)
			(xy 429.545496 -131.167124) (xy 429.541529 -131.168223) (xy 429.533993 -131.171535) (xy 429.53051 -131.173728)
			(xy 429.509174 -131.187952) (xy 429.50384 -131.195064) (xy 429.485704 -131.218399) (xy 429.443447 -131.259713)
			(xy 429.395328 -131.294022) (xy 429.342496 -131.320504) (xy 429.286214 -131.338528) (xy 429.227827 -131.347663)
			(xy 429.198278 -131.348226) (xy 429.170316 -131.347741) (xy 429.114989 -131.339584) (xy 429.061447 -131.323433)
			(xy 429.010838 -131.299636) (xy 428.964248 -131.268701) (xy 428.922676 -131.231293) (xy 428.887013 -131.188215)
			(xy 428.858025 -131.140389) (xy 428.846742 -131.1148) (xy 428.840646 -131.100576) (xy 428.815246 -131.083812)
			(xy 418.203126 -131.083812) (xy 418.1983 -131.084828) (xy 418.18007 -131.088181) (xy 418.143174 -131.091747)
			(xy 418.12464 -131.09194) (xy 418.123116 -131.09194) (xy 418.10471 -131.091708) (xy 418.068069 -131.08815)
			(xy 418.049964 -131.084828) (xy 418.045138 -131.083812) (xy 415.729674 -131.083812) (xy 415.724578 -131.083927)
			(xy 415.714594 -131.085978) (xy 415.709862 -131.087876) (xy 415.683446 -131.099052) (xy 415.676588 -131.105656)
			(xy 415.655159 -131.125868) (xy 415.608017 -131.161192) (xy 415.556733 -131.190178) (xy 415.502156 -131.212347)
			(xy 415.445186 -131.227333) (xy 415.386764 -131.234889) (xy 415.327856 -131.234889) (xy 415.269434 -131.227333)
			(xy 415.212464 -131.212347) (xy 415.157887 -131.190178) (xy 415.106603 -131.161192) (xy 415.059461 -131.125868)
			(xy 415.038032 -131.105656) (xy 415.031174 -131.099052) (xy 415.004758 -131.087876) (xy 415.000018 -131.086011)
			(xy 414.990038 -131.083974) (xy 414.984946 -131.083812) (xy 411.388814 -131.083812) (xy 411.370018 -131.091432)
			(xy 411.362906 -131.098798) (xy 409.884372 -132.577332) (xy 413.045148 -132.577332) (xy 413.045148 -131.713732)
			(xy 413.045638 -131.683748) (xy 413.053466 -131.624292) (xy 413.068987 -131.566367) (xy 413.091936 -131.510963)
			(xy 413.12192 -131.459029) (xy 413.158426 -131.411453) (xy 413.200831 -131.369048) (xy 413.248407 -131.332542)
			(xy 413.300341 -131.302558) (xy 413.355745 -131.279609) (xy 413.41367 -131.264088) (xy 413.473126 -131.25626)
			(xy 413.533094 -131.25626) (xy 413.59255 -131.264088) (xy 413.650475 -131.279609) (xy 413.705879 -131.302558)
			(xy 413.757813 -131.332542) (xy 413.805389 -131.369048) (xy 413.847794 -131.411453) (xy 413.8843 -131.459029)
			(xy 413.914284 -131.510963) (xy 413.937233 -131.566367) (xy 413.952754 -131.624292) (xy 413.960582 -131.683748)
			(xy 413.961072 -131.713732) (xy 413.961072 -132.575808) (xy 432.016408 -132.575808) (xy 432.016408 -131.712208)
			(xy 432.016898 -131.682224) (xy 432.024726 -131.622768) (xy 432.040247 -131.564843) (xy 432.063196 -131.509439)
			(xy 432.09318 -131.457505) (xy 432.129686 -131.409929) (xy 432.172091 -131.367524) (xy 432.219667 -131.331018)
			(xy 432.271601 -131.301034) (xy 432.327005 -131.278085) (xy 432.38493 -131.262564) (xy 432.444386 -131.254736)
			(xy 432.504354 -131.254736) (xy 432.56381 -131.262564) (xy 432.621735 -131.278085) (xy 432.677139 -131.301034)
			(xy 432.729073 -131.331018) (xy 432.776649 -131.367524) (xy 432.819054 -131.409929) (xy 432.85556 -131.457505)
			(xy 432.885544 -131.509439) (xy 432.908493 -131.564843) (xy 432.924014 -131.622768) (xy 432.931842 -131.682224)
			(xy 432.932332 -131.712208) (xy 432.932332 -132.575808) (xy 432.931842 -132.605792) (xy 432.924014 -132.665248)
			(xy 432.908493 -132.723173) (xy 432.885544 -132.778577) (xy 432.85556 -132.830511) (xy 432.819054 -132.878087)
			(xy 432.776649 -132.920492) (xy 432.729073 -132.956998) (xy 432.677139 -132.986982) (xy 432.621735 -133.009931)
			(xy 432.56381 -133.025452) (xy 432.504354 -133.03328) (xy 432.444386 -133.03328) (xy 432.38493 -133.025452)
			(xy 432.327005 -133.009931) (xy 432.271601 -132.986982) (xy 432.219667 -132.956998) (xy 432.172091 -132.920492)
			(xy 432.129686 -132.878087) (xy 432.09318 -132.830511) (xy 432.063196 -132.778577) (xy 432.040247 -132.723173)
			(xy 432.024726 -132.665248) (xy 432.016898 -132.605792) (xy 432.016408 -132.575808) (xy 413.961072 -132.575808)
			(xy 413.961072 -132.577332) (xy 413.960582 -132.607316) (xy 413.952754 -132.666772) (xy 413.937233 -132.724697)
			(xy 413.914284 -132.780101) (xy 413.8843 -132.832035) (xy 413.847794 -132.879611) (xy 413.805389 -132.922016)
			(xy 413.757813 -132.958522) (xy 413.705879 -132.988506) (xy 413.650475 -133.011455) (xy 413.59255 -133.026976)
			(xy 413.533094 -133.034804) (xy 413.473126 -133.034804) (xy 413.41367 -133.026976) (xy 413.355745 -133.011455)
			(xy 413.300341 -132.988506) (xy 413.248407 -132.958522) (xy 413.200831 -132.922016) (xy 413.158426 -132.879611)
			(xy 413.12192 -132.832035) (xy 413.091936 -132.780101) (xy 413.068987 -132.724697) (xy 413.053466 -132.666772)
			(xy 413.045638 -132.607316) (xy 413.045148 -132.577332) (xy 409.884372 -132.577332) (xy 408.597862 -133.863842)
			(xy 408.591051 -133.871187) (xy 408.583324 -133.88965) (xy 408.582876 -133.899656) (xy 408.582876 -134.377176)
			(xy 414.899348 -134.377176) (xy 414.899348 -133.513576) (xy 414.899838 -133.483592) (xy 414.907666 -133.424136)
			(xy 414.923187 -133.366211) (xy 414.946136 -133.310807) (xy 414.97612 -133.258873) (xy 415.012626 -133.211297)
			(xy 415.055031 -133.168892) (xy 415.102607 -133.132386) (xy 415.154541 -133.102402) (xy 415.209945 -133.079453)
			(xy 415.26787 -133.063932) (xy 415.327326 -133.056104) (xy 415.387294 -133.056104) (xy 415.44675 -133.063932)
			(xy 415.504675 -133.079453) (xy 415.560079 -133.102402) (xy 415.612013 -133.132386) (xy 415.659589 -133.168892)
			(xy 415.701994 -133.211297) (xy 415.7385 -133.258873) (xy 415.768484 -133.310807) (xy 415.791433 -133.366211)
			(xy 415.806954 -133.424136) (xy 415.814782 -133.483592) (xy 415.815272 -133.513576) (xy 415.815272 -134.369302)
			(xy 429.3743 -134.369302) (xy 429.3743 -133.505702) (xy 429.37479 -133.475718) (xy 429.382618 -133.416262)
			(xy 429.398139 -133.358337) (xy 429.421088 -133.302933) (xy 429.451072 -133.250999) (xy 429.487578 -133.203423)
			(xy 429.529983 -133.161018) (xy 429.577559 -133.124512) (xy 429.629493 -133.094528) (xy 429.684897 -133.071579)
			(xy 429.742822 -133.056058) (xy 429.802278 -133.04823) (xy 429.862246 -133.04823) (xy 429.921702 -133.056058)
			(xy 429.979627 -133.071579) (xy 430.035031 -133.094528) (xy 430.086965 -133.124512) (xy 430.134541 -133.161018)
			(xy 430.176946 -133.203423) (xy 430.213452 -133.250999) (xy 430.243436 -133.302933) (xy 430.266385 -133.358337)
			(xy 430.281906 -133.416262) (xy 430.289734 -133.475718) (xy 430.290224 -133.505702) (xy 430.290224 -134.369302)
			(xy 430.289734 -134.399286) (xy 430.281906 -134.458742) (xy 430.266385 -134.516667) (xy 430.243436 -134.572071)
			(xy 430.213452 -134.624005) (xy 430.176946 -134.671581) (xy 430.134541 -134.713986) (xy 430.086965 -134.750492)
			(xy 430.035031 -134.780476) (xy 429.979627 -134.803425) (xy 429.921702 -134.818946) (xy 429.862246 -134.826774)
			(xy 429.802278 -134.826774) (xy 429.742822 -134.818946) (xy 429.684897 -134.803425) (xy 429.629493 -134.780476)
			(xy 429.577559 -134.750492) (xy 429.529983 -134.713986) (xy 429.487578 -134.671581) (xy 429.451072 -134.624005)
			(xy 429.421088 -134.572071) (xy 429.398139 -134.516667) (xy 429.382618 -134.458742) (xy 429.37479 -134.399286)
			(xy 429.3743 -134.369302) (xy 415.815272 -134.369302) (xy 415.815272 -134.377176) (xy 415.814782 -134.40716)
			(xy 415.806954 -134.466616) (xy 415.791433 -134.524541) (xy 415.768484 -134.579945) (xy 415.7385 -134.631879)
			(xy 415.701994 -134.679455) (xy 415.659589 -134.72186) (xy 415.612013 -134.758366) (xy 415.560079 -134.78835)
			(xy 415.504675 -134.811299) (xy 415.44675 -134.82682) (xy 415.387294 -134.834648) (xy 415.327326 -134.834648)
			(xy 415.26787 -134.82682) (xy 415.209945 -134.811299) (xy 415.154541 -134.78835) (xy 415.102607 -134.758366)
			(xy 415.055031 -134.72186) (xy 415.012626 -134.679455) (xy 414.97612 -134.631879) (xy 414.946136 -134.579945)
			(xy 414.923187 -134.524541) (xy 414.907666 -134.466616) (xy 414.899838 -134.40716) (xy 414.899348 -134.377176)
			(xy 408.582876 -134.377176) (xy 408.582876 -136.177274) (xy 413.045148 -136.177274) (xy 413.045148 -135.313674)
			(xy 413.045638 -135.28369) (xy 413.053466 -135.224234) (xy 413.068987 -135.166309) (xy 413.091936 -135.110905)
			(xy 413.12192 -135.058971) (xy 413.158426 -135.011395) (xy 413.200831 -134.96899) (xy 413.248407 -134.932484)
			(xy 413.300341 -134.9025) (xy 413.355745 -134.879551) (xy 413.41367 -134.86403) (xy 413.473126 -134.856202)
			(xy 413.533094 -134.856202) (xy 413.59255 -134.86403) (xy 413.650475 -134.879551) (xy 413.705879 -134.9025)
			(xy 413.757813 -134.932484) (xy 413.805389 -134.96899) (xy 413.847794 -135.011395) (xy 413.8843 -135.058971)
			(xy 413.914284 -135.110905) (xy 413.937233 -135.166309) (xy 413.952754 -135.224234) (xy 413.960582 -135.28369)
			(xy 413.961072 -135.313674) (xy 413.961072 -136.17575) (xy 432.016408 -136.17575) (xy 432.016408 -135.31215)
			(xy 432.016898 -135.282166) (xy 432.024726 -135.22271) (xy 432.040247 -135.164785) (xy 432.063196 -135.109381)
			(xy 432.09318 -135.057447) (xy 432.129686 -135.009871) (xy 432.172091 -134.967466) (xy 432.219667 -134.93096)
			(xy 432.271601 -134.900976) (xy 432.327005 -134.878027) (xy 432.38493 -134.862506) (xy 432.444386 -134.854678)
			(xy 432.504354 -134.854678) (xy 432.56381 -134.862506) (xy 432.621735 -134.878027) (xy 432.677139 -134.900976)
			(xy 432.729073 -134.93096) (xy 432.776649 -134.967466) (xy 432.819054 -135.009871) (xy 432.85556 -135.057447)
			(xy 432.885544 -135.109381) (xy 432.908493 -135.164785) (xy 432.924014 -135.22271) (xy 432.931842 -135.282166)
			(xy 432.932332 -135.31215) (xy 432.932332 -136.17575) (xy 432.931842 -136.205734) (xy 432.924014 -136.26519)
			(xy 432.908493 -136.323115) (xy 432.885544 -136.378519) (xy 432.85556 -136.430453) (xy 432.819054 -136.478029)
			(xy 432.776649 -136.520434) (xy 432.729073 -136.55694) (xy 432.677139 -136.586924) (xy 432.621735 -136.609873)
			(xy 432.56381 -136.625394) (xy 432.504354 -136.633222) (xy 432.444386 -136.633222) (xy 432.38493 -136.625394)
			(xy 432.327005 -136.609873) (xy 432.271601 -136.586924) (xy 432.219667 -136.55694) (xy 432.172091 -136.520434)
			(xy 432.129686 -136.478029) (xy 432.09318 -136.430453) (xy 432.063196 -136.378519) (xy 432.040247 -136.323115)
			(xy 432.024726 -136.26519) (xy 432.016898 -136.205734) (xy 432.016408 -136.17575) (xy 413.961072 -136.17575)
			(xy 413.961072 -136.177274) (xy 413.960582 -136.207258) (xy 413.952754 -136.266714) (xy 413.937233 -136.324639)
			(xy 413.914284 -136.380043) (xy 413.8843 -136.431977) (xy 413.847794 -136.479553) (xy 413.805389 -136.521958)
			(xy 413.757813 -136.558464) (xy 413.705879 -136.588448) (xy 413.650475 -136.611397) (xy 413.59255 -136.626918)
			(xy 413.533094 -136.634746) (xy 413.473126 -136.634746) (xy 413.41367 -136.626918) (xy 413.355745 -136.611397)
			(xy 413.300341 -136.588448) (xy 413.248407 -136.558464) (xy 413.200831 -136.521958) (xy 413.158426 -136.479553)
			(xy 413.12192 -136.431977) (xy 413.091936 -136.380043) (xy 413.068987 -136.324639) (xy 413.053466 -136.266714)
			(xy 413.045638 -136.207258) (xy 413.045148 -136.177274) (xy 408.582876 -136.177274) (xy 408.582876 -136.98601)
			(xy 428.857662 -136.98601) (xy 428.861733 -136.930388) (xy 428.873859 -136.875951) (xy 428.893782 -136.82386)
			(xy 428.921078 -136.775225) (xy 428.955164 -136.731082) (xy 428.995313 -136.692373) (xy 429.040671 -136.659922)
			(xy 429.090271 -136.634421) (xy 429.143055 -136.616414) (xy 429.197898 -136.606284) (xy 429.253632 -136.604247)
			(xy 429.309069 -136.610347) (xy 429.363026 -136.624453) (xy 429.414355 -136.646265) (xy 429.461961 -136.675319)
			(xy 429.504829 -136.710994) (xy 429.542046 -136.752531) (xy 429.572819 -136.799044) (xy 429.596491 -136.849541)
			(xy 429.612559 -136.902948) (xy 429.620679 -136.958124) (xy 429.621188 -136.98601) (xy 429.620679 -137.013896)
			(xy 429.612559 -137.069072) (xy 429.596491 -137.122479) (xy 429.572819 -137.172976) (xy 429.542046 -137.219489)
			(xy 429.504829 -137.261026) (xy 429.461961 -137.296701) (xy 429.414355 -137.325755) (xy 429.363026 -137.347567)
			(xy 429.309069 -137.361673) (xy 429.253632 -137.367773) (xy 429.197898 -137.365736) (xy 429.143055 -137.355606)
			(xy 429.090271 -137.337599) (xy 429.040671 -137.312098) (xy 428.995313 -137.279647) (xy 428.955164 -137.240938)
			(xy 428.921078 -137.196795) (xy 428.893782 -137.14816) (xy 428.873859 -137.096069) (xy 428.861733 -137.041632)
			(xy 428.857662 -136.98601) (xy 408.582876 -136.98601) (xy 408.582876 -137.848848) (xy 410.23997 -137.848848)
			(xy 410.244041 -137.793226) (xy 410.256167 -137.738789) (xy 410.27609 -137.686698) (xy 410.303386 -137.638063)
			(xy 410.337472 -137.59392) (xy 410.377621 -137.555211) (xy 410.422979 -137.52276) (xy 410.472579 -137.497259)
			(xy 410.525363 -137.479252) (xy 410.580206 -137.469122) (xy 410.63594 -137.467085) (xy 410.691377 -137.473185)
			(xy 410.745334 -137.487291) (xy 410.796663 -137.509103) (xy 410.844269 -137.538157) (xy 410.887137 -137.573832)
			(xy 410.924354 -137.615369) (xy 410.949092 -137.65276) (xy 444.341248 -137.65276) (xy 444.345319 -137.597138)
			(xy 444.357445 -137.542701) (xy 444.377368 -137.49061) (xy 444.404664 -137.441975) (xy 444.43875 -137.397832)
			(xy 444.478899 -137.359123) (xy 444.524257 -137.326672) (xy 444.573857 -137.301171) (xy 444.626641 -137.283164)
			(xy 444.681484 -137.273034) (xy 444.737218 -137.270997) (xy 444.792655 -137.277097) (xy 444.846612 -137.291203)
			(xy 444.897941 -137.313015) (xy 444.945547 -137.342069) (xy 444.988415 -137.377744) (xy 445.025632 -137.419281)
			(xy 445.056405 -137.465794) (xy 445.080077 -137.516291) (xy 445.096145 -137.569698) (xy 445.104265 -137.624874)
			(xy 445.104774 -137.65276) (xy 445.104265 -137.680646) (xy 445.096145 -137.735822) (xy 445.080077 -137.789229)
			(xy 445.056405 -137.839726) (xy 445.025632 -137.886239) (xy 444.988415 -137.927776) (xy 444.977268 -137.937053)
			(xy 445.665563 -137.937053) (xy 445.665563 -137.882547) (xy 445.67332 -137.828597) (xy 445.688676 -137.7763)
			(xy 445.711319 -137.72672) (xy 445.740787 -137.680868) (xy 445.77648 -137.639676) (xy 445.817673 -137.603983)
			(xy 445.863526 -137.574516) (xy 445.913106 -137.551874) (xy 445.965403 -137.536519) (xy 446.019353 -137.528763)
			(xy 446.046606 -137.5283) (xy 446.074709 -137.528782) (xy 446.130306 -137.537029) (xy 446.184092 -137.553344)
			(xy 446.234901 -137.577374) (xy 446.281636 -137.608598) (xy 446.323284 -137.646341) (xy 446.3415 -137.667746)
			(xy 446.348612 -137.676636) (xy 446.36817 -137.686034) (xy 446.46723 -137.689082) (xy 446.487296 -137.680446)
			(xy 446.494662 -137.672318) (xy 446.512803 -137.653333) (xy 446.553392 -137.620017) (xy 446.598162 -137.592577)
			(xy 446.64627 -137.571529) (xy 446.696808 -137.557272) (xy 446.748823 -137.550074) (xy 446.775078 -137.549636)
			(xy 446.802335 -137.550009) (xy 446.856295 -137.557765) (xy 446.908601 -137.573121) (xy 446.95819 -137.595765)
			(xy 447.004051 -137.625235) (xy 447.045251 -137.660933) (xy 447.080951 -137.702131) (xy 447.110425 -137.747991)
			(xy 447.133072 -137.797578) (xy 447.148431 -137.849884) (xy 447.156189 -137.903843) (xy 447.156189 -137.958357)
			(xy 447.148431 -138.012316) (xy 447.133072 -138.064622) (xy 447.110425 -138.114209) (xy 447.080951 -138.160069)
			(xy 447.045251 -138.201267) (xy 447.004051 -138.236965) (xy 446.95819 -138.266435) (xy 446.908601 -138.289079)
			(xy 446.856295 -138.304435) (xy 446.802335 -138.312191) (xy 446.775078 -138.312652) (xy 446.746976 -138.312128)
			(xy 446.69138 -138.303892) (xy 446.637595 -138.287587) (xy 446.586784 -138.263565) (xy 446.540049 -138.232347)
			(xy 446.4984 -138.194609) (xy 446.480184 -138.173206) (xy 446.473072 -138.164316) (xy 446.453514 -138.154918)
			(xy 446.354454 -138.15187) (xy 446.334388 -138.160506) (xy 446.327022 -138.168634) (xy 446.308879 -138.187617)
			(xy 446.268292 -138.220935) (xy 446.223523 -138.248377) (xy 446.175415 -138.269425) (xy 446.124877 -138.283682)
			(xy 446.072861 -138.290879) (xy 446.046606 -138.291316) (xy 446.019353 -138.290837) (xy 445.965403 -138.283081)
			(xy 445.913106 -138.267726) (xy 445.863526 -138.245084) (xy 445.817673 -138.215617) (xy 445.77648 -138.179924)
			(xy 445.740787 -138.138732) (xy 445.711319 -138.09288) (xy 445.688676 -138.0433) (xy 445.67332 -137.991003)
			(xy 445.665563 -137.937053) (xy 444.977268 -137.937053) (xy 444.945547 -137.963451) (xy 444.897941 -137.992505)
			(xy 444.846612 -138.014317) (xy 444.792655 -138.028423) (xy 444.737218 -138.034523) (xy 444.681484 -138.032486)
			(xy 444.626641 -138.022356) (xy 444.573857 -138.004349) (xy 444.524257 -137.978848) (xy 444.478899 -137.946397)
			(xy 444.43875 -137.907688) (xy 444.404664 -137.863545) (xy 444.377368 -137.81491) (xy 444.357445 -137.762819)
			(xy 444.345319 -137.708382) (xy 444.341248 -137.65276) (xy 410.949092 -137.65276) (xy 410.955127 -137.661882)
			(xy 410.978799 -137.712379) (xy 410.994867 -137.765786) (xy 411.002987 -137.820962) (xy 411.003496 -137.848848)
			(xy 411.002987 -137.876734) (xy 410.994867 -137.93191) (xy 410.978799 -137.985317) (xy 410.955127 -138.035814)
			(xy 410.924354 -138.082327) (xy 410.887137 -138.123864) (xy 410.844269 -138.159539) (xy 410.796663 -138.188593)
			(xy 410.745334 -138.210405) (xy 410.691377 -138.224511) (xy 410.63594 -138.230611) (xy 410.580206 -138.228574)
			(xy 410.525363 -138.218444) (xy 410.472579 -138.200437) (xy 410.422979 -138.174936) (xy 410.377621 -138.142485)
			(xy 410.337472 -138.103776) (xy 410.303386 -138.059633) (xy 410.27609 -138.010998) (xy 410.256167 -137.958907)
			(xy 410.244041 -137.90447) (xy 410.23997 -137.848848) (xy 408.582876 -137.848848) (xy 408.582876 -138.864848)
			(xy 410.23997 -138.864848) (xy 410.244041 -138.809226) (xy 410.256167 -138.754789) (xy 410.27609 -138.702698)
			(xy 410.303386 -138.654063) (xy 410.337472 -138.60992) (xy 410.377621 -138.571211) (xy 410.422979 -138.53876)
			(xy 410.472579 -138.513259) (xy 410.525363 -138.495252) (xy 410.580206 -138.485122) (xy 410.63594 -138.483085)
			(xy 410.691377 -138.489185) (xy 410.745334 -138.503291) (xy 410.796663 -138.525103) (xy 410.844269 -138.554157)
			(xy 410.887137 -138.589832) (xy 410.924354 -138.631369) (xy 410.955127 -138.677882) (xy 410.978799 -138.728379)
			(xy 410.994867 -138.781786) (xy 411.002987 -138.836962) (xy 411.003496 -138.864848) (xy 411.002987 -138.892734)
			(xy 410.994867 -138.94791) (xy 410.978799 -139.001317) (xy 410.955127 -139.051814) (xy 410.924354 -139.098327)
			(xy 410.887137 -139.139864) (xy 410.844269 -139.175539) (xy 410.796663 -139.204593) (xy 410.745334 -139.226405)
			(xy 410.691377 -139.240511) (xy 410.63594 -139.246611) (xy 410.580206 -139.244574) (xy 410.525363 -139.234444)
			(xy 410.472579 -139.216437) (xy 410.422979 -139.190936) (xy 410.377621 -139.158485) (xy 410.337472 -139.119776)
			(xy 410.303386 -139.075633) (xy 410.27609 -139.026998) (xy 410.256167 -138.974907) (xy 410.244041 -138.92047)
			(xy 410.23997 -138.864848) (xy 408.582876 -138.864848) (xy 408.582876 -139.762055) (xy 428.684853 -139.762055)
			(xy 428.684853 -139.707545) (xy 428.692612 -139.65359) (xy 428.70797 -139.601288) (xy 428.730616 -139.551705)
			(xy 428.760088 -139.50585) (xy 428.795787 -139.464655) (xy 428.836985 -139.428962) (xy 428.882844 -139.399495)
			(xy 428.93243 -139.376855) (xy 428.984733 -139.361502) (xy 429.038689 -139.35375) (xy 429.065944 -139.35329)
			(xy 429.09215 -139.353734) (xy 429.144067 -139.360918) (xy 429.194511 -139.375146) (xy 429.24253 -139.396148)
			(xy 429.287221 -139.423529) (xy 429.32774 -139.456773) (xy 429.345852 -139.475718) (xy 429.353411 -139.483041)
			(xy 429.37268 -139.491444) (xy 429.38319 -139.491974) (xy 429.457866 -139.491974) (xy 429.468389 -139.49149)
			(xy 429.487681 -139.483091) (xy 429.495204 -139.475718) (xy 429.513324 -139.45678) (xy 429.553836 -139.423527)
			(xy 429.598524 -139.396139) (xy 429.646543 -139.375133) (xy 429.696987 -139.360905) (xy 429.748906 -139.353725)
			(xy 429.775112 -139.35329) (xy 429.802363 -139.353781) (xy 429.856309 -139.361538) (xy 429.908602 -139.376895)
			(xy 429.958177 -139.399536) (xy 430.004026 -139.429003) (xy 430.045214 -139.464694) (xy 430.080904 -139.505884)
			(xy 430.11037 -139.551733) (xy 430.13301 -139.60131) (xy 430.148364 -139.653603) (xy 430.15612 -139.707549)
			(xy 430.15612 -139.746478) (xy 431.016646 -139.746478) (xy 431.016646 -139.686542) (xy 431.024469 -139.62712)
			(xy 431.039982 -139.569227) (xy 431.062918 -139.513854) (xy 431.092885 -139.461948) (xy 431.129372 -139.414398)
			(xy 431.171752 -139.372018) (xy 431.219302 -139.335531) (xy 431.271208 -139.305564) (xy 431.326581 -139.282628)
			(xy 431.384474 -139.267115) (xy 431.443896 -139.259292) (xy 431.503832 -139.259292) (xy 431.563254 -139.267115)
			(xy 431.621147 -139.282628) (xy 431.67652 -139.305564) (xy 431.728426 -139.335531) (xy 431.775976 -139.372018)
			(xy 431.818356 -139.414398) (xy 431.854843 -139.461948) (xy 431.88481 -139.513854) (xy 431.907746 -139.569227)
			(xy 431.923259 -139.62712) (xy 431.931082 -139.686542) (xy 431.931572 -139.71651) (xy 431.931082 -139.746478)
			(xy 431.923259 -139.8059) (xy 431.907746 -139.863793) (xy 431.88481 -139.919166) (xy 431.854843 -139.971072)
			(xy 431.818356 -140.018622) (xy 431.775976 -140.061002) (xy 431.728426 -140.097489) (xy 431.67652 -140.127456)
			(xy 431.621147 -140.150392) (xy 431.563254 -140.165905) (xy 431.503832 -140.173728) (xy 431.443896 -140.173728)
			(xy 431.384474 -140.165905) (xy 431.326581 -140.150392) (xy 431.271208 -140.127456) (xy 431.219302 -140.097489)
			(xy 431.171752 -140.061002) (xy 431.129372 -140.018622) (xy 431.092885 -139.971072) (xy 431.062918 -139.919166)
			(xy 431.039982 -139.863793) (xy 431.024469 -139.8059) (xy 431.016646 -139.746478) (xy 430.15612 -139.746478)
			(xy 430.15612 -139.762051) (xy 430.148364 -139.815997) (xy 430.13301 -139.86829) (xy 430.11037 -139.917867)
			(xy 430.080904 -139.963716) (xy 430.045214 -140.004906) (xy 430.004026 -140.040597) (xy 429.958177 -140.070064)
			(xy 429.908602 -140.092705) (xy 429.856309 -140.108062) (xy 429.802363 -140.115819) (xy 429.775112 -140.116306)
			(xy 429.748905 -140.115893) (xy 429.696987 -140.108702) (xy 429.646542 -140.094469) (xy 429.598523 -140.073461)
			(xy 429.553833 -140.046074) (xy 429.513315 -140.012825) (xy 429.495204 -139.993878) (xy 429.487662 -139.986535)
			(xy 429.46838 -139.978143) (xy 429.457866 -139.977622) (xy 429.38319 -139.977622) (xy 429.372665 -139.978084)
			(xy 429.353373 -139.986499) (xy 429.345852 -139.993878) (xy 429.327753 -140.012837) (xy 429.287236 -140.046088)
			(xy 429.242544 -140.073474) (xy 429.194521 -140.094476) (xy 429.144073 -140.108699) (xy 429.092151 -140.115874)
			(xy 429.065944 -140.116306) (xy 429.038689 -140.11585) (xy 428.984733 -140.108098) (xy 428.93243 -140.092745)
			(xy 428.882844 -140.070105) (xy 428.836985 -140.040638) (xy 428.795787 -140.004945) (xy 428.760088 -139.96375)
			(xy 428.730616 -139.917895) (xy 428.70797 -139.868312) (xy 428.692612 -139.81601) (xy 428.684853 -139.762055)
			(xy 408.582876 -139.762055) (xy 408.582876 -140.487654) (xy 434.002178 -140.487654) (xy 434.006249 -140.432032)
			(xy 434.018375 -140.377595) (xy 434.038298 -140.325504) (xy 434.065594 -140.276869) (xy 434.09968 -140.232726)
			(xy 434.139829 -140.194017) (xy 434.185187 -140.161566) (xy 434.234787 -140.136065) (xy 434.287571 -140.118058)
			(xy 434.342414 -140.107928) (xy 434.398148 -140.105891) (xy 434.453585 -140.111991) (xy 434.507542 -140.126097)
			(xy 434.558871 -140.147909) (xy 434.606477 -140.176963) (xy 434.649345 -140.212638) (xy 434.686562 -140.254175)
			(xy 434.717335 -140.300688) (xy 434.741007 -140.351185) (xy 434.757075 -140.404592) (xy 434.765195 -140.459768)
			(xy 434.765704 -140.487654) (xy 434.765195 -140.51554) (xy 434.757075 -140.570716) (xy 434.741007 -140.624123)
			(xy 434.717335 -140.67462) (xy 434.686562 -140.721133) (xy 434.649345 -140.76267) (xy 434.606477 -140.798345)
			(xy 434.558871 -140.827399) (xy 434.507542 -140.849211) (xy 434.453585 -140.863317) (xy 434.398148 -140.869417)
			(xy 434.342414 -140.86738) (xy 434.287571 -140.85725) (xy 434.234787 -140.839243) (xy 434.185187 -140.813742)
			(xy 434.139829 -140.781291) (xy 434.09968 -140.742582) (xy 434.065594 -140.698439) (xy 434.038298 -140.649804)
			(xy 434.018375 -140.597713) (xy 434.006249 -140.543276) (xy 434.002178 -140.487654) (xy 408.582876 -140.487654)
			(xy 408.582876 -143.48714) (xy 414.899348 -143.48714) (xy 414.899348 -142.62354) (xy 414.899838 -142.593556)
			(xy 414.907666 -142.5341) (xy 414.923187 -142.476175) (xy 414.946136 -142.420771) (xy 414.97612 -142.368837)
			(xy 415.012626 -142.321261) (xy 415.055031 -142.278856) (xy 415.102607 -142.24235) (xy 415.154541 -142.212366)
			(xy 415.209945 -142.189417) (xy 415.26787 -142.173896) (xy 415.327326 -142.166068) (xy 415.387294 -142.166068)
			(xy 415.44675 -142.173896) (xy 415.504675 -142.189417) (xy 415.560079 -142.212366) (xy 415.612013 -142.24235)
			(xy 415.659589 -142.278856) (xy 415.701994 -142.321261) (xy 415.7385 -142.368837) (xy 415.768484 -142.420771)
			(xy 415.791433 -142.476175) (xy 415.806954 -142.5341) (xy 415.814782 -142.593556) (xy 415.815272 -142.62354)
			(xy 415.815272 -143.479266) (xy 429.3743 -143.479266) (xy 429.3743 -142.615666) (xy 429.37479 -142.585682)
			(xy 429.382618 -142.526226) (xy 429.398139 -142.468301) (xy 429.421088 -142.412897) (xy 429.451072 -142.360963)
			(xy 429.487578 -142.313387) (xy 429.529983 -142.270982) (xy 429.577559 -142.234476) (xy 429.629493 -142.204492)
			(xy 429.684897 -142.181543) (xy 429.742822 -142.166022) (xy 429.802278 -142.158194) (xy 429.862246 -142.158194)
			(xy 429.921702 -142.166022) (xy 429.979627 -142.181543) (xy 430.035031 -142.204492) (xy 430.086965 -142.234476)
			(xy 430.134541 -142.270982) (xy 430.176946 -142.313387) (xy 430.213452 -142.360963) (xy 430.243436 -142.412897)
			(xy 430.266385 -142.468301) (xy 430.281906 -142.526226) (xy 430.289734 -142.585682) (xy 430.290224 -142.615666)
			(xy 430.290224 -143.479266) (xy 430.289734 -143.50925) (xy 430.281906 -143.568706) (xy 430.266385 -143.626631)
			(xy 430.243436 -143.682035) (xy 430.213452 -143.733969) (xy 430.176946 -143.781545) (xy 430.134541 -143.82395)
			(xy 430.086965 -143.860456) (xy 430.035031 -143.89044) (xy 429.979627 -143.913389) (xy 429.921702 -143.92891)
			(xy 429.862246 -143.936738) (xy 429.802278 -143.936738) (xy 429.742822 -143.92891) (xy 429.684897 -143.913389)
			(xy 429.629493 -143.89044) (xy 429.577559 -143.860456) (xy 429.529983 -143.82395) (xy 429.487578 -143.781545)
			(xy 429.451072 -143.733969) (xy 429.421088 -143.682035) (xy 429.398139 -143.626631) (xy 429.382618 -143.568706)
			(xy 429.37479 -143.50925) (xy 429.3743 -143.479266) (xy 415.815272 -143.479266) (xy 415.815272 -143.48714)
			(xy 415.814782 -143.517124) (xy 415.806954 -143.57658) (xy 415.791433 -143.634505) (xy 415.768484 -143.689909)
			(xy 415.7385 -143.741843) (xy 415.701994 -143.789419) (xy 415.659589 -143.831824) (xy 415.612013 -143.86833)
			(xy 415.560079 -143.898314) (xy 415.504675 -143.921263) (xy 415.44675 -143.936784) (xy 415.387294 -143.944612)
			(xy 415.327326 -143.944612) (xy 415.26787 -143.936784) (xy 415.209945 -143.921263) (xy 415.154541 -143.898314)
			(xy 415.102607 -143.86833) (xy 415.055031 -143.831824) (xy 415.012626 -143.789419) (xy 414.97612 -143.741843)
			(xy 414.946136 -143.689909) (xy 414.923187 -143.634505) (xy 414.907666 -143.57658) (xy 414.899838 -143.517124)
			(xy 414.899348 -143.48714) (xy 408.582876 -143.48714) (xy 408.582876 -145.287238) (xy 413.045148 -145.287238)
			(xy 413.045148 -144.423638) (xy 413.045638 -144.393654) (xy 413.053466 -144.334198) (xy 413.068987 -144.276273)
			(xy 413.091936 -144.220869) (xy 413.12192 -144.168935) (xy 413.158426 -144.121359) (xy 413.200831 -144.078954)
			(xy 413.248407 -144.042448) (xy 413.300341 -144.012464) (xy 413.355745 -143.989515) (xy 413.41367 -143.973994)
			(xy 413.473126 -143.966166) (xy 413.533094 -143.966166) (xy 413.59255 -143.973994) (xy 413.650475 -143.989515)
			(xy 413.705879 -144.012464) (xy 413.757813 -144.042448) (xy 413.805389 -144.078954) (xy 413.847794 -144.121359)
			(xy 413.8843 -144.168935) (xy 413.914284 -144.220869) (xy 413.937233 -144.276273) (xy 413.952754 -144.334198)
			(xy 413.960582 -144.393654) (xy 413.961072 -144.423638) (xy 413.961072 -145.285714) (xy 432.016408 -145.285714)
			(xy 432.016408 -144.422114) (xy 432.016898 -144.39213) (xy 432.024726 -144.332674) (xy 432.040247 -144.274749)
			(xy 432.063196 -144.219345) (xy 432.09318 -144.167411) (xy 432.129686 -144.119835) (xy 432.172091 -144.07743)
			(xy 432.219667 -144.040924) (xy 432.271601 -144.01094) (xy 432.327005 -143.987991) (xy 432.38493 -143.97247)
			(xy 432.444386 -143.964642) (xy 432.504354 -143.964642) (xy 432.56381 -143.97247) (xy 432.621735 -143.987991)
			(xy 432.677139 -144.01094) (xy 432.729073 -144.040924) (xy 432.776649 -144.07743) (xy 432.819054 -144.119835)
			(xy 432.85556 -144.167411) (xy 432.885544 -144.219345) (xy 432.908493 -144.274749) (xy 432.924014 -144.332674)
			(xy 432.931842 -144.39213) (xy 432.932332 -144.422114) (xy 432.932332 -145.285714) (xy 432.931842 -145.315698)
			(xy 432.924014 -145.375154) (xy 432.908493 -145.433079) (xy 432.885544 -145.488483) (xy 432.85556 -145.540417)
			(xy 432.819054 -145.587993) (xy 432.776649 -145.630398) (xy 432.729073 -145.666904) (xy 432.677139 -145.696888)
			(xy 432.621735 -145.719837) (xy 432.56381 -145.735358) (xy 432.504354 -145.743186) (xy 432.444386 -145.743186)
			(xy 432.38493 -145.735358) (xy 432.327005 -145.719837) (xy 432.271601 -145.696888) (xy 432.219667 -145.666904)
			(xy 432.172091 -145.630398) (xy 432.129686 -145.587993) (xy 432.09318 -145.540417) (xy 432.063196 -145.488483)
			(xy 432.040247 -145.433079) (xy 432.024726 -145.375154) (xy 432.016898 -145.315698) (xy 432.016408 -145.285714)
			(xy 413.961072 -145.285714) (xy 413.961072 -145.287238) (xy 413.960582 -145.317222) (xy 413.952754 -145.376678)
			(xy 413.937233 -145.434603) (xy 413.914284 -145.490007) (xy 413.8843 -145.541941) (xy 413.847794 -145.589517)
			(xy 413.805389 -145.631922) (xy 413.757813 -145.668428) (xy 413.705879 -145.698412) (xy 413.650475 -145.721361)
			(xy 413.59255 -145.736882) (xy 413.533094 -145.74471) (xy 413.473126 -145.74471) (xy 413.41367 -145.736882)
			(xy 413.355745 -145.721361) (xy 413.300341 -145.698412) (xy 413.248407 -145.668428) (xy 413.200831 -145.631922)
			(xy 413.158426 -145.589517) (xy 413.12192 -145.541941) (xy 413.091936 -145.490007) (xy 413.068987 -145.434603)
			(xy 413.053466 -145.376678) (xy 413.045638 -145.317222) (xy 413.045148 -145.287238) (xy 408.582876 -145.287238)
			(xy 408.582876 -147.087336) (xy 414.899348 -147.087336) (xy 414.899348 -146.223736) (xy 414.899838 -146.193752)
			(xy 414.907666 -146.134296) (xy 414.923187 -146.076371) (xy 414.946136 -146.020967) (xy 414.97612 -145.969033)
			(xy 415.012626 -145.921457) (xy 415.055031 -145.879052) (xy 415.102607 -145.842546) (xy 415.154541 -145.812562)
			(xy 415.209945 -145.789613) (xy 415.26787 -145.774092) (xy 415.327326 -145.766264) (xy 415.387294 -145.766264)
			(xy 415.44675 -145.774092) (xy 415.504675 -145.789613) (xy 415.560079 -145.812562) (xy 415.612013 -145.842546)
			(xy 415.659589 -145.879052) (xy 415.701994 -145.921457) (xy 415.7385 -145.969033) (xy 415.768484 -146.020967)
			(xy 415.791433 -146.076371) (xy 415.806954 -146.134296) (xy 415.814782 -146.193752) (xy 415.815272 -146.223736)
			(xy 415.815272 -147.079208) (xy 429.3743 -147.079208) (xy 429.3743 -146.215608) (xy 429.37479 -146.185624)
			(xy 429.382618 -146.126168) (xy 429.398139 -146.068243) (xy 429.421088 -146.012839) (xy 429.451072 -145.960905)
			(xy 429.487578 -145.913329) (xy 429.529983 -145.870924) (xy 429.577559 -145.834418) (xy 429.629493 -145.804434)
			(xy 429.684897 -145.781485) (xy 429.742822 -145.765964) (xy 429.802278 -145.758136) (xy 429.862246 -145.758136)
			(xy 429.921702 -145.765964) (xy 429.979627 -145.781485) (xy 430.035031 -145.804434) (xy 430.086965 -145.834418)
			(xy 430.134541 -145.870924) (xy 430.176946 -145.913329) (xy 430.213452 -145.960905) (xy 430.243436 -146.012839)
			(xy 430.266385 -146.068243) (xy 430.281906 -146.126168) (xy 430.289734 -146.185624) (xy 430.290224 -146.215608)
			(xy 430.290224 -147.079208) (xy 430.289734 -147.109192) (xy 430.281906 -147.168648) (xy 430.266385 -147.226573)
			(xy 430.243436 -147.281977) (xy 430.213452 -147.333911) (xy 430.176946 -147.381487) (xy 430.134541 -147.423892)
			(xy 430.086965 -147.460398) (xy 430.035031 -147.490382) (xy 429.979627 -147.513331) (xy 429.921702 -147.528852)
			(xy 429.862246 -147.53668) (xy 429.802278 -147.53668) (xy 429.742822 -147.528852) (xy 429.684897 -147.513331)
			(xy 429.629493 -147.490382) (xy 429.577559 -147.460398) (xy 429.529983 -147.423892) (xy 429.487578 -147.381487)
			(xy 429.451072 -147.333911) (xy 429.421088 -147.281977) (xy 429.398139 -147.226573) (xy 429.382618 -147.168648)
			(xy 429.37479 -147.109192) (xy 429.3743 -147.079208) (xy 415.815272 -147.079208) (xy 415.815272 -147.087336)
			(xy 415.814782 -147.11732) (xy 415.806954 -147.176776) (xy 415.791433 -147.234701) (xy 415.768484 -147.290105)
			(xy 415.7385 -147.342039) (xy 415.701994 -147.389615) (xy 415.659589 -147.43202) (xy 415.612013 -147.468526)
			(xy 415.560079 -147.49851) (xy 415.504675 -147.521459) (xy 415.44675 -147.53698) (xy 415.387294 -147.544808)
			(xy 415.327326 -147.544808) (xy 415.26787 -147.53698) (xy 415.209945 -147.521459) (xy 415.154541 -147.49851)
			(xy 415.102607 -147.468526) (xy 415.055031 -147.43202) (xy 415.012626 -147.389615) (xy 414.97612 -147.342039)
			(xy 414.946136 -147.290105) (xy 414.923187 -147.234701) (xy 414.907666 -147.176776) (xy 414.899838 -147.11732)
			(xy 414.899348 -147.087336) (xy 408.582876 -147.087336) (xy 408.582876 -148.887434) (xy 413.045148 -148.887434)
			(xy 413.045148 -148.023834) (xy 413.045638 -147.99385) (xy 413.053466 -147.934394) (xy 413.068987 -147.876469)
			(xy 413.091936 -147.821065) (xy 413.12192 -147.769131) (xy 413.158426 -147.721555) (xy 413.200831 -147.67915)
			(xy 413.248407 -147.642644) (xy 413.300341 -147.61266) (xy 413.355745 -147.589711) (xy 413.41367 -147.57419)
			(xy 413.473126 -147.566362) (xy 413.533094 -147.566362) (xy 413.59255 -147.57419) (xy 413.650475 -147.589711)
			(xy 413.705879 -147.61266) (xy 413.757813 -147.642644) (xy 413.805389 -147.67915) (xy 413.847794 -147.721555)
			(xy 413.8843 -147.769131) (xy 413.914284 -147.821065) (xy 413.937233 -147.876469) (xy 413.952754 -147.934394)
			(xy 413.960582 -147.99385) (xy 413.961072 -148.023834) (xy 413.961072 -148.88591) (xy 432.016408 -148.88591)
			(xy 432.016408 -148.02231) (xy 432.016898 -147.992326) (xy 432.024726 -147.93287) (xy 432.040247 -147.874945)
			(xy 432.063196 -147.819541) (xy 432.09318 -147.767607) (xy 432.129686 -147.720031) (xy 432.172091 -147.677626)
			(xy 432.219667 -147.64112) (xy 432.271601 -147.611136) (xy 432.327005 -147.588187) (xy 432.38493 -147.572666)
			(xy 432.444386 -147.564838) (xy 432.504354 -147.564838) (xy 432.56381 -147.572666) (xy 432.621735 -147.588187)
			(xy 432.677139 -147.611136) (xy 432.729073 -147.64112) (xy 432.776649 -147.677626) (xy 432.819054 -147.720031)
			(xy 432.85556 -147.767607) (xy 432.885544 -147.819541) (xy 432.908493 -147.874945) (xy 432.924014 -147.93287)
			(xy 432.931842 -147.992326) (xy 432.932332 -148.02231) (xy 432.932332 -148.88591) (xy 432.931842 -148.915894)
			(xy 432.924014 -148.97535) (xy 432.908493 -149.033275) (xy 432.885544 -149.088679) (xy 432.85556 -149.140613)
			(xy 432.819054 -149.188189) (xy 432.776649 -149.230594) (xy 432.729073 -149.2671) (xy 432.677139 -149.297084)
			(xy 432.621735 -149.320033) (xy 432.56381 -149.335554) (xy 432.504354 -149.343382) (xy 432.444386 -149.343382)
			(xy 432.38493 -149.335554) (xy 432.327005 -149.320033) (xy 432.271601 -149.297084) (xy 432.219667 -149.2671)
			(xy 432.172091 -149.230594) (xy 432.129686 -149.188189) (xy 432.09318 -149.140613) (xy 432.063196 -149.088679)
			(xy 432.040247 -149.033275) (xy 432.024726 -148.97535) (xy 432.016898 -148.915894) (xy 432.016408 -148.88591)
			(xy 413.961072 -148.88591) (xy 413.961072 -148.887434) (xy 413.960582 -148.917418) (xy 413.952754 -148.976874)
			(xy 413.937233 -149.034799) (xy 413.914284 -149.090203) (xy 413.8843 -149.142137) (xy 413.847794 -149.189713)
			(xy 413.805389 -149.232118) (xy 413.757813 -149.268624) (xy 413.705879 -149.298608) (xy 413.650475 -149.321557)
			(xy 413.59255 -149.337078) (xy 413.533094 -149.344906) (xy 413.473126 -149.344906) (xy 413.41367 -149.337078)
			(xy 413.355745 -149.321557) (xy 413.300341 -149.298608) (xy 413.248407 -149.268624) (xy 413.200831 -149.232118)
			(xy 413.158426 -149.189713) (xy 413.12192 -149.142137) (xy 413.091936 -149.090203) (xy 413.068987 -149.034799)
			(xy 413.053466 -148.976874) (xy 413.045638 -148.917418) (xy 413.045148 -148.887434) (xy 408.582876 -148.887434)
			(xy 408.582876 -150.687278) (xy 414.899348 -150.687278) (xy 414.899348 -149.823678) (xy 414.899838 -149.793694)
			(xy 414.907666 -149.734238) (xy 414.923187 -149.676313) (xy 414.946136 -149.620909) (xy 414.97612 -149.568975)
			(xy 415.012626 -149.521399) (xy 415.055031 -149.478994) (xy 415.102607 -149.442488) (xy 415.154541 -149.412504)
			(xy 415.209945 -149.389555) (xy 415.26787 -149.374034) (xy 415.327326 -149.366206) (xy 415.387294 -149.366206)
			(xy 415.44675 -149.374034) (xy 415.504675 -149.389555) (xy 415.560079 -149.412504) (xy 415.612013 -149.442488)
			(xy 415.659589 -149.478994) (xy 415.701994 -149.521399) (xy 415.7385 -149.568975) (xy 415.768484 -149.620909)
			(xy 415.791433 -149.676313) (xy 415.806954 -149.734238) (xy 415.814782 -149.793694) (xy 415.815272 -149.823678)
			(xy 415.815272 -150.67915) (xy 429.3743 -150.67915) (xy 429.3743 -149.81555) (xy 429.37479 -149.785566)
			(xy 429.382618 -149.72611) (xy 429.398139 -149.668185) (xy 429.421088 -149.612781) (xy 429.451072 -149.560847)
			(xy 429.487578 -149.513271) (xy 429.529983 -149.470866) (xy 429.577559 -149.43436) (xy 429.629493 -149.404376)
			(xy 429.684897 -149.381427) (xy 429.742822 -149.365906) (xy 429.802278 -149.358078) (xy 429.862246 -149.358078)
			(xy 429.921702 -149.365906) (xy 429.979627 -149.381427) (xy 430.035031 -149.404376) (xy 430.086965 -149.43436)
			(xy 430.134541 -149.470866) (xy 430.176946 -149.513271) (xy 430.213452 -149.560847) (xy 430.243436 -149.612781)
			(xy 430.266385 -149.668185) (xy 430.281906 -149.72611) (xy 430.289734 -149.785566) (xy 430.290224 -149.81555)
			(xy 430.290224 -150.67915) (xy 430.289734 -150.709134) (xy 430.281906 -150.76859) (xy 430.266385 -150.826515)
			(xy 430.243436 -150.881919) (xy 430.213452 -150.933853) (xy 430.176946 -150.981429) (xy 430.134541 -151.023834)
			(xy 430.086965 -151.06034) (xy 430.035031 -151.090324) (xy 429.979627 -151.113273) (xy 429.921702 -151.128794)
			(xy 429.862246 -151.136622) (xy 429.802278 -151.136622) (xy 429.742822 -151.128794) (xy 429.684897 -151.113273)
			(xy 429.629493 -151.090324) (xy 429.577559 -151.06034) (xy 429.529983 -151.023834) (xy 429.487578 -150.981429)
			(xy 429.451072 -150.933853) (xy 429.421088 -150.881919) (xy 429.398139 -150.826515) (xy 429.382618 -150.76859)
			(xy 429.37479 -150.709134) (xy 429.3743 -150.67915) (xy 415.815272 -150.67915) (xy 415.815272 -150.687278)
			(xy 415.814782 -150.717262) (xy 415.806954 -150.776718) (xy 415.791433 -150.834643) (xy 415.768484 -150.890047)
			(xy 415.7385 -150.941981) (xy 415.701994 -150.989557) (xy 415.659589 -151.031962) (xy 415.612013 -151.068468)
			(xy 415.560079 -151.098452) (xy 415.504675 -151.121401) (xy 415.44675 -151.136922) (xy 415.387294 -151.14475)
			(xy 415.327326 -151.14475) (xy 415.26787 -151.136922) (xy 415.209945 -151.121401) (xy 415.154541 -151.098452)
			(xy 415.102607 -151.068468) (xy 415.055031 -151.031962) (xy 415.012626 -150.989557) (xy 414.97612 -150.941981)
			(xy 414.946136 -150.890047) (xy 414.923187 -150.834643) (xy 414.907666 -150.776718) (xy 414.899838 -150.717262)
			(xy 414.899348 -150.687278) (xy 408.582876 -150.687278) (xy 408.582876 -152.487376) (xy 413.045148 -152.487376)
			(xy 413.045148 -151.623776) (xy 413.045638 -151.593792) (xy 413.053466 -151.534336) (xy 413.068987 -151.476411)
			(xy 413.091936 -151.421007) (xy 413.12192 -151.369073) (xy 413.158426 -151.321497) (xy 413.200831 -151.279092)
			(xy 413.248407 -151.242586) (xy 413.300341 -151.212602) (xy 413.355745 -151.189653) (xy 413.41367 -151.174132)
			(xy 413.473126 -151.166304) (xy 413.533094 -151.166304) (xy 413.59255 -151.174132) (xy 413.650475 -151.189653)
			(xy 413.705879 -151.212602) (xy 413.757813 -151.242586) (xy 413.805389 -151.279092) (xy 413.847794 -151.321497)
			(xy 413.8843 -151.369073) (xy 413.914284 -151.421007) (xy 413.937233 -151.476411) (xy 413.952754 -151.534336)
			(xy 413.960582 -151.593792) (xy 413.961072 -151.623776) (xy 413.961072 -152.485852) (xy 432.016408 -152.485852)
			(xy 432.016408 -151.622252) (xy 432.016898 -151.592268) (xy 432.024726 -151.532812) (xy 432.040247 -151.474887)
			(xy 432.063196 -151.419483) (xy 432.09318 -151.367549) (xy 432.129686 -151.319973) (xy 432.172091 -151.277568)
			(xy 432.219667 -151.241062) (xy 432.271601 -151.211078) (xy 432.327005 -151.188129) (xy 432.38493 -151.172608)
			(xy 432.444386 -151.16478) (xy 432.504354 -151.16478) (xy 432.56381 -151.172608) (xy 432.621735 -151.188129)
			(xy 432.677139 -151.211078) (xy 432.729073 -151.241062) (xy 432.776649 -151.277568) (xy 432.819054 -151.319973)
			(xy 432.85556 -151.367549) (xy 432.885544 -151.419483) (xy 432.908493 -151.474887) (xy 432.924014 -151.532812)
			(xy 432.931842 -151.592268) (xy 432.932332 -151.622252) (xy 432.932332 -152.485852) (xy 432.931842 -152.515836)
			(xy 432.924014 -152.575292) (xy 432.908493 -152.633217) (xy 432.885544 -152.688621) (xy 432.85556 -152.740555)
			(xy 432.819054 -152.788131) (xy 432.776649 -152.830536) (xy 432.729073 -152.867042) (xy 432.677139 -152.897026)
			(xy 432.621735 -152.919975) (xy 432.56381 -152.935496) (xy 432.504354 -152.943324) (xy 432.444386 -152.943324)
			(xy 432.38493 -152.935496) (xy 432.327005 -152.919975) (xy 432.271601 -152.897026) (xy 432.219667 -152.867042)
			(xy 432.172091 -152.830536) (xy 432.129686 -152.788131) (xy 432.09318 -152.740555) (xy 432.063196 -152.688621)
			(xy 432.040247 -152.633217) (xy 432.024726 -152.575292) (xy 432.016898 -152.515836) (xy 432.016408 -152.485852)
			(xy 413.961072 -152.485852) (xy 413.961072 -152.487376) (xy 413.960582 -152.51736) (xy 413.952754 -152.576816)
			(xy 413.937233 -152.634741) (xy 413.914284 -152.690145) (xy 413.8843 -152.742079) (xy 413.847794 -152.789655)
			(xy 413.805389 -152.83206) (xy 413.757813 -152.868566) (xy 413.705879 -152.89855) (xy 413.650475 -152.921499)
			(xy 413.59255 -152.93702) (xy 413.533094 -152.944848) (xy 413.473126 -152.944848) (xy 413.41367 -152.93702)
			(xy 413.355745 -152.921499) (xy 413.300341 -152.89855) (xy 413.248407 -152.868566) (xy 413.200831 -152.83206)
			(xy 413.158426 -152.789655) (xy 413.12192 -152.742079) (xy 413.091936 -152.690145) (xy 413.068987 -152.634741)
			(xy 413.053466 -152.576816) (xy 413.045638 -152.51736) (xy 413.045148 -152.487376) (xy 408.582876 -152.487376)
			(xy 408.582876 -154.28722) (xy 414.899348 -154.28722) (xy 414.899348 -153.42362) (xy 414.899838 -153.393636)
			(xy 414.907666 -153.33418) (xy 414.923187 -153.276255) (xy 414.946136 -153.220851) (xy 414.97612 -153.168917)
			(xy 415.012626 -153.121341) (xy 415.055031 -153.078936) (xy 415.102607 -153.04243) (xy 415.154541 -153.012446)
			(xy 415.209945 -152.989497) (xy 415.26787 -152.973976) (xy 415.327326 -152.966148) (xy 415.387294 -152.966148)
			(xy 415.44675 -152.973976) (xy 415.504675 -152.989497) (xy 415.560079 -153.012446) (xy 415.612013 -153.04243)
			(xy 415.659589 -153.078936) (xy 415.701994 -153.121341) (xy 415.7385 -153.168917) (xy 415.768484 -153.220851)
			(xy 415.791433 -153.276255) (xy 415.806954 -153.33418) (xy 415.814782 -153.393636) (xy 415.815272 -153.42362)
			(xy 415.815272 -154.279346) (xy 429.3743 -154.279346) (xy 429.3743 -153.415746) (xy 429.37479 -153.385762)
			(xy 429.382618 -153.326306) (xy 429.398139 -153.268381) (xy 429.421088 -153.212977) (xy 429.451072 -153.161043)
			(xy 429.487578 -153.113467) (xy 429.529983 -153.071062) (xy 429.577559 -153.034556) (xy 429.629493 -153.004572)
			(xy 429.684897 -152.981623) (xy 429.742822 -152.966102) (xy 429.802278 -152.958274) (xy 429.862246 -152.958274)
			(xy 429.921702 -152.966102) (xy 429.979627 -152.981623) (xy 430.035031 -153.004572) (xy 430.086965 -153.034556)
			(xy 430.134541 -153.071062) (xy 430.176946 -153.113467) (xy 430.213452 -153.161043) (xy 430.243436 -153.212977)
			(xy 430.266385 -153.268381) (xy 430.281906 -153.326306) (xy 430.289734 -153.385762) (xy 430.290224 -153.415746)
			(xy 430.290224 -154.279346) (xy 430.289734 -154.30933) (xy 430.281906 -154.368786) (xy 430.266385 -154.426711)
			(xy 430.243436 -154.482115) (xy 430.213452 -154.534049) (xy 430.176946 -154.581625) (xy 430.134541 -154.62403)
			(xy 430.086965 -154.660536) (xy 430.035031 -154.69052) (xy 429.979627 -154.713469) (xy 429.921702 -154.72899)
			(xy 429.862246 -154.736818) (xy 429.802278 -154.736818) (xy 429.742822 -154.72899) (xy 429.684897 -154.713469)
			(xy 429.629493 -154.69052) (xy 429.577559 -154.660536) (xy 429.529983 -154.62403) (xy 429.487578 -154.581625)
			(xy 429.451072 -154.534049) (xy 429.421088 -154.482115) (xy 429.398139 -154.426711) (xy 429.382618 -154.368786)
			(xy 429.37479 -154.30933) (xy 429.3743 -154.279346) (xy 415.815272 -154.279346) (xy 415.815272 -154.28722)
			(xy 415.814782 -154.317204) (xy 415.806954 -154.37666) (xy 415.791433 -154.434585) (xy 415.768484 -154.489989)
			(xy 415.7385 -154.541923) (xy 415.701994 -154.589499) (xy 415.659589 -154.631904) (xy 415.612013 -154.66841)
			(xy 415.560079 -154.698394) (xy 415.504675 -154.721343) (xy 415.44675 -154.736864) (xy 415.387294 -154.744692)
			(xy 415.327326 -154.744692) (xy 415.26787 -154.736864) (xy 415.209945 -154.721343) (xy 415.154541 -154.698394)
			(xy 415.102607 -154.66841) (xy 415.055031 -154.631904) (xy 415.012626 -154.589499) (xy 414.97612 -154.541923)
			(xy 414.946136 -154.489989) (xy 414.923187 -154.434585) (xy 414.907666 -154.37666) (xy 414.899838 -154.317204)
			(xy 414.899348 -154.28722) (xy 408.582876 -154.28722) (xy 408.582876 -156.087318) (xy 413.045148 -156.087318)
			(xy 413.045148 -155.223718) (xy 413.045638 -155.193734) (xy 413.053466 -155.134278) (xy 413.068987 -155.076353)
			(xy 413.091936 -155.020949) (xy 413.12192 -154.969015) (xy 413.158426 -154.921439) (xy 413.200831 -154.879034)
			(xy 413.248407 -154.842528) (xy 413.300341 -154.812544) (xy 413.355745 -154.789595) (xy 413.41367 -154.774074)
			(xy 413.473126 -154.766246) (xy 413.533094 -154.766246) (xy 413.59255 -154.774074) (xy 413.650475 -154.789595)
			(xy 413.705879 -154.812544) (xy 413.757813 -154.842528) (xy 413.805389 -154.879034) (xy 413.847794 -154.921439)
			(xy 413.8843 -154.969015) (xy 413.914284 -155.020949) (xy 413.937233 -155.076353) (xy 413.952754 -155.134278)
			(xy 413.960582 -155.193734) (xy 413.961072 -155.223718) (xy 413.961072 -156.085794) (xy 432.016408 -156.085794)
			(xy 432.016408 -155.222194) (xy 432.016898 -155.19221) (xy 432.024726 -155.132754) (xy 432.040247 -155.074829)
			(xy 432.063196 -155.019425) (xy 432.09318 -154.967491) (xy 432.129686 -154.919915) (xy 432.172091 -154.87751)
			(xy 432.219667 -154.841004) (xy 432.271601 -154.81102) (xy 432.327005 -154.788071) (xy 432.38493 -154.77255)
			(xy 432.444386 -154.764722) (xy 432.504354 -154.764722) (xy 432.56381 -154.77255) (xy 432.621735 -154.788071)
			(xy 432.677139 -154.81102) (xy 432.729073 -154.841004) (xy 432.776649 -154.87751) (xy 432.819054 -154.919915)
			(xy 432.85556 -154.967491) (xy 432.885544 -155.019425) (xy 432.908493 -155.074829) (xy 432.924014 -155.132754)
			(xy 432.931842 -155.19221) (xy 432.932332 -155.222194) (xy 432.932332 -156.085794) (xy 432.931842 -156.115778)
			(xy 432.924014 -156.175234) (xy 432.908493 -156.233159) (xy 432.885544 -156.288563) (xy 432.85556 -156.340497)
			(xy 432.819054 -156.388073) (xy 432.776649 -156.430478) (xy 432.729073 -156.466984) (xy 432.677139 -156.496968)
			(xy 432.621735 -156.519917) (xy 432.56381 -156.535438) (xy 432.504354 -156.543266) (xy 432.444386 -156.543266)
			(xy 432.38493 -156.535438) (xy 432.327005 -156.519917) (xy 432.271601 -156.496968) (xy 432.219667 -156.466984)
			(xy 432.172091 -156.430478) (xy 432.129686 -156.388073) (xy 432.09318 -156.340497) (xy 432.063196 -156.288563)
			(xy 432.040247 -156.233159) (xy 432.024726 -156.175234) (xy 432.016898 -156.115778) (xy 432.016408 -156.085794)
			(xy 413.961072 -156.085794) (xy 413.961072 -156.087318) (xy 413.960582 -156.117302) (xy 413.952754 -156.176758)
			(xy 413.937233 -156.234683) (xy 413.914284 -156.290087) (xy 413.8843 -156.342021) (xy 413.847794 -156.389597)
			(xy 413.805389 -156.432002) (xy 413.757813 -156.468508) (xy 413.705879 -156.498492) (xy 413.650475 -156.521441)
			(xy 413.59255 -156.536962) (xy 413.533094 -156.54479) (xy 413.473126 -156.54479) (xy 413.41367 -156.536962)
			(xy 413.355745 -156.521441) (xy 413.300341 -156.498492) (xy 413.248407 -156.468508) (xy 413.200831 -156.432002)
			(xy 413.158426 -156.389597) (xy 413.12192 -156.342021) (xy 413.091936 -156.290087) (xy 413.068987 -156.234683)
			(xy 413.053466 -156.176758) (xy 413.045638 -156.117302) (xy 413.045148 -156.087318) (xy 408.582876 -156.087318)
			(xy 408.582876 -157.045152) (xy 409.710634 -157.045152) (xy 409.714705 -156.98953) (xy 409.726831 -156.935093)
			(xy 409.746754 -156.883002) (xy 409.77405 -156.834367) (xy 409.808136 -156.790224) (xy 409.848285 -156.751515)
			(xy 409.893643 -156.719064) (xy 409.943243 -156.693563) (xy 409.996027 -156.675556) (xy 410.05087 -156.665426)
			(xy 410.106604 -156.663389) (xy 410.162041 -156.669489) (xy 410.215998 -156.683595) (xy 410.267327 -156.705407)
			(xy 410.314933 -156.734461) (xy 410.357801 -156.770136) (xy 410.395018 -156.811673) (xy 410.425791 -156.858186)
			(xy 410.449463 -156.908683) (xy 410.465531 -156.96209) (xy 410.473651 -157.017266) (xy 410.47416 -157.045152)
			(xy 410.473651 -157.073038) (xy 410.473345 -157.07512) (xy 410.651434 -157.07512) (xy 410.651434 -157.015184)
			(xy 410.659257 -156.955762) (xy 410.67477 -156.897869) (xy 410.697706 -156.842496) (xy 410.727673 -156.79059)
			(xy 410.76416 -156.74304) (xy 410.80654 -156.70066) (xy 410.85409 -156.664173) (xy 410.905996 -156.634206)
			(xy 410.961369 -156.61127) (xy 411.019262 -156.595757) (xy 411.078684 -156.587934) (xy 411.13862 -156.587934)
			(xy 411.198042 -156.595757) (xy 411.255935 -156.61127) (xy 411.311308 -156.634206) (xy 411.363214 -156.664173)
			(xy 411.410764 -156.70066) (xy 411.453144 -156.74304) (xy 411.489631 -156.79059) (xy 411.519598 -156.842496)
			(xy 411.542534 -156.897869) (xy 411.558047 -156.955762) (xy 411.56587 -157.015184) (xy 411.56636 -157.045152)
			(xy 411.56587 -157.07512) (xy 411.558047 -157.134542) (xy 411.542534 -157.192435) (xy 411.519598 -157.247808)
			(xy 411.489631 -157.299714) (xy 411.453144 -157.347264) (xy 411.410764 -157.389644) (xy 411.363214 -157.426131)
			(xy 411.311308 -157.456098) (xy 411.255935 -157.479034) (xy 411.198042 -157.494547) (xy 411.13862 -157.50237)
			(xy 411.078684 -157.50237) (xy 411.019262 -157.494547) (xy 410.961369 -157.479034) (xy 410.905996 -157.456098)
			(xy 410.85409 -157.426131) (xy 410.80654 -157.389644) (xy 410.76416 -157.347264) (xy 410.727673 -157.299714)
			(xy 410.697706 -157.247808) (xy 410.67477 -157.192435) (xy 410.659257 -157.134542) (xy 410.651434 -157.07512)
			(xy 410.473345 -157.07512) (xy 410.465531 -157.128214) (xy 410.449463 -157.181621) (xy 410.425791 -157.232118)
			(xy 410.395018 -157.278631) (xy 410.357801 -157.320168) (xy 410.314933 -157.355843) (xy 410.267327 -157.384897)
			(xy 410.215998 -157.406709) (xy 410.162041 -157.420815) (xy 410.106604 -157.426915) (xy 410.05087 -157.424878)
			(xy 409.996027 -157.414748) (xy 409.943243 -157.396741) (xy 409.893643 -157.37124) (xy 409.848285 -157.338789)
			(xy 409.808136 -157.30008) (xy 409.77405 -157.255937) (xy 409.746754 -157.207302) (xy 409.726831 -157.155211)
			(xy 409.714705 -157.100774) (xy 409.710634 -157.045152) (xy 408.582876 -157.045152) (xy 408.582876 -158.219648)
			(xy 429.482248 -158.219648) (xy 429.486319 -158.164026) (xy 429.498445 -158.109589) (xy 429.518368 -158.057498)
			(xy 429.545664 -158.008863) (xy 429.57975 -157.96472) (xy 429.619899 -157.926011) (xy 429.665257 -157.89356)
			(xy 429.714857 -157.868059) (xy 429.767641 -157.850052) (xy 429.822484 -157.839922) (xy 429.878218 -157.837885)
			(xy 429.933655 -157.843985) (xy 429.987612 -157.858091) (xy 430.038941 -157.879903) (xy 430.086547 -157.908957)
			(xy 430.129415 -157.944632) (xy 430.166632 -157.986169) (xy 430.197405 -158.032682) (xy 430.221077 -158.083179)
			(xy 430.237145 -158.136586) (xy 430.245265 -158.191762) (xy 430.245774 -158.219648) (xy 430.245265 -158.247534)
			(xy 430.237145 -158.30271) (xy 430.221077 -158.356117) (xy 430.197405 -158.406614) (xy 430.166632 -158.453127)
			(xy 430.129415 -158.494664) (xy 430.086547 -158.530339) (xy 430.038941 -158.559393) (xy 429.987612 -158.581205)
			(xy 429.933655 -158.595311) (xy 429.878218 -158.601411) (xy 429.822484 -158.599374) (xy 429.767641 -158.589244)
			(xy 429.714857 -158.571237) (xy 429.665257 -158.545736) (xy 429.619899 -158.513285) (xy 429.57975 -158.474576)
			(xy 429.545664 -158.430433) (xy 429.518368 -158.381798) (xy 429.498445 -158.329707) (xy 429.486319 -158.27527)
			(xy 429.482248 -158.219648) (xy 408.582876 -158.219648) (xy 408.582876 -160.1851) (xy 418.189169 -160.1851)
			(xy 418.193124 -160.093263) (xy 418.204959 -160.002106) (xy 418.224586 -159.912303) (xy 418.25186 -159.824521)
			(xy 418.28658 -159.739407) (xy 418.328488 -159.657594) (xy 418.377274 -159.579686) (xy 418.432577 -159.506261)
			(xy 418.493987 -159.437861) (xy 418.561049 -159.374994) (xy 418.633268 -159.318124) (xy 418.710108 -159.267673)
			(xy 418.791001 -159.224014) (xy 418.875347 -159.187471) (xy 418.962523 -159.158314) (xy 419.051882 -159.13676)
			(xy 419.142763 -159.122966) (xy 419.234494 -159.117036) (xy 419.326395 -159.119014) (xy 419.417786 -159.128885)
			(xy 419.50799 -159.146575) (xy 419.596339 -159.171955) (xy 419.682179 -159.204835) (xy 419.745663 -159.235648)
			(xy 429.639982 -159.235648) (xy 429.644053 -159.180026) (xy 429.656179 -159.125589) (xy 429.676102 -159.073498)
			(xy 429.703398 -159.024863) (xy 429.737484 -158.98072) (xy 429.777633 -158.942011) (xy 429.822991 -158.90956)
			(xy 429.872591 -158.884059) (xy 429.925375 -158.866052) (xy 429.980218 -158.855922) (xy 430.035952 -158.853885)
			(xy 430.091389 -158.859985) (xy 430.145346 -158.874091) (xy 430.196675 -158.895903) (xy 430.244281 -158.924957)
			(xy 430.287149 -158.960632) (xy 430.324366 -159.002169) (xy 430.355139 -159.048682) (xy 430.378811 -159.099179)
			(xy 430.394879 -159.152586) (xy 430.402999 -159.207762) (xy 430.403508 -159.235648) (xy 430.402999 -159.263534)
			(xy 430.394879 -159.31871) (xy 430.378811 -159.372117) (xy 430.355139 -159.422614) (xy 430.324366 -159.469127)
			(xy 430.287149 -159.510664) (xy 430.244281 -159.546339) (xy 430.196675 -159.575393) (xy 430.145346 -159.597205)
			(xy 430.091389 -159.611311) (xy 430.035952 -159.617411) (xy 429.980218 -159.615374) (xy 429.925375 -159.605244)
			(xy 429.872591 -159.587237) (xy 429.822991 -159.561736) (xy 429.777633 -159.529285) (xy 429.737484 -159.490576)
			(xy 429.703398 -159.446433) (xy 429.676102 -159.397798) (xy 429.656179 -159.345707) (xy 429.644053 -159.29127)
			(xy 429.639982 -159.235648) (xy 419.745663 -159.235648) (xy 419.764875 -159.244973) (xy 419.843815 -159.292072)
			(xy 419.918413 -159.345782) (xy 419.988119 -159.405706) (xy 420.052414 -159.4714) (xy 420.110825 -159.542378)
			(xy 420.162917 -159.618115) (xy 420.208306 -159.69805) (xy 420.246656 -159.78159) (xy 420.277681 -159.868118)
			(xy 420.301154 -159.956993) (xy 420.3169 -160.047557) (xy 420.324802 -160.139139) (xy 420.325296 -160.1851)
			(xy 420.324802 -160.231061) (xy 420.3169 -160.322643) (xy 420.301154 -160.413207) (xy 420.277681 -160.502082)
			(xy 420.246656 -160.58861) (xy 420.208306 -160.67215) (xy 420.162917 -160.752085) (xy 420.110825 -160.827822)
			(xy 420.052414 -160.8988) (xy 419.988119 -160.964494) (xy 419.918413 -161.024418) (xy 419.843815 -161.078128)
			(xy 419.764875 -161.125227) (xy 419.682179 -161.165365) (xy 419.596339 -161.198245) (xy 419.50799 -161.223625)
			(xy 419.417786 -161.241315) (xy 419.326395 -161.251186) (xy 419.234494 -161.253164) (xy 419.142763 -161.247234)
			(xy 419.051882 -161.23344) (xy 418.962523 -161.211886) (xy 418.875347 -161.182729) (xy 418.791001 -161.146186)
			(xy 418.710108 -161.102527) (xy 418.633268 -161.052076) (xy 418.561049 -160.995206) (xy 418.493987 -160.932339)
			(xy 418.432577 -160.863939) (xy 418.377274 -160.790514) (xy 418.328488 -160.712606) (xy 418.28658 -160.630793)
			(xy 418.25186 -160.545679) (xy 418.224586 -160.457897) (xy 418.204959 -160.368094) (xy 418.193124 -160.276937)
			(xy 418.189169 -160.1851) (xy 408.582876 -160.1851) (xy 408.582876 -160.800034) (xy 408.583305 -160.810102)
			(xy 408.591025 -160.8287) (xy 408.597862 -160.836102) (xy 411.147768 -163.386008) (xy 412.932878 -163.386008)
			(xy 412.936949 -163.330386) (xy 412.949075 -163.275949) (xy 412.968998 -163.223858) (xy 412.996294 -163.175223)
			(xy 413.03038 -163.13108) (xy 413.070529 -163.092371) (xy 413.115887 -163.05992) (xy 413.165487 -163.034419)
			(xy 413.218271 -163.016412) (xy 413.273114 -163.006282) (xy 413.328848 -163.004245) (xy 413.384285 -163.010345)
			(xy 413.438242 -163.024451) (xy 413.489571 -163.046263) (xy 413.537177 -163.075317) (xy 413.580045 -163.110992)
			(xy 413.617262 -163.152529) (xy 413.648035 -163.199042) (xy 413.671707 -163.249539) (xy 413.687775 -163.302946)
			(xy 413.695895 -163.358122) (xy 413.696404 -163.386008) (xy 413.695895 -163.413894) (xy 413.687775 -163.46907)
			(xy 413.671707 -163.522477) (xy 413.648035 -163.572974) (xy 413.617262 -163.619487) (xy 413.580045 -163.661024)
			(xy 413.537177 -163.696699) (xy 413.489571 -163.725753) (xy 413.438242 -163.747565) (xy 413.384285 -163.761671)
			(xy 413.328848 -163.767771) (xy 413.273114 -163.765734) (xy 413.218271 -163.755604) (xy 413.165487 -163.737597)
			(xy 413.115887 -163.712096) (xy 413.070529 -163.679645) (xy 413.03038 -163.640936) (xy 412.996294 -163.596793)
			(xy 412.968998 -163.548158) (xy 412.949075 -163.496067) (xy 412.936949 -163.44163) (xy 412.932878 -163.386008)
			(xy 411.147768 -163.386008) (xy 413.973772 -166.212012) (xy 414.001251 -166.240287) (xy 414.050398 -166.301945)
			(xy 414.092337 -166.368716) (xy 414.126539 -166.439761) (xy 414.152576 -166.514187) (xy 414.17012 -166.591059)
			(xy 414.178951 -166.669412) (xy 414.179512 -166.708836) (xy 414.179512 -166.840154) (xy 414.180041 -166.850145)
			(xy 414.187745 -166.868588) (xy 414.194498 -166.875968) (xy 415.306002 -167.987472) (xy 415.333239 -168.015504)
			(xy 415.381955 -168.076628) (xy 415.423525 -168.142819) (xy 415.457428 -168.213246) (xy 415.483239 -168.287024)
			(xy 415.500633 -168.363227) (xy 415.509392 -168.440897) (xy 415.509964 -168.479978) (xy 415.509964 -169.631868)
			(xy 415.510495 -169.641859) (xy 415.518196 -169.660303) (xy 415.52495 -169.667682) (xy 448.437508 -202.580494)
			(xy 448.464987 -202.60877) (xy 448.514133 -202.670428) (xy 448.556071 -202.737199) (xy 448.590273 -202.808243)
			(xy 448.616311 -202.882669) (xy 448.633856 -202.959541) (xy 448.642689 -203.037894) (xy 448.643248 -203.077318)
			(xy 448.643248 -208.411572) (xy 448.642697 -208.450997) (xy 448.633873 -208.529352) (xy 448.616331 -208.606227)
			(xy 448.590294 -208.680654) (xy 448.556088 -208.751698) (xy 448.514143 -208.818467) (xy 448.464987 -208.88012)
			(xy 448.437508 -208.908396) (xy 447.78676 -209.559144) (xy 447.759507 -209.585672) (xy 447.700231 -209.633328)
			(xy 447.636152 -209.6743) (xy 447.568022 -209.708109) (xy 447.496637 -209.734359) (xy 447.459862 -209.744056)
			(xy 447.457322 -209.744818) (xy 447.424633 -209.75425) (xy 447.357888 -209.767463) (xy 447.290174 -209.774119)
			(xy 447.256154 -209.774536) (xy 446.747392 -209.774536) (xy 446.741174 -209.774681) (xy 446.729097 -209.777634)
			(xy 446.723516 -209.780378) (xy 446.703704 -209.791046) (xy 446.69456 -209.797142) (xy 446.690242 -209.800952)
			(xy 446.686686 -209.805524) (xy 446.686432 -209.806032) (xy 446.668263 -209.829442) (xy 446.625916 -209.870893)
			(xy 446.577681 -209.905314) (xy 446.524714 -209.931883) (xy 446.471974 -209.94878) (xy 451.460108 -209.94878)
			(xy 451.46069 -209.915496) (xy 451.469427 -209.849503) (xy 451.486695 -209.785212) (xy 451.512201 -209.723723)
			(xy 451.545509 -209.666086) (xy 451.58605 -209.613285) (xy 451.609206 -209.58937) (xy 453.584056 -207.61452)
			(xy 453.607977 -207.59138) (xy 453.660785 -207.550872) (xy 453.718426 -207.517601) (xy 453.779916 -207.492135)
			(xy 453.844204 -207.47491) (xy 453.910189 -207.466222) (xy 453.943466 -207.465676) (xy 454.924414 -207.465676)
			(xy 454.95636 -207.466118) (xy 455.019749 -207.474128) (xy 455.081634 -207.490019) (xy 455.14104 -207.513541)
			(xy 455.197029 -207.544322) (xy 455.248719 -207.581878) (xy 455.295294 -207.625617) (xy 455.33602 -207.674847)
			(xy 455.370255 -207.728794) (xy 455.397459 -207.786606) (xy 455.417203 -207.847372) (xy 455.429175 -207.910133)
			(xy 455.433187 -207.9739) (xy 455.429175 -208.037667) (xy 455.417203 -208.100428) (xy 455.397459 -208.161194)
			(xy 455.370255 -208.219006) (xy 455.33602 -208.272953) (xy 455.295294 -208.322183) (xy 455.248719 -208.365922)
			(xy 455.197029 -208.403478) (xy 455.14104 -208.434259) (xy 455.081634 -208.457781) (xy 455.019749 -208.473672)
			(xy 454.95636 -208.481682) (xy 454.924414 -208.482184) (xy 454.175114 -208.482184) (xy 454.165043 -208.482594)
			(xy 454.146444 -208.490323) (xy 454.139046 -208.49717) (xy 452.328026 -210.30819) (xy 452.304121 -210.331362)
			(xy 452.251331 -210.371927) (xy 452.193697 -210.405252) (xy 452.132204 -210.430765) (xy 452.067906 -210.448031)
			(xy 452.001904 -210.456752) (xy 451.968616 -210.457288) (xy 451.937883 -210.456847) (xy 451.876866 -210.44944)
			(xy 451.817187 -210.434732) (xy 451.759716 -210.412937) (xy 451.705291 -210.384373) (xy 451.654706 -210.349457)
			(xy 451.608699 -210.308698) (xy 451.56794 -210.262691) (xy 451.533025 -210.212106) (xy 451.504462 -210.15768)
			(xy 451.482667 -210.100209) (xy 451.467959 -210.04053) (xy 451.460552 -209.979513) (xy 451.460108 -209.94878)
			(xy 446.471974 -209.94878) (xy 446.468282 -209.949963) (xy 446.409736 -209.959121) (xy 446.380108 -209.959702)
			(xy 446.354198 -209.959267) (xy 446.302856 -209.952244) (xy 446.25294 -209.938328) (xy 446.228978 -209.92846)
			(xy 446.220493 -209.925216) (xy 446.202363 -209.924308) (xy 446.185051 -209.929769) (xy 446.17767 -209.935064)
			(xy 446.144277 -209.96029) (xy 446.072593 -210.003487) (xy 445.996285 -210.037862) (xy 445.916434 -210.062928)
			(xy 445.87541 -210.071208) (xy 445.86144 -210.074002) (xy 445.840612 -210.092544) (xy 445.809878 -210.192112)
			(xy 445.807546 -210.201003) (xy 445.80866 -210.219335) (xy 445.816146 -210.236106) (xy 445.822324 -210.242912)
			(xy 447.569082 -211.98967) (xy 447.575919 -211.997072) (xy 447.583631 -212.01567) (xy 447.584068 -212.025738)
			(xy 447.584068 -212.336888) (xy 447.585084 -212.375496) (xy 447.585084 -216.618063) (xy 454.507341 -216.618063)
			(xy 454.507341 -216.502737) (xy 454.515386 -216.387691) (xy 454.531436 -216.273487) (xy 454.555414 -216.160681)
			(xy 454.587202 -216.049822) (xy 454.626646 -215.94145) (xy 454.673554 -215.836094) (xy 454.727696 -215.734267)
			(xy 454.78881 -215.636465) (xy 454.856597 -215.543164) (xy 454.930727 -215.454819) (xy 455.01084 -215.37186)
			(xy 455.096544 -215.294691) (xy 455.187423 -215.223689) (xy 455.283033 -215.159199) (xy 455.382908 -215.101536)
			(xy 455.486563 -215.05098) (xy 455.593492 -215.007778) (xy 455.703174 -214.97214) (xy 455.815075 -214.94424)
			(xy 455.928649 -214.924214) (xy 456.043344 -214.912159) (xy 456.1586 -214.908135) (xy 456.273856 -214.912159)
			(xy 456.388551 -214.924214) (xy 456.502125 -214.94424) (xy 456.614026 -214.97214) (xy 456.723708 -215.007778)
			(xy 456.830637 -215.05098) (xy 456.934292 -215.101536) (xy 457.034167 -215.159199) (xy 457.129777 -215.223689)
			(xy 457.220656 -215.294691) (xy 457.30636 -215.37186) (xy 457.386473 -215.454819) (xy 457.460603 -215.543164)
			(xy 457.52839 -215.636465) (xy 457.589504 -215.734267) (xy 457.643646 -215.836094) (xy 457.690554 -215.94145)
			(xy 457.729998 -216.049822) (xy 457.761786 -216.160681) (xy 457.785764 -216.273487) (xy 457.801814 -216.387691)
			(xy 457.809859 -216.502737) (xy 457.810362 -216.5604) (xy 457.809859 -216.618063) (xy 457.801814 -216.733109)
			(xy 457.785764 -216.847313) (xy 457.761786 -216.960119) (xy 457.729998 -217.070978) (xy 457.690554 -217.17935)
			(xy 457.643646 -217.284706) (xy 457.589504 -217.386533) (xy 457.52839 -217.484335) (xy 457.460603 -217.577636)
			(xy 457.386473 -217.665981) (xy 457.30636 -217.74894) (xy 457.220656 -217.826109) (xy 457.129777 -217.897111)
			(xy 457.034167 -217.961601) (xy 456.934292 -218.019264) (xy 456.830637 -218.06982) (xy 456.723708 -218.113022)
			(xy 456.614026 -218.14866) (xy 456.502125 -218.17656) (xy 456.388551 -218.196586) (xy 456.273856 -218.208641)
			(xy 456.1586 -218.212666) (xy 456.043344 -218.208641) (xy 455.928649 -218.196586) (xy 455.815075 -218.17656)
			(xy 455.703174 -218.14866) (xy 455.593492 -218.113022) (xy 455.486563 -218.06982) (xy 455.382908 -218.019264)
			(xy 455.283033 -217.961601) (xy 455.187423 -217.897111) (xy 455.096544 -217.826109) (xy 455.01084 -217.74894)
			(xy 454.930727 -217.665981) (xy 454.856597 -217.577636) (xy 454.78881 -217.484335) (xy 454.727696 -217.386533)
			(xy 454.673554 -217.284706) (xy 454.626646 -217.17935) (xy 454.587202 -217.070978) (xy 454.555414 -216.960119)
			(xy 454.531436 -216.847313) (xy 454.515386 -216.733109) (xy 454.507341 -216.618063) (xy 447.585084 -216.618063)
			(xy 447.585084 -219.347796) (xy 447.606928 -219.375482) (xy 447.6242 -219.379546) (xy 447.651669 -219.386602)
			(xy 447.704298 -219.40773) (xy 447.753218 -219.436418) (xy 447.797351 -219.472035) (xy 447.835722 -219.513794)
			(xy 447.867487 -219.560775) (xy 447.891944 -219.611942) (xy 447.908554 -219.666167) (xy 447.916951 -219.722253)
			(xy 447.916949 -219.778965) (xy 447.90855 -219.835051) (xy 447.891937 -219.889275) (xy 447.867477 -219.940441)
			(xy 447.835711 -219.987421) (xy 447.797337 -220.029178) (xy 447.753203 -220.064792) (xy 447.704281 -220.093478)
			(xy 447.651651 -220.114604) (xy 447.6242 -220.121734) (xy 447.606928 -220.125798) (xy 447.585084 -220.153484)
			(xy 447.585084 -222.0976) (xy 451.742046 -222.0976) (xy 451.746117 -222.041978) (xy 451.758243 -221.987541)
			(xy 451.778166 -221.93545) (xy 451.805462 -221.886815) (xy 451.839548 -221.842672) (xy 451.879697 -221.803963)
			(xy 451.925055 -221.771512) (xy 451.974655 -221.746011) (xy 452.027439 -221.728004) (xy 452.082282 -221.717874)
			(xy 452.138016 -221.715837) (xy 452.193453 -221.721937) (xy 452.24741 -221.736043) (xy 452.298739 -221.757855)
			(xy 452.346345 -221.786909) (xy 452.389213 -221.822584) (xy 452.42643 -221.864121) (xy 452.457203 -221.910634)
			(xy 452.480875 -221.961131) (xy 452.496943 -222.014538) (xy 452.505063 -222.069714) (xy 452.505572 -222.0976)
			(xy 452.505063 -222.125486) (xy 452.496943 -222.180662) (xy 452.480875 -222.234069) (xy 452.457203 -222.284566)
			(xy 452.42643 -222.331079) (xy 452.389213 -222.372616) (xy 452.346345 -222.408291) (xy 452.298739 -222.437345)
			(xy 452.24741 -222.459157) (xy 452.193453 -222.473263) (xy 452.138016 -222.479363) (xy 452.082282 -222.477326)
			(xy 452.027439 -222.467196) (xy 451.974655 -222.449189) (xy 451.925055 -222.423688) (xy 451.879697 -222.391237)
			(xy 451.839548 -222.352528) (xy 451.805462 -222.308385) (xy 451.778166 -222.25975) (xy 451.758243 -222.207659)
			(xy 451.746117 -222.153222) (xy 451.742046 -222.0976) (xy 447.585084 -222.0976) (xy 447.585084 -226.681538)
			(xy 457.325982 -226.681538) (xy 457.330053 -226.625916) (xy 457.342179 -226.571479) (xy 457.362102 -226.519388)
			(xy 457.389398 -226.470753) (xy 457.423484 -226.42661) (xy 457.463633 -226.387901) (xy 457.508991 -226.35545)
			(xy 457.558591 -226.329949) (xy 457.611375 -226.311942) (xy 457.666218 -226.301812) (xy 457.721952 -226.299775)
			(xy 457.777389 -226.305875) (xy 457.831346 -226.319981) (xy 457.882675 -226.341793) (xy 457.930281 -226.370847)
			(xy 457.973149 -226.406522) (xy 458.010366 -226.448059) (xy 458.041139 -226.494572) (xy 458.064811 -226.545069)
			(xy 458.080879 -226.598476) (xy 458.088999 -226.653652) (xy 458.089508 -226.681538) (xy 458.088999 -226.709424)
			(xy 458.080879 -226.7646) (xy 458.064811 -226.818007) (xy 458.041139 -226.868504) (xy 458.010366 -226.915017)
			(xy 457.973149 -226.956554) (xy 457.930281 -226.992229) (xy 457.882675 -227.021283) (xy 457.831346 -227.043095)
			(xy 457.777389 -227.057201) (xy 457.721952 -227.063301) (xy 457.666218 -227.061264) (xy 457.611375 -227.051134)
			(xy 457.558591 -227.033127) (xy 457.508991 -227.007626) (xy 457.463633 -226.975175) (xy 457.423484 -226.936466)
			(xy 457.389398 -226.892323) (xy 457.362102 -226.843688) (xy 457.342179 -226.791597) (xy 457.330053 -226.73716)
			(xy 457.325982 -226.681538) (xy 447.585084 -226.681538) (xy 447.585084 -229.661212) (xy 447.585375 -229.669086)
			(xy 447.590153 -229.684093) (xy 447.594482 -229.690676) (xy 447.614756 -229.72029) (xy 447.649836 -229.782907)
			(xy 447.678342 -229.848778) (xy 447.699975 -229.917214) (xy 447.714511 -229.9875) (xy 447.721797 -230.058903)
			(xy 447.722244 -230.09479) (xy 447.722244 -230.49865) (xy 447.721692 -230.539657) (xy 447.712196 -230.621118)
			(xy 447.693281 -230.70092) (xy 447.665205 -230.777977) (xy 447.647314 -230.81488) (xy 447.642515 -230.825813)
			(xy 447.642532 -230.849658) (xy 447.647314 -230.8606) (xy 447.665227 -230.897493) (xy 447.693303 -230.974553)
			(xy 447.712215 -231.054358) (xy 447.721705 -231.135822) (xy 447.722244 -231.17683) (xy 447.722244 -231.58069)
			(xy 447.721695 -231.621698) (xy 447.712206 -231.703161) (xy 447.693297 -231.782966) (xy 447.665226 -231.860027)
			(xy 447.647314 -231.89692) (xy 447.642501 -231.907854) (xy 447.642492 -231.931711) (xy 447.647314 -231.94264)
			(xy 447.665225 -231.979533) (xy 447.693297 -232.056594) (xy 447.712204 -232.136399) (xy 447.721689 -232.217862)
			(xy 447.722244 -232.25887) (xy 447.722244 -232.66273) (xy 447.721841 -232.69448) (xy 451.24192 -232.69448)
			(xy 451.245991 -232.638858) (xy 451.258117 -232.584421) (xy 451.27804 -232.53233) (xy 451.305336 -232.483695)
			(xy 451.339422 -232.439552) (xy 451.379571 -232.400843) (xy 451.424929 -232.368392) (xy 451.474529 -232.342891)
			(xy 451.527313 -232.324884) (xy 451.582156 -232.314754) (xy 451.63789 -232.312717) (xy 451.693327 -232.318817)
			(xy 451.747284 -232.332923) (xy 451.798613 -232.354735) (xy 451.846219 -232.383789) (xy 451.889087 -232.419464)
			(xy 451.926304 -232.461001) (xy 451.957077 -232.507514) (xy 451.980749 -232.558011) (xy 451.996817 -232.611418)
			(xy 452.004937 -232.666594) (xy 452.005446 -232.69448) (xy 452.004937 -232.722366) (xy 451.996817 -232.777542)
			(xy 451.980749 -232.830949) (xy 451.957077 -232.881446) (xy 451.926304 -232.927959) (xy 451.889087 -232.969496)
			(xy 451.846219 -233.005171) (xy 451.798613 -233.034225) (xy 451.747284 -233.056037) (xy 451.693327 -233.070143)
			(xy 451.63789 -233.076243) (xy 451.582156 -233.074206) (xy 451.527313 -233.064076) (xy 451.474529 -233.046069)
			(xy 451.424929 -233.020568) (xy 451.379571 -232.988117) (xy 451.339422 -232.949408) (xy 451.305336 -232.905265)
			(xy 451.27804 -232.85663) (xy 451.258117 -232.804539) (xy 451.245991 -232.750102) (xy 451.24192 -232.69448)
			(xy 447.721841 -232.69448) (xy 447.721789 -232.698615) (xy 447.714468 -232.77001) (xy 447.699915 -232.840289)
			(xy 447.678281 -232.90872) (xy 447.649792 -232.974593) (xy 447.614743 -233.037223) (xy 447.594482 -233.066844)
			(xy 447.590156 -233.07343) (xy 447.585377 -233.088434) (xy 447.585084 -233.096308) (xy 447.585084 -235.335826)
			(xy 447.585511 -235.345894) (xy 447.593231 -235.364494) (xy 447.60007 -235.371894) (xy 447.606166 -235.37799)
			(xy 447.613568 -235.384827) (xy 447.632166 -235.392539) (xy 447.642234 -235.392976) (xy 448.018916 -235.392976)
			(xy 448.028933 -235.392553) (xy 448.047441 -235.384879) (xy 448.061602 -235.370707) (xy 448.069261 -235.352194)
			(xy 448.069716 -235.342176) (xy 448.069716 -235.231686) (xy 448.069291 -235.221617) (xy 448.061575 -235.203014)
			(xy 448.05473 -235.195618) (xy 447.981832 -235.12272) (xy 447.954351 -235.094445) (xy 447.905201 -235.032788)
			(xy 447.86326 -234.966018) (xy 447.829054 -234.894974) (xy 447.803013 -234.820547) (xy 447.785465 -234.743675)
			(xy 447.776631 -234.665321) (xy 447.776092 -234.625896) (xy 447.776574 -234.589101) (xy 447.784266 -234.515913)
			(xy 447.799566 -234.443931) (xy 447.822306 -234.373942) (xy 447.852237 -234.306713) (xy 447.889032 -234.242981)
			(xy 447.932286 -234.183444) (xy 447.981526 -234.128754) (xy 448.036213 -234.079511) (xy 448.095748 -234.036253)
			(xy 448.159477 -233.999456) (xy 448.226704 -233.969521) (xy 448.296692 -233.946777) (xy 448.368674 -233.931472)
			(xy 448.441861 -233.923776) (xy 448.478656 -233.923332) (xy 448.514389 -233.923772) (xy 448.585485 -233.931022)
			(xy 448.655478 -233.945451) (xy 448.723645 -233.96691) (xy 448.789282 -233.995178) (xy 448.85171 -234.029962)
			(xy 448.881246 -234.050078) (xy 448.890058 -234.055651) (xy 448.910456 -234.059867) (xy 448.930854 -234.055651)
			(xy 448.939666 -234.050078) (xy 448.969209 -234.029974) (xy 449.031638 -233.995197) (xy 449.097275 -233.966933)
			(xy 449.16544 -233.945475) (xy 449.235431 -233.931044) (xy 449.306525 -233.923789) (xy 449.342256 -233.923332)
			(xy 449.379053 -233.923795) (xy 449.452244 -233.931483) (xy 449.524231 -233.94678) (xy 449.594224 -233.969518)
			(xy 449.661457 -233.999449) (xy 449.725193 -234.036243) (xy 449.784733 -234.079498) (xy 449.839426 -234.12874)
			(xy 449.888672 -234.183429) (xy 449.931931 -234.242967) (xy 449.96873 -234.3067) (xy 449.998664 -234.373931)
			(xy 450.021407 -234.443923) (xy 450.036709 -234.515908) (xy 450.044403 -234.589099) (xy 450.04482 -234.625896)
			(xy 450.044268 -234.665321) (xy 450.03544 -234.743674) (xy 450.017897 -234.820546) (xy 450.01295 -234.834684)
			(xy 450.697598 -234.834684) (xy 450.701669 -234.779062) (xy 450.713795 -234.724625) (xy 450.733718 -234.672534)
			(xy 450.761014 -234.623899) (xy 450.7951 -234.579756) (xy 450.835249 -234.541047) (xy 450.880607 -234.508596)
			(xy 450.930207 -234.483095) (xy 450.982991 -234.465088) (xy 451.037834 -234.454958) (xy 451.093568 -234.452921)
			(xy 451.149005 -234.459021) (xy 451.202962 -234.473127) (xy 451.254291 -234.494939) (xy 451.301897 -234.523993)
			(xy 451.344765 -234.559668) (xy 451.381982 -234.601205) (xy 451.412755 -234.647718) (xy 451.436427 -234.698215)
			(xy 451.452495 -234.751622) (xy 451.460615 -234.806798) (xy 451.461124 -234.834684) (xy 451.460615 -234.86257)
			(xy 451.452495 -234.917746) (xy 451.436427 -234.971153) (xy 451.412755 -235.02165) (xy 451.381982 -235.068163)
			(xy 451.344765 -235.1097) (xy 451.301897 -235.145375) (xy 451.254291 -235.174429) (xy 451.202962 -235.196241)
			(xy 451.149005 -235.210347) (xy 451.093568 -235.216447) (xy 451.037834 -235.21441) (xy 450.982991 -235.20428)
			(xy 450.930207 -235.186273) (xy 450.880607 -235.160772) (xy 450.835249 -235.128321) (xy 450.7951 -235.089612)
			(xy 450.761014 -235.045469) (xy 450.733718 -234.996834) (xy 450.713795 -234.944743) (xy 450.701669 -234.890306)
			(xy 450.697598 -234.834684) (xy 450.01295 -234.834684) (xy 449.991856 -234.894971) (xy 449.957648 -234.966013)
			(xy 449.915701 -235.032778) (xy 449.866542 -235.094428) (xy 449.83908 -235.12272) (xy 449.76415 -235.19765)
			(xy 449.757306 -235.205049) (xy 449.749582 -235.223648) (xy 449.749164 -235.233718) (xy 449.749164 -235.85805)
			(xy 449.748614 -235.897476) (xy 449.739792 -235.975832) (xy 449.722253 -236.052708) (xy 449.696218 -236.127138)
			(xy 449.662014 -236.198184) (xy 449.620071 -236.264955) (xy 449.570917 -236.32661) (xy 449.543424 -236.354874)
			(xy 449.509896 -236.388402) (xy 450.160898 -236.388402) (xy 450.161419 -236.359485) (xy 450.170147 -236.302314)
			(xy 450.187405 -236.247115) (xy 450.212796 -236.195154) (xy 450.245739 -236.14762) (xy 450.285479 -236.105603)
			(xy 450.307964 -236.087412) (xy 450.316727 -236.079852) (xy 450.326907 -236.059091) (xy 450.327522 -236.047534)
			(xy 450.327522 -235.96727) (xy 450.326904 -235.955709) (xy 450.316742 -235.934937) (xy 450.307964 -235.927392)
			(xy 450.285469 -235.909215) (xy 450.245736 -235.867191) (xy 450.2128 -235.819653) (xy 450.187414 -235.767689)
			(xy 450.170159 -235.71249) (xy 450.161432 -235.655319) (xy 450.160898 -235.626402) (xy 450.161384 -235.599151)
			(xy 450.16914 -235.545203) (xy 450.184495 -235.492908) (xy 450.207137 -235.443331) (xy 450.236603 -235.397481)
			(xy 450.272294 -235.35629) (xy 450.313485 -235.320599) (xy 450.359335 -235.291133) (xy 450.408912 -235.268491)
			(xy 450.461207 -235.253136) (xy 450.515155 -235.24538) (xy 450.569657 -235.24538) (xy 450.623605 -235.253136)
			(xy 450.6759 -235.268491) (xy 450.725477 -235.291133) (xy 450.771327 -235.320599) (xy 450.812518 -235.35629)
			(xy 450.848209 -235.397481) (xy 450.877675 -235.443331) (xy 450.900317 -235.492908) (xy 450.915672 -235.545203)
			(xy 450.923428 -235.599151) (xy 450.923914 -235.626402) (xy 450.92343 -235.655321) (xy 450.914698 -235.712495)
			(xy 450.897436 -235.767696) (xy 450.872038 -235.819658) (xy 450.839087 -235.867191) (xy 450.799338 -235.909204)
			(xy 450.776848 -235.927392) (xy 450.768085 -235.934953) (xy 450.757904 -235.955713) (xy 450.75729 -235.96727)
			(xy 450.75729 -236.047534) (xy 450.757902 -236.059096) (xy 450.768068 -236.079868) (xy 450.776848 -236.087412)
			(xy 450.799347 -236.105584) (xy 450.839079 -236.147609) (xy 450.872015 -236.195149) (xy 450.8974 -236.247113)
			(xy 450.914654 -236.302313) (xy 450.921397 -236.346492) (xy 454.16038 -236.346492) (xy 454.164451 -236.29087)
			(xy 454.176577 -236.236433) (xy 454.1965 -236.184342) (xy 454.223796 -236.135707) (xy 454.257882 -236.091564)
			(xy 454.298031 -236.052855) (xy 454.343389 -236.020404) (xy 454.392989 -235.994903) (xy 454.445773 -235.976896)
			(xy 454.500616 -235.966766) (xy 454.55635 -235.964729) (xy 454.611787 -235.970829) (xy 454.665744 -235.984935)
			(xy 454.717073 -236.006747) (xy 454.764679 -236.035801) (xy 454.807547 -236.071476) (xy 454.844764 -236.113013)
			(xy 454.875537 -236.159526) (xy 454.899209 -236.210023) (xy 454.915277 -236.26343) (xy 454.922866 -236.314996)
			(xy 455.160378 -236.314996) (xy 455.164449 -236.259374) (xy 455.176575 -236.204937) (xy 455.196498 -236.152846)
			(xy 455.223794 -236.104211) (xy 455.25788 -236.060068) (xy 455.298029 -236.021359) (xy 455.343387 -235.988908)
			(xy 455.392987 -235.963407) (xy 455.445771 -235.9454) (xy 455.500614 -235.93527) (xy 455.556348 -235.933233)
			(xy 455.611785 -235.939333) (xy 455.665742 -235.953439) (xy 455.717071 -235.975251) (xy 455.764677 -236.004305)
			(xy 455.807545 -236.03998) (xy 455.844762 -236.081517) (xy 455.875535 -236.12803) (xy 455.899207 -236.178527)
			(xy 455.915275 -236.231934) (xy 455.923395 -236.28711) (xy 455.923904 -236.314996) (xy 455.923395 -236.342882)
			(xy 455.915275 -236.398058) (xy 455.910691 -236.413294) (xy 456.148692 -236.413294) (xy 456.152763 -236.357672)
			(xy 456.164889 -236.303235) (xy 456.184812 -236.251144) (xy 456.212108 -236.202509) (xy 456.246194 -236.158366)
			(xy 456.286343 -236.119657) (xy 456.331701 -236.087206) (xy 456.381301 -236.061705) (xy 456.434085 -236.043698)
			(xy 456.488928 -236.033568) (xy 456.544662 -236.031531) (xy 456.600099 -236.037631) (xy 456.654056 -236.051737)
			(xy 456.705385 -236.073549) (xy 456.752991 -236.102603) (xy 456.795859 -236.138278) (xy 456.833076 -236.179815)
			(xy 456.863849 -236.226328) (xy 456.887521 -236.276825) (xy 456.903589 -236.330232) (xy 456.911709 -236.385408)
			(xy 456.912218 -236.413294) (xy 456.911709 -236.44118) (xy 456.903589 -236.496356) (xy 456.887521 -236.549763)
			(xy 456.863849 -236.60026) (xy 456.833076 -236.646773) (xy 456.795859 -236.68831) (xy 456.752991 -236.723985)
			(xy 456.705385 -236.753039) (xy 456.654056 -236.774851) (xy 456.600099 -236.788957) (xy 456.544662 -236.795057)
			(xy 456.488928 -236.79302) (xy 456.434085 -236.78289) (xy 456.381301 -236.764883) (xy 456.331701 -236.739382)
			(xy 456.286343 -236.706931) (xy 456.246194 -236.668222) (xy 456.212108 -236.624079) (xy 456.184812 -236.575444)
			(xy 456.164889 -236.523353) (xy 456.152763 -236.468916) (xy 456.148692 -236.413294) (xy 455.910691 -236.413294)
			(xy 455.899207 -236.451465) (xy 455.875535 -236.501962) (xy 455.844762 -236.548475) (xy 455.807545 -236.590012)
			(xy 455.764677 -236.625687) (xy 455.717071 -236.654741) (xy 455.665742 -236.676553) (xy 455.611785 -236.690659)
			(xy 455.556348 -236.696759) (xy 455.500614 -236.694722) (xy 455.445771 -236.684592) (xy 455.392987 -236.666585)
			(xy 455.343387 -236.641084) (xy 455.298029 -236.608633) (xy 455.25788 -236.569924) (xy 455.223794 -236.525781)
			(xy 455.196498 -236.477146) (xy 455.176575 -236.425055) (xy 455.164449 -236.370618) (xy 455.160378 -236.314996)
			(xy 454.922866 -236.314996) (xy 454.923397 -236.318606) (xy 454.923906 -236.346492) (xy 454.923397 -236.374378)
			(xy 454.915277 -236.429554) (xy 454.899209 -236.482961) (xy 454.875537 -236.533458) (xy 454.844764 -236.579971)
			(xy 454.807547 -236.621508) (xy 454.764679 -236.657183) (xy 454.717073 -236.686237) (xy 454.665744 -236.708049)
			(xy 454.611787 -236.722155) (xy 454.55635 -236.728255) (xy 454.500616 -236.726218) (xy 454.445773 -236.716088)
			(xy 454.392989 -236.698081) (xy 454.343389 -236.67258) (xy 454.298031 -236.640129) (xy 454.257882 -236.60142)
			(xy 454.223796 -236.557277) (xy 454.1965 -236.508642) (xy 454.176577 -236.456551) (xy 454.164451 -236.402114)
			(xy 454.16038 -236.346492) (xy 450.921397 -236.346492) (xy 450.92338 -236.359485) (xy 450.923914 -236.388402)
			(xy 450.923428 -236.415653) (xy 450.915672 -236.469601) (xy 450.900317 -236.521896) (xy 450.877675 -236.571473)
			(xy 450.848209 -236.617323) (xy 450.812518 -236.658514) (xy 450.771327 -236.694205) (xy 450.725477 -236.723671)
			(xy 450.6759 -236.746313) (xy 450.623605 -236.761668) (xy 450.569657 -236.769424) (xy 450.515155 -236.769424)
			(xy 450.461207 -236.761668) (xy 450.408912 -236.746313) (xy 450.359335 -236.723671) (xy 450.313485 -236.694205)
			(xy 450.272294 -236.658514) (xy 450.236603 -236.617323) (xy 450.207137 -236.571473) (xy 450.184495 -236.521896)
			(xy 450.16914 -236.469601) (xy 450.161384 -236.415653) (xy 450.160898 -236.388402) (xy 449.509896 -236.388402)
			(xy 449.031614 -236.866684) (xy 449.003339 -236.894164) (xy 448.941681 -236.943313) (xy 448.874911 -236.985253)
			(xy 448.803866 -237.019457) (xy 448.72944 -237.045496) (xy 448.652568 -237.063043) (xy 448.574215 -237.071877)
			(xy 448.53479 -237.072424) (xy 447.216276 -237.072424) (xy 447.193672 -237.072304) (xy 447.148551 -237.06951)
			(xy 447.126106 -237.066836) (xy 447.122804 -237.066328) (xy 446.948814 -237.066328) (xy 446.938764 -237.065821)
			(xy 446.920205 -237.058099) (xy 446.912746 -237.051342) (xy 446.789556 -236.928152) (xy 446.787016 -236.92612)
			(xy 446.769298 -236.912227) (xy 446.735489 -236.882487) (xy 446.719452 -236.866684) (xy 446.111376 -236.258608)
			(xy 446.095584 -236.242561) (xy 446.065841 -236.208754) (xy 446.05194 -236.191044) (xy 446.049908 -236.188504)
			(xy 445.944498 -236.083094) (xy 445.937653 -236.075695) (xy 445.929921 -236.057097) (xy 445.929512 -236.047026)
			(xy 445.929512 -235.943902) (xy 445.927988 -235.937806) (xy 445.917519 -235.894556) (xy 445.906306 -235.806278)
			(xy 445.905636 -235.761784) (xy 445.905636 -212.801454) (xy 445.905203 -212.791389) (xy 445.897469 -212.772803)
			(xy 445.89065 -212.765386) (xy 444.059056 -210.933792) (xy 444.031493 -210.9055) (xy 443.982225 -210.843758)
			(xy 443.960758 -210.810602) (xy 443.95771 -210.805776) (xy 443.912498 -210.760564) (xy 443.905658 -210.753163)
			(xy 443.897937 -210.734565) (xy 443.897512 -210.724496) (xy 443.897512 -210.68284) (xy 443.894464 -210.674458)
			(xy 443.881372 -210.636251) (xy 443.86303 -210.557595) (xy 443.853841 -210.477352) (xy 443.853316 -210.436968)
			(xy 443.853316 -201.935334) (xy 443.852881 -201.925269) (xy 443.845152 -201.90668) (xy 443.83833 -201.899266)
			(xy 411.26283 -169.32402) (xy 411.256294 -169.317905) (xy 411.240099 -169.310307) (xy 411.222276 -169.308777)
			(xy 411.205024 -169.313504) (xy 411.197552 -169.318432) (xy 411.174229 -169.334509) (xy 411.124375 -169.361408)
			(xy 411.071583 -169.381951) (xy 411.016661 -169.395824) (xy 410.960446 -169.402815) (xy 410.932122 -169.403268)
			(xy 410.902153 -169.4028) (xy 410.842728 -169.394979) (xy 410.784831 -169.379467) (xy 410.729456 -169.356531)
			(xy 410.677548 -169.326562) (xy 410.629996 -169.290074) (xy 410.587614 -169.24769) (xy 410.551128 -169.200137)
			(xy 410.521161 -169.148228) (xy 410.498227 -169.092851) (xy 410.482718 -169.034955) (xy 410.474899 -168.975529)
			(xy 410.474414 -168.94556) (xy 410.475144 -168.908844) (xy 410.486892 -168.836359) (xy 410.497782 -168.801288)
			(xy 410.501592 -168.789604) (xy 410.497782 -168.765474) (xy 410.44241 -168.688766) (xy 410.434804 -168.679371)
			(xy 410.413329 -168.668347) (xy 410.401262 -168.667684) (xy 407.118058 -168.667684) (xy 407.107992 -168.667253)
			(xy 407.0894 -168.659526) (xy 407.08199 -168.652698) (xy 406.637744 -168.208452) (xy 406.630345 -168.201609)
			(xy 406.611746 -168.193886) (xy 406.601676 -168.193466) (xy 405.697436 -168.193466) (xy 405.67864 -168.201086)
			(xy 405.671528 -168.208452) (xy 404.652988 -169.226992) (xy 404.646131 -169.234386) (xy 404.63838 -169.252985)
			(xy 404.638002 -169.26306) (xy 404.638002 -172.329348) (xy 410.148022 -172.329348) (xy 410.152093 -172.273726)
			(xy 410.164219 -172.219289) (xy 410.184142 -172.167198) (xy 410.211438 -172.118563) (xy 410.245524 -172.07442)
			(xy 410.285673 -172.035711) (xy 410.331031 -172.00326) (xy 410.380631 -171.977759) (xy 410.433415 -171.959752)
			(xy 410.488258 -171.949622) (xy 410.543992 -171.947585) (xy 410.599429 -171.953685) (xy 410.653386 -171.967791)
			(xy 410.704715 -171.989603) (xy 410.752321 -172.018657) (xy 410.795189 -172.054332) (xy 410.832406 -172.095869)
			(xy 410.863179 -172.142382) (xy 410.886851 -172.192879) (xy 410.902919 -172.246286) (xy 410.911039 -172.301462)
			(xy 410.911548 -172.329348) (xy 410.911284 -172.343826) (xy 411.085282 -172.343826) (xy 411.089353 -172.288204)
			(xy 411.101479 -172.233767) (xy 411.121402 -172.181676) (xy 411.148698 -172.133041) (xy 411.182784 -172.088898)
			(xy 411.222933 -172.050189) (xy 411.268291 -172.017738) (xy 411.317891 -171.992237) (xy 411.370675 -171.97423)
			(xy 411.425518 -171.9641) (xy 411.481252 -171.962063) (xy 411.536689 -171.968163) (xy 411.590646 -171.982269)
			(xy 411.641975 -172.004081) (xy 411.689581 -172.033135) (xy 411.732449 -172.06881) (xy 411.769666 -172.110347)
			(xy 411.800439 -172.15686) (xy 411.824111 -172.207357) (xy 411.840179 -172.260764) (xy 411.848299 -172.31594)
			(xy 411.848808 -172.343826) (xy 411.848299 -172.371712) (xy 411.840179 -172.426888) (xy 411.824111 -172.480295)
			(xy 411.800439 -172.530792) (xy 411.769666 -172.577305) (xy 411.732449 -172.618842) (xy 411.689581 -172.654517)
			(xy 411.641975 -172.683571) (xy 411.590646 -172.705383) (xy 411.536689 -172.719489) (xy 411.481252 -172.725589)
			(xy 411.425518 -172.723552) (xy 411.370675 -172.713422) (xy 411.317891 -172.695415) (xy 411.268291 -172.669914)
			(xy 411.222933 -172.637463) (xy 411.182784 -172.598754) (xy 411.148698 -172.554611) (xy 411.121402 -172.505976)
			(xy 411.101479 -172.453885) (xy 411.089353 -172.399448) (xy 411.085282 -172.343826) (xy 410.911284 -172.343826)
			(xy 410.911039 -172.357234) (xy 410.902919 -172.41241) (xy 410.886851 -172.465817) (xy 410.863179 -172.516314)
			(xy 410.832406 -172.562827) (xy 410.795189 -172.604364) (xy 410.752321 -172.640039) (xy 410.704715 -172.669093)
			(xy 410.653386 -172.690905) (xy 410.599429 -172.705011) (xy 410.543992 -172.711111) (xy 410.488258 -172.709074)
			(xy 410.433415 -172.698944) (xy 410.380631 -172.680937) (xy 410.331031 -172.655436) (xy 410.285673 -172.622985)
			(xy 410.245524 -172.584276) (xy 410.211438 -172.540133) (xy 410.184142 -172.491498) (xy 410.164219 -172.439407)
			(xy 410.152093 -172.38497) (xy 410.148022 -172.329348) (xy 404.638002 -172.329348) (xy 404.638002 -174.1932)
			(xy 408.892246 -174.1932) (xy 408.896317 -174.137578) (xy 408.908443 -174.083141) (xy 408.928366 -174.03105)
			(xy 408.955662 -173.982415) (xy 408.989748 -173.938272) (xy 409.029897 -173.899563) (xy 409.075255 -173.867112)
			(xy 409.124855 -173.841611) (xy 409.177639 -173.823604) (xy 409.232482 -173.813474) (xy 409.288216 -173.811437)
			(xy 409.343653 -173.817537) (xy 409.39761 -173.831643) (xy 409.448939 -173.853455) (xy 409.496545 -173.882509)
			(xy 409.539413 -173.918184) (xy 409.57663 -173.959721) (xy 409.607403 -174.006234) (xy 409.631075 -174.056731)
			(xy 409.647143 -174.110138) (xy 409.655263 -174.165314) (xy 409.655772 -174.1932) (xy 409.655263 -174.221086)
			(xy 409.647143 -174.276262) (xy 409.631075 -174.329669) (xy 409.607403 -174.380166) (xy 409.57663 -174.426679)
			(xy 409.539413 -174.468216) (xy 409.496545 -174.503891) (xy 409.448939 -174.532945) (xy 409.39761 -174.554757)
			(xy 409.343653 -174.568863) (xy 409.288216 -174.574963) (xy 409.232482 -174.572926) (xy 409.177639 -174.562796)
			(xy 409.124855 -174.544789) (xy 409.075255 -174.519288) (xy 409.029897 -174.486837) (xy 408.989748 -174.448128)
			(xy 408.955662 -174.403985) (xy 408.928366 -174.35535) (xy 408.908443 -174.303259) (xy 408.896317 -174.248822)
			(xy 408.892246 -174.1932) (xy 404.638002 -174.1932) (xy 404.638002 -175.83023) (xy 410.059884 -175.83023)
			(xy 410.063955 -175.774608) (xy 410.076081 -175.720171) (xy 410.096004 -175.66808) (xy 410.1233 -175.619445)
			(xy 410.157386 -175.575302) (xy 410.197535 -175.536593) (xy 410.242893 -175.504142) (xy 410.292493 -175.478641)
			(xy 410.345277 -175.460634) (xy 410.40012 -175.450504) (xy 410.455854 -175.448467) (xy 410.511291 -175.454567)
			(xy 410.565248 -175.468673) (xy 410.616577 -175.490485) (xy 410.664183 -175.519539) (xy 410.707051 -175.555214)
			(xy 410.744268 -175.596751) (xy 410.775041 -175.643264) (xy 410.798713 -175.693761) (xy 410.814781 -175.747168)
			(xy 410.822901 -175.802344) (xy 410.82341 -175.83023) (xy 410.822901 -175.858116) (xy 410.814781 -175.913292)
			(xy 410.798713 -175.966699) (xy 410.775041 -176.017196) (xy 410.744268 -176.063709) (xy 410.707051 -176.105246)
			(xy 410.664183 -176.140921) (xy 410.616577 -176.169975) (xy 410.565248 -176.191787) (xy 410.511291 -176.205893)
			(xy 410.455854 -176.211993) (xy 410.40012 -176.209956) (xy 410.345277 -176.199826) (xy 410.292493 -176.181819)
			(xy 410.242893 -176.156318) (xy 410.197535 -176.123867) (xy 410.157386 -176.085158) (xy 410.1233 -176.041015)
			(xy 410.096004 -175.99238) (xy 410.076081 -175.940289) (xy 410.063955 -175.885852) (xy 410.059884 -175.83023)
			(xy 404.638002 -175.83023) (xy 404.638002 -179.2986) (xy 409.269182 -179.2986) (xy 409.273253 -179.242978)
			(xy 409.285379 -179.188541) (xy 409.305302 -179.13645) (xy 409.332598 -179.087815) (xy 409.366684 -179.043672)
			(xy 409.406833 -179.004963) (xy 409.452191 -178.972512) (xy 409.501791 -178.947011) (xy 409.554575 -178.929004)
			(xy 409.609418 -178.918874) (xy 409.665152 -178.916837) (xy 409.720589 -178.922937) (xy 409.774546 -178.937043)
			(xy 409.825875 -178.958855) (xy 409.873481 -178.987909) (xy 409.916349 -179.023584) (xy 409.953566 -179.065121)
			(xy 409.984339 -179.111634) (xy 410.008011 -179.162131) (xy 410.024079 -179.215538) (xy 410.032199 -179.270714)
			(xy 410.032708 -179.2986) (xy 410.032199 -179.326486) (xy 410.024079 -179.381662) (xy 410.008011 -179.435069)
			(xy 409.984339 -179.485566) (xy 409.953566 -179.532079) (xy 409.916349 -179.573616) (xy 409.873481 -179.609291)
			(xy 409.825875 -179.638345) (xy 409.774546 -179.660157) (xy 409.720589 -179.674263) (xy 409.665152 -179.680363)
			(xy 409.609418 -179.678326) (xy 409.554575 -179.668196) (xy 409.501791 -179.650189) (xy 409.452191 -179.624688)
			(xy 409.406833 -179.592237) (xy 409.366684 -179.553528) (xy 409.332598 -179.509385) (xy 409.305302 -179.46075)
			(xy 409.285379 -179.408659) (xy 409.273253 -179.354222) (xy 409.269182 -179.2986) (xy 404.638002 -179.2986)
			(xy 404.638002 -181.370478) (xy 404.637564 -181.380542) (xy 404.62983 -181.399126) (xy 404.623016 -181.406546)
			(xy 403.75459 -182.274972) (xy 403.747192 -182.28182) (xy 403.728594 -182.289555) (xy 403.718522 -182.289958)
			(xy 387.735572 -182.289958) (xy 387.716776 -182.297578) (xy 387.709664 -182.304944) (xy 386.478018 -183.53659)
			(xy 386.471168 -183.543987) (xy 386.463427 -183.562585) (xy 386.463032 -183.572658) (xy 386.463032 -186.937142)
			(xy 408.89504 -186.937142) (xy 408.899111 -186.88152) (xy 408.911237 -186.827083) (xy 408.93116 -186.774992)
			(xy 408.958456 -186.726357) (xy 408.992542 -186.682214) (xy 409.032691 -186.643505) (xy 409.078049 -186.611054)
			(xy 409.127649 -186.585553) (xy 409.180433 -186.567546) (xy 409.235276 -186.557416) (xy 409.29101 -186.555379)
			(xy 409.346447 -186.561479) (xy 409.400404 -186.575585) (xy 409.451733 -186.597397) (xy 409.499339 -186.626451)
			(xy 409.542207 -186.662126) (xy 409.579424 -186.703663) (xy 409.610197 -186.750176) (xy 409.633869 -186.800673)
			(xy 409.649937 -186.85408) (xy 409.658057 -186.909256) (xy 409.658566 -186.937142) (xy 409.658057 -186.965028)
			(xy 409.649937 -187.020204) (xy 409.633869 -187.073611) (xy 409.610197 -187.124108) (xy 409.579424 -187.170621)
			(xy 409.542207 -187.212158) (xy 409.499339 -187.247833) (xy 409.451733 -187.276887) (xy 409.400404 -187.298699)
			(xy 409.346447 -187.312805) (xy 409.29101 -187.318905) (xy 409.235276 -187.316868) (xy 409.180433 -187.306738)
			(xy 409.127649 -187.288731) (xy 409.078049 -187.26323) (xy 409.032691 -187.230779) (xy 408.992542 -187.19207)
			(xy 408.958456 -187.147927) (xy 408.93116 -187.099292) (xy 408.911237 -187.047201) (xy 408.899111 -186.992764)
			(xy 408.89504 -186.937142) (xy 386.463032 -186.937142) (xy 386.463032 -188.982604) (xy 386.463453 -188.992622)
			(xy 386.471125 -189.011132) (xy 386.485298 -189.025296) (xy 386.503813 -189.032954) (xy 386.513832 -189.033404)
			(xy 407.251154 -189.033404) (xy 407.261145 -189.032875) (xy 407.27959 -189.025174) (xy 407.286968 -189.018418)
			(xy 408.7495 -187.555886) (xy 408.767663 -187.538452) (xy 408.808414 -187.508893) (xy 408.853284 -187.486066)
			(xy 408.901171 -187.470533) (xy 408.950897 -187.462675) (xy 408.976068 -187.46216) (xy 411.107382 -187.46216)
			(xy 411.126178 -187.454286) (xy 411.132528 -187.447936) (xy 411.139109 -187.419884) (xy 411.159571 -187.366022)
			(xy 411.187899 -187.315848) (xy 411.223447 -187.270503) (xy 411.265407 -187.231017) (xy 411.312827 -187.198287)
			(xy 411.364628 -187.173058) (xy 411.419633 -187.155903) (xy 411.476591 -187.147211) (xy 411.5054 -187.146692)
			(xy 411.526014 -187.146957) (xy 411.566999 -187.151411) (xy 411.587188 -187.155582) (xy 411.598618 -187.158122)
			(xy 411.620716 -187.152788) (xy 411.691582 -187.095892) (xy 411.700089 -187.088258) (xy 411.709971 -187.067681)
			(xy 411.710632 -187.056268) (xy 411.710632 -186.095132) (xy 411.710101 -186.085141) (xy 411.7024 -186.066698)
			(xy 411.695646 -186.059318) (xy 409.468066 -183.831738) (xy 409.460721 -183.824928) (xy 409.442258 -183.817202)
			(xy 409.432252 -183.816752) (xy 409.415488 -183.816752) (xy 409.40228 -183.820562) (xy 409.396438 -183.824118)
			(xy 409.374168 -183.836901) (xy 409.32693 -183.857037) (xy 409.277421 -183.870664) (xy 409.226533 -183.877537)
			(xy 409.200858 -183.877966) (xy 409.173612 -183.877477) (xy 409.119675 -183.869716) (xy 409.067391 -183.854359)
			(xy 409.017824 -183.831718) (xy 408.971984 -183.802254) (xy 408.930804 -183.766567) (xy 408.895121 -183.725382)
			(xy 408.865661 -183.679539) (xy 408.843026 -183.62997) (xy 408.827675 -183.577684) (xy 408.81992 -183.523746)
			(xy 408.81992 -183.469254) (xy 408.827675 -183.415316) (xy 408.843026 -183.36303) (xy 408.865661 -183.313461)
			(xy 408.895121 -183.267618) (xy 408.930804 -183.226433) (xy 408.971984 -183.190746) (xy 409.017824 -183.161282)
			(xy 409.067391 -183.138641) (xy 409.119675 -183.123284) (xy 409.173612 -183.115523) (xy 409.200858 -183.11495)
			(xy 409.226536 -183.115348) (xy 409.277431 -183.122203) (xy 409.326943 -183.135835) (xy 409.374175 -183.155997)
			(xy 409.396438 -183.168798) (xy 409.402384 -183.172165) (xy 409.415519 -183.175909) (xy 409.422346 -183.176164)
			(xy 409.585922 -183.176164) (xy 409.611102 -183.176604) (xy 409.660847 -183.184435) (xy 409.708752 -183.199961)
			(xy 409.753633 -183.222801) (xy 409.794382 -183.25239) (xy 409.81249 -183.26989) (xy 410.680916 -184.138316)
			(xy 410.688281 -184.145134) (xy 410.706788 -184.152859) (xy 410.726843 -184.152893) (xy 410.736288 -184.149492)
			(xy 410.750766 -184.143396) (xy 410.767784 -184.117996) (xy 410.767784 -179.842922) (xy 410.768229 -179.817744)
			(xy 410.776067 -179.768004) (xy 410.791601 -179.720105) (xy 410.814447 -179.675231) (xy 410.84404 -179.63449)
			(xy 410.86151 -179.616354) (xy 411.25394 -179.223924) (xy 411.260798 -179.211986) (xy 411.262576 -179.205128)
			(xy 411.269937 -179.178051) (xy 411.291515 -179.126256) (xy 411.320445 -179.078178) (xy 411.356104 -179.034856)
			(xy 411.397723 -178.997224) (xy 411.444405 -178.966092) (xy 411.495142 -178.942132) (xy 411.548842 -178.92586)
			(xy 411.604345 -178.917629) (xy 411.6324 -178.917092) (xy 411.659651 -178.917578) (xy 411.713599 -178.925334)
			(xy 411.765894 -178.940689) (xy 411.815471 -178.963331) (xy 411.861321 -178.992797) (xy 411.902512 -179.028488)
			(xy 411.938203 -179.069679) (xy 411.967669 -179.115529) (xy 411.990311 -179.165106) (xy 412.005666 -179.217401)
			(xy 412.013422 -179.271349) (xy 412.013908 -179.2986) (xy 412.013411 -179.326658) (xy 412.005188 -179.382168)
			(xy 411.988921 -179.435874) (xy 411.96496 -179.486617) (xy 411.933823 -179.533301) (xy 411.896181 -179.574919)
			(xy 411.852848 -179.610573) (xy 411.804758 -179.639492) (xy 411.752949 -179.661053) (xy 411.725872 -179.668424)
			(xy 411.719014 -179.670202) (xy 411.707076 -179.67706) (xy 411.423358 -179.960778) (xy 411.416553 -179.968125)
			(xy 411.40884 -179.986588) (xy 411.408372 -179.996592) (xy 411.408372 -180.699918) (xy 413.180782 -180.699918)
			(xy 413.184853 -180.644296) (xy 413.196979 -180.589859) (xy 413.216902 -180.537768) (xy 413.244198 -180.489133)
			(xy 413.278284 -180.44499) (xy 413.318433 -180.406281) (xy 413.363791 -180.37383) (xy 413.413391 -180.348329)
			(xy 413.466175 -180.330322) (xy 413.521018 -180.320192) (xy 413.576752 -180.318155) (xy 413.632189 -180.324255)
			(xy 413.686146 -180.338361) (xy 413.737475 -180.360173) (xy 413.785081 -180.389227) (xy 413.827949 -180.424902)
			(xy 413.865166 -180.466439) (xy 413.895939 -180.512952) (xy 413.919611 -180.563449) (xy 413.935679 -180.616856)
			(xy 413.943799 -180.672032) (xy 413.944308 -180.699918) (xy 413.943799 -180.727804) (xy 413.935679 -180.78298)
			(xy 413.919611 -180.836387) (xy 413.895939 -180.886884) (xy 413.865166 -180.933397) (xy 413.827949 -180.974934)
			(xy 413.785081 -181.010609) (xy 413.737475 -181.039663) (xy 413.686146 -181.061475) (xy 413.632189 -181.075581)
			(xy 413.576752 -181.081681) (xy 413.521018 -181.079644) (xy 413.466175 -181.069514) (xy 413.413391 -181.051507)
			(xy 413.363791 -181.026006) (xy 413.318433 -180.993555) (xy 413.278284 -180.954846) (xy 413.244198 -180.910703)
			(xy 413.216902 -180.862068) (xy 413.196979 -180.809977) (xy 413.184853 -180.75554) (xy 413.180782 -180.699918)
			(xy 411.408372 -180.699918) (xy 411.408372 -183.219598) (xy 411.408973 -183.230929) (xy 411.418734 -183.251378)
			(xy 411.427168 -183.258968) (xy 411.497272 -183.316118) (xy 411.519116 -183.321452) (xy 411.530546 -183.319166)
			(xy 411.549446 -183.315495) (xy 411.587748 -183.311546) (xy 411.607 -183.311292) (xy 411.635058 -183.311789)
			(xy 411.690568 -183.320012) (xy 411.744274 -183.336279) (xy 411.795017 -183.36024) (xy 411.841701 -183.391377)
			(xy 411.883319 -183.429019) (xy 411.918973 -183.472352) (xy 411.947892 -183.520442) (xy 411.969453 -183.572251)
			(xy 411.976824 -183.599328) (xy 411.978602 -183.606186) (xy 411.98546 -183.618124) (xy 413.10052 -184.733184)
			(xy 413.118009 -184.751313) (xy 413.147639 -184.792048) (xy 413.170527 -184.836918) (xy 413.186109 -184.884818)
			(xy 413.194001 -184.934567) (xy 413.194143 -184.941718) (xy 414.979864 -184.941718) (xy 414.983935 -184.886096)
			(xy 414.996061 -184.831659) (xy 415.015984 -184.779568) (xy 415.04328 -184.730933) (xy 415.077366 -184.68679)
			(xy 415.117515 -184.648081) (xy 415.162873 -184.61563) (xy 415.212473 -184.590129) (xy 415.265257 -184.572122)
			(xy 415.3201 -184.561992) (xy 415.375834 -184.559955) (xy 415.431271 -184.566055) (xy 415.485228 -184.580161)
			(xy 415.536557 -184.601973) (xy 415.584163 -184.631027) (xy 415.627031 -184.666702) (xy 415.664248 -184.708239)
			(xy 415.695021 -184.754752) (xy 415.718693 -184.805249) (xy 415.734761 -184.858656) (xy 415.742881 -184.913832)
			(xy 415.74339 -184.941718) (xy 415.742881 -184.969604) (xy 415.734761 -185.02478) (xy 415.718693 -185.078187)
			(xy 415.695021 -185.128684) (xy 415.664248 -185.175197) (xy 415.627031 -185.216734) (xy 415.584163 -185.252409)
			(xy 415.536557 -185.281463) (xy 415.485228 -185.303275) (xy 415.431271 -185.317381) (xy 415.375834 -185.323481)
			(xy 415.3201 -185.321444) (xy 415.265257 -185.311314) (xy 415.212473 -185.293307) (xy 415.162873 -185.267806)
			(xy 415.117515 -185.235355) (xy 415.077366 -185.196646) (xy 415.04328 -185.152503) (xy 415.015984 -185.103868)
			(xy 414.996061 -185.051777) (xy 414.983935 -184.99734) (xy 414.979864 -184.941718) (xy 413.194143 -184.941718)
			(xy 413.1945 -184.959752) (xy 413.1945 -189.434978) (xy 413.194845 -189.44455) (xy 413.20176 -189.462396)
			(xy 413.214746 -189.476455) (xy 413.223202 -189.480952) (xy 413.319214 -189.526672) (xy 413.34817 -189.52337)
			(xy 413.3596 -189.514226) (xy 413.380037 -189.4983) (xy 413.424396 -189.471528) (xy 413.471969 -189.451003)
			(xy 413.521882 -189.437103) (xy 413.573216 -189.430083) (xy 413.599122 -189.429644) (xy 413.626376 -189.430131)
			(xy 413.680328 -189.437891) (xy 413.732626 -189.45325) (xy 413.782207 -189.475896) (xy 413.828061 -189.505366)
			(xy 413.869253 -189.541062) (xy 413.904947 -189.582257) (xy 413.934415 -189.628112) (xy 413.957057 -189.677694)
			(xy 413.972413 -189.729994) (xy 413.98017 -189.783946) (xy 413.98017 -189.838454) (xy 413.972413 -189.892406)
			(xy 413.957057 -189.944706) (xy 413.934415 -189.994288) (xy 413.904947 -190.040143) (xy 413.869253 -190.081338)
			(xy 413.828061 -190.117034) (xy 413.782207 -190.146504) (xy 413.732626 -190.16915) (xy 413.680328 -190.184509)
			(xy 413.626376 -190.192269) (xy 413.599122 -190.19266) (xy 413.573215 -190.192227) (xy 413.521879 -190.185215)
			(xy 413.471964 -190.171317) (xy 413.424391 -190.150788) (xy 413.380035 -190.124008) (xy 413.3596 -190.108078)
			(xy 413.34817 -190.098934) (xy 413.319214 -190.095632) (xy 413.223202 -190.141352) (xy 413.214764 -190.145874)
			(xy 413.201784 -190.159928) (xy 413.194855 -190.177759) (xy 413.1945 -190.187326) (xy 413.1945 -190.551562)
			(xy 413.19398 -190.576742) (xy 413.186056 -190.626477) (xy 413.170461 -190.674364) (xy 413.147576 -190.719226)
			(xy 413.117964 -190.759963) (xy 413.10052 -190.77813) (xy 412.203138 -191.675512) (xy 412.196289 -191.682909)
			(xy 412.188553 -191.701508) (xy 412.188152 -191.71158) (xy 412.188152 -192.83172) (xy 412.188481 -192.840266)
			(xy 412.194109 -192.856404) (xy 412.204731 -192.869794) (xy 412.211774 -192.874646) (xy 412.29534 -192.927732)
			(xy 412.321248 -192.929256) (xy 412.333186 -192.923668) (xy 412.358759 -192.912124) (xy 412.412448 -192.895831)
			(xy 412.467947 -192.887589) (xy 412.496 -192.887092) (xy 412.523251 -192.887578) (xy 412.577199 -192.895334)
			(xy 412.629494 -192.910689) (xy 412.679071 -192.933331) (xy 412.724921 -192.962797) (xy 412.766112 -192.998488)
			(xy 412.801803 -193.039679) (xy 412.831269 -193.085529) (xy 412.853911 -193.135106) (xy 412.869266 -193.187401)
			(xy 412.877022 -193.241349) (xy 412.877022 -193.295851) (xy 412.869266 -193.349799) (xy 412.853911 -193.402094)
			(xy 412.831269 -193.451671) (xy 412.801803 -193.497521) (xy 412.766112 -193.538712) (xy 412.724921 -193.574403)
			(xy 412.679071 -193.603869) (xy 412.629494 -193.626511) (xy 412.577199 -193.641866) (xy 412.523251 -193.649622)
			(xy 412.496 -193.650108) (xy 412.467948 -193.649592) (xy 412.412454 -193.641342) (xy 412.358763 -193.625064)
			(xy 412.333186 -193.613532) (xy 412.321248 -193.607944) (xy 412.29534 -193.609468) (xy 412.211774 -193.662554)
			(xy 412.204719 -193.667397) (xy 412.194075 -193.680784) (xy 412.188435 -193.696929) (xy 412.188152 -193.70548)
			(xy 412.188152 -194.771518) (xy 412.187724 -194.781586) (xy 412.18 -194.800181) (xy 412.173166 -194.807586)
			(xy 412.051246 -194.929506) (xy 412.044431 -194.936849) (xy 412.036694 -194.955312) (xy 412.03626 -194.96532)
			(xy 412.03626 -195.241926) (xy 420.27043 -195.241926) (xy 420.274501 -195.186304) (xy 420.286627 -195.131867)
			(xy 420.30655 -195.079776) (xy 420.333846 -195.031141) (xy 420.367932 -194.986998) (xy 420.408081 -194.948289)
			(xy 420.453439 -194.915838) (xy 420.503039 -194.890337) (xy 420.555823 -194.87233) (xy 420.610666 -194.8622)
			(xy 420.6664 -194.860163) (xy 420.721837 -194.866263) (xy 420.775794 -194.880369) (xy 420.827123 -194.902181)
			(xy 420.874729 -194.931235) (xy 420.917597 -194.96691) (xy 420.954814 -195.008447) (xy 420.985587 -195.05496)
			(xy 421.009259 -195.105457) (xy 421.025327 -195.158864) (xy 421.033447 -195.21404) (xy 421.033956 -195.241926)
			(xy 421.033447 -195.269812) (xy 421.025327 -195.324988) (xy 421.009259 -195.378395) (xy 420.985587 -195.428892)
			(xy 420.954814 -195.475405) (xy 420.917597 -195.516942) (xy 420.874729 -195.552617) (xy 420.827123 -195.581671)
			(xy 420.775794 -195.603483) (xy 420.721837 -195.617589) (xy 420.6664 -195.623689) (xy 420.610666 -195.621652)
			(xy 420.555823 -195.611522) (xy 420.503039 -195.593515) (xy 420.453439 -195.568014) (xy 420.408081 -195.535563)
			(xy 420.367932 -195.496854) (xy 420.333846 -195.452711) (xy 420.30655 -195.404076) (xy 420.286627 -195.351985)
			(xy 420.274501 -195.297548) (xy 420.27043 -195.241926) (xy 412.03626 -195.241926) (xy 412.03626 -195.615052)
			(xy 412.035817 -195.640231) (xy 412.027983 -195.689975) (xy 412.012454 -195.737877) (xy 411.989613 -195.782756)
			(xy 411.960024 -195.823502) (xy 411.942534 -195.84162) (xy 411.211522 -196.572632) (xy 411.204714 -196.579978)
			(xy 411.19699 -196.598441) (xy 411.196536 -196.608446) (xy 411.196536 -196.755258) (xy 413.72104 -196.755258)
			(xy 413.725111 -196.699636) (xy 413.737237 -196.645199) (xy 413.75716 -196.593108) (xy 413.784456 -196.544473)
			(xy 413.818542 -196.50033) (xy 413.858691 -196.461621) (xy 413.904049 -196.42917) (xy 413.953649 -196.403669)
			(xy 414.006433 -196.385662) (xy 414.061276 -196.375532) (xy 414.11701 -196.373495) (xy 414.172447 -196.379595)
			(xy 414.226404 -196.393701) (xy 414.277733 -196.415513) (xy 414.325339 -196.444567) (xy 414.368207 -196.480242)
			(xy 414.381803 -196.495416) (xy 420.50665 -196.495416) (xy 420.510721 -196.439794) (xy 420.522847 -196.385357)
			(xy 420.54277 -196.333266) (xy 420.570066 -196.284631) (xy 420.604152 -196.240488) (xy 420.644301 -196.201779)
			(xy 420.689659 -196.169328) (xy 420.739259 -196.143827) (xy 420.792043 -196.12582) (xy 420.846886 -196.11569)
			(xy 420.90262 -196.113653) (xy 420.958057 -196.119753) (xy 421.012014 -196.133859) (xy 421.063343 -196.155671)
			(xy 421.110949 -196.184725) (xy 421.153817 -196.2204) (xy 421.191034 -196.261937) (xy 421.221807 -196.30845)
			(xy 421.245479 -196.358947) (xy 421.261547 -196.412354) (xy 421.269667 -196.46753) (xy 421.270176 -196.495416)
			(xy 421.269667 -196.523302) (xy 421.261547 -196.578478) (xy 421.245479 -196.631885) (xy 421.221807 -196.682382)
			(xy 421.191034 -196.728895) (xy 421.153817 -196.770432) (xy 421.110949 -196.806107) (xy 421.063343 -196.835161)
			(xy 421.012014 -196.856973) (xy 420.958057 -196.871079) (xy 420.90262 -196.877179) (xy 420.846886 -196.875142)
			(xy 420.792043 -196.865012) (xy 420.739259 -196.847005) (xy 420.689659 -196.821504) (xy 420.644301 -196.789053)
			(xy 420.604152 -196.750344) (xy 420.570066 -196.706201) (xy 420.54277 -196.657566) (xy 420.522847 -196.605475)
			(xy 420.510721 -196.551038) (xy 420.50665 -196.495416) (xy 414.381803 -196.495416) (xy 414.405424 -196.521779)
			(xy 414.436197 -196.568292) (xy 414.459869 -196.618789) (xy 414.475937 -196.672196) (xy 414.484057 -196.727372)
			(xy 414.484566 -196.755258) (xy 414.484057 -196.783144) (xy 414.475937 -196.83832) (xy 414.459869 -196.891727)
			(xy 414.436197 -196.942224) (xy 414.405424 -196.988737) (xy 414.368207 -197.030274) (xy 414.325339 -197.065949)
			(xy 414.277733 -197.095003) (xy 414.226404 -197.116815) (xy 414.172447 -197.130921) (xy 414.11701 -197.137021)
			(xy 414.061276 -197.134984) (xy 414.006433 -197.124854) (xy 413.953649 -197.106847) (xy 413.904049 -197.081346)
			(xy 413.858691 -197.048895) (xy 413.818542 -197.010186) (xy 413.784456 -196.966043) (xy 413.75716 -196.917408)
			(xy 413.737237 -196.865317) (xy 413.725111 -196.81088) (xy 413.72104 -196.755258) (xy 411.196536 -196.755258)
			(xy 411.196536 -199.981058) (xy 413.61944 -199.981058) (xy 413.623511 -199.925436) (xy 413.635637 -199.870999)
			(xy 413.65556 -199.818908) (xy 413.682856 -199.770273) (xy 413.716942 -199.72613) (xy 413.757091 -199.687421)
			(xy 413.802449 -199.65497) (xy 413.852049 -199.629469) (xy 413.904833 -199.611462) (xy 413.959676 -199.601332)
			(xy 414.01541 -199.599295) (xy 414.070847 -199.605395) (xy 414.124804 -199.619501) (xy 414.176133 -199.641313)
			(xy 414.223739 -199.670367) (xy 414.266607 -199.706042) (xy 414.303824 -199.747579) (xy 414.334597 -199.794092)
			(xy 414.358269 -199.844589) (xy 414.374337 -199.897996) (xy 414.382457 -199.953172) (xy 414.382966 -199.981058)
			(xy 414.382457 -200.008944) (xy 414.374337 -200.06412) (xy 414.358269 -200.117527) (xy 414.334597 -200.168024)
			(xy 414.303824 -200.214537) (xy 414.266607 -200.256074) (xy 414.223739 -200.291749) (xy 414.176133 -200.320803)
			(xy 414.124804 -200.342615) (xy 414.070847 -200.356721) (xy 414.01541 -200.362821) (xy 413.959676 -200.360784)
			(xy 413.904833 -200.350654) (xy 413.852049 -200.332647) (xy 413.802449 -200.307146) (xy 413.757091 -200.274695)
			(xy 413.716942 -200.235986) (xy 413.682856 -200.191843) (xy 413.65556 -200.143208) (xy 413.635637 -200.091117)
			(xy 413.623511 -200.03668) (xy 413.61944 -199.981058) (xy 411.196536 -199.981058) (xy 411.196536 -203.562458)
			(xy 413.13684 -203.562458) (xy 413.140911 -203.506836) (xy 413.153037 -203.452399) (xy 413.17296 -203.400308)
			(xy 413.200256 -203.351673) (xy 413.234342 -203.30753) (xy 413.274491 -203.268821) (xy 413.319849 -203.23637)
			(xy 413.369449 -203.210869) (xy 413.422233 -203.192862) (xy 413.477076 -203.182732) (xy 413.53281 -203.180695)
			(xy 413.588247 -203.186795) (xy 413.642204 -203.200901) (xy 413.693533 -203.222713) (xy 413.741139 -203.251767)
			(xy 413.784007 -203.287442) (xy 413.821224 -203.328979) (xy 413.851997 -203.375492) (xy 413.875669 -203.425989)
			(xy 413.891737 -203.479396) (xy 413.899857 -203.534572) (xy 413.900366 -203.562458) (xy 413.899857 -203.590344)
			(xy 413.891737 -203.64552) (xy 413.875669 -203.698927) (xy 413.851997 -203.749424) (xy 413.821224 -203.795937)
			(xy 413.784007 -203.837474) (xy 413.741139 -203.873149) (xy 413.693533 -203.902203) (xy 413.642204 -203.924015)
			(xy 413.588247 -203.938121) (xy 413.53281 -203.944221) (xy 413.477076 -203.942184) (xy 413.422233 -203.932054)
			(xy 413.369449 -203.914047) (xy 413.319849 -203.888546) (xy 413.274491 -203.856095) (xy 413.234342 -203.817386)
			(xy 413.200256 -203.773243) (xy 413.17296 -203.724608) (xy 413.153037 -203.672517) (xy 413.140911 -203.61808)
			(xy 413.13684 -203.562458) (xy 411.196536 -203.562458) (xy 411.196536 -206.680816) (xy 411.196088 -206.705993)
			(xy 411.188245 -206.755731) (xy 411.172708 -206.803626) (xy 411.14986 -206.848497) (xy 411.120265 -206.889234)
			(xy 411.10281 -206.907384) (xy 409.715716 -208.294478) (xy 409.697554 -208.311915) (xy 409.656805 -208.341479)
			(xy 409.611935 -208.364311) (xy 409.564048 -208.379848) (xy 409.51432 -208.387709) (xy 409.489148 -208.388204)
			(xy 408.451558 -208.388204) (xy 408.442014 -208.388655) (xy 408.42427 -208.395704) (xy 408.417014 -208.40192)
			(xy 408.395745 -208.421231) (xy 408.349237 -208.454953) (xy 408.298875 -208.482592) (xy 408.245451 -208.503713)
			(xy 408.189805 -208.517984) (xy 408.13281 -208.525182) (xy 408.104086 -208.525618) (xy 408.074118 -208.525127)
			(xy 408.014696 -208.517302) (xy 407.956803 -208.501788) (xy 407.90143 -208.478851) (xy 407.849525 -208.448882)
			(xy 407.801976 -208.412395) (xy 407.759596 -208.370013) (xy 407.72311 -208.322463) (xy 407.693143 -208.270557)
			(xy 407.670207 -208.215184) (xy 407.654695 -208.15729) (xy 407.646872 -208.097868) (xy 407.646872 -208.037932)
			(xy 407.654695 -207.97851) (xy 407.670207 -207.920616) (xy 407.693143 -207.865243) (xy 407.72311 -207.813337)
			(xy 407.759596 -207.765787) (xy 407.801976 -207.723405) (xy 407.849525 -207.686918) (xy 407.90143 -207.656949)
			(xy 407.956803 -207.634012) (xy 408.014696 -207.618498) (xy 408.074118 -207.610673) (xy 408.104086 -207.610202)
			(xy 408.13281 -207.61065) (xy 408.189805 -207.617839) (xy 408.245453 -207.632106) (xy 408.298877 -207.653225)
			(xy 408.349237 -207.680866) (xy 408.395742 -207.714593) (xy 408.417014 -207.7339) (xy 408.424253 -207.740143)
			(xy 408.442008 -207.747186) (xy 408.451558 -207.747616) (xy 409.335478 -207.747616) (xy 409.345468 -207.747083)
			(xy 409.363907 -207.739377) (xy 409.371292 -207.73263) (xy 410.540962 -206.56296) (xy 410.54777 -206.555614)
			(xy 410.555494 -206.537151) (xy 410.555948 -206.527146) (xy 410.555948 -203.695046) (xy 410.555533 -203.684993)
			(xy 410.54784 -203.666418) (xy 410.533611 -203.652213) (xy 410.524452 -203.648056) (xy 410.509974 -203.642214)
			(xy 410.480256 -203.648056) (xy 409.743148 -204.385164) (xy 409.725021 -204.402657) (xy 409.684289 -204.432296)
			(xy 409.639419 -204.455193) (xy 409.591518 -204.470783) (xy 409.541767 -204.478682) (xy 409.51658 -204.479144)
			(xy 408.319732 -204.479144) (xy 408.31021 -204.479538) (xy 408.292463 -204.48645) (xy 408.285188 -204.492606)
			(xy 408.263919 -204.511916) (xy 408.21741 -204.545636) (xy 408.167048 -204.573273) (xy 408.113624 -204.594392)
			(xy 408.057978 -204.608661) (xy 408.000983 -204.615856) (xy 407.97226 -204.616304) (xy 407.942294 -204.615811)
			(xy 407.882876 -204.607984) (xy 407.824988 -204.592468) (xy 407.76962 -204.56953) (xy 407.71772 -204.539561)
			(xy 407.670175 -204.503075) (xy 407.627799 -204.460695) (xy 407.591316 -204.413147) (xy 407.561352 -204.361244)
			(xy 407.538419 -204.305874) (xy 407.522908 -204.247985) (xy 407.515086 -204.188566) (xy 407.515086 -204.128634)
			(xy 407.522908 -204.069215) (xy 407.538419 -204.011326) (xy 407.561352 -203.955956) (xy 407.591316 -203.904053)
			(xy 407.627799 -203.856505) (xy 407.670175 -203.814125) (xy 407.71772 -203.777639) (xy 407.76962 -203.74767)
			(xy 407.824988 -203.724732) (xy 407.882876 -203.709216) (xy 407.942294 -203.701389) (xy 407.97226 -203.700888)
			(xy 408.000984 -203.701334) (xy 408.057982 -203.70852) (xy 408.113631 -203.722784) (xy 408.167058 -203.743901)
			(xy 408.217421 -203.771539) (xy 408.263929 -203.805264) (xy 408.285188 -203.824586) (xy 408.292444 -203.830779)
			(xy 408.3102 -203.837714) (xy 408.319732 -203.838048) (xy 409.36291 -203.838048) (xy 409.372876 -203.837571)
			(xy 409.39131 -203.829992) (xy 409.398724 -203.823316) (xy 410.027882 -203.194158) (xy 410.034688 -203.186811)
			(xy 410.042408 -203.168349) (xy 410.042868 -203.158344) (xy 410.042868 -203.129642) (xy 410.04245 -203.119593)
			(xy 410.03475 -203.10103) (xy 410.020513 -203.086845) (xy 410.011372 -203.082652) (xy 409.996894 -203.07681)
			(xy 409.967176 -203.082652) (xy 409.695904 -203.353924) (xy 409.677775 -203.371412) (xy 409.63704 -203.40104)
			(xy 409.592169 -203.423926) (xy 409.544269 -203.439506) (xy 409.494521 -203.447397) (xy 409.469336 -203.447904)
			(xy 393.853416 -203.447904) (xy 393.843455 -203.448394) (xy 393.825036 -203.455986) (xy 393.817602 -203.462636)
			(xy 386.93852 -210.341718) (xy 409.3497 -210.341718) (xy 409.353771 -210.286096) (xy 409.365897 -210.231659)
			(xy 409.38582 -210.179568) (xy 409.413116 -210.130933) (xy 409.447202 -210.08679) (xy 409.487351 -210.048081)
			(xy 409.532709 -210.01563) (xy 409.582309 -209.990129) (xy 409.635093 -209.972122) (xy 409.689936 -209.961992)
			(xy 409.74567 -209.959955) (xy 409.801107 -209.966055) (xy 409.855064 -209.980161) (xy 409.906393 -210.001973)
			(xy 409.953999 -210.031027) (xy 409.996867 -210.066702) (xy 410.034084 -210.108239) (xy 410.064857 -210.154752)
			(xy 410.088529 -210.205249) (xy 410.104597 -210.258656) (xy 410.112717 -210.313832) (xy 410.113226 -210.341718)
			(xy 410.112717 -210.369604) (xy 410.104597 -210.42478) (xy 410.088529 -210.478187) (xy 410.064857 -210.528684)
			(xy 410.034084 -210.575197) (xy 409.996867 -210.616734) (xy 409.953999 -210.652409) (xy 409.906393 -210.681463)
			(xy 409.855064 -210.703275) (xy 409.801107 -210.717381) (xy 409.74567 -210.723481) (xy 409.689936 -210.721444)
			(xy 409.635093 -210.711314) (xy 409.582309 -210.693307) (xy 409.532709 -210.667806) (xy 409.487351 -210.635355)
			(xy 409.447202 -210.596646) (xy 409.413116 -210.552503) (xy 409.38582 -210.503868) (xy 409.365897 -210.451777)
			(xy 409.353771 -210.39734) (xy 409.3497 -210.341718) (xy 386.93852 -210.341718) (xy 386.478018 -210.80222)
			(xy 386.471173 -210.809619) (xy 386.463443 -210.828217) (xy 386.463032 -210.838288) (xy 386.463032 -221.35363)
			(xy 417.25899 -221.35363) (xy 417.25899 -221.293694) (xy 417.266813 -221.234272) (xy 417.282326 -221.176379)
			(xy 417.305262 -221.121006) (xy 417.335229 -221.0691) (xy 417.371716 -221.02155) (xy 417.414096 -220.97917)
			(xy 417.461646 -220.942683) (xy 417.513552 -220.912716) (xy 417.568925 -220.88978) (xy 417.626818 -220.874267)
			(xy 417.68624 -220.866444) (xy 417.746176 -220.866444) (xy 417.805598 -220.874267) (xy 417.863491 -220.88978)
			(xy 417.918864 -220.912716) (xy 417.97077 -220.942683) (xy 418.01832 -220.97917) (xy 418.0607 -221.02155)
			(xy 418.097187 -221.0691) (xy 418.127154 -221.121006) (xy 418.15009 -221.176379) (xy 418.165603 -221.234272)
			(xy 418.173426 -221.293694) (xy 418.173916 -221.323662) (xy 418.173426 -221.35363) (xy 418.165603 -221.413052)
			(xy 418.15009 -221.470945) (xy 418.127154 -221.526318) (xy 418.097187 -221.578224) (xy 418.0607 -221.625774)
			(xy 418.01832 -221.668154) (xy 417.97077 -221.704641) (xy 417.918864 -221.734608) (xy 417.863491 -221.757544)
			(xy 417.805598 -221.773057) (xy 417.746176 -221.78088) (xy 417.68624 -221.78088) (xy 417.626818 -221.773057)
			(xy 417.568925 -221.757544) (xy 417.513552 -221.734608) (xy 417.461646 -221.704641) (xy 417.414096 -221.668154)
			(xy 417.371716 -221.625774) (xy 417.335229 -221.578224) (xy 417.305262 -221.526318) (xy 417.282326 -221.470945)
			(xy 417.266813 -221.413052) (xy 417.25899 -221.35363) (xy 386.463032 -221.35363) (xy 386.463032 -221.544642)
			(xy 386.463463 -221.554708) (xy 386.471192 -221.573299) (xy 386.478018 -221.58071) (xy 388.213854 -223.316546)
			(xy 443.32982 -223.316546) (xy 443.333891 -223.260924) (xy 443.346017 -223.206487) (xy 443.36594 -223.154396)
			(xy 443.393236 -223.105761) (xy 443.427322 -223.061618) (xy 443.467471 -223.022909) (xy 443.512829 -222.990458)
			(xy 443.562429 -222.964957) (xy 443.615213 -222.94695) (xy 443.670056 -222.93682) (xy 443.72579 -222.934783)
			(xy 443.781227 -222.940883) (xy 443.835184 -222.954989) (xy 443.886513 -222.976801) (xy 443.934119 -223.005855)
			(xy 443.976987 -223.04153) (xy 444.014204 -223.083067) (xy 444.044977 -223.12958) (xy 444.068649 -223.180077)
			(xy 444.084717 -223.233484) (xy 444.092837 -223.28866) (xy 444.093346 -223.316546) (xy 444.092837 -223.344432)
			(xy 444.084717 -223.399608) (xy 444.068649 -223.453015) (xy 444.044977 -223.503512) (xy 444.014204 -223.550025)
			(xy 443.976987 -223.591562) (xy 443.934119 -223.627237) (xy 443.886513 -223.656291) (xy 443.835184 -223.678103)
			(xy 443.781227 -223.692209) (xy 443.72579 -223.698309) (xy 443.670056 -223.696272) (xy 443.615213 -223.686142)
			(xy 443.562429 -223.668135) (xy 443.512829 -223.642634) (xy 443.467471 -223.610183) (xy 443.427322 -223.571474)
			(xy 443.393236 -223.527331) (xy 443.36594 -223.478696) (xy 443.346017 -223.426605) (xy 443.333891 -223.372168)
			(xy 443.32982 -223.316546) (xy 388.213854 -223.316546) (xy 388.818116 -223.920808) (xy 417.98289 -223.920808)
			(xy 417.98289 -223.860872) (xy 417.990713 -223.80145) (xy 418.006226 -223.743557) (xy 418.029162 -223.688184)
			(xy 418.059129 -223.636278) (xy 418.095616 -223.588728) (xy 418.137996 -223.546348) (xy 418.185546 -223.509861)
			(xy 418.237452 -223.479894) (xy 418.292825 -223.456958) (xy 418.350718 -223.441445) (xy 418.41014 -223.433622)
			(xy 418.470076 -223.433622) (xy 418.529498 -223.441445) (xy 418.587391 -223.456958) (xy 418.642764 -223.479894)
			(xy 418.69467 -223.509861) (xy 418.74222 -223.546348) (xy 418.7846 -223.588728) (xy 418.821087 -223.636278)
			(xy 418.851054 -223.688184) (xy 418.87399 -223.743557) (xy 418.889503 -223.80145) (xy 418.897326 -223.860872)
			(xy 418.897816 -223.89084) (xy 418.897326 -223.920808) (xy 418.889503 -223.98023) (xy 418.87399 -224.038123)
			(xy 418.851054 -224.093496) (xy 418.821087 -224.145402) (xy 418.7846 -224.192952) (xy 418.74222 -224.235332)
			(xy 418.69467 -224.271819) (xy 418.642764 -224.301786) (xy 418.587391 -224.324722) (xy 418.529498 -224.340235)
			(xy 418.470076 -224.348058) (xy 418.41014 -224.348058) (xy 418.350718 -224.340235) (xy 418.292825 -224.324722)
			(xy 418.237452 -224.301786) (xy 418.185546 -224.271819) (xy 418.137996 -224.235332) (xy 418.095616 -224.192952)
			(xy 418.059129 -224.145402) (xy 418.029162 -224.093496) (xy 418.006226 -224.038123) (xy 417.990713 -223.98023)
			(xy 417.98289 -223.920808) (xy 388.818116 -223.920808) (xy 388.987284 -224.089976) (xy 388.99412 -224.097378)
			(xy 389.001829 -224.115976) (xy 389.00227 -224.126044) (xy 389.00227 -224.700846) (xy 443.326518 -224.700846)
			(xy 443.330589 -224.645224) (xy 443.342715 -224.590787) (xy 443.362638 -224.538696) (xy 443.389934 -224.490061)
			(xy 443.42402 -224.445918) (xy 443.464169 -224.407209) (xy 443.509527 -224.374758) (xy 443.559127 -224.349257)
			(xy 443.611911 -224.33125) (xy 443.666754 -224.32112) (xy 443.722488 -224.319083) (xy 443.777925 -224.325183)
			(xy 443.831882 -224.339289) (xy 443.883211 -224.361101) (xy 443.930817 -224.390155) (xy 443.973685 -224.42583)
			(xy 444.010902 -224.467367) (xy 444.041675 -224.51388) (xy 444.065347 -224.564377) (xy 444.081415 -224.617784)
			(xy 444.089535 -224.67296) (xy 444.090044 -224.700846) (xy 444.089535 -224.728732) (xy 444.081415 -224.783908)
			(xy 444.065347 -224.837315) (xy 444.041675 -224.887812) (xy 444.010902 -224.934325) (xy 443.973685 -224.975862)
			(xy 443.930817 -225.011537) (xy 443.883211 -225.040591) (xy 443.831882 -225.062403) (xy 443.777925 -225.076509)
			(xy 443.722488 -225.082609) (xy 443.666754 -225.080572) (xy 443.611911 -225.070442) (xy 443.559127 -225.052435)
			(xy 443.509527 -225.026934) (xy 443.464169 -224.994483) (xy 443.42402 -224.955774) (xy 443.389934 -224.911631)
			(xy 443.362638 -224.862996) (xy 443.342715 -224.810905) (xy 443.330589 -224.756468) (xy 443.326518 -224.700846)
			(xy 389.00227 -224.700846) (xy 389.00227 -225.267262) (xy 414.877486 -225.267262) (xy 414.877486 -225.207326)
			(xy 414.885309 -225.147904) (xy 414.900822 -225.090011) (xy 414.923758 -225.034638) (xy 414.953725 -224.982732)
			(xy 414.990212 -224.935182) (xy 415.032592 -224.892802) (xy 415.080142 -224.856315) (xy 415.132048 -224.826348)
			(xy 415.187421 -224.803412) (xy 415.245314 -224.787899) (xy 415.304736 -224.780076) (xy 415.364672 -224.780076)
			(xy 415.424094 -224.787899) (xy 415.481987 -224.803412) (xy 415.53736 -224.826348) (xy 415.589266 -224.856315)
			(xy 415.636816 -224.892802) (xy 415.679196 -224.935182) (xy 415.715683 -224.982732) (xy 415.74565 -225.034638)
			(xy 415.768586 -225.090011) (xy 415.784099 -225.147904) (xy 415.791922 -225.207326) (xy 415.792412 -225.237294)
			(xy 415.792391 -225.238564) (xy 418.305232 -225.238564) (xy 418.309303 -225.182942) (xy 418.321429 -225.128505)
			(xy 418.341352 -225.076414) (xy 418.368648 -225.027779) (xy 418.402734 -224.983636) (xy 418.442883 -224.944927)
			(xy 418.488241 -224.912476) (xy 418.537841 -224.886975) (xy 418.590625 -224.868968) (xy 418.645468 -224.858838)
			(xy 418.701202 -224.856801) (xy 418.756639 -224.862901) (xy 418.810596 -224.877007) (xy 418.861925 -224.898819)
			(xy 418.909531 -224.927873) (xy 418.952399 -224.963548) (xy 418.989616 -225.005085) (xy 419.020389 -225.051598)
			(xy 419.044061 -225.102095) (xy 419.060129 -225.155502) (xy 419.068249 -225.210678) (xy 419.068758 -225.238564)
			(xy 419.068249 -225.26645) (xy 419.060129 -225.321626) (xy 419.044061 -225.375033) (xy 419.020389 -225.42553)
			(xy 418.989616 -225.472043) (xy 418.952399 -225.51358) (xy 418.909531 -225.549255) (xy 418.861925 -225.578309)
			(xy 418.810596 -225.600121) (xy 418.756639 -225.614227) (xy 418.701202 -225.620327) (xy 418.645468 -225.61829)
			(xy 418.590625 -225.60816) (xy 418.537841 -225.590153) (xy 418.488241 -225.564652) (xy 418.442883 -225.532201)
			(xy 418.402734 -225.493492) (xy 418.368648 -225.449349) (xy 418.341352 -225.400714) (xy 418.321429 -225.348623)
			(xy 418.309303 -225.294186) (xy 418.305232 -225.238564) (xy 415.792391 -225.238564) (xy 415.791922 -225.267262)
			(xy 415.784099 -225.326684) (xy 415.768586 -225.384577) (xy 415.74565 -225.43995) (xy 415.715683 -225.491856)
			(xy 415.679196 -225.539406) (xy 415.636816 -225.581786) (xy 415.589266 -225.618273) (xy 415.53736 -225.64824)
			(xy 415.481987 -225.671176) (xy 415.424094 -225.686689) (xy 415.364672 -225.694512) (xy 415.304736 -225.694512)
			(xy 415.245314 -225.686689) (xy 415.187421 -225.671176) (xy 415.132048 -225.64824) (xy 415.080142 -225.618273)
			(xy 415.032592 -225.581786) (xy 414.990212 -225.539406) (xy 414.953725 -225.491856) (xy 414.923758 -225.43995)
			(xy 414.900822 -225.384577) (xy 414.885309 -225.326684) (xy 414.877486 -225.267262) (xy 389.00227 -225.267262)
			(xy 389.00227 -227.69322) (xy 389.002696 -227.703289) (xy 389.010412 -227.721891) (xy 389.017256 -227.729288)
			(xy 389.955816 -228.667848) (xy 442.823618 -228.667848) (xy 442.823618 -228.613352) (xy 442.831374 -228.55941)
			(xy 442.846727 -228.50712) (xy 442.869366 -228.457548) (xy 442.898829 -228.411703) (xy 442.934517 -228.370517)
			(xy 442.975703 -228.334829) (xy 443.021548 -228.305366) (xy 443.07112 -228.282727) (xy 443.12341 -228.267374)
			(xy 443.177352 -228.259618) (xy 443.2046 -228.259132) (xy 443.233517 -228.259638) (xy 443.29069 -228.268368)
			(xy 443.345889 -228.285628) (xy 443.397851 -228.311022) (xy 443.445385 -228.343968) (xy 443.487401 -228.383711)
			(xy 443.50559 -228.406198) (xy 443.513161 -228.414951) (xy 443.533913 -228.425139) (xy 443.545468 -228.425756)
			(xy 443.625732 -228.425756) (xy 443.637297 -228.425162) (xy 443.658069 -228.414985) (xy 443.66561 -228.406198)
			(xy 443.683795 -228.383709) (xy 443.725816 -228.343975) (xy 443.773352 -228.311036) (xy 443.825315 -228.285649)
			(xy 443.880513 -228.268394) (xy 443.937684 -228.259666) (xy 443.9666 -228.259132) (xy 443.993854 -228.259538)
			(xy 444.047807 -228.267295) (xy 444.100108 -228.282652) (xy 444.14969 -228.305295) (xy 444.195545 -228.334765)
			(xy 444.23674 -228.37046) (xy 444.272435 -228.411655) (xy 444.301905 -228.45751) (xy 444.324548 -228.507092)
			(xy 444.339905 -228.559393) (xy 444.347662 -228.613346) (xy 444.347662 -228.667854) (xy 444.339905 -228.721807)
			(xy 444.324548 -228.774108) (xy 444.301905 -228.82369) (xy 444.272435 -228.869545) (xy 444.23674 -228.91074)
			(xy 444.195545 -228.946435) (xy 444.14969 -228.975905) (xy 444.100108 -228.998548) (xy 444.047807 -229.013905)
			(xy 443.993854 -229.021662) (xy 443.9666 -229.022148) (xy 443.937682 -229.021649) (xy 443.880509 -229.012919)
			(xy 443.825309 -228.995658) (xy 443.773347 -228.970263) (xy 443.725814 -228.937315) (xy 443.683799 -228.89757)
			(xy 443.66561 -228.875082) (xy 443.658043 -228.866326) (xy 443.637288 -228.85614) (xy 443.625732 -228.855524)
			(xy 443.545468 -228.855524) (xy 443.533904 -228.856125) (xy 443.513132 -228.866297) (xy 443.50559 -228.875082)
			(xy 443.4874 -228.897567) (xy 443.445381 -228.937302) (xy 443.397846 -228.970242) (xy 443.345884 -228.99563)
			(xy 443.290686 -229.012886) (xy 443.233516 -229.021614) (xy 443.2046 -229.022148) (xy 443.177352 -229.021582)
			(xy 443.12341 -229.013826) (xy 443.07112 -228.998473) (xy 443.021548 -228.975834) (xy 442.975703 -228.946371)
			(xy 442.934517 -228.910683) (xy 442.898829 -228.869497) (xy 442.869366 -228.823652) (xy 442.846727 -228.77408)
			(xy 442.831374 -228.72179) (xy 442.823618 -228.667848) (xy 389.955816 -228.667848) (xy 391.15746 -229.869492)
			(xy 391.164867 -229.876183) (xy 391.183303 -229.883781) (xy 391.193274 -229.884224) (xy 392.048492 -229.884224)
			(xy 392.058461 -229.883752) (xy 392.076907 -229.876186) (xy 392.084306 -229.869492) (xy 392.643868 -229.30993)
			(xy 392.65098 -229.296722) (xy 392.65225 -229.289356) (xy 392.658844 -229.258507) (xy 392.679377 -229.198861)
			(xy 392.707901 -229.142596) (xy 392.743877 -229.090778) (xy 392.786623 -229.044387) (xy 392.835331 -229.004301)
			(xy 392.889079 -228.971279) (xy 392.946851 -228.945945) (xy 393.007552 -228.928778) (xy 393.070035 -228.920105)
			(xy 393.101576 -228.919532) (xy 393.131545 -228.92) (xy 393.190971 -228.927821) (xy 393.248867 -228.943332)
			(xy 393.304243 -228.966268) (xy 393.356151 -228.996237) (xy 393.403703 -229.032726) (xy 393.446085 -229.075109)
			(xy 393.482041 -229.12197) (xy 444.350392 -229.12197) (xy 444.354463 -229.066348) (xy 444.366589 -229.011911)
			(xy 444.386512 -228.95982) (xy 444.413808 -228.911185) (xy 444.447894 -228.867042) (xy 444.488043 -228.828333)
			(xy 444.533401 -228.795882) (xy 444.583001 -228.770381) (xy 444.635785 -228.752374) (xy 444.690628 -228.742244)
			(xy 444.746362 -228.740207) (xy 444.801799 -228.746307) (xy 444.855756 -228.760413) (xy 444.907085 -228.782225)
			(xy 444.954691 -228.811279) (xy 444.997559 -228.846954) (xy 445.034776 -228.888491) (xy 445.065549 -228.935004)
			(xy 445.089221 -228.985501) (xy 445.105289 -229.038908) (xy 445.113409 -229.094084) (xy 445.113918 -229.12197)
			(xy 445.113409 -229.149856) (xy 445.105289 -229.205032) (xy 445.089221 -229.258439) (xy 445.065549 -229.308936)
			(xy 445.034776 -229.355449) (xy 444.997559 -229.396986) (xy 444.954691 -229.432661) (xy 444.907085 -229.461715)
			(xy 444.855756 -229.483527) (xy 444.801799 -229.497633) (xy 444.746362 -229.503733) (xy 444.690628 -229.501696)
			(xy 444.635785 -229.491566) (xy 444.583001 -229.473559) (xy 444.533401 -229.448058) (xy 444.488043 -229.415607)
			(xy 444.447894 -229.376898) (xy 444.413808 -229.332755) (xy 444.386512 -229.28412) (xy 444.366589 -229.232029)
			(xy 444.354463 -229.177592) (xy 444.350392 -229.12197) (xy 393.482041 -229.12197) (xy 393.482572 -229.122662)
			(xy 393.512539 -229.174571) (xy 393.535473 -229.229948) (xy 393.550982 -229.287845) (xy 393.558801 -229.347271)
			(xy 393.559284 -229.37724) (xy 393.55876 -229.408785) (xy 393.550105 -229.47128) (xy 393.532949 -229.531993)
			(xy 393.507619 -229.589776) (xy 393.474593 -229.643532) (xy 393.434499 -229.692245) (xy 393.388095 -229.73499)
			(xy 393.33626 -229.770957) (xy 393.279978 -229.799466) (xy 393.220314 -229.819975) (xy 393.18946 -229.826566)
			(xy 393.182094 -229.827836) (xy 393.168886 -229.834948) (xy 392.768836 -230.234998) (xy 392.76129 -230.243461)
			(xy 392.753778 -230.264822) (xy 392.754358 -230.276146) (xy 392.763756 -230.366062) (xy 392.775694 -230.38562)
			(xy 392.785346 -230.39197) (xy 392.801559 -230.402805) (xy 392.831844 -230.427371) (xy 392.845798 -230.440992)
			(xy 393.27963 -230.87457) (xy 393.292838 -230.881682) (xy 393.300204 -230.882952) (xy 393.331055 -230.889544)
			(xy 393.390706 -230.910073) (xy 393.446975 -230.938595) (xy 393.498797 -230.974569) (xy 393.507698 -230.98277)
			(xy 417.301154 -230.98277) (xy 417.301154 -230.922834) (xy 417.308977 -230.863412) (xy 417.32449 -230.805519)
			(xy 417.347426 -230.750146) (xy 417.377393 -230.69824) (xy 417.41388 -230.65069) (xy 417.45626 -230.60831)
			(xy 417.50381 -230.571823) (xy 417.555716 -230.541856) (xy 417.611089 -230.51892) (xy 417.668982 -230.503407)
			(xy 417.728404 -230.495584) (xy 417.78834 -230.495584) (xy 417.847762 -230.503407) (xy 417.905655 -230.51892)
			(xy 417.961028 -230.541856) (xy 418.012934 -230.571823) (xy 418.060484 -230.60831) (xy 418.102864 -230.65069)
			(xy 418.139351 -230.69824) (xy 418.169318 -230.750146) (xy 418.192254 -230.805519) (xy 418.207767 -230.863412)
			(xy 418.21559 -230.922834) (xy 418.21608 -230.952802) (xy 418.21559 -230.98277) (xy 418.207767 -231.042192)
			(xy 418.192254 -231.100085) (xy 418.169318 -231.155458) (xy 418.139351 -231.207364) (xy 418.102864 -231.254914)
			(xy 418.060484 -231.297294) (xy 418.012934 -231.333781) (xy 417.961028 -231.363748) (xy 417.905655 -231.386684)
			(xy 417.847762 -231.402197) (xy 417.78834 -231.41002) (xy 417.728404 -231.41002) (xy 417.668982 -231.402197)
			(xy 417.611089 -231.386684) (xy 417.555716 -231.363748) (xy 417.50381 -231.333781) (xy 417.45626 -231.297294)
			(xy 417.41388 -231.254914) (xy 417.377393 -231.207364) (xy 417.347426 -231.155458) (xy 417.32449 -231.100085)
			(xy 417.308977 -231.042192) (xy 417.301154 -230.98277) (xy 393.507698 -230.98277) (xy 393.545192 -231.017315)
			(xy 393.585282 -231.066023) (xy 393.618307 -231.119773) (xy 393.643644 -231.177546) (xy 393.660811 -231.23825)
			(xy 393.669486 -231.300736) (xy 393.670028 -231.332278) (xy 393.66956 -231.362248) (xy 393.661739 -231.421677)
			(xy 393.646228 -231.479576) (xy 393.623292 -231.534955) (xy 393.593324 -231.586867) (xy 393.556837 -231.634423)
			(xy 393.514454 -231.676809) (xy 393.466902 -231.713301) (xy 393.414993 -231.743274) (xy 393.359616 -231.766215)
			(xy 393.301718 -231.781731) (xy 393.24229 -231.789558) (xy 393.21232 -231.789986) (xy 393.180776 -231.78946)
			(xy 393.118286 -231.780799) (xy 393.057576 -231.76364) (xy 392.999798 -231.738307) (xy 392.946046 -231.705281)
			(xy 392.897339 -231.665186) (xy 392.854598 -231.618782) (xy 392.818634 -231.566949) (xy 392.790128 -231.510669)
			(xy 392.769621 -231.451007) (xy 392.762994 -231.420162) (xy 392.761724 -231.412796) (xy 392.754612 -231.399588)
			(xy 392.444478 -231.089454) (xy 392.437134 -231.082641) (xy 392.418671 -231.074908) (xy 392.408664 -231.074468)
			(xy 390.527794 -231.074468) (xy 390.517747 -231.074893) (xy 390.499191 -231.082598) (xy 390.485006 -231.096829)
			(xy 390.480804 -231.105964) (xy 390.474962 -231.120442) (xy 390.480804 -231.15016) (xy 391.70102 -232.370376)
			(xy 391.718509 -232.388505) (xy 391.74814 -232.429239) (xy 391.771029 -232.474109) (xy 391.786613 -232.52201)
			(xy 391.794506 -232.571758) (xy 391.795 -232.596944) (xy 391.795 -235.972858) (xy 391.795489 -235.982858)
			(xy 391.803116 -236.001348) (xy 391.817201 -236.015549) (xy 391.826242 -236.019848) (xy 391.84072 -236.02569)
			(xy 391.870438 -236.019848) (xy 392.984736 -234.90555) (xy 392.991424 -234.898141) (xy 392.999019 -234.879706)
			(xy 392.999468 -234.869736) (xy 392.999468 -232.806494) (xy 392.999248 -232.799686) (xy 392.995637 -232.786556)
			(xy 392.992356 -232.780586) (xy 392.979571 -232.758316) (xy 392.95943 -232.711079) (xy 392.945798 -232.66157)
			(xy 392.93892 -232.610682) (xy 392.938508 -232.585006) (xy 392.938994 -232.557755) (xy 392.94675 -232.503807)
			(xy 392.962105 -232.451512) (xy 392.984747 -232.401935) (xy 393.014213 -232.356085) (xy 393.049904 -232.314894)
			(xy 393.091095 -232.279203) (xy 393.136945 -232.249737) (xy 393.186522 -232.227095) (xy 393.238817 -232.21174)
			(xy 393.292765 -232.203984) (xy 393.347267 -232.203984) (xy 393.401215 -232.21174) (xy 393.45351 -232.227095)
			(xy 393.503087 -232.249737) (xy 393.548937 -232.279203) (xy 393.590128 -232.314894) (xy 393.625819 -232.356085)
			(xy 393.655285 -232.401935) (xy 393.677927 -232.451512) (xy 393.693282 -232.503807) (xy 393.701038 -232.557755)
			(xy 393.701524 -232.585006) (xy 393.701123 -232.610683) (xy 393.694262 -232.661575) (xy 393.680623 -232.711084)
			(xy 393.660455 -232.758311) (xy 393.647676 -232.780586) (xy 393.644397 -232.786555) (xy 393.640804 -232.799687)
			(xy 393.640564 -232.806494) (xy 393.640564 -233.52277) (xy 414.832782 -233.52277) (xy 414.832782 -233.462834)
			(xy 414.840605 -233.403412) (xy 414.856118 -233.345519) (xy 414.879054 -233.290146) (xy 414.909021 -233.23824)
			(xy 414.945508 -233.19069) (xy 414.987888 -233.14831) (xy 415.035438 -233.111823) (xy 415.087344 -233.081856)
			(xy 415.142717 -233.05892) (xy 415.20061 -233.043407) (xy 415.260032 -233.035584) (xy 415.319968 -233.035584)
			(xy 415.37939 -233.043407) (xy 415.437283 -233.05892) (xy 415.492656 -233.081856) (xy 415.544562 -233.111823)
			(xy 415.592112 -233.14831) (xy 415.634492 -233.19069) (xy 415.670979 -233.23824) (xy 415.700946 -233.290146)
			(xy 415.723882 -233.345519) (xy 415.739395 -233.403412) (xy 415.747218 -233.462834) (xy 415.747708 -233.492802)
			(xy 415.747687 -233.494072) (xy 418.149784 -233.494072) (xy 418.153855 -233.43845) (xy 418.165981 -233.384013)
			(xy 418.185904 -233.331922) (xy 418.2132 -233.283287) (xy 418.247286 -233.239144) (xy 418.287435 -233.200435)
			(xy 418.332793 -233.167984) (xy 418.382393 -233.142483) (xy 418.435177 -233.124476) (xy 418.49002 -233.114346)
			(xy 418.545754 -233.112309) (xy 418.601191 -233.118409) (xy 418.655148 -233.132515) (xy 418.688293 -233.1466)
			(xy 442.035182 -233.1466) (xy 442.039253 -233.090978) (xy 442.051379 -233.036541) (xy 442.071302 -232.98445)
			(xy 442.098598 -232.935815) (xy 442.132684 -232.891672) (xy 442.172833 -232.852963) (xy 442.218191 -232.820512)
			(xy 442.267791 -232.795011) (xy 442.320575 -232.777004) (xy 442.375418 -232.766874) (xy 442.431152 -232.764837)
			(xy 442.486589 -232.770937) (xy 442.540546 -232.785043) (xy 442.591875 -232.806855) (xy 442.639481 -232.835909)
			(xy 442.682349 -232.871584) (xy 442.719566 -232.913121) (xy 442.750339 -232.959634) (xy 442.774011 -233.010131)
			(xy 442.790079 -233.063538) (xy 442.798199 -233.118714) (xy 442.798708 -233.1466) (xy 442.798199 -233.174486)
			(xy 442.790079 -233.229662) (xy 442.775866 -233.276902) (xy 443.9318 -233.276902) (xy 443.935871 -233.22128)
			(xy 443.947997 -233.166843) (xy 443.96792 -233.114752) (xy 443.995216 -233.066117) (xy 444.029302 -233.021974)
			(xy 444.069451 -232.983265) (xy 444.114809 -232.950814) (xy 444.164409 -232.925313) (xy 444.217193 -232.907306)
			(xy 444.272036 -232.897176) (xy 444.32777 -232.895139) (xy 444.383207 -232.901239) (xy 444.437164 -232.915345)
			(xy 444.488493 -232.937157) (xy 444.536099 -232.966211) (xy 444.578967 -233.001886) (xy 444.616184 -233.043423)
			(xy 444.646957 -233.089936) (xy 444.670629 -233.140433) (xy 444.686697 -233.19384) (xy 444.694817 -233.249016)
			(xy 444.695326 -233.276902) (xy 444.694817 -233.304788) (xy 444.686697 -233.359964) (xy 444.670629 -233.413371)
			(xy 444.646957 -233.463868) (xy 444.616184 -233.510381) (xy 444.578967 -233.551918) (xy 444.536099 -233.587593)
			(xy 444.488493 -233.616647) (xy 444.437164 -233.638459) (xy 444.383207 -233.652565) (xy 444.32777 -233.658665)
			(xy 444.272036 -233.656628) (xy 444.217193 -233.646498) (xy 444.164409 -233.628491) (xy 444.114809 -233.60299)
			(xy 444.069451 -233.570539) (xy 444.029302 -233.53183) (xy 443.995216 -233.487687) (xy 443.96792 -233.439052)
			(xy 443.947997 -233.386961) (xy 443.935871 -233.332524) (xy 443.9318 -233.276902) (xy 442.775866 -233.276902)
			(xy 442.774011 -233.283069) (xy 442.750339 -233.333566) (xy 442.719566 -233.380079) (xy 442.682349 -233.421616)
			(xy 442.639481 -233.457291) (xy 442.591875 -233.486345) (xy 442.540546 -233.508157) (xy 442.486589 -233.522263)
			(xy 442.431152 -233.528363) (xy 442.375418 -233.526326) (xy 442.320575 -233.516196) (xy 442.267791 -233.498189)
			(xy 442.218191 -233.472688) (xy 442.172833 -233.440237) (xy 442.132684 -233.401528) (xy 442.098598 -233.357385)
			(xy 442.071302 -233.30875) (xy 442.051379 -233.256659) (xy 442.039253 -233.202222) (xy 442.035182 -233.1466)
			(xy 418.688293 -233.1466) (xy 418.706477 -233.154327) (xy 418.754083 -233.183381) (xy 418.796951 -233.219056)
			(xy 418.834168 -233.260593) (xy 418.864941 -233.307106) (xy 418.888613 -233.357603) (xy 418.904681 -233.41101)
			(xy 418.912801 -233.466186) (xy 418.91331 -233.494072) (xy 418.912801 -233.521958) (xy 418.904681 -233.577134)
			(xy 418.888613 -233.630541) (xy 418.864941 -233.681038) (xy 418.834168 -233.727551) (xy 418.796951 -233.769088)
			(xy 418.754083 -233.804763) (xy 418.706477 -233.833817) (xy 418.655148 -233.855629) (xy 418.601191 -233.869735)
			(xy 418.545754 -233.875835) (xy 418.49002 -233.873798) (xy 418.435177 -233.863668) (xy 418.382393 -233.845661)
			(xy 418.332793 -233.82016) (xy 418.287435 -233.787709) (xy 418.247286 -233.749) (xy 418.2132 -233.704857)
			(xy 418.185904 -233.656222) (xy 418.165981 -233.604131) (xy 418.153855 -233.549694) (xy 418.149784 -233.494072)
			(xy 415.747687 -233.494072) (xy 415.747218 -233.52277) (xy 415.739395 -233.582192) (xy 415.723882 -233.640085)
			(xy 415.700946 -233.695458) (xy 415.670979 -233.747364) (xy 415.634492 -233.794914) (xy 415.592112 -233.837294)
			(xy 415.544562 -233.873781) (xy 415.492656 -233.903748) (xy 415.437283 -233.926684) (xy 415.37939 -233.942197)
			(xy 415.319968 -233.95002) (xy 415.260032 -233.95002) (xy 415.20061 -233.942197) (xy 415.142717 -233.926684)
			(xy 415.087344 -233.903748) (xy 415.035438 -233.873781) (xy 414.987888 -233.837294) (xy 414.945508 -233.794914)
			(xy 414.909021 -233.747364) (xy 414.879054 -233.695458) (xy 414.856118 -233.640085) (xy 414.840605 -233.582192)
			(xy 414.832782 -233.52277) (xy 393.640564 -233.52277) (xy 393.640564 -235.023406) (xy 393.640048 -235.048588)
			(xy 393.632131 -235.098327) (xy 393.616541 -235.146217) (xy 393.598601 -235.181394) (xy 418.770052 -235.181394)
			(xy 418.774123 -235.125772) (xy 418.786249 -235.071335) (xy 418.806172 -235.019244) (xy 418.833468 -234.970609)
			(xy 418.867554 -234.926466) (xy 418.907703 -234.887757) (xy 418.953061 -234.855306) (xy 419.002661 -234.829805)
			(xy 419.055445 -234.811798) (xy 419.110288 -234.801668) (xy 419.166022 -234.799631) (xy 419.221459 -234.805731)
			(xy 419.275416 -234.819837) (xy 419.326745 -234.841649) (xy 419.374351 -234.870703) (xy 419.417219 -234.906378)
			(xy 419.454436 -234.947915) (xy 419.485209 -234.994428) (xy 419.508881 -235.044925) (xy 419.524949 -235.098332)
			(xy 419.533069 -235.153508) (xy 419.533578 -235.181394) (xy 419.533069 -235.20928) (xy 419.524949 -235.264456)
			(xy 419.508881 -235.317863) (xy 419.485209 -235.36836) (xy 419.454436 -235.414873) (xy 419.417219 -235.45641)
			(xy 419.374351 -235.492085) (xy 419.326745 -235.521139) (xy 419.275416 -235.542951) (xy 419.221459 -235.557057)
			(xy 419.166022 -235.563157) (xy 419.110288 -235.56112) (xy 419.055445 -235.55099) (xy 419.002661 -235.532983)
			(xy 418.953061 -235.507482) (xy 418.907703 -235.475031) (xy 418.867554 -235.436322) (xy 418.833468 -235.392179)
			(xy 418.806172 -235.343544) (xy 418.786249 -235.291453) (xy 418.774123 -235.237016) (xy 418.770052 -235.181394)
			(xy 393.598601 -235.181394) (xy 393.593659 -235.191084) (xy 393.564048 -235.231825) (xy 393.546584 -235.249974)
			(xy 393.5349 -235.261658) (xy 393.528059 -235.269023) (xy 393.520315 -235.287556) (xy 393.520314 -235.307642)
			(xy 393.528058 -235.326176) (xy 393.5349 -235.33354) (xy 393.539472 -235.338112) (xy 393.54506 -235.341414)
			(xy 393.569233 -235.356219) (xy 393.613315 -235.391851) (xy 393.65164 -235.433614) (xy 393.683362 -235.480589)
			(xy 393.707785 -235.531741) (xy 393.724369 -235.585943) (xy 393.73275 -235.642003) (xy 393.733274 -235.670344)
			(xy 393.73278 -235.698404) (xy 393.724565 -235.753918) (xy 393.708302 -235.807629) (xy 393.684344 -235.858377)
			(xy 393.653207 -235.905066) (xy 393.615565 -235.946688) (xy 393.572229 -235.982344) (xy 393.524136 -236.011265)
			(xy 393.472324 -236.032825) (xy 393.445238 -236.040168) (xy 393.43838 -236.041946) (xy 393.426442 -236.048804)
			(xy 393.389866 -236.08538) (xy 393.383754 -236.092018) (xy 393.376227 -236.108404) (xy 393.374833 -236.126382)
			(xy 393.376912 -236.135164) (xy 393.404598 -236.23397) (xy 393.424156 -236.252766) (xy 393.437872 -236.256068)
			(xy 393.465252 -236.263201) (xy 393.517692 -236.284444) (xy 393.56642 -236.313198) (xy 393.610367 -236.348832)
			(xy 393.648571 -236.390565) (xy 393.680194 -236.437482) (xy 393.704542 -236.488554) (xy 393.707857 -236.4994)
			(xy 444.422782 -236.4994) (xy 444.426853 -236.443778) (xy 444.438979 -236.389341) (xy 444.458902 -236.33725)
			(xy 444.486198 -236.288615) (xy 444.520284 -236.244472) (xy 444.560433 -236.205763) (xy 444.605791 -236.173312)
			(xy 444.655391 -236.147811) (xy 444.708175 -236.129804) (xy 444.763018 -236.119674) (xy 444.818752 -236.117637)
			(xy 444.874189 -236.123737) (xy 444.928146 -236.137843) (xy 444.979475 -236.159655) (xy 445.027081 -236.188709)
			(xy 445.069949 -236.224384) (xy 445.107166 -236.265921) (xy 445.137939 -236.312434) (xy 445.161611 -236.362931)
			(xy 445.177679 -236.416338) (xy 445.185799 -236.471514) (xy 445.186308 -236.4994) (xy 445.185799 -236.527286)
			(xy 445.177679 -236.582462) (xy 445.161611 -236.635869) (xy 445.137939 -236.686366) (xy 445.107166 -236.732879)
			(xy 445.069949 -236.774416) (xy 445.027081 -236.810091) (xy 444.979475 -236.839145) (xy 444.928146 -236.860957)
			(xy 444.874189 -236.875063) (xy 444.818752 -236.881163) (xy 444.763018 -236.879126) (xy 444.708175 -236.868996)
			(xy 444.655391 -236.850989) (xy 444.605791 -236.825488) (xy 444.560433 -236.793037) (xy 444.520284 -236.754328)
			(xy 444.486198 -236.710185) (xy 444.458902 -236.66155) (xy 444.438979 -236.609459) (xy 444.426853 -236.555022)
			(xy 444.422782 -236.4994) (xy 393.707857 -236.4994) (xy 393.721081 -236.542662) (xy 393.72945 -236.598619)
			(xy 393.729972 -236.626908) (xy 393.729481 -236.654969) (xy 393.721269 -236.710487) (xy 393.70501 -236.764202)
			(xy 393.681054 -236.814954) (xy 393.649919 -236.861648) (xy 393.612277 -236.903274) (xy 393.56894 -236.938934)
			(xy 393.520846 -236.967858) (xy 393.469032 -236.989421) (xy 393.441936 -236.996732) (xy 393.435078 -236.99851)
			(xy 393.42314 -237.005368) (xy 392.913108 -237.5154) (xy 443.254382 -237.5154) (xy 443.258453 -237.459778)
			(xy 443.270579 -237.405341) (xy 443.290502 -237.35325) (xy 443.317798 -237.304615) (xy 443.351884 -237.260472)
			(xy 443.392033 -237.221763) (xy 443.437391 -237.189312) (xy 443.486991 -237.163811) (xy 443.539775 -237.145804)
			(xy 443.594618 -237.135674) (xy 443.650352 -237.133637) (xy 443.705789 -237.139737) (xy 443.759746 -237.153843)
			(xy 443.811075 -237.175655) (xy 443.858681 -237.204709) (xy 443.901549 -237.240384) (xy 443.938766 -237.281921)
			(xy 443.969539 -237.328434) (xy 443.993211 -237.378931) (xy 444.009279 -237.432338) (xy 444.017399 -237.487514)
			(xy 444.017908 -237.5154) (xy 444.017399 -237.543286) (xy 444.009279 -237.598462) (xy 443.993211 -237.651869)
			(xy 443.969539 -237.702366) (xy 443.938766 -237.748879) (xy 443.901549 -237.790416) (xy 443.858681 -237.826091)
			(xy 443.811075 -237.855145) (xy 443.759746 -237.876957) (xy 443.705789 -237.891063) (xy 443.650352 -237.897163)
			(xy 443.594618 -237.895126) (xy 443.539775 -237.884996) (xy 443.486991 -237.866989) (xy 443.437391 -237.841488)
			(xy 443.392033 -237.809037) (xy 443.351884 -237.770328) (xy 443.317798 -237.726185) (xy 443.290502 -237.67755)
			(xy 443.270579 -237.625459) (xy 443.258453 -237.571022) (xy 443.254382 -237.5154) (xy 392.913108 -237.5154)
			(xy 392.663172 -237.765336) (xy 392.656496 -237.772749) (xy 392.648932 -237.791185) (xy 392.64844 -237.80115)
			(xy 392.64844 -239.328448) (xy 417.201332 -239.328448) (xy 417.201332 -239.268512) (xy 417.209155 -239.20909)
			(xy 417.224668 -239.151197) (xy 417.247604 -239.095824) (xy 417.277571 -239.043918) (xy 417.314058 -238.996368)
			(xy 417.356438 -238.953988) (xy 417.403988 -238.917501) (xy 417.455894 -238.887534) (xy 417.511267 -238.864598)
			(xy 417.56916 -238.849085) (xy 417.628582 -238.841262) (xy 417.688518 -238.841262) (xy 417.74794 -238.849085)
			(xy 417.805833 -238.864598) (xy 417.861206 -238.887534) (xy 417.913112 -238.917501) (xy 417.960662 -238.953988)
			(xy 418.003042 -238.996368) (xy 418.039529 -239.043918) (xy 418.069496 -239.095824) (xy 418.092432 -239.151197)
			(xy 418.107945 -239.20909) (xy 418.115768 -239.268512) (xy 418.116258 -239.29848) (xy 418.115768 -239.328448)
			(xy 418.107945 -239.38787) (xy 418.092432 -239.445763) (xy 418.069496 -239.501136) (xy 418.039529 -239.553042)
			(xy 418.003042 -239.600592) (xy 417.960662 -239.642972) (xy 417.913112 -239.679459) (xy 417.861206 -239.709426)
			(xy 417.805833 -239.732362) (xy 417.74794 -239.747875) (xy 417.688518 -239.755698) (xy 417.628582 -239.755698)
			(xy 417.56916 -239.747875) (xy 417.511267 -239.732362) (xy 417.455894 -239.709426) (xy 417.403988 -239.679459)
			(xy 417.356438 -239.642972) (xy 417.314058 -239.600592) (xy 417.277571 -239.553042) (xy 417.247604 -239.501136)
			(xy 417.224668 -239.445763) (xy 417.209155 -239.38787) (xy 417.201332 -239.328448) (xy 392.64844 -239.328448)
			(xy 392.64844 -240.170716) (xy 418.30828 -240.170716) (xy 418.312351 -240.115094) (xy 418.324477 -240.060657)
			(xy 418.3444 -240.008566) (xy 418.371696 -239.959931) (xy 418.405782 -239.915788) (xy 418.445931 -239.877079)
			(xy 418.491289 -239.844628) (xy 418.540889 -239.819127) (xy 418.593673 -239.80112) (xy 418.648516 -239.79099)
			(xy 418.70425 -239.788953) (xy 418.759687 -239.795053) (xy 418.813644 -239.809159) (xy 418.864973 -239.830971)
			(xy 418.912579 -239.860025) (xy 418.955447 -239.8957) (xy 418.992664 -239.937237) (xy 419.023437 -239.98375)
			(xy 419.047109 -240.034247) (xy 419.063177 -240.087654) (xy 419.071297 -240.14283) (xy 419.071806 -240.170716)
			(xy 419.071297 -240.198602) (xy 419.063177 -240.253778) (xy 419.047109 -240.307185) (xy 419.023437 -240.357682)
			(xy 418.992664 -240.404195) (xy 418.955447 -240.445732) (xy 418.912579 -240.481407) (xy 418.864973 -240.510461)
			(xy 418.813644 -240.532273) (xy 418.759687 -240.546379) (xy 418.70425 -240.552479) (xy 418.648516 -240.550442)
			(xy 418.593673 -240.540312) (xy 418.540889 -240.522305) (xy 418.491289 -240.496804) (xy 418.445931 -240.464353)
			(xy 418.405782 -240.425644) (xy 418.371696 -240.381501) (xy 418.3444 -240.332866) (xy 418.324477 -240.280775)
			(xy 418.312351 -240.226338) (xy 418.30828 -240.170716) (xy 392.64844 -240.170716) (xy 392.64844 -242.033552)
			(xy 393.613384 -242.033552) (xy 393.617455 -241.97793) (xy 393.629581 -241.923493) (xy 393.649504 -241.871402)
			(xy 393.6768 -241.822767) (xy 393.710886 -241.778624) (xy 393.751035 -241.739915) (xy 393.796393 -241.707464)
			(xy 393.845993 -241.681963) (xy 393.898777 -241.663956) (xy 393.95362 -241.653826) (xy 394.009354 -241.651789)
			(xy 394.064791 -241.657889) (xy 394.118748 -241.671995) (xy 394.170077 -241.693807) (xy 394.217683 -241.722861)
			(xy 394.260551 -241.758536) (xy 394.297768 -241.800073) (xy 394.328541 -241.846586) (xy 394.338789 -241.868448)
			(xy 415.536616 -241.868448) (xy 415.536616 -241.808512) (xy 415.544439 -241.74909) (xy 415.559952 -241.691197)
			(xy 415.582888 -241.635824) (xy 415.612855 -241.583918) (xy 415.649342 -241.536368) (xy 415.691722 -241.493988)
			(xy 415.739272 -241.457501) (xy 415.791178 -241.427534) (xy 415.846551 -241.404598) (xy 415.904444 -241.389085)
			(xy 415.963866 -241.381262) (xy 416.023802 -241.381262) (xy 416.083224 -241.389085) (xy 416.141117 -241.404598)
			(xy 416.19649 -241.427534) (xy 416.248396 -241.457501) (xy 416.295946 -241.493988) (xy 416.338326 -241.536368)
			(xy 416.374813 -241.583918) (xy 416.40478 -241.635824) (xy 416.427716 -241.691197) (xy 416.443229 -241.74909)
			(xy 416.451052 -241.808512) (xy 416.451542 -241.83848) (xy 416.451521 -241.83975) (xy 418.075362 -241.83975)
			(xy 418.079433 -241.784128) (xy 418.091559 -241.729691) (xy 418.111482 -241.6776) (xy 418.138778 -241.628965)
			(xy 418.172864 -241.584822) (xy 418.213013 -241.546113) (xy 418.258371 -241.513662) (xy 418.307971 -241.488161)
			(xy 418.360755 -241.470154) (xy 418.415598 -241.460024) (xy 418.471332 -241.457987) (xy 418.526769 -241.464087)
			(xy 418.580726 -241.478193) (xy 418.632055 -241.500005) (xy 418.679661 -241.529059) (xy 418.722529 -241.564734)
			(xy 418.759746 -241.606271) (xy 418.790519 -241.652784) (xy 418.814191 -241.703281) (xy 418.830259 -241.756688)
			(xy 418.838379 -241.811864) (xy 418.838888 -241.83975) (xy 418.838379 -241.867636) (xy 418.830259 -241.922812)
			(xy 418.814191 -241.976219) (xy 418.790519 -242.026716) (xy 418.759746 -242.073229) (xy 418.722529 -242.114766)
			(xy 418.679661 -242.150441) (xy 418.632055 -242.179495) (xy 418.580726 -242.201307) (xy 418.526769 -242.215413)
			(xy 418.471332 -242.221513) (xy 418.415598 -242.219476) (xy 418.360755 -242.209346) (xy 418.307971 -242.191339)
			(xy 418.258371 -242.165838) (xy 418.213013 -242.133387) (xy 418.172864 -242.094678) (xy 418.138778 -242.050535)
			(xy 418.111482 -242.0019) (xy 418.091559 -241.949809) (xy 418.079433 -241.895372) (xy 418.075362 -241.83975)
			(xy 416.451521 -241.83975) (xy 416.451052 -241.868448) (xy 416.443229 -241.92787) (xy 416.427716 -241.985763)
			(xy 416.40478 -242.041136) (xy 416.374813 -242.093042) (xy 416.338326 -242.140592) (xy 416.295946 -242.182972)
			(xy 416.248396 -242.219459) (xy 416.19649 -242.249426) (xy 416.141117 -242.272362) (xy 416.083224 -242.287875)
			(xy 416.023802 -242.295698) (xy 415.963866 -242.295698) (xy 415.904444 -242.287875) (xy 415.846551 -242.272362)
			(xy 415.791178 -242.249426) (xy 415.739272 -242.219459) (xy 415.691722 -242.182972) (xy 415.649342 -242.140592)
			(xy 415.612855 -242.093042) (xy 415.582888 -242.041136) (xy 415.559952 -241.985763) (xy 415.544439 -241.92787)
			(xy 415.536616 -241.868448) (xy 394.338789 -241.868448) (xy 394.352213 -241.897083) (xy 394.368281 -241.95049)
			(xy 394.376401 -242.005666) (xy 394.37691 -242.033552) (xy 394.376401 -242.061438) (xy 394.368281 -242.116614)
			(xy 394.352213 -242.170021) (xy 394.328541 -242.220518) (xy 394.297768 -242.267031) (xy 394.260551 -242.308568)
			(xy 394.217683 -242.344243) (xy 394.170077 -242.373297) (xy 394.118748 -242.395109) (xy 394.064791 -242.409215)
			(xy 394.009354 -242.415315) (xy 393.95362 -242.413278) (xy 393.898777 -242.403148) (xy 393.845993 -242.385141)
			(xy 393.796393 -242.35964) (xy 393.751035 -242.327189) (xy 393.710886 -242.28848) (xy 393.6768 -242.244337)
			(xy 393.649504 -242.195702) (xy 393.629581 -242.143611) (xy 393.617455 -242.089174) (xy 393.613384 -242.033552)
			(xy 392.64844 -242.033552) (xy 392.64844 -242.84813) (xy 451.778624 -242.84813) (xy 451.779043 -242.821813)
			(xy 451.786269 -242.769677) (xy 451.800588 -242.719028) (xy 451.821729 -242.670826) (xy 451.849291 -242.625985)
			(xy 451.882751 -242.585355) (xy 451.901814 -242.567206) (xy 451.909217 -242.559686) (xy 451.91774 -242.540405)
			(xy 451.918324 -242.529868) (xy 451.918324 -242.455192) (xy 451.917806 -242.444641) (xy 451.909262 -242.425346)
			(xy 451.901814 -242.417854) (xy 451.882715 -242.399739) (xy 451.849238 -242.359115) (xy 451.82167 -242.31427)
			(xy 451.800535 -242.266059) (xy 451.786235 -242.215398) (xy 451.779042 -242.163251) (xy 451.778624 -242.13693)
			(xy 451.779083 -242.109676) (xy 451.786837 -242.055724) (xy 451.802191 -242.003424) (xy 451.824832 -241.953842)
			(xy 451.8543 -241.907987) (xy 451.889994 -241.866793) (xy 451.931188 -241.831099) (xy 451.977043 -241.801631)
			(xy 452.026626 -241.77899) (xy 452.078926 -241.763637) (xy 452.132878 -241.755883) (xy 452.160132 -241.755422)
			(xy 452.186448 -241.755867) (xy 452.238583 -241.763088) (xy 452.289232 -241.777402) (xy 452.337434 -241.798538)
			(xy 452.382275 -241.826095) (xy 452.422907 -241.859551) (xy 452.441056 -241.878612) (xy 452.44859 -241.885998)
			(xy 452.467861 -241.894531) (xy 452.478394 -241.895122) (xy 452.55307 -241.895122) (xy 452.563618 -241.894583)
			(xy 452.582913 -241.886054) (xy 452.590408 -241.878612) (xy 452.608541 -241.859531) (xy 452.649162 -241.826053)
			(xy 452.694002 -241.798482) (xy 452.74221 -241.777344) (xy 452.792868 -241.76304) (xy 452.845012 -241.755842)
			(xy 452.871332 -241.755422) (xy 452.897648 -241.755867) (xy 452.949783 -241.763088) (xy 453.000432 -241.777402)
			(xy 453.048634 -241.798538) (xy 453.093475 -241.826095) (xy 453.134107 -241.859551) (xy 453.152256 -241.878612)
			(xy 453.15979 -241.885998) (xy 453.179061 -241.894531) (xy 453.189594 -241.895122) (xy 453.26427 -241.895122)
			(xy 453.274818 -241.894583) (xy 453.294113 -241.886054) (xy 453.301608 -241.878612) (xy 453.319741 -241.859531)
			(xy 453.360362 -241.826053) (xy 453.405202 -241.798482) (xy 453.45341 -241.777344) (xy 453.504068 -241.76304)
			(xy 453.556212 -241.755842) (xy 453.582532 -241.755422) (xy 453.609785 -241.755848) (xy 453.663737 -241.76361)
			(xy 453.716035 -241.77897) (xy 453.765614 -241.801618) (xy 453.811466 -241.83109) (xy 453.852656 -241.866788)
			(xy 453.888347 -241.907984) (xy 453.917812 -241.953841) (xy 453.940451 -242.003424) (xy 453.955803 -242.055724)
			(xy 453.963556 -242.109677) (xy 453.96404 -242.13693) (xy 453.963574 -242.163245) (xy 453.956355 -242.215378)
			(xy 453.942043 -242.266026) (xy 453.920911 -242.314227) (xy 453.893359 -242.35907) (xy 453.859909 -242.399703)
			(xy 453.84085 -242.417854) (xy 453.83343 -242.42536) (xy 453.824915 -242.444652) (xy 453.82434 -242.455192)
			(xy 453.82434 -242.529868) (xy 453.824861 -242.540419) (xy 453.833401 -242.559715) (xy 453.84085 -242.567206)
			(xy 453.859923 -242.585348) (xy 453.893403 -242.625965) (xy 453.920976 -242.670804) (xy 453.942116 -242.71901)
			(xy 453.956421 -242.769667) (xy 453.96362 -242.821811) (xy 453.96404 -242.84813) (xy 453.96355 -242.875381)
			(xy 453.95579 -242.929326) (xy 453.940433 -242.981619) (xy 453.917791 -243.031194) (xy 453.888324 -243.077043)
			(xy 453.852634 -243.118232) (xy 453.811445 -243.153923) (xy 453.765596 -243.18339) (xy 453.716021 -243.206032)
			(xy 453.663728 -243.22139) (xy 453.609783 -243.22915) (xy 453.582532 -243.229638) (xy 453.556216 -243.229198)
			(xy 453.504082 -243.221973) (xy 453.453434 -243.207657) (xy 453.405232 -243.18652) (xy 453.36039 -243.158963)
			(xy 453.319758 -243.125508) (xy 453.301608 -243.106448) (xy 453.294079 -243.099055) (xy 453.274805 -243.090524)
			(xy 453.26427 -243.089938) (xy 453.189594 -243.089938) (xy 453.179041 -243.090439) (xy 453.159745 -243.098993)
			(xy 453.152256 -243.106448) (xy 453.134133 -243.125539) (xy 453.093511 -243.159018) (xy 453.048668 -243.186588)
			(xy 453.000458 -243.207725) (xy 452.949798 -243.222026) (xy 452.897652 -243.22922) (xy 452.871332 -243.229638)
			(xy 452.845016 -243.229198) (xy 452.792882 -243.221973) (xy 452.742234 -243.207657) (xy 452.694032 -243.18652)
			(xy 452.64919 -243.158963) (xy 452.608558 -243.125508) (xy 452.590408 -243.106448) (xy 452.582879 -243.099055)
			(xy 452.563605 -243.090524) (xy 452.55307 -243.089938) (xy 452.478394 -243.089938) (xy 452.467841 -243.090439)
			(xy 452.448545 -243.098993) (xy 452.441056 -243.106448) (xy 452.422933 -243.125539) (xy 452.382311 -243.159018)
			(xy 452.337468 -243.186588) (xy 452.289258 -243.207725) (xy 452.238598 -243.222026) (xy 452.186452 -243.22922)
			(xy 452.160132 -243.229638) (xy 452.132881 -243.229115) (xy 452.078934 -243.221363) (xy 452.026639 -243.206013)
			(xy 451.977061 -243.183376) (xy 451.931209 -243.153914) (xy 451.890017 -243.118227) (xy 451.854323 -243.07704)
			(xy 451.824854 -243.031193) (xy 451.802209 -242.981619) (xy 451.78685 -242.929327) (xy 451.779089 -242.875381)
			(xy 451.778624 -242.84813) (xy 392.64844 -242.84813) (xy 392.64844 -244.586506) (xy 392.648916 -244.596472)
			(xy 392.656493 -244.614908) (xy 392.663172 -244.62232) (xy 394.02639 -245.985538) (xy 394.0556 -245.991888)
			(xy 394.070078 -245.9863) (xy 394.092138 -245.978103) (xy 394.137769 -245.966584) (xy 394.184469 -245.960761)
			(xy 394.208 -245.960392) (xy 394.235378 -245.960865) (xy 394.28957 -245.968694) (xy 394.342086 -245.984193)
			(xy 394.391845 -246.007043) (xy 394.437826 -246.036773) (xy 394.479083 -246.072773) (xy 394.514767 -246.114303)
			(xy 394.529818 -246.137176) (xy 394.536676 -246.145812) (xy 394.557511 -246.16664) (xy 454.116184 -246.16664)
			(xy 454.120255 -246.111018) (xy 454.132381 -246.056581) (xy 454.152304 -246.00449) (xy 454.1796 -245.955855)
			(xy 454.213686 -245.911712) (xy 454.253835 -245.873003) (xy 454.299193 -245.840552) (xy 454.348793 -245.815051)
			(xy 454.401577 -245.797044) (xy 454.45642 -245.786914) (xy 454.512154 -245.784877) (xy 454.567591 -245.790977)
			(xy 454.621548 -245.805083) (xy 454.672877 -245.826895) (xy 454.720483 -245.855949) (xy 454.763351 -245.891624)
			(xy 454.800568 -245.933161) (xy 454.831341 -245.979674) (xy 454.855013 -246.030171) (xy 454.871081 -246.083578)
			(xy 454.879201 -246.138754) (xy 454.87971 -246.16664) (xy 454.879201 -246.194526) (xy 454.871081 -246.249702)
			(xy 454.855013 -246.303109) (xy 454.831341 -246.353606) (xy 454.800568 -246.400119) (xy 454.763351 -246.441656)
			(xy 454.720483 -246.477331) (xy 454.672877 -246.506385) (xy 454.621548 -246.528197) (xy 454.567591 -246.542303)
			(xy 454.512154 -246.548403) (xy 454.45642 -246.546366) (xy 454.401577 -246.536236) (xy 454.348793 -246.518229)
			(xy 454.299193 -246.492728) (xy 454.253835 -246.460277) (xy 454.213686 -246.421568) (xy 454.1796 -246.377425)
			(xy 454.152304 -246.32879) (xy 454.132381 -246.276699) (xy 454.120255 -246.222262) (xy 454.116184 -246.16664)
			(xy 394.557511 -246.16664) (xy 395.312646 -246.921528) (xy 395.320054 -246.928218) (xy 395.33849 -246.935815)
			(xy 395.34846 -246.93626) (xy 449.377308 -246.93626) (xy 449.411234 -246.937064) (xy 449.477945 -246.949464)
			(xy 449.509896 -246.960898) (xy 449.518532 -246.9642) (xy 455.070718 -246.9642) (xy 455.080787 -246.964627)
			(xy 455.099386 -246.972346) (xy 455.106786 -246.979186) (xy 455.296016 -247.168416) (xy 455.302869 -247.175811)
			(xy 455.310611 -247.19441) (xy 455.311002 -247.204484) (xy 455.311002 -249.930158) (xy 455.311436 -249.940223)
			(xy 455.319165 -249.958812) (xy 455.325988 -249.966226) (xy 455.448416 -250.088654) (xy 455.455813 -250.095503)
			(xy 455.474412 -250.103239) (xy 455.484484 -250.10364)
		)
		(stroke
			(width 0)
			(type solid)
		)
		(fill yes)
		(layer "B.Cu")
		(net "GND")
	)
	(gr_poly
		(pts
			(xy 459.918816 -359.64368) (xy 459.928884 -359.643253) (xy 459.947483 -359.635533) (xy 459.954884 -359.628694)
			(xy 463.043778 -356.5398) (xy 463.050627 -356.532402) (xy 463.058365 -356.513804) (xy 463.058764 -356.503732)
			(xy 463.058764 -340.71687) (xy 463.058335 -340.706803) (xy 463.050609 -340.68821) (xy 463.043778 -340.680802)
			(xy 458.165708 -335.802732) (xy 458.158311 -335.795881) (xy 458.139713 -335.788139) (xy 458.12964 -335.787746)
			(xy 372.450868 -335.787746) (xy 372.440801 -335.788176) (xy 372.42221 -335.795904) (xy 372.4148 -335.802732)
			(xy 369.229894 -338.987638) (xy 369.223054 -338.995039) (xy 369.215335 -339.013637) (xy 369.214908 -339.023706)
			(xy 369.214908 -342.466769) (xy 370.806722 -342.466769) (xy 370.806722 -342.412231) (xy 370.814484 -342.358249)
			(xy 370.829848 -342.305921) (xy 370.852503 -342.256312) (xy 370.881987 -342.210432) (xy 370.9177 -342.169214)
			(xy 370.958916 -342.133499) (xy 371.004794 -342.104012) (xy 371.054402 -342.081355) (xy 371.10673 -342.065988)
			(xy 371.160711 -342.058224) (xy 371.18798 -342.057736) (xy 372.05158 -342.057736) (xy 372.078852 -342.058202)
			(xy 372.132841 -342.065962) (xy 372.185175 -342.081326) (xy 372.234791 -342.103983) (xy 372.280677 -342.13347)
			(xy 372.321899 -342.169187) (xy 372.357618 -342.210407) (xy 372.387108 -342.256292) (xy 372.409767 -342.305906)
			(xy 372.425134 -342.35824) (xy 372.432896 -342.412228) (xy 372.432896 -342.466772) (xy 372.432896 -342.466773)
			(xy 373.9156 -342.466773) (xy 373.9156 -342.412227) (xy 373.923363 -342.358236) (xy 373.938731 -342.3059)
			(xy 373.961392 -342.256284) (xy 373.990883 -342.210398) (xy 374.026605 -342.169177) (xy 374.06783 -342.133459)
			(xy 374.113719 -342.103973) (xy 374.163338 -342.081317) (xy 374.215676 -342.065954) (xy 374.269667 -342.058197)
			(xy 374.29694 -342.057736) (xy 375.16054 -342.057736) (xy 375.187807 -342.058229) (xy 375.241786 -342.065995)
			(xy 375.294111 -342.081364) (xy 375.343716 -342.104022) (xy 375.389591 -342.133509) (xy 375.430804 -342.169224)
			(xy 375.466515 -342.210441) (xy 375.495997 -342.256319) (xy 375.51865 -342.305927) (xy 375.534013 -342.358253)
			(xy 375.541774 -342.412233) (xy 375.541774 -342.466767) (xy 375.541774 -342.46677) (xy 377.024622 -342.46677)
			(xy 377.024622 -342.41223) (xy 377.032384 -342.358247) (xy 377.04775 -342.305917) (xy 377.070406 -342.256306)
			(xy 377.099892 -342.210425) (xy 377.135607 -342.169207) (xy 377.176825 -342.133492) (xy 377.222706 -342.104006)
			(xy 377.272317 -342.08135) (xy 377.324647 -342.065984) (xy 377.37863 -342.058222) (xy 377.4059 -342.057736)
			(xy 378.2695 -342.057736) (xy 378.296769 -342.058226) (xy 378.350753 -342.065988) (xy 378.403082 -342.081353)
			(xy 378.452692 -342.104009) (xy 378.498572 -342.133495) (xy 378.53979 -342.16921) (xy 378.575505 -342.210428)
			(xy 378.604991 -342.256308) (xy 378.627647 -342.305918) (xy 378.643012 -342.358247) (xy 378.650774 -342.412231)
			(xy 378.650774 -342.466768) (xy 380.133622 -342.466768) (xy 380.133622 -342.412232) (xy 380.141383 -342.358252)
			(xy 380.156746 -342.305925) (xy 380.1794 -342.256318) (xy 380.208882 -342.210438) (xy 380.244593 -342.169222)
			(xy 380.285806 -342.133506) (xy 380.331682 -342.104019) (xy 380.381288 -342.08136) (xy 380.433613 -342.065991)
			(xy 380.487592 -342.058225) (xy 380.51486 -342.057736) (xy 381.37846 -342.057736) (xy 381.405733 -342.058201)
			(xy 381.459724 -342.065958) (xy 381.512061 -342.081321) (xy 381.561679 -342.103976) (xy 381.607567 -342.133463)
			(xy 381.648792 -342.16918) (xy 381.684513 -342.210401) (xy 381.714005 -342.256286) (xy 381.736665 -342.305902)
			(xy 381.752033 -342.358237) (xy 381.759796 -342.412227) (xy 381.759796 -342.466772) (xy 383.2425 -342.466772)
			(xy 383.2425 -342.412228) (xy 383.250262 -342.358239) (xy 383.26563 -342.305904) (xy 383.288289 -342.25629)
			(xy 383.317778 -342.210405) (xy 383.353498 -342.169184) (xy 383.394721 -342.133466) (xy 383.440607 -342.103979)
			(xy 383.490223 -342.081323) (xy 383.542559 -342.065958) (xy 383.596548 -342.058198) (xy 383.62382 -342.057736)
			(xy 384.48742 -342.057736) (xy 384.514688 -342.058228) (xy 384.568669 -342.065992) (xy 384.620996 -342.081359)
			(xy 384.670604 -342.104016) (xy 384.716482 -342.133502) (xy 384.757697 -342.169217) (xy 384.79341 -342.210434)
			(xy 384.822894 -342.256314) (xy 384.845548 -342.305922) (xy 384.860913 -342.35825) (xy 384.868674 -342.412232)
			(xy 384.868674 -342.466768) (xy 384.868674 -342.466769) (xy 386.351522 -342.466769) (xy 386.351522 -342.412231)
			(xy 386.359284 -342.358249) (xy 386.374648 -342.305921) (xy 386.397303 -342.256312) (xy 386.426787 -342.210432)
			(xy 386.4625 -342.169214) (xy 386.503716 -342.133499) (xy 386.549594 -342.104012) (xy 386.599202 -342.081355)
			(xy 386.65153 -342.065988) (xy 386.705511 -342.058224) (xy 386.73278 -342.057736) (xy 387.59638 -342.057736)
			(xy 387.623652 -342.058202) (xy 387.677641 -342.065962) (xy 387.729975 -342.081326) (xy 387.779591 -342.103983)
			(xy 387.825477 -342.13347) (xy 387.866699 -342.169187) (xy 387.902418 -342.210407) (xy 387.931908 -342.256292)
			(xy 387.954567 -342.305906) (xy 387.969934 -342.35824) (xy 387.977696 -342.412228) (xy 387.977696 -342.466772)
			(xy 387.977696 -342.466773) (xy 389.4604 -342.466773) (xy 389.4604 -342.412227) (xy 389.468163 -342.358236)
			(xy 389.483531 -342.3059) (xy 389.506192 -342.256284) (xy 389.535683 -342.210398) (xy 389.571405 -342.169177)
			(xy 389.61263 -342.133459) (xy 389.658519 -342.103973) (xy 389.708138 -342.081317) (xy 389.760476 -342.065954)
			(xy 389.814467 -342.058197) (xy 389.84174 -342.057736) (xy 390.70534 -342.057736) (xy 390.732607 -342.058229)
			(xy 390.786586 -342.065995) (xy 390.838911 -342.081364) (xy 390.888516 -342.104022) (xy 390.934391 -342.133509)
			(xy 390.975604 -342.169224) (xy 391.011315 -342.210441) (xy 391.040797 -342.256319) (xy 391.06345 -342.305927)
			(xy 391.078813 -342.358253) (xy 391.086574 -342.412233) (xy 391.086574 -342.466767) (xy 391.086574 -342.46677)
			(xy 392.569422 -342.46677) (xy 392.569422 -342.41223) (xy 392.577184 -342.358247) (xy 392.59255 -342.305917)
			(xy 392.615206 -342.256306) (xy 392.644692 -342.210425) (xy 392.680407 -342.169207) (xy 392.721625 -342.133492)
			(xy 392.767506 -342.104006) (xy 392.817117 -342.08135) (xy 392.869447 -342.065984) (xy 392.92343 -342.058222)
			(xy 392.9507 -342.057736) (xy 393.8143 -342.057736) (xy 393.841569 -342.058226) (xy 393.895553 -342.065988)
			(xy 393.947882 -342.081353) (xy 393.997492 -342.104009) (xy 394.043372 -342.133495) (xy 394.08459 -342.16921)
			(xy 394.120305 -342.210428) (xy 394.149791 -342.256308) (xy 394.172447 -342.305918) (xy 394.187812 -342.358247)
			(xy 394.195574 -342.412231) (xy 394.195574 -342.466768) (xy 395.678422 -342.466768) (xy 395.678422 -342.412232)
			(xy 395.686183 -342.358252) (xy 395.701546 -342.305925) (xy 395.7242 -342.256318) (xy 395.753682 -342.210438)
			(xy 395.789393 -342.169222) (xy 395.830606 -342.133506) (xy 395.876482 -342.104019) (xy 395.926088 -342.08136)
			(xy 395.978413 -342.065991) (xy 396.032392 -342.058225) (xy 396.05966 -342.057736) (xy 396.92326 -342.057736)
			(xy 396.950533 -342.058201) (xy 397.004524 -342.065958) (xy 397.056861 -342.081321) (xy 397.106479 -342.103976)
			(xy 397.152367 -342.133463) (xy 397.193592 -342.16918) (xy 397.229313 -342.210401) (xy 397.258805 -342.256286)
			(xy 397.281465 -342.305902) (xy 397.296833 -342.358237) (xy 397.304596 -342.412227) (xy 397.304596 -342.466772)
			(xy 398.7873 -342.466772) (xy 398.7873 -342.412228) (xy 398.795062 -342.358239) (xy 398.81043 -342.305904)
			(xy 398.833089 -342.25629) (xy 398.862578 -342.210405) (xy 398.898298 -342.169184) (xy 398.939521 -342.133466)
			(xy 398.985407 -342.103979) (xy 399.035023 -342.081323) (xy 399.087359 -342.065958) (xy 399.141348 -342.058198)
			(xy 399.16862 -342.057736) (xy 400.03222 -342.057736) (xy 400.059488 -342.058228) (xy 400.113469 -342.065992)
			(xy 400.165796 -342.081359) (xy 400.215404 -342.104016) (xy 400.261282 -342.133502) (xy 400.302497 -342.169217)
			(xy 400.33821 -342.210434) (xy 400.367694 -342.256314) (xy 400.390348 -342.305922) (xy 400.405713 -342.35825)
			(xy 400.413474 -342.412232) (xy 400.413474 -342.466768) (xy 400.413474 -342.466769) (xy 401.896322 -342.466769)
			(xy 401.896322 -342.412231) (xy 401.904084 -342.358249) (xy 401.919448 -342.305921) (xy 401.942103 -342.256312)
			(xy 401.971587 -342.210432) (xy 402.0073 -342.169214) (xy 402.048516 -342.133499) (xy 402.094394 -342.104012)
			(xy 402.144002 -342.081355) (xy 402.19633 -342.065988) (xy 402.250311 -342.058224) (xy 402.27758 -342.057736)
			(xy 403.14118 -342.057736) (xy 403.168452 -342.058202) (xy 403.222441 -342.065962) (xy 403.274775 -342.081326)
			(xy 403.324391 -342.103983) (xy 403.370277 -342.13347) (xy 403.411499 -342.169187) (xy 403.447218 -342.210407)
			(xy 403.476708 -342.256292) (xy 403.499367 -342.305906) (xy 403.514734 -342.35824) (xy 403.522496 -342.412228)
			(xy 403.522496 -342.466769) (xy 408.913822 -342.466769) (xy 408.913822 -342.412231) (xy 408.921584 -342.358248)
			(xy 408.936949 -342.305918) (xy 408.959605 -342.256309) (xy 408.98909 -342.210428) (xy 409.024805 -342.16921)
			(xy 409.066021 -342.133495) (xy 409.111902 -342.104009) (xy 409.161511 -342.081352) (xy 409.21384 -342.065986)
			(xy 409.267823 -342.058223) (xy 409.295092 -342.057736) (xy 410.158692 -342.057736) (xy 410.185963 -342.058203)
			(xy 410.239951 -342.065964) (xy 410.292284 -342.08133) (xy 410.341898 -342.103987) (xy 410.387782 -342.133474)
			(xy 410.429003 -342.169191) (xy 410.464721 -342.210411) (xy 410.49421 -342.256295) (xy 410.516868 -342.305908)
			(xy 410.532234 -342.358241) (xy 410.539996 -342.412229) (xy 410.539996 -342.466767) (xy 412.022822 -342.466767)
			(xy 412.022822 -342.412233) (xy 412.030583 -342.358253) (xy 412.045946 -342.305927) (xy 412.068599 -342.25632)
			(xy 412.09808 -342.210441) (xy 412.13379 -342.169224) (xy 412.175002 -342.133509) (xy 412.220878 -342.104022)
			(xy 412.270482 -342.081363) (xy 412.322806 -342.065993) (xy 412.376785 -342.058226) (xy 412.404052 -342.057736)
			(xy 413.267652 -342.057736) (xy 413.294925 -342.0582) (xy 413.348917 -342.065957) (xy 413.401255 -342.081319)
			(xy 413.450874 -342.103974) (xy 413.496763 -342.13346) (xy 413.537989 -342.169177) (xy 413.573712 -342.210398)
			(xy 413.603203 -342.256284) (xy 413.625864 -342.3059) (xy 413.641233 -342.358236) (xy 413.648996 -342.412227)
			(xy 413.648996 -342.466772) (xy 415.1317 -342.466772) (xy 415.1317 -342.412228) (xy 415.139462 -342.35824)
			(xy 415.154829 -342.305906) (xy 415.177488 -342.256292) (xy 415.206976 -342.210407) (xy 415.242695 -342.169187)
			(xy 415.283917 -342.133469) (xy 415.329803 -342.103982) (xy 415.379417 -342.081325) (xy 415.431752 -342.065959)
			(xy 415.48574 -342.058199) (xy 415.513012 -342.057736) (xy 416.376612 -342.057736) (xy 416.403881 -342.058227)
			(xy 416.457863 -342.06599) (xy 416.510191 -342.081357) (xy 416.559799 -342.104013) (xy 416.605678 -342.133499)
			(xy 416.646894 -342.169214) (xy 416.682608 -342.210432) (xy 416.712092 -342.256312) (xy 416.734748 -342.305921)
			(xy 416.750112 -342.358249) (xy 416.757874 -342.412231) (xy 416.757874 -342.466768) (xy 418.240722 -342.466768)
			(xy 418.240722 -342.412232) (xy 418.248483 -342.35825) (xy 418.263847 -342.305923) (xy 418.286502 -342.256314)
			(xy 418.315985 -342.210434) (xy 418.351697 -342.169217) (xy 418.392912 -342.133502) (xy 418.43879 -342.104015)
			(xy 418.488396 -342.081357) (xy 418.540723 -342.065989) (xy 418.594704 -342.058224) (xy 418.621972 -342.057736)
			(xy 419.485572 -342.057736) (xy 419.512844 -342.058202) (xy 419.566834 -342.06596) (xy 419.61917 -342.081324)
			(xy 419.668786 -342.10398) (xy 419.714673 -342.133467) (xy 419.755896 -342.169184) (xy 419.791616 -342.210405)
			(xy 419.821107 -342.256289) (xy 419.843766 -342.305904) (xy 419.859134 -342.358239) (xy 419.866896 -342.412228)
			(xy 419.866896 -342.466772) (xy 419.866896 -342.466773) (xy 421.3496 -342.466773) (xy 421.3496 -342.412227)
			(xy 421.357363 -342.358237) (xy 421.372731 -342.305902) (xy 421.395391 -342.256286) (xy 421.424881 -342.210401)
			(xy 421.460602 -342.16918) (xy 421.501827 -342.133462) (xy 421.547715 -342.103975) (xy 421.597332 -342.081319)
			(xy 421.649669 -342.065956) (xy 421.703659 -342.058197) (xy 421.730932 -342.057736) (xy 422.594532 -342.057736)
			(xy 422.6218 -342.058229) (xy 422.67578 -342.065994) (xy 422.728105 -342.081362) (xy 422.777711 -342.10402)
			(xy 422.823588 -342.133506) (xy 422.864801 -342.169222) (xy 422.900513 -342.210438) (xy 422.929995 -342.256317)
			(xy 422.952649 -342.305925) (xy 422.968013 -342.358252) (xy 422.975774 -342.412232) (xy 422.975774 -342.466768)
			(xy 422.975774 -342.466769) (xy 424.458622 -342.466769) (xy 424.458622 -342.412231) (xy 424.466384 -342.358248)
			(xy 424.481749 -342.305918) (xy 424.504405 -342.256309) (xy 424.53389 -342.210428) (xy 424.569605 -342.16921)
			(xy 424.610821 -342.133495) (xy 424.656702 -342.104009) (xy 424.706311 -342.081352) (xy 424.75864 -342.065986)
			(xy 424.812623 -342.058223) (xy 424.839892 -342.057736) (xy 425.703492 -342.057736) (xy 425.730763 -342.058203)
			(xy 425.784751 -342.065964) (xy 425.837084 -342.08133) (xy 425.886698 -342.103987) (xy 425.932582 -342.133474)
			(xy 425.973803 -342.169191) (xy 426.009521 -342.210411) (xy 426.03901 -342.256295) (xy 426.061668 -342.305908)
			(xy 426.077034 -342.358241) (xy 426.084796 -342.412229) (xy 426.084796 -342.466767) (xy 427.567622 -342.466767)
			(xy 427.567622 -342.412233) (xy 427.575383 -342.358253) (xy 427.590746 -342.305927) (xy 427.613399 -342.25632)
			(xy 427.64288 -342.210441) (xy 427.67859 -342.169224) (xy 427.719802 -342.133509) (xy 427.765678 -342.104022)
			(xy 427.815282 -342.081363) (xy 427.867606 -342.065993) (xy 427.921585 -342.058226) (xy 427.948852 -342.057736)
			(xy 428.812452 -342.057736) (xy 428.839725 -342.0582) (xy 428.893717 -342.065957) (xy 428.946055 -342.081319)
			(xy 428.995674 -342.103974) (xy 429.041563 -342.13346) (xy 429.082789 -342.169177) (xy 429.118512 -342.210398)
			(xy 429.148003 -342.256284) (xy 429.170664 -342.3059) (xy 429.186033 -342.358236) (xy 429.193796 -342.412227)
			(xy 429.193796 -342.466772) (xy 430.6765 -342.466772) (xy 430.6765 -342.412228) (xy 430.684262 -342.35824)
			(xy 430.699629 -342.305906) (xy 430.722288 -342.256292) (xy 430.751776 -342.210407) (xy 430.787495 -342.169187)
			(xy 430.828717 -342.133469) (xy 430.874603 -342.103982) (xy 430.924217 -342.081325) (xy 430.976552 -342.065959)
			(xy 431.03054 -342.058199) (xy 431.057812 -342.057736) (xy 431.921412 -342.057736) (xy 431.948681 -342.058227)
			(xy 432.002663 -342.06599) (xy 432.054991 -342.081357) (xy 432.104599 -342.104013) (xy 432.150478 -342.133499)
			(xy 432.191694 -342.169214) (xy 432.227408 -342.210432) (xy 432.256892 -342.256312) (xy 432.279548 -342.305921)
			(xy 432.294912 -342.358249) (xy 432.302674 -342.412231) (xy 432.302674 -342.466768) (xy 433.785522 -342.466768)
			(xy 433.785522 -342.412232) (xy 433.793283 -342.35825) (xy 433.808647 -342.305923) (xy 433.831302 -342.256314)
			(xy 433.860785 -342.210434) (xy 433.896497 -342.169217) (xy 433.937712 -342.133502) (xy 433.98359 -342.104015)
			(xy 434.033196 -342.081357) (xy 434.085523 -342.065989) (xy 434.139504 -342.058224) (xy 434.166772 -342.057736)
			(xy 435.030372 -342.057736) (xy 435.057644 -342.058202) (xy 435.111634 -342.06596) (xy 435.16397 -342.081324)
			(xy 435.213586 -342.10398) (xy 435.259473 -342.133467) (xy 435.300696 -342.169184) (xy 435.336416 -342.210405)
			(xy 435.365907 -342.256289) (xy 435.388566 -342.305904) (xy 435.403934 -342.358239) (xy 435.411696 -342.412228)
			(xy 435.411696 -342.466772) (xy 435.411696 -342.466773) (xy 436.8944 -342.466773) (xy 436.8944 -342.412227)
			(xy 436.902163 -342.358237) (xy 436.917531 -342.305902) (xy 436.940191 -342.256286) (xy 436.969681 -342.210401)
			(xy 437.005402 -342.16918) (xy 437.046627 -342.133462) (xy 437.092515 -342.103975) (xy 437.142132 -342.081319)
			(xy 437.194469 -342.065956) (xy 437.248459 -342.058197) (xy 437.275732 -342.057736) (xy 438.139332 -342.057736)
			(xy 438.1666 -342.058229) (xy 438.22058 -342.065994) (xy 438.272905 -342.081362) (xy 438.322511 -342.10402)
			(xy 438.368388 -342.133506) (xy 438.409601 -342.169222) (xy 438.445313 -342.210438) (xy 438.474795 -342.256317)
			(xy 438.497449 -342.305925) (xy 438.512813 -342.358252) (xy 438.520574 -342.412232) (xy 438.520574 -342.466768)
			(xy 438.520574 -342.466769) (xy 440.003422 -342.466769) (xy 440.003422 -342.412231) (xy 440.011184 -342.358248)
			(xy 440.026549 -342.305918) (xy 440.049205 -342.256309) (xy 440.07869 -342.210428) (xy 440.114405 -342.16921)
			(xy 440.155621 -342.133495) (xy 440.201502 -342.104009) (xy 440.251111 -342.081352) (xy 440.30344 -342.065986)
			(xy 440.357423 -342.058223) (xy 440.384692 -342.057736) (xy 441.248292 -342.057736) (xy 441.275563 -342.058203)
			(xy 441.329551 -342.065964) (xy 441.381884 -342.08133) (xy 441.431498 -342.103987) (xy 441.477382 -342.133474)
			(xy 441.518603 -342.169191) (xy 441.554321 -342.210411) (xy 441.58381 -342.256295) (xy 441.606468 -342.305908)
			(xy 441.621834 -342.358241) (xy 441.629596 -342.412229) (xy 441.629596 -342.466771) (xy 441.621834 -342.520759)
			(xy 441.606468 -342.573092) (xy 441.58381 -342.622705) (xy 441.554321 -342.668589) (xy 441.518603 -342.709809)
			(xy 441.477382 -342.745526) (xy 441.431498 -342.775013) (xy 441.381884 -342.79767) (xy 441.329551 -342.813036)
			(xy 441.275563 -342.820797) (xy 441.248292 -342.82126) (xy 440.384692 -342.82126) (xy 440.357423 -342.820777)
			(xy 440.30344 -342.813014) (xy 440.251111 -342.797648) (xy 440.201502 -342.774991) (xy 440.155621 -342.745505)
			(xy 440.114405 -342.70979) (xy 440.07869 -342.668572) (xy 440.049205 -342.622691) (xy 440.026549 -342.573082)
			(xy 440.011184 -342.520752) (xy 440.003422 -342.466769) (xy 438.520574 -342.466769) (xy 438.512813 -342.520748)
			(xy 438.497449 -342.573075) (xy 438.474795 -342.622683) (xy 438.445313 -342.668562) (xy 438.409601 -342.709778)
			(xy 438.368388 -342.745494) (xy 438.322511 -342.77498) (xy 438.272905 -342.797638) (xy 438.22058 -342.813006)
			(xy 438.1666 -342.820771) (xy 438.139332 -342.82126) (xy 437.275732 -342.82126) (xy 437.248459 -342.820803)
			(xy 437.194469 -342.813044) (xy 437.142132 -342.797681) (xy 437.092515 -342.775025) (xy 437.046627 -342.745538)
			(xy 437.005402 -342.70982) (xy 436.969681 -342.668599) (xy 436.940191 -342.622714) (xy 436.917531 -342.573098)
			(xy 436.902163 -342.520763) (xy 436.8944 -342.466773) (xy 435.411696 -342.466773) (xy 435.403934 -342.520761)
			(xy 435.388566 -342.573096) (xy 435.365907 -342.622711) (xy 435.336416 -342.668595) (xy 435.300696 -342.709816)
			(xy 435.259473 -342.745533) (xy 435.213586 -342.77502) (xy 435.16397 -342.797676) (xy 435.111634 -342.81304)
			(xy 435.057644 -342.820798) (xy 435.030372 -342.82126) (xy 434.166772 -342.82126) (xy 434.139504 -342.820776)
			(xy 434.085523 -342.813011) (xy 434.033196 -342.797643) (xy 433.98359 -342.774985) (xy 433.937712 -342.745498)
			(xy 433.896497 -342.709783) (xy 433.860785 -342.668566) (xy 433.831302 -342.622686) (xy 433.808647 -342.573077)
			(xy 433.793283 -342.52075) (xy 433.785522 -342.466768) (xy 432.302674 -342.466768) (xy 432.302674 -342.466769)
			(xy 432.294912 -342.520751) (xy 432.279548 -342.573079) (xy 432.256892 -342.622688) (xy 432.227408 -342.668568)
			(xy 432.191694 -342.709786) (xy 432.150478 -342.745501) (xy 432.104599 -342.774987) (xy 432.054991 -342.797643)
			(xy 432.002663 -342.81301) (xy 431.948681 -342.820773) (xy 431.921412 -342.82126) (xy 431.057812 -342.82126)
			(xy 431.03054 -342.820801) (xy 430.976552 -342.813041) (xy 430.924217 -342.797675) (xy 430.874603 -342.775018)
			(xy 430.828717 -342.745531) (xy 430.787495 -342.709813) (xy 430.751776 -342.668593) (xy 430.722288 -342.622708)
			(xy 430.699629 -342.573094) (xy 430.684262 -342.52076) (xy 430.6765 -342.466772) (xy 429.193796 -342.466772)
			(xy 429.193796 -342.466773) (xy 429.186033 -342.520764) (xy 429.170664 -342.5731) (xy 429.148003 -342.622716)
			(xy 429.118512 -342.668602) (xy 429.082789 -342.709823) (xy 429.041563 -342.74554) (xy 428.995674 -342.775026)
			(xy 428.946055 -342.797681) (xy 428.893717 -342.813043) (xy 428.839725 -342.8208) (xy 428.812452 -342.82126)
			(xy 427.948852 -342.82126) (xy 427.921585 -342.820774) (xy 427.867606 -342.813007) (xy 427.815282 -342.797637)
			(xy 427.765678 -342.774978) (xy 427.719802 -342.745491) (xy 427.67859 -342.709776) (xy 427.64288 -342.668559)
			(xy 427.613399 -342.62268) (xy 427.590746 -342.573073) (xy 427.575383 -342.520747) (xy 427.567622 -342.466767)
			(xy 426.084796 -342.466767) (xy 426.084796 -342.466771) (xy 426.077034 -342.520759) (xy 426.061668 -342.573092)
			(xy 426.03901 -342.622705) (xy 426.009521 -342.668589) (xy 425.973803 -342.709809) (xy 425.932582 -342.745526)
			(xy 425.886698 -342.775013) (xy 425.837084 -342.79767) (xy 425.784751 -342.813036) (xy 425.730763 -342.820797)
			(xy 425.703492 -342.82126) (xy 424.839892 -342.82126) (xy 424.812623 -342.820777) (xy 424.75864 -342.813014)
			(xy 424.706311 -342.797648) (xy 424.656702 -342.774991) (xy 424.610821 -342.745505) (xy 424.569605 -342.70979)
			(xy 424.53389 -342.668572) (xy 424.504405 -342.622691) (xy 424.481749 -342.573082) (xy 424.466384 -342.520752)
			(xy 424.458622 -342.466769) (xy 422.975774 -342.466769) (xy 422.968013 -342.520748) (xy 422.952649 -342.573075)
			(xy 422.929995 -342.622683) (xy 422.900513 -342.668562) (xy 422.864801 -342.709778) (xy 422.823588 -342.745494)
			(xy 422.777711 -342.77498) (xy 422.728105 -342.797638) (xy 422.67578 -342.813006) (xy 422.6218 -342.820771)
			(xy 422.594532 -342.82126) (xy 421.730932 -342.82126) (xy 421.703659 -342.820803) (xy 421.649669 -342.813044)
			(xy 421.597332 -342.797681) (xy 421.547715 -342.775025) (xy 421.501827 -342.745538) (xy 421.460602 -342.70982)
			(xy 421.424881 -342.668599) (xy 421.395391 -342.622714) (xy 421.372731 -342.573098) (xy 421.357363 -342.520763)
			(xy 421.3496 -342.466773) (xy 419.866896 -342.466773) (xy 419.859134 -342.520761) (xy 419.843766 -342.573096)
			(xy 419.821107 -342.622711) (xy 419.791616 -342.668595) (xy 419.755896 -342.709816) (xy 419.714673 -342.745533)
			(xy 419.668786 -342.77502) (xy 419.61917 -342.797676) (xy 419.566834 -342.81304) (xy 419.512844 -342.820798)
			(xy 419.485572 -342.82126) (xy 418.621972 -342.82126) (xy 418.594704 -342.820776) (xy 418.540723 -342.813011)
			(xy 418.488396 -342.797643) (xy 418.43879 -342.774985) (xy 418.392912 -342.745498) (xy 418.351697 -342.709783)
			(xy 418.315985 -342.668566) (xy 418.286502 -342.622686) (xy 418.263847 -342.573077) (xy 418.248483 -342.52075)
			(xy 418.240722 -342.466768) (xy 416.757874 -342.466768) (xy 416.757874 -342.466769) (xy 416.750112 -342.520751)
			(xy 416.734748 -342.573079) (xy 416.712092 -342.622688) (xy 416.682608 -342.668568) (xy 416.646894 -342.709786)
			(xy 416.605678 -342.745501) (xy 416.559799 -342.774987) (xy 416.510191 -342.797643) (xy 416.457863 -342.81301)
			(xy 416.403881 -342.820773) (xy 416.376612 -342.82126) (xy 415.513012 -342.82126) (xy 415.48574 -342.820801)
			(xy 415.431752 -342.813041) (xy 415.379417 -342.797675) (xy 415.329803 -342.775018) (xy 415.283917 -342.745531)
			(xy 415.242695 -342.709813) (xy 415.206976 -342.668593) (xy 415.177488 -342.622708) (xy 415.154829 -342.573094)
			(xy 415.139462 -342.52076) (xy 415.1317 -342.466772) (xy 413.648996 -342.466772) (xy 413.648996 -342.466773)
			(xy 413.641233 -342.520764) (xy 413.625864 -342.5731) (xy 413.603203 -342.622716) (xy 413.573712 -342.668602)
			(xy 413.537989 -342.709823) (xy 413.496763 -342.74554) (xy 413.450874 -342.775026) (xy 413.401255 -342.797681)
			(xy 413.348917 -342.813043) (xy 413.294925 -342.8208) (xy 413.267652 -342.82126) (xy 412.404052 -342.82126)
			(xy 412.376785 -342.820774) (xy 412.322806 -342.813007) (xy 412.270482 -342.797637) (xy 412.220878 -342.774978)
			(xy 412.175002 -342.745491) (xy 412.13379 -342.709776) (xy 412.09808 -342.668559) (xy 412.068599 -342.62268)
			(xy 412.045946 -342.573073) (xy 412.030583 -342.520747) (xy 412.022822 -342.466767) (xy 410.539996 -342.466767)
			(xy 410.539996 -342.466771) (xy 410.532234 -342.520759) (xy 410.516868 -342.573092) (xy 410.49421 -342.622705)
			(xy 410.464721 -342.668589) (xy 410.429003 -342.709809) (xy 410.387782 -342.745526) (xy 410.341898 -342.775013)
			(xy 410.292284 -342.79767) (xy 410.239951 -342.813036) (xy 410.185963 -342.820797) (xy 410.158692 -342.82126)
			(xy 409.295092 -342.82126) (xy 409.267823 -342.820777) (xy 409.21384 -342.813014) (xy 409.161511 -342.797648)
			(xy 409.111902 -342.774991) (xy 409.066021 -342.745505) (xy 409.024805 -342.70979) (xy 408.98909 -342.668572)
			(xy 408.959605 -342.622691) (xy 408.936949 -342.573082) (xy 408.921584 -342.520752) (xy 408.913822 -342.466769)
			(xy 403.522496 -342.466769) (xy 403.522496 -342.466772) (xy 403.514734 -342.52076) (xy 403.499367 -342.573094)
			(xy 403.476708 -342.622708) (xy 403.447218 -342.668593) (xy 403.411499 -342.709813) (xy 403.370277 -342.74553)
			(xy 403.324391 -342.775017) (xy 403.274775 -342.797674) (xy 403.222441 -342.813038) (xy 403.168452 -342.820798)
			(xy 403.14118 -342.82126) (xy 402.27758 -342.82126) (xy 402.250311 -342.820776) (xy 402.19633 -342.813012)
			(xy 402.144002 -342.797645) (xy 402.094394 -342.774988) (xy 402.048516 -342.745501) (xy 402.0073 -342.709786)
			(xy 401.971587 -342.668568) (xy 401.942103 -342.622688) (xy 401.919448 -342.573079) (xy 401.904084 -342.520751)
			(xy 401.896322 -342.466769) (xy 400.413474 -342.466769) (xy 400.405713 -342.52075) (xy 400.390348 -342.573078)
			(xy 400.367694 -342.622686) (xy 400.33821 -342.668566) (xy 400.302497 -342.709783) (xy 400.261282 -342.745498)
			(xy 400.215404 -342.774984) (xy 400.165796 -342.797641) (xy 400.113469 -342.813008) (xy 400.059488 -342.820772)
			(xy 400.03222 -342.82126) (xy 399.16862 -342.82126) (xy 399.141348 -342.820802) (xy 399.087359 -342.813042)
			(xy 399.035023 -342.797677) (xy 398.985407 -342.775021) (xy 398.939521 -342.745534) (xy 398.898298 -342.709816)
			(xy 398.862578 -342.668595) (xy 398.833089 -342.62271) (xy 398.81043 -342.573096) (xy 398.795062 -342.520761)
			(xy 398.7873 -342.466772) (xy 397.304596 -342.466772) (xy 397.304596 -342.466773) (xy 397.296833 -342.520763)
			(xy 397.281465 -342.573098) (xy 397.258805 -342.622714) (xy 397.229313 -342.668599) (xy 397.193592 -342.70982)
			(xy 397.152367 -342.745537) (xy 397.106479 -342.775024) (xy 397.056861 -342.797679) (xy 397.004524 -342.813042)
			(xy 396.950533 -342.820799) (xy 396.92326 -342.82126) (xy 396.05966 -342.82126) (xy 396.032392 -342.820775)
			(xy 395.978413 -342.813009) (xy 395.926088 -342.79764) (xy 395.876482 -342.774981) (xy 395.830606 -342.745494)
			(xy 395.789393 -342.709778) (xy 395.753682 -342.668562) (xy 395.7242 -342.622682) (xy 395.701546 -342.573075)
			(xy 395.686183 -342.520748) (xy 395.678422 -342.466768) (xy 394.195574 -342.466768) (xy 394.195574 -342.466769)
			(xy 394.187812 -342.520753) (xy 394.172447 -342.573082) (xy 394.149791 -342.622692) (xy 394.120305 -342.668572)
			(xy 394.08459 -342.70979) (xy 394.043372 -342.745505) (xy 393.997492 -342.774991) (xy 393.947882 -342.797647)
			(xy 393.895553 -342.813012) (xy 393.841569 -342.820774) (xy 393.8143 -342.82126) (xy 392.9507 -342.82126)
			(xy 392.92343 -342.820778) (xy 392.869447 -342.813016) (xy 392.817117 -342.79765) (xy 392.767506 -342.774994)
			(xy 392.721625 -342.745508) (xy 392.680407 -342.709793) (xy 392.644692 -342.668575) (xy 392.615206 -342.622694)
			(xy 392.59255 -342.573083) (xy 392.577184 -342.520753) (xy 392.569422 -342.46677) (xy 391.086574 -342.46677)
			(xy 391.078813 -342.520747) (xy 391.06345 -342.573073) (xy 391.040797 -342.622681) (xy 391.011315 -342.668559)
			(xy 390.975604 -342.709776) (xy 390.934391 -342.745491) (xy 390.888516 -342.774978) (xy 390.838911 -342.797636)
			(xy 390.786586 -342.813005) (xy 390.732607 -342.820771) (xy 390.70534 -342.82126) (xy 389.84174 -342.82126)
			(xy 389.814467 -342.820803) (xy 389.760476 -342.813046) (xy 389.708138 -342.797683) (xy 389.658519 -342.775027)
			(xy 389.61263 -342.745541) (xy 389.571405 -342.709823) (xy 389.535683 -342.668602) (xy 389.506192 -342.622716)
			(xy 389.483531 -342.5731) (xy 389.468163 -342.520764) (xy 389.4604 -342.466773) (xy 387.977696 -342.466773)
			(xy 387.969934 -342.52076) (xy 387.954567 -342.573094) (xy 387.931908 -342.622708) (xy 387.902418 -342.668593)
			(xy 387.866699 -342.709813) (xy 387.825477 -342.74553) (xy 387.779591 -342.775017) (xy 387.729975 -342.797674)
			(xy 387.677641 -342.813038) (xy 387.623652 -342.820798) (xy 387.59638 -342.82126) (xy 386.73278 -342.82126)
			(xy 386.705511 -342.820776) (xy 386.65153 -342.813012) (xy 386.599202 -342.797645) (xy 386.549594 -342.774988)
			(xy 386.503716 -342.745501) (xy 386.4625 -342.709786) (xy 386.426787 -342.668568) (xy 386.397303 -342.622688)
			(xy 386.374648 -342.573079) (xy 386.359284 -342.520751) (xy 386.351522 -342.466769) (xy 384.868674 -342.466769)
			(xy 384.860913 -342.52075) (xy 384.845548 -342.573078) (xy 384.822894 -342.622686) (xy 384.79341 -342.668566)
			(xy 384.757697 -342.709783) (xy 384.716482 -342.745498) (xy 384.670604 -342.774984) (xy 384.620996 -342.797641)
			(xy 384.568669 -342.813008) (xy 384.514688 -342.820772) (xy 384.48742 -342.82126) (xy 383.62382 -342.82126)
			(xy 383.596548 -342.820802) (xy 383.542559 -342.813042) (xy 383.490223 -342.797677) (xy 383.440607 -342.775021)
			(xy 383.394721 -342.745534) (xy 383.353498 -342.709816) (xy 383.317778 -342.668595) (xy 383.288289 -342.62271)
			(xy 383.26563 -342.573096) (xy 383.250262 -342.520761) (xy 383.2425 -342.466772) (xy 381.759796 -342.466772)
			(xy 381.759796 -342.466773) (xy 381.752033 -342.520763) (xy 381.736665 -342.573098) (xy 381.714005 -342.622714)
			(xy 381.684513 -342.668599) (xy 381.648792 -342.70982) (xy 381.607567 -342.745537) (xy 381.561679 -342.775024)
			(xy 381.512061 -342.797679) (xy 381.459724 -342.813042) (xy 381.405733 -342.820799) (xy 381.37846 -342.82126)
			(xy 380.51486 -342.82126) (xy 380.487592 -342.820775) (xy 380.433613 -342.813009) (xy 380.381288 -342.79764)
			(xy 380.331682 -342.774981) (xy 380.285806 -342.745494) (xy 380.244593 -342.709778) (xy 380.208882 -342.668562)
			(xy 380.1794 -342.622682) (xy 380.156746 -342.573075) (xy 380.141383 -342.520748) (xy 380.133622 -342.466768)
			(xy 378.650774 -342.466768) (xy 378.650774 -342.466769) (xy 378.643012 -342.520753) (xy 378.627647 -342.573082)
			(xy 378.604991 -342.622692) (xy 378.575505 -342.668572) (xy 378.53979 -342.70979) (xy 378.498572 -342.745505)
			(xy 378.452692 -342.774991) (xy 378.403082 -342.797647) (xy 378.350753 -342.813012) (xy 378.296769 -342.820774)
			(xy 378.2695 -342.82126) (xy 377.4059 -342.82126) (xy 377.37863 -342.820778) (xy 377.324647 -342.813016)
			(xy 377.272317 -342.79765) (xy 377.222706 -342.774994) (xy 377.176825 -342.745508) (xy 377.135607 -342.709793)
			(xy 377.099892 -342.668575) (xy 377.070406 -342.622694) (xy 377.04775 -342.573083) (xy 377.032384 -342.520753)
			(xy 377.024622 -342.46677) (xy 375.541774 -342.46677) (xy 375.534013 -342.520747) (xy 375.51865 -342.573073)
			(xy 375.495997 -342.622681) (xy 375.466515 -342.668559) (xy 375.430804 -342.709776) (xy 375.389591 -342.745491)
			(xy 375.343716 -342.774978) (xy 375.294111 -342.797636) (xy 375.241786 -342.813005) (xy 375.187807 -342.820771)
			(xy 375.16054 -342.82126) (xy 374.29694 -342.82126) (xy 374.269667 -342.820803) (xy 374.215676 -342.813046)
			(xy 374.163338 -342.797683) (xy 374.113719 -342.775027) (xy 374.06783 -342.745541) (xy 374.026605 -342.709823)
			(xy 373.990883 -342.668602) (xy 373.961392 -342.622716) (xy 373.938731 -342.5731) (xy 373.923363 -342.520764)
			(xy 373.9156 -342.466773) (xy 372.432896 -342.466773) (xy 372.425134 -342.52076) (xy 372.409767 -342.573094)
			(xy 372.387108 -342.622708) (xy 372.357618 -342.668593) (xy 372.321899 -342.709813) (xy 372.280677 -342.74553)
			(xy 372.234791 -342.775017) (xy 372.185175 -342.797674) (xy 372.132841 -342.813038) (xy 372.078852 -342.820798)
			(xy 372.05158 -342.82126) (xy 371.18798 -342.82126) (xy 371.160711 -342.820776) (xy 371.10673 -342.813012)
			(xy 371.054402 -342.797645) (xy 371.004794 -342.774988) (xy 370.958916 -342.745501) (xy 370.9177 -342.709786)
			(xy 370.881987 -342.668568) (xy 370.852503 -342.622688) (xy 370.829848 -342.573079) (xy 370.814484 -342.520751)
			(xy 370.806722 -342.466769) (xy 369.214908 -342.466769) (xy 369.214908 -345.492365) (xy 370.80677 -345.492365)
			(xy 370.80677 -345.437835) (xy 370.81453 -345.383859) (xy 370.829893 -345.331538) (xy 370.852545 -345.281935)
			(xy 370.882025 -345.236061) (xy 370.917734 -345.194848) (xy 370.958945 -345.159137) (xy 371.004817 -345.129655)
			(xy 371.054419 -345.107) (xy 371.10674 -345.091635) (xy 371.160715 -345.083872) (xy 371.18798 -345.083384)
			(xy 372.05158 -345.083384) (xy 372.078855 -345.083754) (xy 372.132851 -345.091515) (xy 372.185192 -345.106881)
			(xy 372.234814 -345.129541) (xy 372.280705 -345.159031) (xy 372.321933 -345.194753) (xy 372.357657 -345.235978)
			(xy 372.38715 -345.281869) (xy 372.409812 -345.331489) (xy 372.425181 -345.38383) (xy 372.432944 -345.437825)
			(xy 372.432944 -345.49237) (xy 373.915647 -345.49237) (xy 373.915647 -345.43783) (xy 373.92341 -345.383847)
			(xy 373.938776 -345.331517) (xy 373.961434 -345.281907) (xy 373.990922 -345.236027) (xy 374.026639 -345.194811)
			(xy 374.067859 -345.159098) (xy 374.113742 -345.129615) (xy 374.163355 -345.106962) (xy 374.215686 -345.091601)
			(xy 374.26967 -345.083845) (xy 374.29694 -345.083384) (xy 375.16054 -345.083384) (xy 375.187811 -345.083781)
			(xy 375.241797 -345.091549) (xy 375.294128 -345.106919) (xy 375.343739 -345.12958) (xy 375.38962 -345.159071)
			(xy 375.430838 -345.19479) (xy 375.466553 -345.236012) (xy 375.496039 -345.281896) (xy 375.518695 -345.33151)
			(xy 375.53406 -345.383843) (xy 375.541822 -345.437829) (xy 375.541822 -345.492366) (xy 377.02467 -345.492366)
			(xy 377.02467 -345.437834) (xy 377.032431 -345.383857) (xy 377.047795 -345.331534) (xy 377.070448 -345.281929)
			(xy 377.09993 -345.236054) (xy 377.135641 -345.194841) (xy 377.176854 -345.15913) (xy 377.222729 -345.129648)
			(xy 377.272334 -345.106995) (xy 377.324657 -345.091631) (xy 377.378634 -345.08387) (xy 377.4059 -345.083384)
			(xy 378.2695 -345.083384) (xy 378.296773 -345.083779) (xy 378.350763 -345.091541) (xy 378.403099 -345.106908)
			(xy 378.452715 -345.129567) (xy 378.498601 -345.159057) (xy 378.539824 -345.194776) (xy 378.575543 -345.235999)
			(xy 378.605033 -345.281885) (xy 378.627692 -345.331501) (xy 378.643059 -345.383837) (xy 378.650821 -345.437827)
			(xy 378.650821 -345.492364) (xy 380.13367 -345.492364) (xy 380.13367 -345.437836) (xy 380.14143 -345.383862)
			(xy 380.156791 -345.331542) (xy 380.179442 -345.281941) (xy 380.208921 -345.236067) (xy 380.244627 -345.194855)
			(xy 380.285835 -345.159145) (xy 380.331705 -345.129661) (xy 380.381305 -345.107005) (xy 380.433623 -345.091638)
			(xy 380.487596 -345.083873) (xy 380.51486 -345.083384) (xy 381.37846 -345.083384) (xy 381.405736 -345.083753)
			(xy 381.459734 -345.091511) (xy 381.512078 -345.106876) (xy 381.561702 -345.129534) (xy 381.607596 -345.159024)
			(xy 381.648826 -345.194746) (xy 381.684552 -345.235972) (xy 381.714047 -345.281863) (xy 381.73671 -345.331485)
			(xy 381.75208 -345.383827) (xy 381.759844 -345.437824) (xy 381.759844 -345.492369) (xy 383.242547 -345.492369)
			(xy 383.242547 -345.437831) (xy 383.250309 -345.383849) (xy 383.265675 -345.331521) (xy 383.288331 -345.281913)
			(xy 383.317817 -345.236034) (xy 383.353532 -345.194818) (xy 383.39475 -345.159105) (xy 383.44063 -345.129621)
			(xy 383.49024 -345.106968) (xy 383.542569 -345.091605) (xy 383.596551 -345.083846) (xy 383.62382 -345.083384)
			(xy 384.48742 -345.083384) (xy 384.514692 -345.08378) (xy 384.56868 -345.091545) (xy 384.621013 -345.106914)
			(xy 384.670627 -345.129574) (xy 384.716511 -345.159064) (xy 384.757731 -345.194783) (xy 384.793448 -345.236005)
			(xy 384.822936 -345.281891) (xy 384.845593 -345.331506) (xy 384.860959 -345.38384) (xy 384.868722 -345.437828)
			(xy 384.868722 -345.492365) (xy 386.35157 -345.492365) (xy 386.35157 -345.437835) (xy 386.35933 -345.383859)
			(xy 386.374693 -345.331538) (xy 386.397345 -345.281935) (xy 386.426825 -345.236061) (xy 386.462534 -345.194848)
			(xy 386.503745 -345.159137) (xy 386.549617 -345.129655) (xy 386.599219 -345.107) (xy 386.65154 -345.091635)
			(xy 386.705515 -345.083872) (xy 386.73278 -345.083384) (xy 387.59638 -345.083384) (xy 387.623655 -345.083754)
			(xy 387.677651 -345.091515) (xy 387.729992 -345.106881) (xy 387.779614 -345.129541) (xy 387.825505 -345.159031)
			(xy 387.866733 -345.194753) (xy 387.902457 -345.235978) (xy 387.93195 -345.281869) (xy 387.954612 -345.331489)
			(xy 387.969981 -345.38383) (xy 387.977744 -345.437825) (xy 387.977744 -345.49237) (xy 389.460447 -345.49237)
			(xy 389.460447 -345.43783) (xy 389.46821 -345.383847) (xy 389.483576 -345.331517) (xy 389.506234 -345.281907)
			(xy 389.535722 -345.236027) (xy 389.571439 -345.194811) (xy 389.612659 -345.159098) (xy 389.658542 -345.129615)
			(xy 389.708155 -345.106962) (xy 389.760486 -345.091601) (xy 389.81447 -345.083845) (xy 389.84174 -345.083384)
			(xy 390.70534 -345.083384) (xy 390.732611 -345.083781) (xy 390.786597 -345.091549) (xy 390.838928 -345.106919)
			(xy 390.888539 -345.12958) (xy 390.93442 -345.159071) (xy 390.975638 -345.19479) (xy 391.011353 -345.236012)
			(xy 391.040839 -345.281896) (xy 391.063495 -345.33151) (xy 391.07886 -345.383843) (xy 391.086622 -345.437829)
			(xy 391.086622 -345.492366) (xy 392.56947 -345.492366) (xy 392.56947 -345.437834) (xy 392.577231 -345.383857)
			(xy 392.592595 -345.331534) (xy 392.615248 -345.281929) (xy 392.64473 -345.236054) (xy 392.680441 -345.194841)
			(xy 392.721654 -345.15913) (xy 392.767529 -345.129648) (xy 392.817134 -345.106995) (xy 392.869457 -345.091631)
			(xy 392.923434 -345.08387) (xy 392.9507 -345.083384) (xy 393.8143 -345.083384) (xy 393.841573 -345.083779)
			(xy 393.895563 -345.091541) (xy 393.947899 -345.106908) (xy 393.997515 -345.129567) (xy 394.043401 -345.159057)
			(xy 394.084624 -345.194776) (xy 394.120343 -345.235999) (xy 394.149833 -345.281885) (xy 394.172492 -345.331501)
			(xy 394.187859 -345.383837) (xy 394.195621 -345.437827) (xy 394.195621 -345.492364) (xy 395.67847 -345.492364)
			(xy 395.67847 -345.437836) (xy 395.68623 -345.383862) (xy 395.701591 -345.331542) (xy 395.724242 -345.281941)
			(xy 395.753721 -345.236067) (xy 395.789427 -345.194855) (xy 395.830635 -345.159145) (xy 395.876505 -345.129661)
			(xy 395.926105 -345.107005) (xy 395.978423 -345.091638) (xy 396.032396 -345.083873) (xy 396.05966 -345.083384)
			(xy 396.92326 -345.083384) (xy 396.950536 -345.083753) (xy 397.004534 -345.091511) (xy 397.056878 -345.106876)
			(xy 397.106502 -345.129534) (xy 397.152396 -345.159024) (xy 397.193626 -345.194746) (xy 397.229352 -345.235972)
			(xy 397.258847 -345.281863) (xy 397.28151 -345.331485) (xy 397.29688 -345.383827) (xy 397.304644 -345.437824)
			(xy 397.304644 -345.492369) (xy 398.787347 -345.492369) (xy 398.787347 -345.437831) (xy 398.795109 -345.383849)
			(xy 398.810475 -345.331521) (xy 398.833131 -345.281913) (xy 398.862617 -345.236034) (xy 398.898332 -345.194818)
			(xy 398.93955 -345.159105) (xy 398.98543 -345.129621) (xy 399.03504 -345.106968) (xy 399.087369 -345.091605)
			(xy 399.141351 -345.083846) (xy 399.16862 -345.083384) (xy 400.03222 -345.083384) (xy 400.059492 -345.08378)
			(xy 400.11348 -345.091545) (xy 400.165813 -345.106914) (xy 400.215427 -345.129574) (xy 400.261311 -345.159064)
			(xy 400.302531 -345.194783) (xy 400.338248 -345.236005) (xy 400.367736 -345.281891) (xy 400.390393 -345.331506)
			(xy 400.405759 -345.38384) (xy 400.413522 -345.437828) (xy 400.413522 -345.492365) (xy 401.89637 -345.492365)
			(xy 401.89637 -345.437835) (xy 401.90413 -345.383859) (xy 401.919493 -345.331538) (xy 401.942145 -345.281935)
			(xy 401.971625 -345.236061) (xy 402.007334 -345.194848) (xy 402.048545 -345.159137) (xy 402.094417 -345.129655)
			(xy 402.144019 -345.107) (xy 402.19634 -345.091635) (xy 402.250315 -345.083872) (xy 402.27758 -345.083384)
			(xy 403.14118 -345.083384) (xy 403.168455 -345.083754) (xy 403.222451 -345.091515) (xy 403.274792 -345.106881)
			(xy 403.324414 -345.129541) (xy 403.370305 -345.159031) (xy 403.411533 -345.194753) (xy 403.447257 -345.235978)
			(xy 403.47675 -345.281869) (xy 403.499412 -345.331489) (xy 403.514781 -345.38383) (xy 403.522544 -345.437825)
			(xy 403.522544 -345.492366) (xy 408.91387 -345.492366) (xy 408.91387 -345.437834) (xy 408.921631 -345.383858)
			(xy 408.936994 -345.331535) (xy 408.959647 -345.281932) (xy 408.989128 -345.236057) (xy 409.024838 -345.194844)
			(xy 409.06605 -345.159133) (xy 409.111925 -345.129651) (xy 409.161528 -345.106997) (xy 409.21385 -345.091633)
			(xy 409.267826 -345.083871) (xy 409.295092 -345.083384) (xy 410.158692 -345.083384) (xy 410.185967 -345.083755)
			(xy 410.239961 -345.091517) (xy 410.292301 -345.106885) (xy 410.341921 -345.129544) (xy 410.387811 -345.159035)
			(xy 410.429037 -345.194757) (xy 410.46476 -345.235982) (xy 410.494252 -345.281872) (xy 410.516913 -345.331492)
			(xy 410.532281 -345.383831) (xy 410.540044 -345.437825) (xy 410.540044 -345.492364) (xy 412.02287 -345.492364)
			(xy 412.02287 -345.437836) (xy 412.03063 -345.383863) (xy 412.045991 -345.331544) (xy 412.068641 -345.281943)
			(xy 412.098119 -345.23607) (xy 412.133824 -345.194858) (xy 412.175031 -345.159147) (xy 412.220901 -345.129664)
			(xy 412.270499 -345.107008) (xy 412.322816 -345.09164) (xy 412.376788 -345.083874) (xy 412.404052 -345.083384)
			(xy 413.267652 -345.083384) (xy 413.294929 -345.083752) (xy 413.348927 -345.09151) (xy 413.401272 -345.106874)
			(xy 413.450897 -345.129531) (xy 413.496792 -345.159021) (xy 413.538023 -345.194743) (xy 413.57375 -345.235969)
			(xy 413.603246 -345.281861) (xy 413.625909 -345.331483) (xy 413.64128 -345.383826) (xy 413.649044 -345.437824)
			(xy 413.649044 -345.492368) (xy 415.131747 -345.492368) (xy 415.131747 -345.437832) (xy 415.139509 -345.38385)
			(xy 415.154874 -345.331523) (xy 415.17753 -345.281915) (xy 415.207015 -345.236036) (xy 415.242729 -345.194821)
			(xy 415.283946 -345.159108) (xy 415.329826 -345.129624) (xy 415.379434 -345.10697) (xy 415.431762 -345.091606)
			(xy 415.485744 -345.083847) (xy 415.513012 -345.083384) (xy 416.376612 -345.083384) (xy 416.403884 -345.083779)
			(xy 416.457873 -345.091543) (xy 416.510207 -345.106912) (xy 416.559822 -345.129571) (xy 416.605707 -345.159061)
			(xy 416.646928 -345.194781) (xy 416.682646 -345.236003) (xy 416.712135 -345.281889) (xy 416.734793 -345.331504)
			(xy 416.750159 -345.383839) (xy 416.757921 -345.437828) (xy 416.757921 -345.492365) (xy 418.24077 -345.492365)
			(xy 418.24077 -345.437835) (xy 418.24853 -345.383861) (xy 418.263892 -345.33154) (xy 418.286544 -345.281937)
			(xy 418.316023 -345.236063) (xy 418.351731 -345.194851) (xy 418.392941 -345.15914) (xy 418.438813 -345.129657)
			(xy 418.488413 -345.107002) (xy 418.540733 -345.091636) (xy 418.594707 -345.083872) (xy 418.621972 -345.083384)
			(xy 419.485572 -345.083384) (xy 419.512848 -345.083754) (xy 419.566844 -345.091514) (xy 419.619186 -345.106879)
			(xy 419.668809 -345.129538) (xy 419.714702 -345.159028) (xy 419.75593 -345.19475) (xy 419.791655 -345.235976)
			(xy 419.821149 -345.281866) (xy 419.843811 -345.331487) (xy 419.859181 -345.383829) (xy 419.866944 -345.437824)
			(xy 419.866944 -345.492369) (xy 421.349647 -345.492369) (xy 421.349647 -345.437831) (xy 421.35741 -345.383848)
			(xy 421.372776 -345.331519) (xy 421.395433 -345.281909) (xy 421.42492 -345.23603) (xy 421.460636 -345.194814)
			(xy 421.501855 -345.159101) (xy 421.547738 -345.129617) (xy 421.597349 -345.106964) (xy 421.649679 -345.091603)
			(xy 421.703663 -345.083845) (xy 421.730932 -345.083384) (xy 422.594532 -345.083384) (xy 422.621803 -345.083781)
			(xy 422.67579 -345.091547) (xy 422.728122 -345.106917) (xy 422.777734 -345.129578) (xy 422.823616 -345.159068)
			(xy 422.864835 -345.194788) (xy 422.900551 -345.236009) (xy 422.930038 -345.281894) (xy 422.952694 -345.331508)
			(xy 422.96806 -345.383842) (xy 422.975822 -345.437829) (xy 422.975822 -345.492366) (xy 424.45867 -345.492366)
			(xy 424.45867 -345.437834) (xy 424.466431 -345.383858) (xy 424.481794 -345.331535) (xy 424.504447 -345.281932)
			(xy 424.533928 -345.236057) (xy 424.569638 -345.194844) (xy 424.61085 -345.159133) (xy 424.656725 -345.129651)
			(xy 424.706328 -345.106997) (xy 424.75865 -345.091633) (xy 424.812626 -345.083871) (xy 424.839892 -345.083384)
			(xy 425.703492 -345.083384) (xy 425.730767 -345.083755) (xy 425.784761 -345.091517) (xy 425.837101 -345.106885)
			(xy 425.886721 -345.129544) (xy 425.932611 -345.159035) (xy 425.973837 -345.194757) (xy 426.00956 -345.235982)
			(xy 426.039052 -345.281872) (xy 426.061713 -345.331492) (xy 426.077081 -345.383831) (xy 426.084844 -345.437825)
			(xy 426.084844 -345.492364) (xy 427.56767 -345.492364) (xy 427.56767 -345.437836) (xy 427.57543 -345.383863)
			(xy 427.590791 -345.331544) (xy 427.613441 -345.281943) (xy 427.642919 -345.23607) (xy 427.678624 -345.194858)
			(xy 427.719831 -345.159147) (xy 427.765701 -345.129664) (xy 427.815299 -345.107008) (xy 427.867616 -345.09164)
			(xy 427.921588 -345.083874) (xy 427.948852 -345.083384) (xy 428.812452 -345.083384) (xy 428.839729 -345.083752)
			(xy 428.893727 -345.09151) (xy 428.946072 -345.106874) (xy 428.995697 -345.129531) (xy 429.041592 -345.159021)
			(xy 429.082823 -345.194743) (xy 429.11855 -345.235969) (xy 429.148046 -345.281861) (xy 429.170709 -345.331483)
			(xy 429.18608 -345.383826) (xy 429.193844 -345.437824) (xy 429.193844 -345.492368) (xy 430.676547 -345.492368)
			(xy 430.676547 -345.437832) (xy 430.684309 -345.38385) (xy 430.699674 -345.331523) (xy 430.72233 -345.281915)
			(xy 430.751815 -345.236036) (xy 430.787529 -345.194821) (xy 430.828746 -345.159108) (xy 430.874626 -345.129624)
			(xy 430.924234 -345.10697) (xy 430.976562 -345.091606) (xy 431.030544 -345.083847) (xy 431.057812 -345.083384)
			(xy 431.921412 -345.083384) (xy 431.948684 -345.083779) (xy 432.002673 -345.091543) (xy 432.055007 -345.106912)
			(xy 432.104622 -345.129571) (xy 432.150507 -345.159061) (xy 432.191728 -345.194781) (xy 432.227446 -345.236003)
			(xy 432.256935 -345.281889) (xy 432.279593 -345.331504) (xy 432.294959 -345.383839) (xy 432.302721 -345.437828)
			(xy 432.302721 -345.492365) (xy 433.78557 -345.492365) (xy 433.78557 -345.437835) (xy 433.79333 -345.383861)
			(xy 433.808692 -345.33154) (xy 433.831344 -345.281937) (xy 433.860823 -345.236063) (xy 433.896531 -345.194851)
			(xy 433.937741 -345.15914) (xy 433.983613 -345.129657) (xy 434.033213 -345.107002) (xy 434.085533 -345.091636)
			(xy 434.139507 -345.083872) (xy 434.166772 -345.083384) (xy 435.030372 -345.083384) (xy 435.057648 -345.083754)
			(xy 435.111644 -345.091514) (xy 435.163986 -345.106879) (xy 435.213609 -345.129538) (xy 435.259502 -345.159028)
			(xy 435.30073 -345.19475) (xy 435.336455 -345.235976) (xy 435.365949 -345.281866) (xy 435.388611 -345.331487)
			(xy 435.403981 -345.383829) (xy 435.411744 -345.437824) (xy 435.411744 -345.492369) (xy 436.894447 -345.492369)
			(xy 436.894447 -345.437831) (xy 436.90221 -345.383848) (xy 436.917576 -345.331519) (xy 436.940233 -345.281909)
			(xy 436.96972 -345.23603) (xy 437.005436 -345.194814) (xy 437.046655 -345.159101) (xy 437.092538 -345.129617)
			(xy 437.142149 -345.106964) (xy 437.194479 -345.091603) (xy 437.248463 -345.083845) (xy 437.275732 -345.083384)
			(xy 438.139332 -345.083384) (xy 438.166603 -345.083781) (xy 438.22059 -345.091547) (xy 438.272922 -345.106917)
			(xy 438.322534 -345.129578) (xy 438.368416 -345.159068) (xy 438.409635 -345.194788) (xy 438.445351 -345.236009)
			(xy 438.474838 -345.281894) (xy 438.497494 -345.331508) (xy 438.51286 -345.383842) (xy 438.520622 -345.437829)
			(xy 438.520622 -345.492366) (xy 440.00347 -345.492366) (xy 440.00347 -345.437834) (xy 440.011231 -345.383858)
			(xy 440.026594 -345.331535) (xy 440.049247 -345.281932) (xy 440.078728 -345.236057) (xy 440.114438 -345.194844)
			(xy 440.15565 -345.159133) (xy 440.201525 -345.129651) (xy 440.251128 -345.106997) (xy 440.30345 -345.091633)
			(xy 440.357426 -345.083871) (xy 440.384692 -345.083384) (xy 441.248292 -345.083384) (xy 441.275567 -345.083755)
			(xy 441.329561 -345.091517) (xy 441.381901 -345.106885) (xy 441.431521 -345.129544) (xy 441.477411 -345.159035)
			(xy 441.518637 -345.194757) (xy 441.55436 -345.235982) (xy 441.583852 -345.281872) (xy 441.606513 -345.331492)
			(xy 441.621881 -345.383831) (xy 441.629644 -345.437825) (xy 441.629644 -345.492375) (xy 441.621881 -345.546369)
			(xy 441.606513 -345.598708) (xy 441.583852 -345.648328) (xy 441.55436 -345.694218) (xy 441.518637 -345.735443)
			(xy 441.477411 -345.771165) (xy 441.431521 -345.800656) (xy 441.381901 -345.823315) (xy 441.329561 -345.838683)
			(xy 441.275567 -345.846445) (xy 441.248292 -345.846908) (xy 440.384692 -345.846908) (xy 440.357426 -345.846329)
			(xy 440.30345 -345.838567) (xy 440.251128 -345.823203) (xy 440.201525 -345.800549) (xy 440.15565 -345.771067)
			(xy 440.114438 -345.735356) (xy 440.078728 -345.694143) (xy 440.049247 -345.648268) (xy 440.026594 -345.598665)
			(xy 440.011231 -345.546342) (xy 440.00347 -345.492366) (xy 438.520622 -345.492366) (xy 438.520622 -345.492371)
			(xy 438.51286 -345.546358) (xy 438.497494 -345.598692) (xy 438.474838 -345.648306) (xy 438.445351 -345.694191)
			(xy 438.409635 -345.735412) (xy 438.368416 -345.771132) (xy 438.322534 -345.800622) (xy 438.272922 -345.823283)
			(xy 438.22059 -345.838653) (xy 438.166603 -345.846419) (xy 438.139332 -345.846908) (xy 437.275732 -345.846908)
			(xy 437.248463 -345.846355) (xy 437.194479 -345.838597) (xy 437.142149 -345.823236) (xy 437.092538 -345.800583)
			(xy 437.046655 -345.771099) (xy 437.005436 -345.735386) (xy 436.96972 -345.69417) (xy 436.940233 -345.648291)
			(xy 436.917576 -345.598681) (xy 436.90221 -345.546352) (xy 436.894447 -345.492369) (xy 435.411744 -345.492369)
			(xy 435.411744 -345.492376) (xy 435.403981 -345.546371) (xy 435.388611 -345.598713) (xy 435.365949 -345.648334)
			(xy 435.336455 -345.694224) (xy 435.30073 -345.73545) (xy 435.259502 -345.771172) (xy 435.213609 -345.800662)
			(xy 435.163986 -345.823321) (xy 435.111644 -345.838686) (xy 435.057648 -345.846446) (xy 435.030372 -345.846908)
			(xy 434.166772 -345.846908) (xy 434.139507 -345.846328) (xy 434.085533 -345.838564) (xy 434.033213 -345.823198)
			(xy 433.983613 -345.800543) (xy 433.937741 -345.77106) (xy 433.896531 -345.735349) (xy 433.860823 -345.694137)
			(xy 433.831344 -345.648263) (xy 433.808692 -345.59866) (xy 433.79333 -345.546339) (xy 433.78557 -345.492365)
			(xy 432.302721 -345.492365) (xy 432.302721 -345.492372) (xy 432.294959 -345.546361) (xy 432.279593 -345.598696)
			(xy 432.256935 -345.648311) (xy 432.227446 -345.694197) (xy 432.191728 -345.735419) (xy 432.150507 -345.771139)
			(xy 432.104622 -345.800629) (xy 432.055007 -345.823288) (xy 432.002673 -345.838657) (xy 431.948684 -345.846421)
			(xy 431.921412 -345.846908) (xy 431.057812 -345.846908) (xy 431.030544 -345.846353) (xy 430.976562 -345.838594)
			(xy 430.924234 -345.82323) (xy 430.874626 -345.800576) (xy 430.828746 -345.771092) (xy 430.787529 -345.735379)
			(xy 430.751815 -345.694164) (xy 430.72233 -345.648285) (xy 430.699674 -345.598677) (xy 430.684309 -345.54635)
			(xy 430.676547 -345.492368) (xy 429.193844 -345.492368) (xy 429.193844 -345.492376) (xy 429.18608 -345.546374)
			(xy 429.170709 -345.598717) (xy 429.148046 -345.648339) (xy 429.11855 -345.694231) (xy 429.082823 -345.735457)
			(xy 429.041592 -345.771179) (xy 428.995697 -345.800669) (xy 428.946072 -345.823326) (xy 428.893727 -345.83869)
			(xy 428.839729 -345.846448) (xy 428.812452 -345.846908) (xy 427.948852 -345.846908) (xy 427.921588 -345.846326)
			(xy 427.867616 -345.83856) (xy 427.815299 -345.823192) (xy 427.765701 -345.800536) (xy 427.719831 -345.771053)
			(xy 427.678624 -345.735342) (xy 427.642919 -345.69413) (xy 427.613441 -345.648257) (xy 427.590791 -345.598656)
			(xy 427.57543 -345.546337) (xy 427.56767 -345.492364) (xy 426.084844 -345.492364) (xy 426.084844 -345.492375)
			(xy 426.077081 -345.546369) (xy 426.061713 -345.598708) (xy 426.039052 -345.648328) (xy 426.00956 -345.694218)
			(xy 425.973837 -345.735443) (xy 425.932611 -345.771165) (xy 425.886721 -345.800656) (xy 425.837101 -345.823315)
			(xy 425.784761 -345.838683) (xy 425.730767 -345.846445) (xy 425.703492 -345.846908) (xy 424.839892 -345.846908)
			(xy 424.812626 -345.846329) (xy 424.75865 -345.838567) (xy 424.706328 -345.823203) (xy 424.656725 -345.800549)
			(xy 424.61085 -345.771067) (xy 424.569638 -345.735356) (xy 424.533928 -345.694143) (xy 424.504447 -345.648268)
			(xy 424.481794 -345.598665) (xy 424.466431 -345.546342) (xy 424.45867 -345.492366) (xy 422.975822 -345.492366)
			(xy 422.975822 -345.492371) (xy 422.96806 -345.546358) (xy 422.952694 -345.598692) (xy 422.930038 -345.648306)
			(xy 422.900551 -345.694191) (xy 422.864835 -345.735412) (xy 422.823616 -345.771132) (xy 422.777734 -345.800622)
			(xy 422.728122 -345.823283) (xy 422.67579 -345.838653) (xy 422.621803 -345.846419) (xy 422.594532 -345.846908)
			(xy 421.730932 -345.846908) (xy 421.703663 -345.846355) (xy 421.649679 -345.838597) (xy 421.597349 -345.823236)
			(xy 421.547738 -345.800583) (xy 421.501855 -345.771099) (xy 421.460636 -345.735386) (xy 421.42492 -345.69417)
			(xy 421.395433 -345.648291) (xy 421.372776 -345.598681) (xy 421.35741 -345.546352) (xy 421.349647 -345.492369)
			(xy 419.866944 -345.492369) (xy 419.866944 -345.492376) (xy 419.859181 -345.546371) (xy 419.843811 -345.598713)
			(xy 419.821149 -345.648334) (xy 419.791655 -345.694224) (xy 419.75593 -345.73545) (xy 419.714702 -345.771172)
			(xy 419.668809 -345.800662) (xy 419.619186 -345.823321) (xy 419.566844 -345.838686) (xy 419.512848 -345.846446)
			(xy 419.485572 -345.846908) (xy 418.621972 -345.846908) (xy 418.594707 -345.846328) (xy 418.540733 -345.838564)
			(xy 418.488413 -345.823198) (xy 418.438813 -345.800543) (xy 418.392941 -345.77106) (xy 418.351731 -345.735349)
			(xy 418.316023 -345.694137) (xy 418.286544 -345.648263) (xy 418.263892 -345.59866) (xy 418.24853 -345.546339)
			(xy 418.24077 -345.492365) (xy 416.757921 -345.492365) (xy 416.757921 -345.492372) (xy 416.750159 -345.546361)
			(xy 416.734793 -345.598696) (xy 416.712135 -345.648311) (xy 416.682646 -345.694197) (xy 416.646928 -345.735419)
			(xy 416.605707 -345.771139) (xy 416.559822 -345.800629) (xy 416.510207 -345.823288) (xy 416.457873 -345.838657)
			(xy 416.403884 -345.846421) (xy 416.376612 -345.846908) (xy 415.513012 -345.846908) (xy 415.485744 -345.846353)
			(xy 415.431762 -345.838594) (xy 415.379434 -345.82323) (xy 415.329826 -345.800576) (xy 415.283946 -345.771092)
			(xy 415.242729 -345.735379) (xy 415.207015 -345.694164) (xy 415.17753 -345.648285) (xy 415.154874 -345.598677)
			(xy 415.139509 -345.54635) (xy 415.131747 -345.492368) (xy 413.649044 -345.492368) (xy 413.649044 -345.492376)
			(xy 413.64128 -345.546374) (xy 413.625909 -345.598717) (xy 413.603246 -345.648339) (xy 413.57375 -345.694231)
			(xy 413.538023 -345.735457) (xy 413.496792 -345.771179) (xy 413.450897 -345.800669) (xy 413.401272 -345.823326)
			(xy 413.348927 -345.83869) (xy 413.294929 -345.846448) (xy 413.267652 -345.846908) (xy 412.404052 -345.846908)
			(xy 412.376788 -345.846326) (xy 412.322816 -345.83856) (xy 412.270499 -345.823192) (xy 412.220901 -345.800536)
			(xy 412.175031 -345.771053) (xy 412.133824 -345.735342) (xy 412.098119 -345.69413) (xy 412.068641 -345.648257)
			(xy 412.045991 -345.598656) (xy 412.03063 -345.546337) (xy 412.02287 -345.492364) (xy 410.540044 -345.492364)
			(xy 410.540044 -345.492375) (xy 410.532281 -345.546369) (xy 410.516913 -345.598708) (xy 410.494252 -345.648328)
			(xy 410.46476 -345.694218) (xy 410.429037 -345.735443) (xy 410.387811 -345.771165) (xy 410.341921 -345.800656)
			(xy 410.292301 -345.823315) (xy 410.239961 -345.838683) (xy 410.185967 -345.846445) (xy 410.158692 -345.846908)
			(xy 409.295092 -345.846908) (xy 409.267826 -345.846329) (xy 409.21385 -345.838567) (xy 409.161528 -345.823203)
			(xy 409.111925 -345.800549) (xy 409.06605 -345.771067) (xy 409.024838 -345.735356) (xy 408.989128 -345.694143)
			(xy 408.959647 -345.648268) (xy 408.936994 -345.598665) (xy 408.921631 -345.546342) (xy 408.91387 -345.492366)
			(xy 403.522544 -345.492366) (xy 403.522544 -345.492375) (xy 403.514781 -345.54637) (xy 403.499412 -345.598711)
			(xy 403.47675 -345.648331) (xy 403.447257 -345.694221) (xy 403.411533 -345.735447) (xy 403.370305 -345.771169)
			(xy 403.324414 -345.800659) (xy 403.274792 -345.823319) (xy 403.222451 -345.838685) (xy 403.168455 -345.846446)
			(xy 403.14118 -345.846908) (xy 402.27758 -345.846908) (xy 402.250315 -345.846328) (xy 402.19634 -345.838565)
			(xy 402.144019 -345.8232) (xy 402.094417 -345.800545) (xy 402.048545 -345.771063) (xy 402.007334 -345.735352)
			(xy 401.971625 -345.694139) (xy 401.942145 -345.648265) (xy 401.919493 -345.598662) (xy 401.90413 -345.546341)
			(xy 401.89637 -345.492365) (xy 400.413522 -345.492365) (xy 400.413522 -345.492372) (xy 400.405759 -345.54636)
			(xy 400.390393 -345.598694) (xy 400.367736 -345.648309) (xy 400.338248 -345.694195) (xy 400.302531 -345.735417)
			(xy 400.261311 -345.771136) (xy 400.215427 -345.800626) (xy 400.165813 -345.823286) (xy 400.11348 -345.838655)
			(xy 400.059492 -345.84642) (xy 400.03222 -345.846908) (xy 399.16862 -345.846908) (xy 399.141351 -345.846354)
			(xy 399.087369 -345.838595) (xy 399.03504 -345.823232) (xy 398.98543 -345.800579) (xy 398.93955 -345.771095)
			(xy 398.898332 -345.735382) (xy 398.862617 -345.694166) (xy 398.833131 -345.648287) (xy 398.810475 -345.598679)
			(xy 398.795109 -345.546351) (xy 398.787347 -345.492369) (xy 397.304644 -345.492369) (xy 397.304644 -345.492376)
			(xy 397.29688 -345.546373) (xy 397.28151 -345.598715) (xy 397.258847 -345.648337) (xy 397.229352 -345.694228)
			(xy 397.193626 -345.735454) (xy 397.152396 -345.771176) (xy 397.106502 -345.800666) (xy 397.056878 -345.823324)
			(xy 397.004534 -345.838689) (xy 396.950536 -345.846447) (xy 396.92326 -345.846908) (xy 396.05966 -345.846908)
			(xy 396.032396 -345.846327) (xy 395.978423 -345.838562) (xy 395.926105 -345.823195) (xy 395.876505 -345.800539)
			(xy 395.830635 -345.771055) (xy 395.789427 -345.735345) (xy 395.753721 -345.694133) (xy 395.724242 -345.648259)
			(xy 395.701591 -345.598658) (xy 395.68623 -345.546338) (xy 395.67847 -345.492364) (xy 394.195621 -345.492364)
			(xy 394.195621 -345.492373) (xy 394.187859 -345.546363) (xy 394.172492 -345.598699) (xy 394.149833 -345.648315)
			(xy 394.120343 -345.694201) (xy 394.084624 -345.735424) (xy 394.043401 -345.771143) (xy 393.997515 -345.800633)
			(xy 393.947899 -345.823292) (xy 393.895563 -345.838659) (xy 393.841573 -345.846421) (xy 393.8143 -345.846908)
			(xy 392.9507 -345.846908) (xy 392.923434 -345.84633) (xy 392.869457 -345.838569) (xy 392.817134 -345.823205)
			(xy 392.767529 -345.800552) (xy 392.721654 -345.77107) (xy 392.680441 -345.735359) (xy 392.64473 -345.694146)
			(xy 392.615248 -345.648271) (xy 392.592595 -345.598666) (xy 392.577231 -345.546343) (xy 392.56947 -345.492366)
			(xy 391.086622 -345.492366) (xy 391.086622 -345.492371) (xy 391.07886 -345.546357) (xy 391.063495 -345.59869)
			(xy 391.040839 -345.648304) (xy 391.011353 -345.694188) (xy 390.975638 -345.73541) (xy 390.93442 -345.771129)
			(xy 390.888539 -345.80062) (xy 390.838928 -345.823281) (xy 390.786597 -345.838651) (xy 390.732611 -345.846419)
			(xy 390.70534 -345.846908) (xy 389.84174 -345.846908) (xy 389.81447 -345.846355) (xy 389.760486 -345.838599)
			(xy 389.708155 -345.823238) (xy 389.658542 -345.800585) (xy 389.612659 -345.771102) (xy 389.571439 -345.735389)
			(xy 389.535722 -345.694173) (xy 389.506234 -345.648293) (xy 389.483576 -345.598683) (xy 389.46821 -345.546353)
			(xy 389.460447 -345.49237) (xy 387.977744 -345.49237) (xy 387.977744 -345.492375) (xy 387.969981 -345.54637)
			(xy 387.954612 -345.598711) (xy 387.93195 -345.648331) (xy 387.902457 -345.694221) (xy 387.866733 -345.735447)
			(xy 387.825505 -345.771169) (xy 387.779614 -345.800659) (xy 387.729992 -345.823319) (xy 387.677651 -345.838685)
			(xy 387.623655 -345.846446) (xy 387.59638 -345.846908) (xy 386.73278 -345.846908) (xy 386.705515 -345.846328)
			(xy 386.65154 -345.838565) (xy 386.599219 -345.8232) (xy 386.549617 -345.800545) (xy 386.503745 -345.771063)
			(xy 386.462534 -345.735352) (xy 386.426825 -345.694139) (xy 386.397345 -345.648265) (xy 386.374693 -345.598662)
			(xy 386.35933 -345.546341) (xy 386.35157 -345.492365) (xy 384.868722 -345.492365) (xy 384.868722 -345.492372)
			(xy 384.860959 -345.54636) (xy 384.845593 -345.598694) (xy 384.822936 -345.648309) (xy 384.793448 -345.694195)
			(xy 384.757731 -345.735417) (xy 384.716511 -345.771136) (xy 384.670627 -345.800626) (xy 384.621013 -345.823286)
			(xy 384.56868 -345.838655) (xy 384.514692 -345.84642) (xy 384.48742 -345.846908) (xy 383.62382 -345.846908)
			(xy 383.596551 -345.846354) (xy 383.542569 -345.838595) (xy 383.49024 -345.823232) (xy 383.44063 -345.800579)
			(xy 383.39475 -345.771095) (xy 383.353532 -345.735382) (xy 383.317817 -345.694166) (xy 383.288331 -345.648287)
			(xy 383.265675 -345.598679) (xy 383.250309 -345.546351) (xy 383.242547 -345.492369) (xy 381.759844 -345.492369)
			(xy 381.759844 -345.492376) (xy 381.75208 -345.546373) (xy 381.73671 -345.598715) (xy 381.714047 -345.648337)
			(xy 381.684552 -345.694228) (xy 381.648826 -345.735454) (xy 381.607596 -345.771176) (xy 381.561702 -345.800666)
			(xy 381.512078 -345.823324) (xy 381.459734 -345.838689) (xy 381.405736 -345.846447) (xy 381.37846 -345.846908)
			(xy 380.51486 -345.846908) (xy 380.487596 -345.846327) (xy 380.433623 -345.838562) (xy 380.381305 -345.823195)
			(xy 380.331705 -345.800539) (xy 380.285835 -345.771055) (xy 380.244627 -345.735345) (xy 380.208921 -345.694133)
			(xy 380.179442 -345.648259) (xy 380.156791 -345.598658) (xy 380.14143 -345.546338) (xy 380.13367 -345.492364)
			(xy 378.650821 -345.492364) (xy 378.650821 -345.492373) (xy 378.643059 -345.546363) (xy 378.627692 -345.598699)
			(xy 378.605033 -345.648315) (xy 378.575543 -345.694201) (xy 378.539824 -345.735424) (xy 378.498601 -345.771143)
			(xy 378.452715 -345.800633) (xy 378.403099 -345.823292) (xy 378.350763 -345.838659) (xy 378.296773 -345.846421)
			(xy 378.2695 -345.846908) (xy 377.4059 -345.846908) (xy 377.378634 -345.84633) (xy 377.324657 -345.838569)
			(xy 377.272334 -345.823205) (xy 377.222729 -345.800552) (xy 377.176854 -345.77107) (xy 377.135641 -345.735359)
			(xy 377.09993 -345.694146) (xy 377.070448 -345.648271) (xy 377.047795 -345.598666) (xy 377.032431 -345.546343)
			(xy 377.02467 -345.492366) (xy 375.541822 -345.492366) (xy 375.541822 -345.492371) (xy 375.53406 -345.546357)
			(xy 375.518695 -345.59869) (xy 375.496039 -345.648304) (xy 375.466553 -345.694188) (xy 375.430838 -345.73541)
			(xy 375.38962 -345.771129) (xy 375.343739 -345.80062) (xy 375.294128 -345.823281) (xy 375.241797 -345.838651)
			(xy 375.187811 -345.846419) (xy 375.16054 -345.846908) (xy 374.29694 -345.846908) (xy 374.26967 -345.846355)
			(xy 374.215686 -345.838599) (xy 374.163355 -345.823238) (xy 374.113742 -345.800585) (xy 374.067859 -345.771102)
			(xy 374.026639 -345.735389) (xy 373.990922 -345.694173) (xy 373.961434 -345.648293) (xy 373.938776 -345.598683)
			(xy 373.92341 -345.546353) (xy 373.915647 -345.49237) (xy 372.432944 -345.49237) (xy 372.432944 -345.492375)
			(xy 372.425181 -345.54637) (xy 372.409812 -345.598711) (xy 372.38715 -345.648331) (xy 372.357657 -345.694221)
			(xy 372.321933 -345.735447) (xy 372.280705 -345.771169) (xy 372.234814 -345.800659) (xy 372.185192 -345.823319)
			(xy 372.132851 -345.838685) (xy 372.078855 -345.846446) (xy 372.05158 -345.846908) (xy 371.18798 -345.846908)
			(xy 371.160715 -345.846328) (xy 371.10674 -345.838565) (xy 371.054419 -345.8232) (xy 371.004817 -345.800545)
			(xy 370.958945 -345.771063) (xy 370.917734 -345.735352) (xy 370.882025 -345.694139) (xy 370.852545 -345.648265)
			(xy 370.829893 -345.598662) (xy 370.81453 -345.546341) (xy 370.80677 -345.492365) (xy 369.214908 -345.492365)
			(xy 369.214908 -348.613069) (xy 370.806714 -348.613069) (xy 370.806714 -348.558531) (xy 370.814476 -348.504548)
			(xy 370.82984 -348.452218) (xy 370.852496 -348.402608) (xy 370.881981 -348.356727) (xy 370.917695 -348.315509)
			(xy 370.958911 -348.279793) (xy 371.004791 -348.250305) (xy 371.054399 -348.227647) (xy 371.106728 -348.21228)
			(xy 371.160711 -348.204516) (xy 371.18798 -348.204028) (xy 372.05158 -348.204028) (xy 372.078851 -348.20451)
			(xy 372.132839 -348.21227) (xy 372.185173 -348.227634) (xy 372.234787 -348.25029) (xy 372.280672 -348.279776)
			(xy 372.321893 -348.315493) (xy 372.357612 -348.356712) (xy 372.387101 -348.402595) (xy 372.409759 -348.452209)
			(xy 372.425126 -348.504542) (xy 372.432888 -348.558529) (xy 372.432888 -348.613071) (xy 372.432888 -348.613074)
			(xy 373.915592 -348.613074) (xy 373.915592 -348.558526) (xy 373.923355 -348.504535) (xy 373.938724 -348.452197)
			(xy 373.961385 -348.40258) (xy 373.990877 -348.356694) (xy 374.0266 -348.315471) (xy 374.067826 -348.279753)
			(xy 374.113715 -348.250266) (xy 374.163335 -348.22761) (xy 374.215674 -348.212246) (xy 374.269666 -348.204489)
			(xy 374.29694 -348.204028) (xy 375.16054 -348.204028) (xy 375.187807 -348.204537) (xy 375.241785 -348.212303)
			(xy 375.294108 -348.227672) (xy 375.343712 -348.25033) (xy 375.389587 -348.279816) (xy 375.430798 -348.31553)
			(xy 375.466508 -348.356746) (xy 375.49599 -348.402623) (xy 375.518642 -348.45223) (xy 375.534005 -348.504554)
			(xy 375.541766 -348.558533) (xy 375.541766 -348.613067) (xy 375.541766 -348.61307) (xy 377.024614 -348.61307)
			(xy 377.024614 -348.55853) (xy 377.032376 -348.504545) (xy 377.047742 -348.452214) (xy 377.070399 -348.402603)
			(xy 377.099886 -348.35672) (xy 377.135602 -348.315502) (xy 377.17682 -348.279786) (xy 377.222703 -348.250299)
			(xy 377.272314 -348.227642) (xy 377.324645 -348.212276) (xy 377.37863 -348.204514) (xy 377.4059 -348.204028)
			(xy 378.2695 -348.204028) (xy 378.296769 -348.204534) (xy 378.350751 -348.212296) (xy 378.403079 -348.227661)
			(xy 378.452688 -348.250316) (xy 378.498568 -348.279802) (xy 378.539784 -348.315516) (xy 378.575498 -348.356732)
			(xy 378.604984 -348.402612) (xy 378.627639 -348.452221) (xy 378.643004 -348.504549) (xy 378.650766 -348.558531)
			(xy 378.650766 -348.613068) (xy 380.133614 -348.613068) (xy 380.133614 -348.558532) (xy 380.141375 -348.50455)
			(xy 380.156739 -348.452223) (xy 380.179393 -348.402614) (xy 380.208876 -348.356734) (xy 380.244588 -348.315516)
			(xy 380.285801 -348.2798) (xy 380.331679 -348.250312) (xy 380.381285 -348.227653) (xy 380.433611 -348.212284)
			(xy 380.487592 -348.204517) (xy 380.51486 -348.204028) (xy 381.37846 -348.204028) (xy 381.405732 -348.204509)
			(xy 381.459722 -348.212266) (xy 381.512058 -348.227628) (xy 381.561675 -348.250283) (xy 381.607562 -348.279769)
			(xy 381.648786 -348.315485) (xy 381.684507 -348.356706) (xy 381.713998 -348.40259) (xy 381.736658 -348.452204)
			(xy 381.752025 -348.504539) (xy 381.759788 -348.558528) (xy 381.759788 -348.613072) (xy 381.759788 -348.613073)
			(xy 383.242492 -348.613073) (xy 383.242492 -348.558527) (xy 383.250254 -348.504537) (xy 383.265622 -348.452202)
			(xy 383.288282 -348.402586) (xy 383.317772 -348.3567) (xy 383.353493 -348.315478) (xy 383.394716 -348.27976)
			(xy 383.440603 -348.250272) (xy 383.49022 -348.227615) (xy 383.542557 -348.21225) (xy 383.596547 -348.20449)
			(xy 383.62382 -348.204028) (xy 384.48742 -348.204028) (xy 384.514688 -348.204536) (xy 384.568668 -348.2123)
			(xy 384.620994 -348.227666) (xy 384.6706 -348.250323) (xy 384.716477 -348.279809) (xy 384.757691 -348.315523)
			(xy 384.793403 -348.356739) (xy 384.822887 -348.402618) (xy 384.845541 -348.452225) (xy 384.860905 -348.504552)
			(xy 384.868666 -348.558532) (xy 384.868666 -348.613068) (xy 384.868666 -348.613069) (xy 386.351514 -348.613069)
			(xy 386.351514 -348.558531) (xy 386.359276 -348.504548) (xy 386.37464 -348.452218) (xy 386.397296 -348.402608)
			(xy 386.426781 -348.356727) (xy 386.462495 -348.315509) (xy 386.503711 -348.279793) (xy 386.549591 -348.250305)
			(xy 386.599199 -348.227647) (xy 386.651528 -348.21228) (xy 386.705511 -348.204516) (xy 386.73278 -348.204028)
			(xy 387.59638 -348.204028) (xy 387.623651 -348.20451) (xy 387.677639 -348.21227) (xy 387.729973 -348.227634)
			(xy 387.779587 -348.25029) (xy 387.825472 -348.279776) (xy 387.866693 -348.315493) (xy 387.902412 -348.356712)
			(xy 387.931901 -348.402595) (xy 387.954559 -348.452209) (xy 387.969926 -348.504542) (xy 387.977688 -348.558529)
			(xy 387.977688 -348.613071) (xy 387.977688 -348.613074) (xy 389.460392 -348.613074) (xy 389.460392 -348.558526)
			(xy 389.468155 -348.504535) (xy 389.483524 -348.452197) (xy 389.506185 -348.40258) (xy 389.535677 -348.356694)
			(xy 389.5714 -348.315471) (xy 389.612626 -348.279753) (xy 389.658515 -348.250266) (xy 389.708135 -348.22761)
			(xy 389.760474 -348.212246) (xy 389.814466 -348.204489) (xy 389.84174 -348.204028) (xy 390.70534 -348.204028)
			(xy 390.732607 -348.204537) (xy 390.786585 -348.212303) (xy 390.838908 -348.227672) (xy 390.888512 -348.25033)
			(xy 390.934387 -348.279816) (xy 390.975598 -348.31553) (xy 391.011308 -348.356746) (xy 391.04079 -348.402623)
			(xy 391.063442 -348.45223) (xy 391.078805 -348.504554) (xy 391.086566 -348.558533) (xy 391.086566 -348.613067)
			(xy 391.086566 -348.61307) (xy 392.569414 -348.61307) (xy 392.569414 -348.55853) (xy 392.577176 -348.504545)
			(xy 392.592542 -348.452214) (xy 392.615199 -348.402603) (xy 392.644686 -348.35672) (xy 392.680402 -348.315502)
			(xy 392.72162 -348.279786) (xy 392.767503 -348.250299) (xy 392.817114 -348.227642) (xy 392.869445 -348.212276)
			(xy 392.92343 -348.204514) (xy 392.9507 -348.204028) (xy 393.8143 -348.204028) (xy 393.841569 -348.204534)
			(xy 393.895551 -348.212296) (xy 393.947879 -348.227661) (xy 393.997488 -348.250316) (xy 394.043368 -348.279802)
			(xy 394.084584 -348.315516) (xy 394.120298 -348.356732) (xy 394.149784 -348.402612) (xy 394.172439 -348.452221)
			(xy 394.187804 -348.504549) (xy 394.195566 -348.558531) (xy 394.195566 -348.613068) (xy 395.678414 -348.613068)
			(xy 395.678414 -348.558532) (xy 395.686175 -348.50455) (xy 395.701539 -348.452223) (xy 395.724193 -348.402614)
			(xy 395.753676 -348.356734) (xy 395.789388 -348.315516) (xy 395.830601 -348.2798) (xy 395.876479 -348.250312)
			(xy 395.926085 -348.227653) (xy 395.978411 -348.212284) (xy 396.032392 -348.204517) (xy 396.05966 -348.204028)
			(xy 396.92326 -348.204028) (xy 396.950532 -348.204509) (xy 397.004522 -348.212266) (xy 397.056858 -348.227628)
			(xy 397.106475 -348.250283) (xy 397.152362 -348.279769) (xy 397.193586 -348.315485) (xy 397.229307 -348.356706)
			(xy 397.258798 -348.40259) (xy 397.281458 -348.452204) (xy 397.296825 -348.504539) (xy 397.304588 -348.558528)
			(xy 397.304588 -348.613072) (xy 397.304588 -348.613073) (xy 398.787292 -348.613073) (xy 398.787292 -348.558527)
			(xy 398.795054 -348.504537) (xy 398.810422 -348.452202) (xy 398.833082 -348.402586) (xy 398.862572 -348.3567)
			(xy 398.898293 -348.315478) (xy 398.939516 -348.27976) (xy 398.985403 -348.250272) (xy 399.03502 -348.227615)
			(xy 399.087357 -348.21225) (xy 399.141347 -348.20449) (xy 399.16862 -348.204028) (xy 400.03222 -348.204028)
			(xy 400.059488 -348.204536) (xy 400.113468 -348.2123) (xy 400.165794 -348.227666) (xy 400.2154 -348.250323)
			(xy 400.261277 -348.279809) (xy 400.302491 -348.315523) (xy 400.338203 -348.356739) (xy 400.367687 -348.402618)
			(xy 400.390341 -348.452225) (xy 400.405705 -348.504552) (xy 400.413466 -348.558532) (xy 400.413466 -348.613068)
			(xy 400.413466 -348.613069) (xy 401.896314 -348.613069) (xy 401.896314 -348.558531) (xy 401.904076 -348.504548)
			(xy 401.91944 -348.452218) (xy 401.942096 -348.402608) (xy 401.971581 -348.356727) (xy 402.007295 -348.315509)
			(xy 402.048511 -348.279793) (xy 402.094391 -348.250305) (xy 402.143999 -348.227647) (xy 402.196328 -348.21228)
			(xy 402.250311 -348.204516) (xy 402.27758 -348.204028) (xy 403.14118 -348.204028) (xy 403.168451 -348.20451)
			(xy 403.222439 -348.21227) (xy 403.274773 -348.227634) (xy 403.324387 -348.25029) (xy 403.370272 -348.279776)
			(xy 403.411493 -348.315493) (xy 403.447212 -348.356712) (xy 403.476701 -348.402595) (xy 403.499359 -348.452209)
			(xy 403.514726 -348.504542) (xy 403.522488 -348.558529) (xy 403.522488 -348.61307) (xy 408.913814 -348.61307)
			(xy 408.913814 -348.55853) (xy 408.921576 -348.504546) (xy 408.936941 -348.452216) (xy 408.959598 -348.402605)
			(xy 408.989084 -348.356723) (xy 409.024799 -348.315505) (xy 409.066017 -348.279788) (xy 409.111898 -348.250301)
			(xy 409.161508 -348.227644) (xy 409.213838 -348.212278) (xy 409.267822 -348.204515) (xy 409.295092 -348.204028)
			(xy 410.158692 -348.204028) (xy 410.185963 -348.204511) (xy 410.239949 -348.212272) (xy 410.292281 -348.227637)
			(xy 410.341894 -348.250294) (xy 410.387778 -348.27978) (xy 410.428998 -348.315497) (xy 410.464715 -348.356716)
			(xy 410.494203 -348.402599) (xy 410.51686 -348.452211) (xy 410.532226 -348.504543) (xy 410.539989 -348.558529)
			(xy 410.539989 -348.613068) (xy 412.022814 -348.613068) (xy 412.022814 -348.558532) (xy 412.030575 -348.504551)
			(xy 412.045938 -348.452224) (xy 412.068592 -348.402616) (xy 412.098074 -348.356736) (xy 412.133785 -348.315519)
			(xy 412.174998 -348.279803) (xy 412.220874 -348.250315) (xy 412.270479 -348.227655) (xy 412.322804 -348.212285)
			(xy 412.376784 -348.204518) (xy 412.404052 -348.204028) (xy 413.267652 -348.204028) (xy 413.294925 -348.204508)
			(xy 413.348915 -348.212265) (xy 413.401252 -348.227626) (xy 413.45087 -348.250281) (xy 413.496759 -348.279766)
			(xy 413.537983 -348.315483) (xy 413.573705 -348.356703) (xy 413.603196 -348.402588) (xy 413.625857 -348.452203)
			(xy 413.641225 -348.504538) (xy 413.648988 -348.558528) (xy 413.648988 -348.613072) (xy 415.131692 -348.613072)
			(xy 415.131692 -348.558528) (xy 415.139454 -348.504538) (xy 415.154821 -348.452203) (xy 415.177481 -348.402588)
			(xy 415.20697 -348.356703) (xy 415.24269 -348.315481) (xy 415.283912 -348.279763) (xy 415.329799 -348.250275)
			(xy 415.379415 -348.227617) (xy 415.43175 -348.212252) (xy 415.48574 -348.204491) (xy 415.513012 -348.204028)
			(xy 416.376612 -348.204028) (xy 416.40388 -348.204535) (xy 416.457861 -348.212298) (xy 416.510188 -348.227664)
			(xy 416.559795 -348.25032) (xy 416.605673 -348.279806) (xy 416.646888 -348.31552) (xy 416.682601 -348.356736)
			(xy 416.712085 -348.402615) (xy 416.73474 -348.452224) (xy 416.750104 -348.504551) (xy 416.757866 -348.558532)
			(xy 416.757866 -348.613068) (xy 416.757866 -348.613069) (xy 418.240714 -348.613069) (xy 418.240714 -348.558531)
			(xy 418.248476 -348.504549) (xy 418.26384 -348.45222) (xy 418.286495 -348.40261) (xy 418.315979 -348.35673)
			(xy 418.351692 -348.315512) (xy 418.392907 -348.279795) (xy 418.438786 -348.250308) (xy 418.488394 -348.22765)
			(xy 418.540721 -348.212281) (xy 418.594703 -348.204516) (xy 418.621972 -348.204028) (xy 419.485572 -348.204028)
			(xy 419.512844 -348.20451) (xy 419.566832 -348.212268) (xy 419.619167 -348.227632) (xy 419.668782 -348.250287)
			(xy 419.714668 -348.279773) (xy 419.75589 -348.31549) (xy 419.79161 -348.356709) (xy 419.821099 -348.402593)
			(xy 419.843759 -348.452207) (xy 419.859126 -348.504541) (xy 419.866888 -348.558528) (xy 419.866888 -348.613072)
			(xy 419.866888 -348.613073) (xy 421.349592 -348.613073) (xy 421.349592 -348.558527) (xy 421.357355 -348.504536)
			(xy 421.372723 -348.452199) (xy 421.395384 -348.402583) (xy 421.424875 -348.356696) (xy 421.460597 -348.315474)
			(xy 421.501822 -348.279756) (xy 421.547711 -348.250268) (xy 421.597329 -348.227612) (xy 421.649667 -348.212248)
			(xy 421.703659 -348.204489) (xy 421.730932 -348.204028) (xy 422.594532 -348.204028) (xy 422.621799 -348.204537)
			(xy 422.675778 -348.212302) (xy 422.728102 -348.227669) (xy 422.777707 -348.250327) (xy 422.823583 -348.279813)
			(xy 422.864795 -348.315527) (xy 422.900506 -348.356743) (xy 422.929988 -348.402621) (xy 422.952642 -348.452228)
			(xy 422.968005 -348.504553) (xy 422.975766 -348.558533) (xy 422.975766 -348.613067) (xy 422.975766 -348.61307)
			(xy 424.458614 -348.61307) (xy 424.458614 -348.55853) (xy 424.466376 -348.504546) (xy 424.481741 -348.452216)
			(xy 424.504398 -348.402605) (xy 424.533884 -348.356723) (xy 424.569599 -348.315505) (xy 424.610817 -348.279788)
			(xy 424.656698 -348.250301) (xy 424.706308 -348.227644) (xy 424.758638 -348.212278) (xy 424.812622 -348.204515)
			(xy 424.839892 -348.204028) (xy 425.703492 -348.204028) (xy 425.730763 -348.204511) (xy 425.784749 -348.212272)
			(xy 425.837081 -348.227637) (xy 425.886694 -348.250294) (xy 425.932578 -348.27978) (xy 425.973798 -348.315497)
			(xy 426.009515 -348.356716) (xy 426.039003 -348.402599) (xy 426.06166 -348.452211) (xy 426.077026 -348.504543)
			(xy 426.084789 -348.558529) (xy 426.084789 -348.613068) (xy 427.567614 -348.613068) (xy 427.567614 -348.558532)
			(xy 427.575375 -348.504551) (xy 427.590738 -348.452224) (xy 427.613392 -348.402616) (xy 427.642874 -348.356736)
			(xy 427.678585 -348.315519) (xy 427.719798 -348.279803) (xy 427.765674 -348.250315) (xy 427.815279 -348.227655)
			(xy 427.867604 -348.212285) (xy 427.921584 -348.204518) (xy 427.948852 -348.204028) (xy 428.812452 -348.204028)
			(xy 428.839725 -348.204508) (xy 428.893715 -348.212265) (xy 428.946052 -348.227626) (xy 428.99567 -348.250281)
			(xy 429.041559 -348.279766) (xy 429.082783 -348.315483) (xy 429.118505 -348.356703) (xy 429.147996 -348.402588)
			(xy 429.170657 -348.452203) (xy 429.186025 -348.504538) (xy 429.193788 -348.558528) (xy 429.193788 -348.613072)
			(xy 430.676492 -348.613072) (xy 430.676492 -348.558528) (xy 430.684254 -348.504538) (xy 430.699621 -348.452203)
			(xy 430.722281 -348.402588) (xy 430.75177 -348.356703) (xy 430.78749 -348.315481) (xy 430.828712 -348.279763)
			(xy 430.874599 -348.250275) (xy 430.924215 -348.227617) (xy 430.97655 -348.212252) (xy 431.03054 -348.204491)
			(xy 431.057812 -348.204028) (xy 431.921412 -348.204028) (xy 431.94868 -348.204535) (xy 432.002661 -348.212298)
			(xy 432.054988 -348.227664) (xy 432.104595 -348.25032) (xy 432.150473 -348.279806) (xy 432.191688 -348.31552)
			(xy 432.227401 -348.356736) (xy 432.256885 -348.402615) (xy 432.27954 -348.452224) (xy 432.294904 -348.504551)
			(xy 432.302666 -348.558532) (xy 432.302666 -348.613068) (xy 432.302666 -348.613069) (xy 433.785514 -348.613069)
			(xy 433.785514 -348.558531) (xy 433.793276 -348.504549) (xy 433.80864 -348.45222) (xy 433.831295 -348.40261)
			(xy 433.860779 -348.35673) (xy 433.896492 -348.315512) (xy 433.937707 -348.279795) (xy 433.983586 -348.250308)
			(xy 434.033194 -348.22765) (xy 434.085521 -348.212281) (xy 434.139503 -348.204516) (xy 434.166772 -348.204028)
			(xy 435.030372 -348.204028) (xy 435.057644 -348.20451) (xy 435.111632 -348.212268) (xy 435.163967 -348.227632)
			(xy 435.213582 -348.250287) (xy 435.259468 -348.279773) (xy 435.30069 -348.31549) (xy 435.33641 -348.356709)
			(xy 435.365899 -348.402593) (xy 435.388559 -348.452207) (xy 435.403926 -348.504541) (xy 435.411688 -348.558528)
			(xy 435.411688 -348.613072) (xy 435.411688 -348.613073) (xy 436.894392 -348.613073) (xy 436.894392 -348.558527)
			(xy 436.902155 -348.504536) (xy 436.917523 -348.452199) (xy 436.940184 -348.402583) (xy 436.969675 -348.356696)
			(xy 437.005397 -348.315474) (xy 437.046622 -348.279756) (xy 437.092511 -348.250268) (xy 437.142129 -348.227612)
			(xy 437.194467 -348.212248) (xy 437.248459 -348.204489) (xy 437.275732 -348.204028) (xy 438.139332 -348.204028)
			(xy 438.166599 -348.204537) (xy 438.220578 -348.212302) (xy 438.272902 -348.227669) (xy 438.322507 -348.250327)
			(xy 438.368383 -348.279813) (xy 438.409595 -348.315527) (xy 438.445306 -348.356743) (xy 438.474788 -348.402621)
			(xy 438.497442 -348.452228) (xy 438.512805 -348.504553) (xy 438.520566 -348.558533) (xy 438.520566 -348.613067)
			(xy 438.520566 -348.61307) (xy 440.003414 -348.61307) (xy 440.003414 -348.55853) (xy 440.011176 -348.504546)
			(xy 440.026541 -348.452216) (xy 440.049198 -348.402605) (xy 440.078684 -348.356723) (xy 440.114399 -348.315505)
			(xy 440.155617 -348.279788) (xy 440.201498 -348.250301) (xy 440.251108 -348.227644) (xy 440.303438 -348.212278)
			(xy 440.357422 -348.204515) (xy 440.384692 -348.204028) (xy 441.248292 -348.204028) (xy 441.275563 -348.204511)
			(xy 441.329549 -348.212272) (xy 441.381881 -348.227637) (xy 441.431494 -348.250294) (xy 441.477378 -348.27978)
			(xy 441.518598 -348.315497) (xy 441.554315 -348.356716) (xy 441.583803 -348.402599) (xy 441.60646 -348.452211)
			(xy 441.621826 -348.504543) (xy 441.629589 -348.558529) (xy 441.629589 -348.613071) (xy 441.621826 -348.667057)
			(xy 441.60646 -348.719389) (xy 441.583803 -348.769001) (xy 441.554315 -348.814884) (xy 441.518598 -348.856103)
			(xy 441.477378 -348.89182) (xy 441.431494 -348.921306) (xy 441.381881 -348.943963) (xy 441.329549 -348.959328)
			(xy 441.275563 -348.967089) (xy 441.248292 -348.967552) (xy 440.384692 -348.967552) (xy 440.357422 -348.967085)
			(xy 440.303438 -348.959322) (xy 440.251108 -348.943956) (xy 440.201498 -348.921299) (xy 440.155617 -348.891812)
			(xy 440.114399 -348.856095) (xy 440.078684 -348.814877) (xy 440.049198 -348.768995) (xy 440.026541 -348.719384)
			(xy 440.011176 -348.667054) (xy 440.003414 -348.61307) (xy 438.520566 -348.61307) (xy 438.512805 -348.667047)
			(xy 438.497442 -348.719372) (xy 438.474788 -348.768979) (xy 438.445306 -348.814857) (xy 438.409595 -348.856073)
			(xy 438.368383 -348.891787) (xy 438.322507 -348.921273) (xy 438.272902 -348.943931) (xy 438.220578 -348.959298)
			(xy 438.166599 -348.967063) (xy 438.139332 -348.967552) (xy 437.275732 -348.967552) (xy 437.248459 -348.967111)
			(xy 437.194467 -348.959352) (xy 437.142129 -348.943988) (xy 437.092511 -348.921332) (xy 437.046622 -348.891844)
			(xy 437.005397 -348.856126) (xy 436.969675 -348.814904) (xy 436.940184 -348.769017) (xy 436.917523 -348.719401)
			(xy 436.902155 -348.667064) (xy 436.894392 -348.613073) (xy 435.411688 -348.613073) (xy 435.403926 -348.667059)
			(xy 435.388559 -348.719393) (xy 435.365899 -348.769007) (xy 435.33641 -348.814891) (xy 435.30069 -348.85611)
			(xy 435.259468 -348.891827) (xy 435.213582 -348.921313) (xy 435.163967 -348.943968) (xy 435.111632 -348.959332)
			(xy 435.057644 -348.96709) (xy 435.030372 -348.967552) (xy 434.166772 -348.967552) (xy 434.139503 -348.967084)
			(xy 434.085521 -348.959319) (xy 434.033194 -348.94395) (xy 433.983586 -348.921292) (xy 433.937707 -348.891805)
			(xy 433.896492 -348.856088) (xy 433.860779 -348.81487) (xy 433.831295 -348.76899) (xy 433.80864 -348.71938)
			(xy 433.793276 -348.667051) (xy 433.785514 -348.613069) (xy 432.302666 -348.613069) (xy 432.294904 -348.667049)
			(xy 432.27954 -348.719376) (xy 432.256885 -348.768985) (xy 432.227401 -348.814864) (xy 432.191688 -348.85608)
			(xy 432.150473 -348.891794) (xy 432.104595 -348.92128) (xy 432.054988 -348.943936) (xy 432.002661 -348.959302)
			(xy 431.94868 -348.967065) (xy 431.921412 -348.967552) (xy 431.057812 -348.967552) (xy 431.03054 -348.967109)
			(xy 430.97655 -348.959348) (xy 430.924215 -348.943983) (xy 430.874599 -348.921325) (xy 430.828712 -348.891837)
			(xy 430.78749 -348.856119) (xy 430.75177 -348.814897) (xy 430.722281 -348.769012) (xy 430.699621 -348.719397)
			(xy 430.684254 -348.667062) (xy 430.676492 -348.613072) (xy 429.193788 -348.613072) (xy 429.186025 -348.667062)
			(xy 429.170657 -348.719397) (xy 429.147996 -348.769012) (xy 429.118505 -348.814897) (xy 429.082783 -348.856117)
			(xy 429.041559 -348.891834) (xy 428.99567 -348.921319) (xy 428.946052 -348.943974) (xy 428.893715 -348.959335)
			(xy 428.839725 -348.967092) (xy 428.812452 -348.967552) (xy 427.948852 -348.967552) (xy 427.921584 -348.967082)
			(xy 427.867604 -348.959315) (xy 427.815279 -348.943945) (xy 427.765674 -348.921285) (xy 427.719798 -348.891797)
			(xy 427.678585 -348.856081) (xy 427.642874 -348.814864) (xy 427.613392 -348.768984) (xy 427.590738 -348.719376)
			(xy 427.575375 -348.667049) (xy 427.567614 -348.613068) (xy 426.084789 -348.613068) (xy 426.084789 -348.613071)
			(xy 426.077026 -348.667057) (xy 426.06166 -348.719389) (xy 426.039003 -348.769001) (xy 426.009515 -348.814884)
			(xy 425.973798 -348.856103) (xy 425.932578 -348.89182) (xy 425.886694 -348.921306) (xy 425.837081 -348.943963)
			(xy 425.784749 -348.959328) (xy 425.730763 -348.967089) (xy 425.703492 -348.967552) (xy 424.839892 -348.967552)
			(xy 424.812622 -348.967085) (xy 424.758638 -348.959322) (xy 424.706308 -348.943956) (xy 424.656698 -348.921299)
			(xy 424.610817 -348.891812) (xy 424.569599 -348.856095) (xy 424.533884 -348.814877) (xy 424.504398 -348.768995)
			(xy 424.481741 -348.719384) (xy 424.466376 -348.667054) (xy 424.458614 -348.61307) (xy 422.975766 -348.61307)
			(xy 422.968005 -348.667047) (xy 422.952642 -348.719372) (xy 422.929988 -348.768979) (xy 422.900506 -348.814857)
			(xy 422.864795 -348.856073) (xy 422.823583 -348.891787) (xy 422.777707 -348.921273) (xy 422.728102 -348.943931)
			(xy 422.675778 -348.959298) (xy 422.621799 -348.967063) (xy 422.594532 -348.967552) (xy 421.730932 -348.967552)
			(xy 421.703659 -348.967111) (xy 421.649667 -348.959352) (xy 421.597329 -348.943988) (xy 421.547711 -348.921332)
			(xy 421.501822 -348.891844) (xy 421.460597 -348.856126) (xy 421.424875 -348.814904) (xy 421.395384 -348.769017)
			(xy 421.372723 -348.719401) (xy 421.357355 -348.667064) (xy 421.349592 -348.613073) (xy 419.866888 -348.613073)
			(xy 419.859126 -348.667059) (xy 419.843759 -348.719393) (xy 419.821099 -348.769007) (xy 419.79161 -348.814891)
			(xy 419.75589 -348.85611) (xy 419.714668 -348.891827) (xy 419.668782 -348.921313) (xy 419.619167 -348.943968)
			(xy 419.566832 -348.959332) (xy 419.512844 -348.96709) (xy 419.485572 -348.967552) (xy 418.621972 -348.967552)
			(xy 418.594703 -348.967084) (xy 418.540721 -348.959319) (xy 418.488394 -348.94395) (xy 418.438786 -348.921292)
			(xy 418.392907 -348.891805) (xy 418.351692 -348.856088) (xy 418.315979 -348.81487) (xy 418.286495 -348.76899)
			(xy 418.26384 -348.71938) (xy 418.248476 -348.667051) (xy 418.240714 -348.613069) (xy 416.757866 -348.613069)
			(xy 416.750104 -348.667049) (xy 416.73474 -348.719376) (xy 416.712085 -348.768985) (xy 416.682601 -348.814864)
			(xy 416.646888 -348.85608) (xy 416.605673 -348.891794) (xy 416.559795 -348.92128) (xy 416.510188 -348.943936)
			(xy 416.457861 -348.959302) (xy 416.40388 -348.967065) (xy 416.376612 -348.967552) (xy 415.513012 -348.967552)
			(xy 415.48574 -348.967109) (xy 415.43175 -348.959348) (xy 415.379415 -348.943983) (xy 415.329799 -348.921325)
			(xy 415.283912 -348.891837) (xy 415.24269 -348.856119) (xy 415.20697 -348.814897) (xy 415.177481 -348.769012)
			(xy 415.154821 -348.719397) (xy 415.139454 -348.667062) (xy 415.131692 -348.613072) (xy 413.648988 -348.613072)
			(xy 413.641225 -348.667062) (xy 413.625857 -348.719397) (xy 413.603196 -348.769012) (xy 413.573705 -348.814897)
			(xy 413.537983 -348.856117) (xy 413.496759 -348.891834) (xy 413.45087 -348.921319) (xy 413.401252 -348.943974)
			(xy 413.348915 -348.959335) (xy 413.294925 -348.967092) (xy 413.267652 -348.967552) (xy 412.404052 -348.967552)
			(xy 412.376784 -348.967082) (xy 412.322804 -348.959315) (xy 412.270479 -348.943945) (xy 412.220874 -348.921285)
			(xy 412.174998 -348.891797) (xy 412.133785 -348.856081) (xy 412.098074 -348.814864) (xy 412.068592 -348.768984)
			(xy 412.045938 -348.719376) (xy 412.030575 -348.667049) (xy 412.022814 -348.613068) (xy 410.539989 -348.613068)
			(xy 410.539989 -348.613071) (xy 410.532226 -348.667057) (xy 410.51686 -348.719389) (xy 410.494203 -348.769001)
			(xy 410.464715 -348.814884) (xy 410.428998 -348.856103) (xy 410.387778 -348.89182) (xy 410.341894 -348.921306)
			(xy 410.292281 -348.943963) (xy 410.239949 -348.959328) (xy 410.185963 -348.967089) (xy 410.158692 -348.967552)
			(xy 409.295092 -348.967552) (xy 409.267822 -348.967085) (xy 409.213838 -348.959322) (xy 409.161508 -348.943956)
			(xy 409.111898 -348.921299) (xy 409.066017 -348.891812) (xy 409.024799 -348.856095) (xy 408.989084 -348.814877)
			(xy 408.959598 -348.768995) (xy 408.936941 -348.719384) (xy 408.921576 -348.667054) (xy 408.913814 -348.61307)
			(xy 403.522488 -348.61307) (xy 403.522488 -348.613071) (xy 403.514726 -348.667058) (xy 403.499359 -348.719391)
			(xy 403.476701 -348.769005) (xy 403.447212 -348.814888) (xy 403.411493 -348.856107) (xy 403.370272 -348.891824)
			(xy 403.324387 -348.92131) (xy 403.274773 -348.943966) (xy 403.222439 -348.95933) (xy 403.168451 -348.96709)
			(xy 403.14118 -348.967552) (xy 402.27758 -348.967552) (xy 402.250311 -348.967084) (xy 402.196328 -348.95932)
			(xy 402.143999 -348.943953) (xy 402.094391 -348.921295) (xy 402.048511 -348.891807) (xy 402.007295 -348.856091)
			(xy 401.971581 -348.814873) (xy 401.942096 -348.768992) (xy 401.91944 -348.719382) (xy 401.904076 -348.667052)
			(xy 401.896314 -348.613069) (xy 400.413466 -348.613069) (xy 400.405705 -348.667048) (xy 400.390341 -348.719375)
			(xy 400.367687 -348.768982) (xy 400.338203 -348.814861) (xy 400.302491 -348.856077) (xy 400.261277 -348.891791)
			(xy 400.2154 -348.921277) (xy 400.165794 -348.943934) (xy 400.113468 -348.9593) (xy 400.059488 -348.967064)
			(xy 400.03222 -348.967552) (xy 399.16862 -348.967552) (xy 399.141347 -348.96711) (xy 399.087357 -348.95935)
			(xy 399.03502 -348.943985) (xy 398.985403 -348.921328) (xy 398.939516 -348.89184) (xy 398.898293 -348.856122)
			(xy 398.862572 -348.8149) (xy 398.833082 -348.769014) (xy 398.810422 -348.719398) (xy 398.795054 -348.667063)
			(xy 398.787292 -348.613073) (xy 397.304588 -348.613073) (xy 397.296825 -348.667061) (xy 397.281458 -348.719396)
			(xy 397.258798 -348.76901) (xy 397.229307 -348.814894) (xy 397.193586 -348.856115) (xy 397.152362 -348.891831)
			(xy 397.106475 -348.921317) (xy 397.056858 -348.943972) (xy 397.004522 -348.959334) (xy 396.950532 -348.967091)
			(xy 396.92326 -348.967552) (xy 396.05966 -348.967552) (xy 396.032392 -348.967083) (xy 395.978411 -348.959316)
			(xy 395.926085 -348.943947) (xy 395.876479 -348.921288) (xy 395.830601 -348.8918) (xy 395.789388 -348.856084)
			(xy 395.753676 -348.814866) (xy 395.724193 -348.768986) (xy 395.701539 -348.719377) (xy 395.686175 -348.66705)
			(xy 395.678414 -348.613068) (xy 394.195566 -348.613068) (xy 394.195566 -348.613069) (xy 394.187804 -348.667051)
			(xy 394.172439 -348.719379) (xy 394.149784 -348.768988) (xy 394.120298 -348.814868) (xy 394.084584 -348.856084)
			(xy 394.043368 -348.891798) (xy 393.997488 -348.921284) (xy 393.947879 -348.943939) (xy 393.895551 -348.959304)
			(xy 393.841569 -348.967066) (xy 393.8143 -348.967552) (xy 392.9507 -348.967552) (xy 392.92343 -348.967086)
			(xy 392.869445 -348.959324) (xy 392.817114 -348.943958) (xy 392.767503 -348.921301) (xy 392.72162 -348.891814)
			(xy 392.680402 -348.856098) (xy 392.644686 -348.81488) (xy 392.615199 -348.768997) (xy 392.592542 -348.719386)
			(xy 392.577176 -348.667055) (xy 392.569414 -348.61307) (xy 391.086566 -348.61307) (xy 391.078805 -348.667046)
			(xy 391.063442 -348.71937) (xy 391.04079 -348.768977) (xy 391.011308 -348.814854) (xy 390.975598 -348.85607)
			(xy 390.934387 -348.891784) (xy 390.888512 -348.92127) (xy 390.838908 -348.943928) (xy 390.786585 -348.959297)
			(xy 390.732607 -348.967063) (xy 390.70534 -348.967552) (xy 389.84174 -348.967552) (xy 389.814466 -348.967111)
			(xy 389.760474 -348.959354) (xy 389.708135 -348.94399) (xy 389.658515 -348.921334) (xy 389.612626 -348.891847)
			(xy 389.5714 -348.856129) (xy 389.535677 -348.814906) (xy 389.506185 -348.76902) (xy 389.483524 -348.719403)
			(xy 389.468155 -348.667065) (xy 389.460392 -348.613074) (xy 387.977688 -348.613074) (xy 387.969926 -348.667058)
			(xy 387.954559 -348.719391) (xy 387.931901 -348.769005) (xy 387.902412 -348.814888) (xy 387.866693 -348.856107)
			(xy 387.825472 -348.891824) (xy 387.779587 -348.92131) (xy 387.729973 -348.943966) (xy 387.677639 -348.95933)
			(xy 387.623651 -348.96709) (xy 387.59638 -348.967552) (xy 386.73278 -348.967552) (xy 386.705511 -348.967084)
			(xy 386.651528 -348.95932) (xy 386.599199 -348.943953) (xy 386.549591 -348.921295) (xy 386.503711 -348.891807)
			(xy 386.462495 -348.856091) (xy 386.426781 -348.814873) (xy 386.397296 -348.768992) (xy 386.37464 -348.719382)
			(xy 386.359276 -348.667052) (xy 386.351514 -348.613069) (xy 384.868666 -348.613069) (xy 384.860905 -348.667048)
			(xy 384.845541 -348.719375) (xy 384.822887 -348.768982) (xy 384.793403 -348.814861) (xy 384.757691 -348.856077)
			(xy 384.716477 -348.891791) (xy 384.6706 -348.921277) (xy 384.620994 -348.943934) (xy 384.568668 -348.9593)
			(xy 384.514688 -348.967064) (xy 384.48742 -348.967552) (xy 383.62382 -348.967552) (xy 383.596547 -348.96711)
			(xy 383.542557 -348.95935) (xy 383.49022 -348.943985) (xy 383.440603 -348.921328) (xy 383.394716 -348.89184)
			(xy 383.353493 -348.856122) (xy 383.317772 -348.8149) (xy 383.288282 -348.769014) (xy 383.265622 -348.719398)
			(xy 383.250254 -348.667063) (xy 383.242492 -348.613073) (xy 381.759788 -348.613073) (xy 381.752025 -348.667061)
			(xy 381.736658 -348.719396) (xy 381.713998 -348.76901) (xy 381.684507 -348.814894) (xy 381.648786 -348.856115)
			(xy 381.607562 -348.891831) (xy 381.561675 -348.921317) (xy 381.512058 -348.943972) (xy 381.459722 -348.959334)
			(xy 381.405732 -348.967091) (xy 381.37846 -348.967552) (xy 380.51486 -348.967552) (xy 380.487592 -348.967083)
			(xy 380.433611 -348.959316) (xy 380.381285 -348.943947) (xy 380.331679 -348.921288) (xy 380.285801 -348.8918)
			(xy 380.244588 -348.856084) (xy 380.208876 -348.814866) (xy 380.179393 -348.768986) (xy 380.156739 -348.719377)
			(xy 380.141375 -348.66705) (xy 380.133614 -348.613068) (xy 378.650766 -348.613068) (xy 378.650766 -348.613069)
			(xy 378.643004 -348.667051) (xy 378.627639 -348.719379) (xy 378.604984 -348.768988) (xy 378.575498 -348.814868)
			(xy 378.539784 -348.856084) (xy 378.498568 -348.891798) (xy 378.452688 -348.921284) (xy 378.403079 -348.943939)
			(xy 378.350751 -348.959304) (xy 378.296769 -348.967066) (xy 378.2695 -348.967552) (xy 377.4059 -348.967552)
			(xy 377.37863 -348.967086) (xy 377.324645 -348.959324) (xy 377.272314 -348.943958) (xy 377.222703 -348.921301)
			(xy 377.17682 -348.891814) (xy 377.135602 -348.856098) (xy 377.099886 -348.81488) (xy 377.070399 -348.768997)
			(xy 377.047742 -348.719386) (xy 377.032376 -348.667055) (xy 377.024614 -348.61307) (xy 375.541766 -348.61307)
			(xy 375.534005 -348.667046) (xy 375.518642 -348.71937) (xy 375.49599 -348.768977) (xy 375.466508 -348.814854)
			(xy 375.430798 -348.85607) (xy 375.389587 -348.891784) (xy 375.343712 -348.92127) (xy 375.294108 -348.943928)
			(xy 375.241785 -348.959297) (xy 375.187807 -348.967063) (xy 375.16054 -348.967552) (xy 374.29694 -348.967552)
			(xy 374.269666 -348.967111) (xy 374.215674 -348.959354) (xy 374.163335 -348.94399) (xy 374.113715 -348.921334)
			(xy 374.067826 -348.891847) (xy 374.0266 -348.856129) (xy 373.990877 -348.814906) (xy 373.961385 -348.76902)
			(xy 373.938724 -348.719403) (xy 373.923355 -348.667065) (xy 373.915592 -348.613074) (xy 372.432888 -348.613074)
			(xy 372.425126 -348.667058) (xy 372.409759 -348.719391) (xy 372.387101 -348.769005) (xy 372.357612 -348.814888)
			(xy 372.321893 -348.856107) (xy 372.280672 -348.891824) (xy 372.234787 -348.92131) (xy 372.185173 -348.943966)
			(xy 372.132839 -348.95933) (xy 372.078851 -348.96709) (xy 372.05158 -348.967552) (xy 371.18798 -348.967552)
			(xy 371.160711 -348.967084) (xy 371.106728 -348.95932) (xy 371.054399 -348.943953) (xy 371.004791 -348.921295)
			(xy 370.958911 -348.891807) (xy 370.917695 -348.856091) (xy 370.881981 -348.814873) (xy 370.852496 -348.768992)
			(xy 370.82984 -348.719382) (xy 370.814476 -348.667052) (xy 370.806714 -348.613069) (xy 369.214908 -348.613069)
			(xy 369.214908 -351.638666) (xy 370.806762 -351.638666) (xy 370.806762 -351.584134) (xy 370.814523 -351.530158)
			(xy 370.829885 -351.477835) (xy 370.852538 -351.428231) (xy 370.882019 -351.382356) (xy 370.917729 -351.341143)
			(xy 370.95894 -351.305431) (xy 371.004814 -351.275948) (xy 371.054416 -351.253292) (xy 371.106738 -351.237927)
			(xy 371.160714 -351.230164) (xy 371.18798 -351.229676) (xy 372.05158 -351.229676) (xy 372.078855 -351.230062)
			(xy 372.132849 -351.237823) (xy 372.185189 -351.253189) (xy 372.23481 -351.275848) (xy 372.280701 -351.305338)
			(xy 372.321927 -351.341059) (xy 372.35765 -351.382283) (xy 372.387143 -351.428172) (xy 372.409804 -351.477792)
			(xy 372.425173 -351.530131) (xy 372.432936 -351.584125) (xy 372.432936 -351.63867) (xy 373.91564 -351.63867)
			(xy 373.91564 -351.58413) (xy 373.923402 -351.530145) (xy 373.938769 -351.477814) (xy 373.961427 -351.428203)
			(xy 373.990915 -351.382322) (xy 374.026634 -351.341105) (xy 374.067854 -351.305391) (xy 374.113738 -351.275908)
			(xy 374.163352 -351.253255) (xy 374.215684 -351.237893) (xy 374.26967 -351.230137) (xy 374.29694 -351.229676)
			(xy 375.16054 -351.229676) (xy 375.18781 -351.230089) (xy 375.241795 -351.237856) (xy 375.294125 -351.253227)
			(xy 375.343735 -351.275887) (xy 375.389615 -351.305377) (xy 375.430832 -351.341096) (xy 375.466547 -351.382317)
			(xy 375.496032 -351.4282) (xy 375.518687 -351.477813) (xy 375.534052 -351.530144) (xy 375.541814 -351.58413)
			(xy 375.541814 -351.638667) (xy 377.024662 -351.638667) (xy 377.024662 -351.584133) (xy 377.032423 -351.530155)
			(xy 377.047787 -351.477831) (xy 377.070441 -351.428226) (xy 377.099924 -351.382349) (xy 377.135636 -351.341136)
			(xy 377.176849 -351.305424) (xy 377.222726 -351.275941) (xy 377.272331 -351.253287) (xy 377.324655 -351.237923)
			(xy 377.378633 -351.230162) (xy 377.4059 -351.229676) (xy 378.2695 -351.229676) (xy 378.296772 -351.230087)
			(xy 378.350761 -351.237849) (xy 378.403096 -351.253216) (xy 378.452711 -351.275874) (xy 378.498596 -351.305363)
			(xy 378.539818 -351.341082) (xy 378.575537 -351.382304) (xy 378.605026 -351.428189) (xy 378.627684 -351.477804)
			(xy 378.643051 -351.530139) (xy 378.650813 -351.584128) (xy 378.650813 -351.638665) (xy 380.133662 -351.638665)
			(xy 380.133662 -351.584135) (xy 380.141422 -351.53016) (xy 380.156784 -351.477839) (xy 380.179435 -351.428237)
			(xy 380.208914 -351.382362) (xy 380.244621 -351.34115) (xy 380.28583 -351.305438) (xy 380.331702 -351.275954)
			(xy 380.381302 -351.253298) (xy 380.433621 -351.237931) (xy 380.487595 -351.230165) (xy 380.51486 -351.229676)
			(xy 381.37846 -351.229676) (xy 381.405736 -351.230061) (xy 381.459732 -351.237819) (xy 381.512075 -351.253183)
			(xy 381.561698 -351.275841) (xy 381.607591 -351.30533) (xy 381.64882 -351.341051) (xy 381.684546 -351.382277)
			(xy 381.71404 -351.428167) (xy 381.736703 -351.477788) (xy 381.752072 -351.530129) (xy 381.759836 -351.584124)
			(xy 381.759836 -351.638669) (xy 383.242539 -351.638669) (xy 383.242539 -351.584131) (xy 383.250301 -351.530148)
			(xy 383.265667 -351.477818) (xy 383.288324 -351.428209) (xy 383.31781 -351.382329) (xy 383.353526 -351.341112)
			(xy 383.394745 -351.305398) (xy 383.440626 -351.275914) (xy 383.490237 -351.25326) (xy 383.542567 -351.237897)
			(xy 383.596551 -351.230138) (xy 383.62382 -351.229676) (xy 384.48742 -351.229676) (xy 384.514691 -351.230088)
			(xy 384.568678 -351.237853) (xy 384.62101 -351.253221) (xy 384.670623 -351.275881) (xy 384.716506 -351.30537)
			(xy 384.757725 -351.341089) (xy 384.793442 -351.38231) (xy 384.822929 -351.428195) (xy 384.845586 -351.477808)
			(xy 384.860952 -351.530142) (xy 384.868714 -351.584129) (xy 384.868714 -351.638666) (xy 386.351562 -351.638666)
			(xy 386.351562 -351.584134) (xy 386.359323 -351.530158) (xy 386.374685 -351.477835) (xy 386.397338 -351.428231)
			(xy 386.426819 -351.382356) (xy 386.462529 -351.341143) (xy 386.50374 -351.305431) (xy 386.549614 -351.275948)
			(xy 386.599216 -351.253292) (xy 386.651538 -351.237927) (xy 386.705514 -351.230164) (xy 386.73278 -351.229676)
			(xy 387.59638 -351.229676) (xy 387.623655 -351.230062) (xy 387.677649 -351.237823) (xy 387.729989 -351.253189)
			(xy 387.77961 -351.275848) (xy 387.825501 -351.305338) (xy 387.866727 -351.341059) (xy 387.90245 -351.382283)
			(xy 387.931943 -351.428172) (xy 387.954604 -351.477792) (xy 387.969973 -351.530131) (xy 387.977736 -351.584125)
			(xy 387.977736 -351.63867) (xy 389.46044 -351.63867) (xy 389.46044 -351.58413) (xy 389.468202 -351.530145)
			(xy 389.483569 -351.477814) (xy 389.506227 -351.428203) (xy 389.535715 -351.382322) (xy 389.571434 -351.341105)
			(xy 389.612654 -351.305391) (xy 389.658538 -351.275908) (xy 389.708152 -351.253255) (xy 389.760484 -351.237893)
			(xy 389.81447 -351.230137) (xy 389.84174 -351.229676) (xy 390.70534 -351.229676) (xy 390.73261 -351.230089)
			(xy 390.786595 -351.237856) (xy 390.838925 -351.253227) (xy 390.888535 -351.275887) (xy 390.934415 -351.305377)
			(xy 390.975632 -351.341096) (xy 391.011347 -351.382317) (xy 391.040832 -351.4282) (xy 391.063487 -351.477813)
			(xy 391.078852 -351.530144) (xy 391.086614 -351.58413) (xy 391.086614 -351.638667) (xy 392.569462 -351.638667)
			(xy 392.569462 -351.584133) (xy 392.577223 -351.530155) (xy 392.592587 -351.477831) (xy 392.615241 -351.428226)
			(xy 392.644724 -351.382349) (xy 392.680436 -351.341136) (xy 392.721649 -351.305424) (xy 392.767526 -351.275941)
			(xy 392.817131 -351.253287) (xy 392.869455 -351.237923) (xy 392.923433 -351.230162) (xy 392.9507 -351.229676)
			(xy 393.8143 -351.229676) (xy 393.841572 -351.230087) (xy 393.895561 -351.237849) (xy 393.947896 -351.253216)
			(xy 393.997511 -351.275874) (xy 394.043396 -351.305363) (xy 394.084618 -351.341082) (xy 394.120337 -351.382304)
			(xy 394.149826 -351.428189) (xy 394.172484 -351.477804) (xy 394.187851 -351.530139) (xy 394.195613 -351.584128)
			(xy 394.195613 -351.638665) (xy 395.678462 -351.638665) (xy 395.678462 -351.584135) (xy 395.686222 -351.53016)
			(xy 395.701584 -351.477839) (xy 395.724235 -351.428237) (xy 395.753714 -351.382362) (xy 395.789421 -351.34115)
			(xy 395.83063 -351.305438) (xy 395.876502 -351.275954) (xy 395.926102 -351.253298) (xy 395.978421 -351.237931)
			(xy 396.032395 -351.230165) (xy 396.05966 -351.229676) (xy 396.92326 -351.229676) (xy 396.950536 -351.230061)
			(xy 397.004532 -351.237819) (xy 397.056875 -351.253183) (xy 397.106498 -351.275841) (xy 397.152391 -351.30533)
			(xy 397.19362 -351.341051) (xy 397.229346 -351.382277) (xy 397.25884 -351.428167) (xy 397.281503 -351.477788)
			(xy 397.296872 -351.530129) (xy 397.304636 -351.584124) (xy 397.304636 -351.638669) (xy 398.787339 -351.638669)
			(xy 398.787339 -351.584131) (xy 398.795101 -351.530148) (xy 398.810467 -351.477818) (xy 398.833124 -351.428209)
			(xy 398.86261 -351.382329) (xy 398.898326 -351.341112) (xy 398.939545 -351.305398) (xy 398.985426 -351.275914)
			(xy 399.035037 -351.25326) (xy 399.087367 -351.237897) (xy 399.141351 -351.230138) (xy 399.16862 -351.229676)
			(xy 400.03222 -351.229676) (xy 400.059491 -351.230088) (xy 400.113478 -351.237853) (xy 400.16581 -351.253221)
			(xy 400.215423 -351.275881) (xy 400.261306 -351.30537) (xy 400.302525 -351.341089) (xy 400.338242 -351.38231)
			(xy 400.367729 -351.428195) (xy 400.390386 -351.477808) (xy 400.405752 -351.530142) (xy 400.413514 -351.584129)
			(xy 400.413514 -351.638666) (xy 401.896362 -351.638666) (xy 401.896362 -351.584134) (xy 401.904123 -351.530158)
			(xy 401.919485 -351.477835) (xy 401.942138 -351.428231) (xy 401.971619 -351.382356) (xy 402.007329 -351.341143)
			(xy 402.04854 -351.305431) (xy 402.094414 -351.275948) (xy 402.144016 -351.253292) (xy 402.196338 -351.237927)
			(xy 402.250314 -351.230164) (xy 402.27758 -351.229676) (xy 403.14118 -351.229676) (xy 403.168455 -351.230062)
			(xy 403.222449 -351.237823) (xy 403.274789 -351.253189) (xy 403.32441 -351.275848) (xy 403.370301 -351.305338)
			(xy 403.411527 -351.341059) (xy 403.44725 -351.382283) (xy 403.476743 -351.428172) (xy 403.499404 -351.477792)
			(xy 403.514773 -351.530131) (xy 403.522536 -351.584125) (xy 403.522536 -351.638666) (xy 408.913862 -351.638666)
			(xy 408.913862 -351.584134) (xy 408.921623 -351.530156) (xy 408.936986 -351.477832) (xy 408.95964 -351.428228)
			(xy 408.989122 -351.382352) (xy 409.024833 -351.341138) (xy 409.066045 -351.305427) (xy 409.111921 -351.275944)
			(xy 409.161525 -351.253289) (xy 409.213848 -351.237925) (xy 409.267826 -351.230163) (xy 409.295092 -351.229676)
			(xy 410.158692 -351.229676) (xy 410.185966 -351.230063) (xy 410.239959 -351.237825) (xy 410.292298 -351.253192)
			(xy 410.341917 -351.275851) (xy 410.387806 -351.305342) (xy 410.429032 -351.341063) (xy 410.464753 -351.382287)
			(xy 410.494245 -351.428176) (xy 410.516905 -351.477794) (xy 410.532273 -351.530133) (xy 410.540036 -351.584126)
			(xy 410.540036 -351.638664) (xy 412.022862 -351.638664) (xy 412.022862 -351.584136) (xy 412.030622 -351.530162)
			(xy 412.045983 -351.477841) (xy 412.068634 -351.428239) (xy 412.098112 -351.382365) (xy 412.133819 -351.341153)
			(xy 412.175026 -351.305441) (xy 412.220897 -351.275957) (xy 412.270496 -351.2533) (xy 412.322815 -351.237932)
			(xy 412.376788 -351.230166) (xy 412.404052 -351.229676) (xy 413.267652 -351.229676) (xy 413.294928 -351.23006)
			(xy 413.348925 -351.237818) (xy 413.401269 -351.253181) (xy 413.450893 -351.275838) (xy 413.496787 -351.305328)
			(xy 413.538017 -351.341049) (xy 413.573744 -351.382274) (xy 413.603239 -351.428165) (xy 413.625902 -351.477786)
			(xy 413.641272 -351.530128) (xy 413.649036 -351.584124) (xy 413.649036 -351.638669) (xy 415.131739 -351.638669)
			(xy 415.131739 -351.584131) (xy 415.139501 -351.530149) (xy 415.154866 -351.47782) (xy 415.177523 -351.428211)
			(xy 415.207008 -351.382331) (xy 415.242724 -351.341115) (xy 415.283941 -351.305401) (xy 415.329822 -351.275917)
			(xy 415.379431 -351.253262) (xy 415.43176 -351.237899) (xy 415.485743 -351.230139) (xy 415.513012 -351.229676)
			(xy 416.376612 -351.229676) (xy 416.403884 -351.230087) (xy 416.457871 -351.237851) (xy 416.510204 -351.253219)
			(xy 416.559818 -351.275878) (xy 416.605702 -351.305367) (xy 416.646922 -351.341086) (xy 416.68264 -351.382308)
			(xy 416.712128 -351.428192) (xy 416.734785 -351.477807) (xy 416.750151 -351.530141) (xy 416.757914 -351.584128)
			(xy 416.757914 -351.638665) (xy 418.240762 -351.638665) (xy 418.240762 -351.584135) (xy 418.248522 -351.530159)
			(xy 418.263885 -351.477837) (xy 418.286537 -351.428233) (xy 418.316017 -351.382358) (xy 418.351726 -351.341146)
			(xy 418.392936 -351.305434) (xy 418.438809 -351.27595) (xy 418.48841 -351.253295) (xy 418.540731 -351.237928)
			(xy 418.594707 -351.230164) (xy 418.621972 -351.229676) (xy 419.485572 -351.229676) (xy 419.512847 -351.230062)
			(xy 419.566842 -351.237821) (xy 419.619184 -351.253187) (xy 419.668805 -351.275845) (xy 419.714697 -351.305335)
			(xy 419.755924 -351.341056) (xy 419.791648 -351.382281) (xy 419.821142 -351.42817) (xy 419.843803 -351.47779)
			(xy 419.859173 -351.53013) (xy 419.866936 -351.584125) (xy 419.866936 -351.63867) (xy 421.349639 -351.63867)
			(xy 421.349639 -351.58413) (xy 421.357402 -351.530146) (xy 421.372768 -351.477816) (xy 421.395426 -351.428206)
			(xy 421.424913 -351.382325) (xy 421.460631 -351.341108) (xy 421.501851 -351.305394) (xy 421.547734 -351.27591)
			(xy 421.597346 -351.253257) (xy 421.649677 -351.237895) (xy 421.703662 -351.230137) (xy 421.730932 -351.229676)
			(xy 422.594532 -351.229676) (xy 422.621803 -351.230089) (xy 422.675788 -351.237855) (xy 422.728119 -351.253224)
			(xy 422.77773 -351.275885) (xy 422.823612 -351.305374) (xy 422.864829 -351.341093) (xy 422.900545 -351.382314)
			(xy 422.930031 -351.428198) (xy 422.952687 -351.477811) (xy 422.968052 -351.530143) (xy 422.975814 -351.584129)
			(xy 422.975814 -351.638666) (xy 424.458662 -351.638666) (xy 424.458662 -351.584134) (xy 424.466423 -351.530156)
			(xy 424.481786 -351.477832) (xy 424.50444 -351.428228) (xy 424.533922 -351.382352) (xy 424.569633 -351.341138)
			(xy 424.610845 -351.305427) (xy 424.656721 -351.275944) (xy 424.706325 -351.253289) (xy 424.758648 -351.237925)
			(xy 424.812626 -351.230163) (xy 424.839892 -351.229676) (xy 425.703492 -351.229676) (xy 425.730766 -351.230063)
			(xy 425.784759 -351.237825) (xy 425.837098 -351.253192) (xy 425.886717 -351.275851) (xy 425.932606 -351.305342)
			(xy 425.973832 -351.341063) (xy 426.009553 -351.382287) (xy 426.039045 -351.428176) (xy 426.061705 -351.477794)
			(xy 426.077073 -351.530133) (xy 426.084836 -351.584126) (xy 426.084836 -351.638664) (xy 427.567662 -351.638664)
			(xy 427.567662 -351.584136) (xy 427.575422 -351.530162) (xy 427.590783 -351.477841) (xy 427.613434 -351.428239)
			(xy 427.642912 -351.382365) (xy 427.678619 -351.341153) (xy 427.719826 -351.305441) (xy 427.765697 -351.275957)
			(xy 427.815296 -351.2533) (xy 427.867615 -351.237932) (xy 427.921588 -351.230166) (xy 427.948852 -351.229676)
			(xy 428.812452 -351.229676) (xy 428.839728 -351.23006) (xy 428.893725 -351.237818) (xy 428.946069 -351.253181)
			(xy 428.995693 -351.275838) (xy 429.041587 -351.305328) (xy 429.082817 -351.341049) (xy 429.118544 -351.382274)
			(xy 429.148039 -351.428165) (xy 429.170702 -351.477786) (xy 429.186072 -351.530128) (xy 429.193836 -351.584124)
			(xy 429.193836 -351.638669) (xy 430.676539 -351.638669) (xy 430.676539 -351.584131) (xy 430.684301 -351.530149)
			(xy 430.699666 -351.47782) (xy 430.722323 -351.428211) (xy 430.751808 -351.382331) (xy 430.787524 -351.341115)
			(xy 430.828741 -351.305401) (xy 430.874622 -351.275917) (xy 430.924231 -351.253262) (xy 430.97656 -351.237899)
			(xy 431.030543 -351.230139) (xy 431.057812 -351.229676) (xy 431.921412 -351.229676) (xy 431.948684 -351.230087)
			(xy 432.002671 -351.237851) (xy 432.055004 -351.253219) (xy 432.104618 -351.275878) (xy 432.150502 -351.305367)
			(xy 432.191722 -351.341086) (xy 432.22744 -351.382308) (xy 432.256928 -351.428192) (xy 432.279585 -351.477807)
			(xy 432.294951 -351.530141) (xy 432.302714 -351.584128) (xy 432.302714 -351.638665) (xy 433.785562 -351.638665)
			(xy 433.785562 -351.584135) (xy 433.793322 -351.530159) (xy 433.808685 -351.477837) (xy 433.831337 -351.428233)
			(xy 433.860817 -351.382358) (xy 433.896526 -351.341146) (xy 433.937736 -351.305434) (xy 433.983609 -351.27595)
			(xy 434.03321 -351.253295) (xy 434.085531 -351.237928) (xy 434.139507 -351.230164) (xy 434.166772 -351.229676)
			(xy 435.030372 -351.229676) (xy 435.057647 -351.230062) (xy 435.111642 -351.237821) (xy 435.163984 -351.253187)
			(xy 435.213605 -351.275845) (xy 435.259497 -351.305335) (xy 435.300724 -351.341056) (xy 435.336448 -351.382281)
			(xy 435.365942 -351.42817) (xy 435.388603 -351.47779) (xy 435.403973 -351.53013) (xy 435.411736 -351.584125)
			(xy 435.411736 -351.63867) (xy 436.894439 -351.63867) (xy 436.894439 -351.58413) (xy 436.902202 -351.530146)
			(xy 436.917568 -351.477816) (xy 436.940226 -351.428206) (xy 436.969713 -351.382325) (xy 437.005431 -351.341108)
			(xy 437.046651 -351.305394) (xy 437.092534 -351.27591) (xy 437.142146 -351.253257) (xy 437.194477 -351.237895)
			(xy 437.248462 -351.230137) (xy 437.275732 -351.229676) (xy 438.139332 -351.229676) (xy 438.166603 -351.230089)
			(xy 438.220588 -351.237855) (xy 438.272919 -351.253224) (xy 438.32253 -351.275885) (xy 438.368412 -351.305374)
			(xy 438.409629 -351.341093) (xy 438.445345 -351.382314) (xy 438.474831 -351.428198) (xy 438.497487 -351.477811)
			(xy 438.512852 -351.530143) (xy 438.520614 -351.584129) (xy 438.520614 -351.638666) (xy 440.003462 -351.638666)
			(xy 440.003462 -351.584134) (xy 440.011223 -351.530156) (xy 440.026586 -351.477832) (xy 440.04924 -351.428228)
			(xy 440.078722 -351.382352) (xy 440.114433 -351.341138) (xy 440.155645 -351.305427) (xy 440.201521 -351.275944)
			(xy 440.251125 -351.253289) (xy 440.303448 -351.237925) (xy 440.357426 -351.230163) (xy 440.384692 -351.229676)
			(xy 441.248292 -351.229676) (xy 441.275566 -351.230063) (xy 441.329559 -351.237825) (xy 441.381898 -351.253192)
			(xy 441.431517 -351.275851) (xy 441.477406 -351.305342) (xy 441.518632 -351.341063) (xy 441.554353 -351.382287)
			(xy 441.583845 -351.428176) (xy 441.606505 -351.477794) (xy 441.621873 -351.530133) (xy 441.629636 -351.584126)
			(xy 441.629636 -351.638674) (xy 441.621873 -351.692667) (xy 441.606505 -351.745006) (xy 441.583845 -351.794624)
			(xy 441.554353 -351.840513) (xy 441.518632 -351.881737) (xy 441.477406 -351.917458) (xy 441.431517 -351.946949)
			(xy 441.381898 -351.969608) (xy 441.329559 -351.984975) (xy 441.275566 -351.992737) (xy 441.248292 -351.9932)
			(xy 440.384692 -351.9932) (xy 440.357426 -351.992637) (xy 440.303448 -351.984875) (xy 440.251125 -351.969511)
			(xy 440.201521 -351.946856) (xy 440.155645 -351.917373) (xy 440.114433 -351.881662) (xy 440.078722 -351.840448)
			(xy 440.04924 -351.794572) (xy 440.026586 -351.744968) (xy 440.011223 -351.692644) (xy 440.003462 -351.638666)
			(xy 438.520614 -351.638666) (xy 438.520614 -351.638671) (xy 438.512852 -351.692657) (xy 438.497487 -351.744989)
			(xy 438.474831 -351.794602) (xy 438.445345 -351.840486) (xy 438.409629 -351.881707) (xy 438.368412 -351.917426)
			(xy 438.32253 -351.946915) (xy 438.272919 -351.969576) (xy 438.220588 -351.984945) (xy 438.166603 -351.992711)
			(xy 438.139332 -351.9932) (xy 437.275732 -351.9932) (xy 437.248462 -351.992663) (xy 437.194477 -351.984905)
			(xy 437.142146 -351.969543) (xy 437.092534 -351.94689) (xy 437.046651 -351.917406) (xy 437.005431 -351.881692)
			(xy 436.969713 -351.840475) (xy 436.940226 -351.794594) (xy 436.917568 -351.744984) (xy 436.902202 -351.692654)
			(xy 436.894439 -351.63867) (xy 435.411736 -351.63867) (xy 435.411736 -351.638675) (xy 435.403973 -351.69267)
			(xy 435.388603 -351.74501) (xy 435.365942 -351.79463) (xy 435.336448 -351.840519) (xy 435.300724 -351.881744)
			(xy 435.259497 -351.917465) (xy 435.213605 -351.946955) (xy 435.163984 -351.969613) (xy 435.111642 -351.984979)
			(xy 435.057647 -351.992738) (xy 435.030372 -351.9932) (xy 434.166772 -351.9932) (xy 434.139507 -351.992636)
			(xy 434.085531 -351.984872) (xy 434.03321 -351.969505) (xy 433.983609 -351.94685) (xy 433.937736 -351.917366)
			(xy 433.896526 -351.881654) (xy 433.860817 -351.840442) (xy 433.831337 -351.794567) (xy 433.808685 -351.744963)
			(xy 433.793322 -351.692641) (xy 433.785562 -351.638665) (xy 432.302714 -351.638665) (xy 432.302714 -351.638672)
			(xy 432.294951 -351.692659) (xy 432.279585 -351.744993) (xy 432.256928 -351.794608) (xy 432.22744 -351.840492)
			(xy 432.191722 -351.881714) (xy 432.150502 -351.917433) (xy 432.104618 -351.946922) (xy 432.055004 -351.969581)
			(xy 432.002671 -351.984949) (xy 431.948684 -351.992713) (xy 431.921412 -351.9932) (xy 431.057812 -351.9932)
			(xy 431.030543 -351.992661) (xy 430.97656 -351.984901) (xy 430.924231 -351.969538) (xy 430.874622 -351.946883)
			(xy 430.828741 -351.917399) (xy 430.787524 -351.881685) (xy 430.751808 -351.840469) (xy 430.722323 -351.794589)
			(xy 430.699666 -351.74498) (xy 430.684301 -351.692651) (xy 430.676539 -351.638669) (xy 429.193836 -351.638669)
			(xy 429.193836 -351.638676) (xy 429.186072 -351.692672) (xy 429.170702 -351.745014) (xy 429.148039 -351.794635)
			(xy 429.118544 -351.840526) (xy 429.082817 -351.881751) (xy 429.041587 -351.917472) (xy 428.995693 -351.946962)
			(xy 428.946069 -351.969619) (xy 428.893725 -351.984982) (xy 428.839728 -351.99274) (xy 428.812452 -351.9932)
			(xy 427.948852 -351.9932) (xy 427.921588 -351.992634) (xy 427.867615 -351.984868) (xy 427.815296 -351.9695)
			(xy 427.765697 -351.946843) (xy 427.719826 -351.917359) (xy 427.678619 -351.881647) (xy 427.642912 -351.840435)
			(xy 427.613434 -351.794561) (xy 427.590783 -351.744959) (xy 427.575422 -351.692639) (xy 427.567662 -351.638664)
			(xy 426.084836 -351.638664) (xy 426.084836 -351.638674) (xy 426.077073 -351.692667) (xy 426.061705 -351.745006)
			(xy 426.039045 -351.794624) (xy 426.009553 -351.840513) (xy 425.973832 -351.881737) (xy 425.932606 -351.917458)
			(xy 425.886717 -351.946949) (xy 425.837098 -351.969608) (xy 425.784759 -351.984975) (xy 425.730766 -351.992737)
			(xy 425.703492 -351.9932) (xy 424.839892 -351.9932) (xy 424.812626 -351.992637) (xy 424.758648 -351.984875)
			(xy 424.706325 -351.969511) (xy 424.656721 -351.946856) (xy 424.610845 -351.917373) (xy 424.569633 -351.881662)
			(xy 424.533922 -351.840448) (xy 424.50444 -351.794572) (xy 424.481786 -351.744968) (xy 424.466423 -351.692644)
			(xy 424.458662 -351.638666) (xy 422.975814 -351.638666) (xy 422.975814 -351.638671) (xy 422.968052 -351.692657)
			(xy 422.952687 -351.744989) (xy 422.930031 -351.794602) (xy 422.900545 -351.840486) (xy 422.864829 -351.881707)
			(xy 422.823612 -351.917426) (xy 422.77773 -351.946915) (xy 422.728119 -351.969576) (xy 422.675788 -351.984945)
			(xy 422.621803 -351.992711) (xy 422.594532 -351.9932) (xy 421.730932 -351.9932) (xy 421.703662 -351.992663)
			(xy 421.649677 -351.984905) (xy 421.597346 -351.969543) (xy 421.547734 -351.94689) (xy 421.501851 -351.917406)
			(xy 421.460631 -351.881692) (xy 421.424913 -351.840475) (xy 421.395426 -351.794594) (xy 421.372768 -351.744984)
			(xy 421.357402 -351.692654) (xy 421.349639 -351.63867) (xy 419.866936 -351.63867) (xy 419.866936 -351.638675)
			(xy 419.859173 -351.69267) (xy 419.843803 -351.74501) (xy 419.821142 -351.79463) (xy 419.791648 -351.840519)
			(xy 419.755924 -351.881744) (xy 419.714697 -351.917465) (xy 419.668805 -351.946955) (xy 419.619184 -351.969613)
			(xy 419.566842 -351.984979) (xy 419.512847 -351.992738) (xy 419.485572 -351.9932) (xy 418.621972 -351.9932)
			(xy 418.594707 -351.992636) (xy 418.540731 -351.984872) (xy 418.48841 -351.969505) (xy 418.438809 -351.94685)
			(xy 418.392936 -351.917366) (xy 418.351726 -351.881654) (xy 418.316017 -351.840442) (xy 418.286537 -351.794567)
			(xy 418.263885 -351.744963) (xy 418.248522 -351.692641) (xy 418.240762 -351.638665) (xy 416.757914 -351.638665)
			(xy 416.757914 -351.638672) (xy 416.750151 -351.692659) (xy 416.734785 -351.744993) (xy 416.712128 -351.794608)
			(xy 416.68264 -351.840492) (xy 416.646922 -351.881714) (xy 416.605702 -351.917433) (xy 416.559818 -351.946922)
			(xy 416.510204 -351.969581) (xy 416.457871 -351.984949) (xy 416.403884 -351.992713) (xy 416.376612 -351.9932)
			(xy 415.513012 -351.9932) (xy 415.485743 -351.992661) (xy 415.43176 -351.984901) (xy 415.379431 -351.969538)
			(xy 415.329822 -351.946883) (xy 415.283941 -351.917399) (xy 415.242724 -351.881685) (xy 415.207008 -351.840469)
			(xy 415.177523 -351.794589) (xy 415.154866 -351.74498) (xy 415.139501 -351.692651) (xy 415.131739 -351.638669)
			(xy 413.649036 -351.638669) (xy 413.649036 -351.638676) (xy 413.641272 -351.692672) (xy 413.625902 -351.745014)
			(xy 413.603239 -351.794635) (xy 413.573744 -351.840526) (xy 413.538017 -351.881751) (xy 413.496787 -351.917472)
			(xy 413.450893 -351.946962) (xy 413.401269 -351.969619) (xy 413.348925 -351.984982) (xy 413.294928 -351.99274)
			(xy 413.267652 -351.9932) (xy 412.404052 -351.9932) (xy 412.376788 -351.992634) (xy 412.322815 -351.984868)
			(xy 412.270496 -351.9695) (xy 412.220897 -351.946843) (xy 412.175026 -351.917359) (xy 412.133819 -351.881647)
			(xy 412.098112 -351.840435) (xy 412.068634 -351.794561) (xy 412.045983 -351.744959) (xy 412.030622 -351.692639)
			(xy 412.022862 -351.638664) (xy 410.540036 -351.638664) (xy 410.540036 -351.638674) (xy 410.532273 -351.692667)
			(xy 410.516905 -351.745006) (xy 410.494245 -351.794624) (xy 410.464753 -351.840513) (xy 410.429032 -351.881737)
			(xy 410.387806 -351.917458) (xy 410.341917 -351.946949) (xy 410.292298 -351.969608) (xy 410.239959 -351.984975)
			(xy 410.185966 -351.992737) (xy 410.158692 -351.9932) (xy 409.295092 -351.9932) (xy 409.267826 -351.992637)
			(xy 409.213848 -351.984875) (xy 409.161525 -351.969511) (xy 409.111921 -351.946856) (xy 409.066045 -351.917373)
			(xy 409.024833 -351.881662) (xy 408.989122 -351.840448) (xy 408.95964 -351.794572) (xy 408.936986 -351.744968)
			(xy 408.921623 -351.692644) (xy 408.913862 -351.638666) (xy 403.522536 -351.638666) (xy 403.522536 -351.638675)
			(xy 403.514773 -351.692669) (xy 403.499404 -351.745008) (xy 403.476743 -351.794628) (xy 403.44725 -351.840517)
			(xy 403.411527 -351.881741) (xy 403.370301 -351.917462) (xy 403.32441 -351.946952) (xy 403.274789 -351.969611)
			(xy 403.222449 -351.984977) (xy 403.168455 -351.992738) (xy 403.14118 -351.9932) (xy 402.27758 -351.9932)
			(xy 402.250314 -351.992636) (xy 402.196338 -351.984873) (xy 402.144016 -351.969508) (xy 402.094414 -351.946852)
			(xy 402.04854 -351.917369) (xy 402.007329 -351.881657) (xy 401.971619 -351.840444) (xy 401.942138 -351.794569)
			(xy 401.919485 -351.744965) (xy 401.904123 -351.692642) (xy 401.896362 -351.638666) (xy 400.413514 -351.638666)
			(xy 400.413514 -351.638671) (xy 400.405752 -351.692658) (xy 400.390386 -351.744992) (xy 400.367729 -351.794605)
			(xy 400.338242 -351.84049) (xy 400.302525 -351.881711) (xy 400.261306 -351.91743) (xy 400.215423 -351.946919)
			(xy 400.16581 -351.969579) (xy 400.113478 -351.984947) (xy 400.059491 -351.992712) (xy 400.03222 -351.9932)
			(xy 399.16862 -351.9932) (xy 399.141351 -351.992662) (xy 399.087367 -351.984903) (xy 399.035037 -351.96954)
			(xy 398.985426 -351.946886) (xy 398.939545 -351.917402) (xy 398.898326 -351.881688) (xy 398.86261 -351.840471)
			(xy 398.833124 -351.794591) (xy 398.810467 -351.744982) (xy 398.795101 -351.692652) (xy 398.787339 -351.638669)
			(xy 397.304636 -351.638669) (xy 397.304636 -351.638676) (xy 397.296872 -351.692671) (xy 397.281503 -351.745012)
			(xy 397.25884 -351.794633) (xy 397.229346 -351.840523) (xy 397.19362 -351.881749) (xy 397.152391 -351.91747)
			(xy 397.106498 -351.946959) (xy 397.056875 -351.969617) (xy 397.004532 -351.984981) (xy 396.950536 -351.992739)
			(xy 396.92326 -351.9932) (xy 396.05966 -351.9932) (xy 396.032395 -351.992635) (xy 395.978421 -351.984869)
			(xy 395.926102 -351.969502) (xy 395.876502 -351.946846) (xy 395.83063 -351.917362) (xy 395.789421 -351.88165)
			(xy 395.753714 -351.840438) (xy 395.724235 -351.794563) (xy 395.701584 -351.744961) (xy 395.686222 -351.69264)
			(xy 395.678462 -351.638665) (xy 394.195613 -351.638665) (xy 394.195613 -351.638672) (xy 394.187851 -351.692661)
			(xy 394.172484 -351.744996) (xy 394.149826 -351.794611) (xy 394.120337 -351.840496) (xy 394.084618 -351.881718)
			(xy 394.043396 -351.917437) (xy 393.997511 -351.946926) (xy 393.947896 -351.969584) (xy 393.895561 -351.984951)
			(xy 393.841572 -351.992713) (xy 393.8143 -351.9932) (xy 392.9507 -351.9932) (xy 392.923433 -351.992638)
			(xy 392.869455 -351.984877) (xy 392.817131 -351.969513) (xy 392.767526 -351.946859) (xy 392.721649 -351.917376)
			(xy 392.680436 -351.881664) (xy 392.644724 -351.840451) (xy 392.615241 -351.794574) (xy 392.592587 -351.744969)
			(xy 392.577223 -351.692645) (xy 392.569462 -351.638667) (xy 391.086614 -351.638667) (xy 391.086614 -351.63867)
			(xy 391.078852 -351.692656) (xy 391.063487 -351.744987) (xy 391.040832 -351.7946) (xy 391.011347 -351.840483)
			(xy 390.975632 -351.881704) (xy 390.934415 -351.917423) (xy 390.888535 -351.946913) (xy 390.838925 -351.969573)
			(xy 390.786595 -351.984944) (xy 390.73261 -351.992711) (xy 390.70534 -351.9932) (xy 389.84174 -351.9932)
			(xy 389.81447 -351.992663) (xy 389.760484 -351.984907) (xy 389.708152 -351.969545) (xy 389.658538 -351.946892)
			(xy 389.612654 -351.917409) (xy 389.571434 -351.881695) (xy 389.535715 -351.840478) (xy 389.506227 -351.794597)
			(xy 389.483569 -351.744986) (xy 389.468202 -351.692655) (xy 389.46044 -351.63867) (xy 387.977736 -351.63867)
			(xy 387.977736 -351.638675) (xy 387.969973 -351.692669) (xy 387.954604 -351.745008) (xy 387.931943 -351.794628)
			(xy 387.90245 -351.840517) (xy 387.866727 -351.881741) (xy 387.825501 -351.917462) (xy 387.77961 -351.946952)
			(xy 387.729989 -351.969611) (xy 387.677649 -351.984977) (xy 387.623655 -351.992738) (xy 387.59638 -351.9932)
			(xy 386.73278 -351.9932) (xy 386.705514 -351.992636) (xy 386.651538 -351.984873) (xy 386.599216 -351.969508)
			(xy 386.549614 -351.946852) (xy 386.50374 -351.917369) (xy 386.462529 -351.881657) (xy 386.426819 -351.840444)
			(xy 386.397338 -351.794569) (xy 386.374685 -351.744965) (xy 386.359323 -351.692642) (xy 386.351562 -351.638666)
			(xy 384.868714 -351.638666) (xy 384.868714 -351.638671) (xy 384.860952 -351.692658) (xy 384.845586 -351.744992)
			(xy 384.822929 -351.794605) (xy 384.793442 -351.84049) (xy 384.757725 -351.881711) (xy 384.716506 -351.91743)
			(xy 384.670623 -351.946919) (xy 384.62101 -351.969579) (xy 384.568678 -351.984947) (xy 384.514691 -351.992712)
			(xy 384.48742 -351.9932) (xy 383.62382 -351.9932) (xy 383.596551 -351.992662) (xy 383.542567 -351.984903)
			(xy 383.490237 -351.96954) (xy 383.440626 -351.946886) (xy 383.394745 -351.917402) (xy 383.353526 -351.881688)
			(xy 383.31781 -351.840471) (xy 383.288324 -351.794591) (xy 383.265667 -351.744982) (xy 383.250301 -351.692652)
			(xy 383.242539 -351.638669) (xy 381.759836 -351.638669) (xy 381.759836 -351.638676) (xy 381.752072 -351.692671)
			(xy 381.736703 -351.745012) (xy 381.71404 -351.794633) (xy 381.684546 -351.840523) (xy 381.64882 -351.881749)
			(xy 381.607591 -351.91747) (xy 381.561698 -351.946959) (xy 381.512075 -351.969617) (xy 381.459732 -351.984981)
			(xy 381.405736 -351.992739) (xy 381.37846 -351.9932) (xy 380.51486 -351.9932) (xy 380.487595 -351.992635)
			(xy 380.433621 -351.984869) (xy 380.381302 -351.969502) (xy 380.331702 -351.946846) (xy 380.28583 -351.917362)
			(xy 380.244621 -351.88165) (xy 380.208914 -351.840438) (xy 380.179435 -351.794563) (xy 380.156784 -351.744961)
			(xy 380.141422 -351.69264) (xy 380.133662 -351.638665) (xy 378.650813 -351.638665) (xy 378.650813 -351.638672)
			(xy 378.643051 -351.692661) (xy 378.627684 -351.744996) (xy 378.605026 -351.794611) (xy 378.575537 -351.840496)
			(xy 378.539818 -351.881718) (xy 378.498596 -351.917437) (xy 378.452711 -351.946926) (xy 378.403096 -351.969584)
			(xy 378.350761 -351.984951) (xy 378.296772 -351.992713) (xy 378.2695 -351.9932) (xy 377.4059 -351.9932)
			(xy 377.378633 -351.992638) (xy 377.324655 -351.984877) (xy 377.272331 -351.969513) (xy 377.222726 -351.946859)
			(xy 377.176849 -351.917376) (xy 377.135636 -351.881664) (xy 377.099924 -351.840451) (xy 377.070441 -351.794574)
			(xy 377.047787 -351.744969) (xy 377.032423 -351.692645) (xy 377.024662 -351.638667) (xy 375.541814 -351.638667)
			(xy 375.541814 -351.63867) (xy 375.534052 -351.692656) (xy 375.518687 -351.744987) (xy 375.496032 -351.7946)
			(xy 375.466547 -351.840483) (xy 375.430832 -351.881704) (xy 375.389615 -351.917423) (xy 375.343735 -351.946913)
			(xy 375.294125 -351.969573) (xy 375.241795 -351.984944) (xy 375.18781 -351.992711) (xy 375.16054 -351.9932)
			(xy 374.29694 -351.9932) (xy 374.26967 -351.992663) (xy 374.215684 -351.984907) (xy 374.163352 -351.969545)
			(xy 374.113738 -351.946892) (xy 374.067854 -351.917409) (xy 374.026634 -351.881695) (xy 373.990915 -351.840478)
			(xy 373.961427 -351.794597) (xy 373.938769 -351.744986) (xy 373.923402 -351.692655) (xy 373.91564 -351.63867)
			(xy 372.432936 -351.63867) (xy 372.432936 -351.638675) (xy 372.425173 -351.692669) (xy 372.409804 -351.745008)
			(xy 372.387143 -351.794628) (xy 372.35765 -351.840517) (xy 372.321927 -351.881741) (xy 372.280701 -351.917462)
			(xy 372.23481 -351.946952) (xy 372.185189 -351.969611) (xy 372.132849 -351.984977) (xy 372.078855 -351.992738)
			(xy 372.05158 -351.9932) (xy 371.18798 -351.9932) (xy 371.160714 -351.992636) (xy 371.106738 -351.984873)
			(xy 371.054416 -351.969508) (xy 371.004814 -351.946852) (xy 370.95894 -351.917369) (xy 370.917729 -351.881657)
			(xy 370.882019 -351.840444) (xy 370.852538 -351.794569) (xy 370.829885 -351.744965) (xy 370.814523 -351.692642)
			(xy 370.806762 -351.638666) (xy 369.214908 -351.638666) (xy 369.214908 -353.8728) (xy 369.215331 -353.88287)
			(xy 369.223047 -353.901474) (xy 369.229894 -353.908868) (xy 370.0804 -354.759374) (xy 373.915584 -354.759374)
			(xy 373.915584 -354.704826) (xy 373.923347 -354.650833) (xy 373.938716 -354.598495) (xy 373.961378 -354.548876)
			(xy 373.990871 -354.502989) (xy 374.026594 -354.461766) (xy 374.067821 -354.426047) (xy 374.113712 -354.396559)
			(xy 374.163332 -354.373902) (xy 374.215672 -354.358539) (xy 374.269666 -354.350781) (xy 374.29694 -354.35032)
			(xy 375.16054 -354.35032) (xy 375.187806 -354.350845) (xy 375.241783 -354.358611) (xy 375.294105 -354.373979)
			(xy 375.343708 -354.396637) (xy 375.389582 -354.426122) (xy 375.430793 -354.461836) (xy 375.466502 -354.50305)
			(xy 375.495983 -354.548927) (xy 375.518635 -354.598532) (xy 375.533997 -354.650856) (xy 375.541758 -354.704834)
			(xy 375.541758 -354.759366) (xy 375.541757 -354.759371) (xy 377.024606 -354.759371) (xy 377.024606 -354.704829)
			(xy 377.032369 -354.650843) (xy 377.047735 -354.598511) (xy 377.070392 -354.548899) (xy 377.099879 -354.503016)
			(xy 377.135596 -354.461796) (xy 377.176816 -354.426079) (xy 377.222699 -354.396592) (xy 377.272311 -354.373935)
			(xy 377.324643 -354.358569) (xy 377.378629 -354.350806) (xy 377.4059 -354.35032) (xy 378.2695 -354.35032)
			(xy 378.296768 -354.350842) (xy 378.350749 -354.358604) (xy 378.403076 -354.373968) (xy 378.452684 -354.396623)
			(xy 378.498563 -354.426108) (xy 378.539778 -354.461822) (xy 378.575492 -354.503037) (xy 378.604977 -354.548916)
			(xy 378.627632 -354.598524) (xy 378.642996 -354.650851) (xy 378.650758 -354.704832) (xy 378.650758 -354.759368)
			(xy 378.650758 -354.759369) (xy 380.133606 -354.759369) (xy 380.133606 -354.704831) (xy 380.141367 -354.650849)
			(xy 380.156731 -354.59852) (xy 380.179386 -354.54891) (xy 380.208869 -354.503029) (xy 380.244582 -354.46181)
			(xy 380.285797 -354.426093) (xy 380.331675 -354.396605) (xy 380.381282 -354.373945) (xy 380.433609 -354.358576)
			(xy 380.487591 -354.350809) (xy 380.51486 -354.35032) (xy 381.37846 -354.35032) (xy 381.405732 -354.350817)
			(xy 381.45972 -354.358574) (xy 381.512055 -354.373936) (xy 381.561671 -354.39659) (xy 381.607558 -354.426075)
			(xy 381.648781 -354.461791) (xy 381.684501 -354.50301) (xy 381.713991 -354.548894) (xy 381.73665 -354.598507)
			(xy 381.752018 -354.650841) (xy 381.75978 -354.704828) (xy 381.75978 -354.759372) (xy 381.75978 -354.759373)
			(xy 383.242484 -354.759373) (xy 383.242484 -354.704827) (xy 383.250247 -354.650836) (xy 383.265615 -354.598499)
			(xy 383.288275 -354.548882) (xy 383.317766 -354.502995) (xy 383.353487 -354.461773) (xy 383.394711 -354.426054)
			(xy 383.4406 -354.396565) (xy 383.490218 -354.373908) (xy 383.542555 -354.358542) (xy 383.596547 -354.350782)
			(xy 383.62382 -354.35032) (xy 384.48742 -354.35032) (xy 384.514687 -354.350844) (xy 384.568666 -354.358607)
			(xy 384.620991 -354.373974) (xy 384.670596 -354.39663) (xy 384.716472 -354.426115) (xy 384.757686 -354.461829)
			(xy 384.793397 -354.503044) (xy 384.82288 -354.548922) (xy 384.845533 -354.598528) (xy 384.860897 -354.650854)
			(xy 384.868658 -354.704833) (xy 384.868658 -354.759367) (xy 384.868658 -354.75937) (xy 386.351506 -354.75937)
			(xy 386.351506 -354.70483) (xy 386.359268 -354.650846) (xy 386.374633 -354.598515) (xy 386.397289 -354.548904)
			(xy 386.426774 -354.503022) (xy 386.462489 -354.461803) (xy 386.503706 -354.426086) (xy 386.549587 -354.396598)
			(xy 386.599197 -354.37394) (xy 386.651526 -354.358572) (xy 386.70551 -354.350808) (xy 386.73278 -354.35032)
			(xy 387.59638 -354.35032) (xy 387.623651 -354.350818) (xy 387.677637 -354.358578) (xy 387.72997 -354.373941)
			(xy 387.779583 -354.396597) (xy 387.825467 -354.426082) (xy 387.866688 -354.461798) (xy 387.902406 -354.503017)
			(xy 387.931894 -354.548899) (xy 387.954552 -354.598511) (xy 387.969918 -354.650843) (xy 387.97768 -354.704829)
			(xy 387.97768 -354.759371) (xy 387.97768 -354.759374) (xy 389.460384 -354.759374) (xy 389.460384 -354.704826)
			(xy 389.468147 -354.650833) (xy 389.483516 -354.598495) (xy 389.506178 -354.548876) (xy 389.535671 -354.502989)
			(xy 389.571394 -354.461766) (xy 389.612621 -354.426047) (xy 389.658512 -354.396559) (xy 389.708132 -354.373902)
			(xy 389.760472 -354.358539) (xy 389.814466 -354.350781) (xy 389.84174 -354.35032) (xy 390.70534 -354.35032)
			(xy 390.732606 -354.350845) (xy 390.786583 -354.358611) (xy 390.838905 -354.373979) (xy 390.888508 -354.396637)
			(xy 390.934382 -354.426122) (xy 390.975593 -354.461836) (xy 391.011302 -354.50305) (xy 391.040783 -354.548927)
			(xy 391.063435 -354.598532) (xy 391.078797 -354.650856) (xy 391.086558 -354.704834) (xy 391.086558 -354.759366)
			(xy 391.086557 -354.759371) (xy 392.569406 -354.759371) (xy 392.569406 -354.704829) (xy 392.577169 -354.650843)
			(xy 392.592535 -354.598511) (xy 392.615192 -354.548899) (xy 392.644679 -354.503016) (xy 392.680396 -354.461796)
			(xy 392.721616 -354.426079) (xy 392.767499 -354.396592) (xy 392.817111 -354.373935) (xy 392.869443 -354.358569)
			(xy 392.923429 -354.350806) (xy 392.9507 -354.35032) (xy 393.8143 -354.35032) (xy 393.841568 -354.350842)
			(xy 393.895549 -354.358604) (xy 393.947876 -354.373968) (xy 393.997484 -354.396623) (xy 394.043363 -354.426108)
			(xy 394.084578 -354.461822) (xy 394.120292 -354.503037) (xy 394.149777 -354.548916) (xy 394.172432 -354.598524)
			(xy 394.187796 -354.650851) (xy 394.195558 -354.704832) (xy 394.195558 -354.759368) (xy 394.195558 -354.759369)
			(xy 395.678406 -354.759369) (xy 395.678406 -354.704831) (xy 395.686167 -354.650849) (xy 395.701531 -354.59852)
			(xy 395.724186 -354.54891) (xy 395.753669 -354.503029) (xy 395.789382 -354.46181) (xy 395.830597 -354.426093)
			(xy 395.876475 -354.396605) (xy 395.926082 -354.373945) (xy 395.978409 -354.358576) (xy 396.032391 -354.350809)
			(xy 396.05966 -354.35032) (xy 396.92326 -354.35032) (xy 396.950532 -354.350817) (xy 397.00452 -354.358574)
			(xy 397.056855 -354.373936) (xy 397.106471 -354.39659) (xy 397.152358 -354.426075) (xy 397.193581 -354.461791)
			(xy 397.229301 -354.50301) (xy 397.258791 -354.548894) (xy 397.28145 -354.598507) (xy 397.296818 -354.650841)
			(xy 397.30458 -354.704828) (xy 397.30458 -354.759372) (xy 397.30458 -354.759373) (xy 398.787284 -354.759373)
			(xy 398.787284 -354.704827) (xy 398.795047 -354.650836) (xy 398.810415 -354.598499) (xy 398.833075 -354.548882)
			(xy 398.862566 -354.502995) (xy 398.898287 -354.461773) (xy 398.939511 -354.426054) (xy 398.9854 -354.396565)
			(xy 399.035018 -354.373908) (xy 399.087355 -354.358542) (xy 399.141347 -354.350782) (xy 399.16862 -354.35032)
			(xy 400.03222 -354.35032) (xy 400.059487 -354.350844) (xy 400.113466 -354.358607) (xy 400.165791 -354.373974)
			(xy 400.215396 -354.39663) (xy 400.261272 -354.426115) (xy 400.302486 -354.461829) (xy 400.338197 -354.503044)
			(xy 400.36768 -354.548922) (xy 400.390333 -354.598528) (xy 400.405697 -354.650854) (xy 400.413458 -354.704833)
			(xy 400.413458 -354.759367) (xy 400.413458 -354.75937) (xy 401.896306 -354.75937) (xy 401.896306 -354.70483)
			(xy 401.904068 -354.650846) (xy 401.919433 -354.598515) (xy 401.942089 -354.548904) (xy 401.971574 -354.503022)
			(xy 402.007289 -354.461803) (xy 402.048506 -354.426086) (xy 402.094387 -354.396598) (xy 402.143997 -354.37394)
			(xy 402.196326 -354.358572) (xy 402.25031 -354.350808) (xy 402.27758 -354.35032) (xy 403.14118 -354.35032)
			(xy 403.168451 -354.350818) (xy 403.222437 -354.358578) (xy 403.27477 -354.373941) (xy 403.324383 -354.396597)
			(xy 403.370267 -354.426082) (xy 403.411488 -354.461798) (xy 403.447206 -354.503017) (xy 403.476694 -354.548899)
			(xy 403.499352 -354.598511) (xy 403.514718 -354.650843) (xy 403.52248 -354.704829) (xy 403.52248 -354.759368)
			(xy 412.022806 -354.759368) (xy 412.022806 -354.704832) (xy 412.030567 -354.65085) (xy 412.045931 -354.598521)
			(xy 412.068585 -354.548912) (xy 412.098067 -354.503031) (xy 412.133779 -354.461813) (xy 412.174993 -354.426096)
			(xy 412.22087 -354.396608) (xy 412.270476 -354.373948) (xy 412.322803 -354.358577) (xy 412.376784 -354.35081)
			(xy 412.404052 -354.35032) (xy 413.267652 -354.35032) (xy 413.294924 -354.350816) (xy 413.348913 -354.358572)
			(xy 413.401249 -354.373934) (xy 413.450866 -354.396588) (xy 413.496754 -354.426072) (xy 413.537978 -354.461788)
			(xy 413.573699 -354.503008) (xy 413.603189 -354.548891) (xy 413.625849 -354.598506) (xy 413.641217 -354.65084)
			(xy 413.64898 -354.704828) (xy 413.64898 -354.759372) (xy 413.64898 -354.759373) (xy 415.131684 -354.759373)
			(xy 415.131684 -354.704827) (xy 415.139446 -354.650837) (xy 415.154814 -354.598501) (xy 415.177473 -354.548884)
			(xy 415.206964 -354.502998) (xy 415.242684 -354.461776) (xy 415.283908 -354.426056) (xy 415.329795 -354.396568)
			(xy 415.379412 -354.37391) (xy 415.431748 -354.358544) (xy 415.485739 -354.350783) (xy 415.513012 -354.35032)
			(xy 416.376612 -354.35032) (xy 416.40388 -354.350843) (xy 416.457859 -354.358606) (xy 416.510185 -354.373972)
			(xy 416.559791 -354.396627) (xy 416.605668 -354.426112) (xy 416.646883 -354.461826) (xy 416.682595 -354.503041)
			(xy 416.712078 -354.548919) (xy 416.734733 -354.598526) (xy 416.750097 -354.650852) (xy 416.757858 -354.704832)
			(xy 416.757858 -354.759368) (xy 416.757858 -354.759369) (xy 418.240706 -354.759369) (xy 418.240706 -354.704831)
			(xy 418.248468 -354.650847) (xy 418.263832 -354.598517) (xy 418.286488 -354.548907) (xy 418.315972 -354.503025)
			(xy 418.351686 -354.461806) (xy 418.392902 -354.426089) (xy 418.438782 -354.396601) (xy 418.488391 -354.373942)
			(xy 418.54072 -354.358574) (xy 418.594703 -354.350808) (xy 418.621972 -354.35032) (xy 419.485572 -354.35032)
			(xy 419.512843 -354.350818) (xy 419.56683 -354.358576) (xy 419.619164 -354.373939) (xy 419.668778 -354.396594)
			(xy 419.714663 -354.42608) (xy 419.755885 -354.461795) (xy 419.791604 -354.503014) (xy 419.821092 -354.548897)
			(xy 419.843751 -354.59851) (xy 419.859118 -354.650842) (xy 419.86688 -354.704829) (xy 419.86688 -354.759371)
			(xy 419.86688 -354.759374) (xy 421.349584 -354.759374) (xy 421.349584 -354.704826) (xy 421.357347 -354.650834)
			(xy 421.372716 -354.598496) (xy 421.395377 -354.548879) (xy 421.424869 -354.502991) (xy 421.460591 -354.461768)
			(xy 421.501817 -354.426049) (xy 421.547707 -354.396561) (xy 421.597326 -354.373904) (xy 421.649665 -354.35854)
			(xy 421.703658 -354.350781) (xy 421.730932 -354.35032) (xy 422.594532 -354.35032) (xy 422.621799 -354.350845)
			(xy 422.675776 -354.35861) (xy 422.728099 -354.373977) (xy 422.777703 -354.396634) (xy 422.823578 -354.426119)
			(xy 422.86479 -354.461833) (xy 422.9005 -354.503048) (xy 422.929981 -354.548925) (xy 422.952634 -354.598531)
			(xy 422.967997 -354.650855) (xy 422.975758 -354.704833) (xy 422.975758 -354.759367) (xy 422.975758 -354.75937)
			(xy 424.458606 -354.75937) (xy 424.458606 -354.70483) (xy 424.466368 -354.650844) (xy 424.481734 -354.598513)
			(xy 424.504391 -354.548901) (xy 424.533877 -354.503018) (xy 424.569593 -354.461799) (xy 424.610812 -354.426082)
			(xy 424.656694 -354.396594) (xy 424.706305 -354.373937) (xy 424.758636 -354.35857) (xy 424.812622 -354.350807)
			(xy 424.839892 -354.35032) (xy 425.703492 -354.35032) (xy 425.730762 -354.350819) (xy 425.784747 -354.35858)
			(xy 425.837078 -354.373945) (xy 425.88669 -354.396601) (xy 425.932573 -354.426087) (xy 425.973792 -354.461802)
			(xy 426.009509 -354.503021) (xy 426.038996 -354.548903) (xy 426.061653 -354.598514) (xy 426.077019 -354.650845)
			(xy 426.084781 -354.70483) (xy 426.084781 -354.759368) (xy 427.567606 -354.759368) (xy 427.567606 -354.704832)
			(xy 427.575367 -354.65085) (xy 427.590731 -354.598521) (xy 427.613385 -354.548912) (xy 427.642867 -354.503031)
			(xy 427.678579 -354.461813) (xy 427.719793 -354.426096) (xy 427.76567 -354.396608) (xy 427.815276 -354.373948)
			(xy 427.867603 -354.358577) (xy 427.921584 -354.35081) (xy 427.948852 -354.35032) (xy 428.812452 -354.35032)
			(xy 428.839724 -354.350816) (xy 428.893713 -354.358572) (xy 428.946049 -354.373934) (xy 428.995666 -354.396588)
			(xy 429.041554 -354.426072) (xy 429.082778 -354.461788) (xy 429.118499 -354.503008) (xy 429.147989 -354.548891)
			(xy 429.170649 -354.598506) (xy 429.186017 -354.65084) (xy 429.19378 -354.704828) (xy 429.19378 -354.759372)
			(xy 429.19378 -354.759373) (xy 430.676484 -354.759373) (xy 430.676484 -354.704827) (xy 430.684246 -354.650837)
			(xy 430.699614 -354.598501) (xy 430.722273 -354.548884) (xy 430.751764 -354.502998) (xy 430.787484 -354.461776)
			(xy 430.828708 -354.426056) (xy 430.874595 -354.396568) (xy 430.924212 -354.37391) (xy 430.976548 -354.358544)
			(xy 431.030539 -354.350783) (xy 431.057812 -354.35032) (xy 431.921412 -354.35032) (xy 431.94868 -354.350843)
			(xy 432.002659 -354.358606) (xy 432.054985 -354.373972) (xy 432.104591 -354.396627) (xy 432.150468 -354.426112)
			(xy 432.191683 -354.461826) (xy 432.227395 -354.503041) (xy 432.256878 -354.548919) (xy 432.279533 -354.598526)
			(xy 432.294897 -354.650852) (xy 432.302658 -354.704832) (xy 432.302658 -354.759368) (xy 432.302658 -354.759369)
			(xy 433.785506 -354.759369) (xy 433.785506 -354.704831) (xy 433.793268 -354.650847) (xy 433.808632 -354.598517)
			(xy 433.831288 -354.548907) (xy 433.860772 -354.503025) (xy 433.896486 -354.461806) (xy 433.937702 -354.426089)
			(xy 433.983582 -354.396601) (xy 434.033191 -354.373942) (xy 434.08552 -354.358574) (xy 434.139503 -354.350808)
			(xy 434.166772 -354.35032) (xy 435.030372 -354.35032) (xy 435.057643 -354.350818) (xy 435.11163 -354.358576)
			(xy 435.163964 -354.373939) (xy 435.213578 -354.396594) (xy 435.259463 -354.42608) (xy 435.300685 -354.461795)
			(xy 435.336404 -354.503014) (xy 435.365892 -354.548897) (xy 435.388551 -354.59851) (xy 435.403918 -354.650842)
			(xy 435.41168 -354.704829) (xy 435.41168 -354.759371) (xy 435.41168 -354.759374) (xy 436.894384 -354.759374)
			(xy 436.894384 -354.704826) (xy 436.902147 -354.650834) (xy 436.917516 -354.598496) (xy 436.940177 -354.548879)
			(xy 436.969669 -354.502991) (xy 437.005391 -354.461768) (xy 437.046617 -354.426049) (xy 437.092507 -354.396561)
			(xy 437.142126 -354.373904) (xy 437.194465 -354.35854) (xy 437.248458 -354.350781) (xy 437.275732 -354.35032)
			(xy 438.139332 -354.35032) (xy 438.166599 -354.350845) (xy 438.220576 -354.35861) (xy 438.272899 -354.373977)
			(xy 438.322503 -354.396634) (xy 438.368378 -354.426119) (xy 438.40959 -354.461833) (xy 438.4453 -354.503048)
			(xy 438.474781 -354.548925) (xy 438.497434 -354.598531) (xy 438.512797 -354.650855) (xy 438.520558 -354.704833)
			(xy 438.520558 -354.759367) (xy 438.520558 -354.75937) (xy 440.003406 -354.75937) (xy 440.003406 -354.70483)
			(xy 440.011168 -354.650844) (xy 440.026534 -354.598513) (xy 440.049191 -354.548901) (xy 440.078677 -354.503018)
			(xy 440.114393 -354.461799) (xy 440.155612 -354.426082) (xy 440.201494 -354.396594) (xy 440.251105 -354.373937)
			(xy 440.303436 -354.35857) (xy 440.357422 -354.350807) (xy 440.384692 -354.35032) (xy 441.248292 -354.35032)
			(xy 441.275562 -354.350819) (xy 441.329547 -354.35858) (xy 441.381878 -354.373945) (xy 441.43149 -354.396601)
			(xy 441.477373 -354.426087) (xy 441.518592 -354.461802) (xy 441.554309 -354.503021) (xy 441.583796 -354.548903)
			(xy 441.606453 -354.598514) (xy 441.621819 -354.650845) (xy 441.629581 -354.70483) (xy 441.629581 -354.75937)
			(xy 441.621819 -354.813355) (xy 441.606453 -354.865686) (xy 441.583796 -354.915297) (xy 441.554309 -354.961179)
			(xy 441.518592 -355.002398) (xy 441.477373 -355.038113) (xy 441.43149 -355.067599) (xy 441.381878 -355.090255)
			(xy 441.329547 -355.10562) (xy 441.275562 -355.113381) (xy 441.248292 -355.113844) (xy 440.384692 -355.113844)
			(xy 440.357422 -355.113393) (xy 440.303436 -355.10563) (xy 440.251105 -355.090263) (xy 440.201494 -355.067606)
			(xy 440.155612 -355.038118) (xy 440.114393 -355.002401) (xy 440.078677 -354.961182) (xy 440.049191 -354.915299)
			(xy 440.026534 -354.865687) (xy 440.011168 -354.813356) (xy 440.003406 -354.75937) (xy 438.520558 -354.75937)
			(xy 438.512797 -354.813345) (xy 438.497434 -354.865669) (xy 438.474781 -354.915275) (xy 438.4453 -354.961152)
			(xy 438.40959 -355.002367) (xy 438.368378 -355.038081) (xy 438.322503 -355.067566) (xy 438.272899 -355.090223)
			(xy 438.220576 -355.10559) (xy 438.166599 -355.113355) (xy 438.139332 -355.113844) (xy 437.275732 -355.113844)
			(xy 437.248458 -355.113419) (xy 437.194465 -355.10566) (xy 437.142126 -355.090296) (xy 437.092507 -355.067639)
			(xy 437.046617 -355.038151) (xy 437.005391 -355.002432) (xy 436.969669 -354.961209) (xy 436.940177 -354.915321)
			(xy 436.917516 -354.865704) (xy 436.902147 -354.813366) (xy 436.894384 -354.759374) (xy 435.41168 -354.759374)
			(xy 435.403918 -354.813358) (xy 435.388551 -354.86569) (xy 435.365892 -354.915303) (xy 435.336404 -354.961186)
			(xy 435.300685 -355.002405) (xy 435.259463 -355.03812) (xy 435.213578 -355.067606) (xy 435.163964 -355.090261)
			(xy 435.11163 -355.105624) (xy 435.057643 -355.113382) (xy 435.030372 -355.113844) (xy 434.166772 -355.113844)
			(xy 434.139503 -355.113392) (xy 434.08552 -355.105626) (xy 434.033191 -355.090258) (xy 433.983582 -355.067599)
			(xy 433.937702 -355.038111) (xy 433.896486 -355.002394) (xy 433.860772 -354.961175) (xy 433.831288 -354.915293)
			(xy 433.808632 -354.865683) (xy 433.793268 -354.813353) (xy 433.785506 -354.759369) (xy 432.302658 -354.759369)
			(xy 432.294897 -354.813348) (xy 432.279533 -354.865674) (xy 432.256878 -354.915281) (xy 432.227395 -354.961159)
			(xy 432.191683 -355.002374) (xy 432.150468 -355.038088) (xy 432.104591 -355.067573) (xy 432.054985 -355.090228)
			(xy 432.002659 -355.105594) (xy 431.94868 -355.113357) (xy 431.921412 -355.113844) (xy 431.057812 -355.113844)
			(xy 431.030539 -355.113417) (xy 430.976548 -355.105656) (xy 430.924212 -355.09029) (xy 430.874595 -355.067632)
			(xy 430.828708 -355.038144) (xy 430.787484 -355.002424) (xy 430.751764 -354.961202) (xy 430.722273 -354.915316)
			(xy 430.699614 -354.865699) (xy 430.684246 -354.813363) (xy 430.676484 -354.759373) (xy 429.19378 -354.759373)
			(xy 429.186017 -354.81336) (xy 429.170649 -354.865694) (xy 429.147989 -354.915309) (xy 429.118499 -354.961192)
			(xy 429.082778 -355.002412) (xy 429.041554 -355.038128) (xy 428.995666 -355.067612) (xy 428.946049 -355.090266)
			(xy 428.893713 -355.105628) (xy 428.839724 -355.113384) (xy 428.812452 -355.113844) (xy 427.948852 -355.113844)
			(xy 427.921584 -355.11339) (xy 427.867603 -355.105623) (xy 427.815276 -355.090252) (xy 427.76567 -355.067592)
			(xy 427.719793 -355.038104) (xy 427.678579 -355.002387) (xy 427.642867 -354.961169) (xy 427.613385 -354.915288)
			(xy 427.590731 -354.865679) (xy 427.575367 -354.81335) (xy 427.567606 -354.759368) (xy 426.084781 -354.759368)
			(xy 426.084781 -354.75937) (xy 426.077019 -354.813355) (xy 426.061653 -354.865686) (xy 426.038996 -354.915297)
			(xy 426.009509 -354.961179) (xy 425.973792 -355.002398) (xy 425.932573 -355.038113) (xy 425.88669 -355.067599)
			(xy 425.837078 -355.090255) (xy 425.784747 -355.10562) (xy 425.730762 -355.113381) (xy 425.703492 -355.113844)
			(xy 424.839892 -355.113844) (xy 424.812622 -355.113393) (xy 424.758636 -355.10563) (xy 424.706305 -355.090263)
			(xy 424.656694 -355.067606) (xy 424.610812 -355.038118) (xy 424.569593 -355.002401) (xy 424.533877 -354.961182)
			(xy 424.504391 -354.915299) (xy 424.481734 -354.865687) (xy 424.466368 -354.813356) (xy 424.458606 -354.75937)
			(xy 422.975758 -354.75937) (xy 422.967997 -354.813345) (xy 422.952634 -354.865669) (xy 422.929981 -354.915275)
			(xy 422.9005 -354.961152) (xy 422.86479 -355.002367) (xy 422.823578 -355.038081) (xy 422.777703 -355.067566)
			(xy 422.728099 -355.090223) (xy 422.675776 -355.10559) (xy 422.621799 -355.113355) (xy 422.594532 -355.113844)
			(xy 421.730932 -355.113844) (xy 421.703658 -355.113419) (xy 421.649665 -355.10566) (xy 421.597326 -355.090296)
			(xy 421.547707 -355.067639) (xy 421.501817 -355.038151) (xy 421.460591 -355.002432) (xy 421.424869 -354.961209)
			(xy 421.395377 -354.915321) (xy 421.372716 -354.865704) (xy 421.357347 -354.813366) (xy 421.349584 -354.759374)
			(xy 419.86688 -354.759374) (xy 419.859118 -354.813358) (xy 419.843751 -354.86569) (xy 419.821092 -354.915303)
			(xy 419.791604 -354.961186) (xy 419.755885 -355.002405) (xy 419.714663 -355.03812) (xy 419.668778 -355.067606)
			(xy 419.619164 -355.090261) (xy 419.56683 -355.105624) (xy 419.512843 -355.113382) (xy 419.485572 -355.113844)
			(xy 418.621972 -355.113844) (xy 418.594703 -355.113392) (xy 418.54072 -355.105626) (xy 418.488391 -355.090258)
			(xy 418.438782 -355.067599) (xy 418.392902 -355.038111) (xy 418.351686 -355.002394) (xy 418.315972 -354.961175)
			(xy 418.286488 -354.915293) (xy 418.263832 -354.865683) (xy 418.248468 -354.813353) (xy 418.240706 -354.759369)
			(xy 416.757858 -354.759369) (xy 416.750097 -354.813348) (xy 416.734733 -354.865674) (xy 416.712078 -354.915281)
			(xy 416.682595 -354.961159) (xy 416.646883 -355.002374) (xy 416.605668 -355.038088) (xy 416.559791 -355.067573)
			(xy 416.510185 -355.090228) (xy 416.457859 -355.105594) (xy 416.40388 -355.113357) (xy 416.376612 -355.113844)
			(xy 415.513012 -355.113844) (xy 415.485739 -355.113417) (xy 415.431748 -355.105656) (xy 415.379412 -355.09029)
			(xy 415.329795 -355.067632) (xy 415.283908 -355.038144) (xy 415.242684 -355.002424) (xy 415.206964 -354.961202)
			(xy 415.177473 -354.915316) (xy 415.154814 -354.865699) (xy 415.139446 -354.813363) (xy 415.131684 -354.759373)
			(xy 413.64898 -354.759373) (xy 413.641217 -354.81336) (xy 413.625849 -354.865694) (xy 413.603189 -354.915309)
			(xy 413.573699 -354.961192) (xy 413.537978 -355.002412) (xy 413.496754 -355.038128) (xy 413.450866 -355.067612)
			(xy 413.401249 -355.090266) (xy 413.348913 -355.105628) (xy 413.294924 -355.113384) (xy 413.267652 -355.113844)
			(xy 412.404052 -355.113844) (xy 412.376784 -355.11339) (xy 412.322803 -355.105623) (xy 412.270476 -355.090252)
			(xy 412.22087 -355.067592) (xy 412.174993 -355.038104) (xy 412.133779 -355.002387) (xy 412.098067 -354.961169)
			(xy 412.068585 -354.915288) (xy 412.045931 -354.865679) (xy 412.030567 -354.81335) (xy 412.022806 -354.759368)
			(xy 403.52248 -354.759368) (xy 403.52248 -354.759371) (xy 403.514718 -354.813357) (xy 403.499352 -354.865689)
			(xy 403.476694 -354.915301) (xy 403.447206 -354.961183) (xy 403.411488 -355.002402) (xy 403.370267 -355.038118)
			(xy 403.324383 -355.067603) (xy 403.27477 -355.090259) (xy 403.222437 -355.105622) (xy 403.168451 -355.113382)
			(xy 403.14118 -355.113844) (xy 402.27758 -355.113844) (xy 402.25031 -355.113392) (xy 402.196326 -355.105628)
			(xy 402.143997 -355.09026) (xy 402.094387 -355.067602) (xy 402.048506 -355.038114) (xy 402.007289 -355.002397)
			(xy 401.971574 -354.961178) (xy 401.942089 -354.915296) (xy 401.919433 -354.865685) (xy 401.904068 -354.813354)
			(xy 401.896306 -354.75937) (xy 400.413458 -354.75937) (xy 400.405697 -354.813346) (xy 400.390333 -354.865672)
			(xy 400.36768 -354.915278) (xy 400.338197 -354.961156) (xy 400.302486 -355.002371) (xy 400.261272 -355.038085)
			(xy 400.215396 -355.06757) (xy 400.165791 -355.090226) (xy 400.113466 -355.105593) (xy 400.059487 -355.113356)
			(xy 400.03222 -355.113844) (xy 399.16862 -355.113844) (xy 399.141347 -355.113418) (xy 399.087355 -355.105658)
			(xy 399.035018 -355.090292) (xy 398.9854 -355.067635) (xy 398.939511 -355.038146) (xy 398.898287 -355.002427)
			(xy 398.862566 -354.961205) (xy 398.833075 -354.915318) (xy 398.810415 -354.865701) (xy 398.795047 -354.813364)
			(xy 398.787284 -354.759373) (xy 397.30458 -354.759373) (xy 397.296818 -354.813359) (xy 397.28145 -354.865693)
			(xy 397.258791 -354.915306) (xy 397.229301 -354.96119) (xy 397.193581 -355.002409) (xy 397.152358 -355.038125)
			(xy 397.106471 -355.06761) (xy 397.056855 -355.090264) (xy 397.00452 -355.105626) (xy 396.950532 -355.113383)
			(xy 396.92326 -355.113844) (xy 396.05966 -355.113844) (xy 396.032391 -355.113391) (xy 395.978409 -355.105624)
			(xy 395.926082 -355.090255) (xy 395.876475 -355.067595) (xy 395.830597 -355.038107) (xy 395.789382 -355.00239)
			(xy 395.753669 -354.961171) (xy 395.724186 -354.91529) (xy 395.701531 -354.86568) (xy 395.686167 -354.813351)
			(xy 395.678406 -354.759369) (xy 394.195558 -354.759369) (xy 394.187796 -354.813349) (xy 394.172432 -354.865676)
			(xy 394.149777 -354.915284) (xy 394.120292 -354.961163) (xy 394.084578 -355.002378) (xy 394.043363 -355.038092)
			(xy 393.997484 -355.067577) (xy 393.947876 -355.090232) (xy 393.895549 -355.105596) (xy 393.841568 -355.113358)
			(xy 393.8143 -355.113844) (xy 392.9507 -355.113844) (xy 392.923429 -355.113394) (xy 392.869443 -355.105631)
			(xy 392.817111 -355.090265) (xy 392.767499 -355.067608) (xy 392.721616 -355.038121) (xy 392.680396 -355.002404)
			(xy 392.644679 -354.961184) (xy 392.615192 -354.915301) (xy 392.592535 -354.865689) (xy 392.577169 -354.813357)
			(xy 392.569406 -354.759371) (xy 391.086557 -354.759371) (xy 391.078797 -354.813344) (xy 391.063435 -354.865668)
			(xy 391.040783 -354.915273) (xy 391.011302 -354.96115) (xy 390.975593 -355.002364) (xy 390.934382 -355.038078)
			(xy 390.888508 -355.067563) (xy 390.838905 -355.090221) (xy 390.786583 -355.105589) (xy 390.732606 -355.113355)
			(xy 390.70534 -355.113844) (xy 389.84174 -355.113844) (xy 389.814466 -355.113419) (xy 389.760472 -355.105661)
			(xy 389.708132 -355.090298) (xy 389.658512 -355.067641) (xy 389.612621 -355.038153) (xy 389.571394 -355.002434)
			(xy 389.535671 -354.961211) (xy 389.506178 -354.915324) (xy 389.483516 -354.865705) (xy 389.468147 -354.813367)
			(xy 389.460384 -354.759374) (xy 387.97768 -354.759374) (xy 387.969918 -354.813357) (xy 387.954552 -354.865689)
			(xy 387.931894 -354.915301) (xy 387.902406 -354.961183) (xy 387.866688 -355.002402) (xy 387.825467 -355.038118)
			(xy 387.779583 -355.067603) (xy 387.72997 -355.090259) (xy 387.677637 -355.105622) (xy 387.623651 -355.113382)
			(xy 387.59638 -355.113844) (xy 386.73278 -355.113844) (xy 386.70551 -355.113392) (xy 386.651526 -355.105628)
			(xy 386.599197 -355.09026) (xy 386.549587 -355.067602) (xy 386.503706 -355.038114) (xy 386.462489 -355.002397)
			(xy 386.426774 -354.961178) (xy 386.397289 -354.915296) (xy 386.374633 -354.865685) (xy 386.359268 -354.813354)
			(xy 386.351506 -354.75937) (xy 384.868658 -354.75937) (xy 384.860897 -354.813346) (xy 384.845533 -354.865672)
			(xy 384.82288 -354.915278) (xy 384.793397 -354.961156) (xy 384.757686 -355.002371) (xy 384.716472 -355.038085)
			(xy 384.670596 -355.06757) (xy 384.620991 -355.090226) (xy 384.568666 -355.105593) (xy 384.514687 -355.113356)
			(xy 384.48742 -355.113844) (xy 383.62382 -355.113844) (xy 383.596547 -355.113418) (xy 383.542555 -355.105658)
			(xy 383.490218 -355.090292) (xy 383.4406 -355.067635) (xy 383.394711 -355.038146) (xy 383.353487 -355.002427)
			(xy 383.317766 -354.961205) (xy 383.288275 -354.915318) (xy 383.265615 -354.865701) (xy 383.250247 -354.813364)
			(xy 383.242484 -354.759373) (xy 381.75978 -354.759373) (xy 381.752018 -354.813359) (xy 381.73665 -354.865693)
			(xy 381.713991 -354.915306) (xy 381.684501 -354.96119) (xy 381.648781 -355.002409) (xy 381.607558 -355.038125)
			(xy 381.561671 -355.06761) (xy 381.512055 -355.090264) (xy 381.45972 -355.105626) (xy 381.405732 -355.113383)
			(xy 381.37846 -355.113844) (xy 380.51486 -355.113844) (xy 380.487591 -355.113391) (xy 380.433609 -355.105624)
			(xy 380.381282 -355.090255) (xy 380.331675 -355.067595) (xy 380.285797 -355.038107) (xy 380.244582 -355.00239)
			(xy 380.208869 -354.961171) (xy 380.179386 -354.91529) (xy 380.156731 -354.86568) (xy 380.141367 -354.813351)
			(xy 380.133606 -354.759369) (xy 378.650758 -354.759369) (xy 378.642996 -354.813349) (xy 378.627632 -354.865676)
			(xy 378.604977 -354.915284) (xy 378.575492 -354.961163) (xy 378.539778 -355.002378) (xy 378.498563 -355.038092)
			(xy 378.452684 -355.067577) (xy 378.403076 -355.090232) (xy 378.350749 -355.105596) (xy 378.296768 -355.113358)
			(xy 378.2695 -355.113844) (xy 377.4059 -355.113844) (xy 377.378629 -355.113394) (xy 377.324643 -355.105631)
			(xy 377.272311 -355.090265) (xy 377.222699 -355.067608) (xy 377.176816 -355.038121) (xy 377.135596 -355.002404)
			(xy 377.099879 -354.961184) (xy 377.070392 -354.915301) (xy 377.047735 -354.865689) (xy 377.032369 -354.813357)
			(xy 377.024606 -354.759371) (xy 375.541757 -354.759371) (xy 375.533997 -354.813344) (xy 375.518635 -354.865668)
			(xy 375.495983 -354.915273) (xy 375.466502 -354.96115) (xy 375.430793 -355.002364) (xy 375.389582 -355.038078)
			(xy 375.343708 -355.067563) (xy 375.294105 -355.090221) (xy 375.241783 -355.105589) (xy 375.187806 -355.113355)
			(xy 375.16054 -355.113844) (xy 374.29694 -355.113844) (xy 374.269666 -355.113419) (xy 374.215672 -355.105661)
			(xy 374.163332 -355.090298) (xy 374.113712 -355.067641) (xy 374.067821 -355.038153) (xy 374.026594 -355.002434)
			(xy 373.990871 -354.961211) (xy 373.961378 -354.915324) (xy 373.938716 -354.865705) (xy 373.923347 -354.813367)
			(xy 373.915584 -354.759374) (xy 370.0804 -354.759374) (xy 373.105997 -357.784971) (xy 373.915632 -357.784971)
			(xy 373.915632 -357.730429) (xy 373.923394 -357.676443) (xy 373.938761 -357.624111) (xy 373.96142 -357.574499)
			(xy 373.990909 -357.528617) (xy 374.026628 -357.4874) (xy 374.06785 -357.451685) (xy 374.113735 -357.422201)
			(xy 374.163349 -357.399547) (xy 374.215682 -357.384186) (xy 374.269669 -357.376429) (xy 374.29694 -357.375968)
			(xy 375.16054 -357.375968) (xy 375.18781 -357.376397) (xy 375.241793 -357.384164) (xy 375.294122 -357.399534)
			(xy 375.343731 -357.422194) (xy 375.389611 -357.451684) (xy 375.430827 -357.487402) (xy 375.46654 -357.528622)
			(xy 375.496025 -357.574504) (xy 375.51868 -357.624116) (xy 375.534044 -357.676446) (xy 375.541806 -357.73043)
			(xy 375.541806 -357.784967) (xy 377.024654 -357.784967) (xy 377.024654 -357.730433) (xy 377.032415 -357.676453)
			(xy 377.04778 -357.624128) (xy 377.070434 -357.574522) (xy 377.099918 -357.528644) (xy 377.13563 -357.48743)
			(xy 377.176844 -357.451718) (xy 377.222722 -357.422234) (xy 377.272328 -357.39958) (xy 377.324653 -357.384215)
			(xy 377.378633 -357.376454) (xy 377.4059 -357.375968) (xy 378.2695 -357.375968) (xy 378.296772 -357.376395)
			(xy 378.350759 -357.384157) (xy 378.403093 -357.399523) (xy 378.452707 -357.422181) (xy 378.498592 -357.451669)
			(xy 378.539812 -357.487388) (xy 378.575531 -357.528608) (xy 378.605019 -357.574493) (xy 378.627677 -357.624107)
			(xy 378.643043 -357.676441) (xy 378.650805 -357.730428) (xy 378.650805 -357.784965) (xy 380.133654 -357.784965)
			(xy 380.133654 -357.730435) (xy 380.141414 -357.676459) (xy 380.156776 -357.624137) (xy 380.179428 -357.574533)
			(xy 380.208908 -357.528658) (xy 380.244616 -357.487444) (xy 380.285825 -357.451732) (xy 380.331698 -357.422247)
			(xy 380.381299 -357.39959) (xy 380.43362 -357.384223) (xy 380.487595 -357.376457) (xy 380.51486 -357.375968)
			(xy 381.37846 -357.375968) (xy 381.405735 -357.376369) (xy 381.45973 -357.384127) (xy 381.512072 -357.399491)
			(xy 381.561694 -357.422148) (xy 381.607586 -357.451637) (xy 381.648815 -357.487357) (xy 381.684539 -357.528582)
			(xy 381.714033 -357.574471) (xy 381.736695 -357.62409) (xy 381.752065 -357.67643) (xy 381.759828 -357.730425)
			(xy 381.759828 -357.78497) (xy 383.242531 -357.78497) (xy 383.242531 -357.73043) (xy 383.250294 -357.676446)
			(xy 383.26566 -357.624116) (xy 383.288317 -357.574505) (xy 383.317804 -357.528624) (xy 383.353521 -357.487407)
			(xy 383.39474 -357.451692) (xy 383.440623 -357.422207) (xy 383.490234 -357.399553) (xy 383.542565 -357.384189)
			(xy 383.59655 -357.37643) (xy 383.62382 -357.375968) (xy 384.48742 -357.375968) (xy 384.514691 -357.376396)
			(xy 384.568676 -357.38416) (xy 384.621007 -357.399529) (xy 384.670619 -357.422188) (xy 384.716501 -357.451677)
			(xy 384.75772 -357.487395) (xy 384.793435 -357.528615) (xy 384.822922 -357.574499) (xy 384.845578 -357.624111)
			(xy 384.860944 -357.676443) (xy 384.868706 -357.730429) (xy 384.868706 -357.784966) (xy 386.351554 -357.784966)
			(xy 386.351554 -357.730434) (xy 386.359315 -357.676456) (xy 386.374678 -357.624132) (xy 386.397331 -357.574527)
			(xy 386.426813 -357.528651) (xy 386.462523 -357.487437) (xy 386.503735 -357.451725) (xy 386.54961 -357.422241)
			(xy 386.599213 -357.399585) (xy 386.651537 -357.384219) (xy 386.705514 -357.376456) (xy 386.73278 -357.375968)
			(xy 387.59638 -357.375968) (xy 387.623654 -357.37637) (xy 387.677647 -357.384131) (xy 387.729987 -357.399496)
			(xy 387.779606 -357.422155) (xy 387.825496 -357.451644) (xy 387.866722 -357.487364) (xy 387.902444 -357.528588)
			(xy 387.931936 -357.574476) (xy 387.954597 -357.624095) (xy 387.969965 -357.676433) (xy 387.977728 -357.730426)
			(xy 387.977728 -357.784971) (xy 389.460432 -357.784971) (xy 389.460432 -357.730429) (xy 389.468194 -357.676443)
			(xy 389.483561 -357.624111) (xy 389.50622 -357.574499) (xy 389.535709 -357.528617) (xy 389.571428 -357.4874)
			(xy 389.61265 -357.451685) (xy 389.658535 -357.422201) (xy 389.708149 -357.399547) (xy 389.760482 -357.384186)
			(xy 389.814469 -357.376429) (xy 389.84174 -357.375968) (xy 390.70534 -357.375968) (xy 390.73261 -357.376397)
			(xy 390.786593 -357.384164) (xy 390.838922 -357.399534) (xy 390.888531 -357.422194) (xy 390.934411 -357.451684)
			(xy 390.975627 -357.487402) (xy 391.01134 -357.528622) (xy 391.040825 -357.574504) (xy 391.06348 -357.624116)
			(xy 391.078844 -357.676446) (xy 391.086606 -357.73043) (xy 391.086606 -357.784967) (xy 392.569454 -357.784967)
			(xy 392.569454 -357.730433) (xy 392.577215 -357.676453) (xy 392.59258 -357.624128) (xy 392.615234 -357.574522)
			(xy 392.644718 -357.528644) (xy 392.68043 -357.48743) (xy 392.721644 -357.451718) (xy 392.767522 -357.422234)
			(xy 392.817128 -357.39958) (xy 392.869453 -357.384215) (xy 392.923433 -357.376454) (xy 392.9507 -357.375968)
			(xy 393.8143 -357.375968) (xy 393.841572 -357.376395) (xy 393.895559 -357.384157) (xy 393.947893 -357.399523)
			(xy 393.997507 -357.422181) (xy 394.043392 -357.451669) (xy 394.084612 -357.487388) (xy 394.120331 -357.528608)
			(xy 394.149819 -357.574493) (xy 394.172477 -357.624107) (xy 394.187843 -357.676441) (xy 394.195605 -357.730428)
			(xy 394.195605 -357.784965) (xy 395.678454 -357.784965) (xy 395.678454 -357.730435) (xy 395.686214 -357.676459)
			(xy 395.701576 -357.624137) (xy 395.724228 -357.574533) (xy 395.753708 -357.528658) (xy 395.789416 -357.487444)
			(xy 395.830625 -357.451732) (xy 395.876498 -357.422247) (xy 395.926099 -357.39959) (xy 395.97842 -357.384223)
			(xy 396.032395 -357.376457) (xy 396.05966 -357.375968) (xy 396.92326 -357.375968) (xy 396.950535 -357.376369)
			(xy 397.00453 -357.384127) (xy 397.056872 -357.399491) (xy 397.106494 -357.422148) (xy 397.152386 -357.451637)
			(xy 397.193615 -357.487357) (xy 397.229339 -357.528582) (xy 397.258833 -357.574471) (xy 397.281495 -357.62409)
			(xy 397.296865 -357.67643) (xy 397.304628 -357.730425) (xy 397.304628 -357.78497) (xy 398.787331 -357.78497)
			(xy 398.787331 -357.73043) (xy 398.795094 -357.676446) (xy 398.81046 -357.624116) (xy 398.833117 -357.574505)
			(xy 398.862604 -357.528624) (xy 398.898321 -357.487407) (xy 398.93954 -357.451692) (xy 398.985423 -357.422207)
			(xy 399.035034 -357.399553) (xy 399.087365 -357.384189) (xy 399.14135 -357.37643) (xy 399.16862 -357.375968)
			(xy 400.03222 -357.375968) (xy 400.059491 -357.376396) (xy 400.113476 -357.38416) (xy 400.165807 -357.399529)
			(xy 400.215419 -357.422188) (xy 400.261301 -357.451677) (xy 400.30252 -357.487395) (xy 400.338235 -357.528615)
			(xy 400.367722 -357.574499) (xy 400.390378 -357.624111) (xy 400.405744 -357.676443) (xy 400.413506 -357.730429)
			(xy 400.413506 -357.784966) (xy 401.896354 -357.784966) (xy 401.896354 -357.730434) (xy 401.904115 -357.676456)
			(xy 401.919478 -357.624132) (xy 401.942131 -357.574527) (xy 401.971613 -357.528651) (xy 402.007323 -357.487437)
			(xy 402.048535 -357.451725) (xy 402.09441 -357.422241) (xy 402.144013 -357.399585) (xy 402.196337 -357.384219)
			(xy 402.250314 -357.376456) (xy 402.27758 -357.375968) (xy 403.14118 -357.375968) (xy 403.168454 -357.37637)
			(xy 403.222447 -357.384131) (xy 403.274787 -357.399496) (xy 403.324406 -357.422155) (xy 403.370296 -357.451644)
			(xy 403.411522 -357.487364) (xy 403.447244 -357.528588) (xy 403.476736 -357.574476) (xy 403.499397 -357.624095)
			(xy 403.514765 -357.676433) (xy 403.522528 -357.730426) (xy 403.522528 -357.784965) (xy 412.022854 -357.784965)
			(xy 412.022854 -357.730435) (xy 412.030614 -357.67646) (xy 412.045976 -357.624138) (xy 412.068627 -357.574535)
			(xy 412.098106 -357.52866) (xy 412.133813 -357.487447) (xy 412.175022 -357.451735) (xy 412.220893 -357.42225)
			(xy 412.270493 -357.399593) (xy 412.322813 -357.384224) (xy 412.376787 -357.376458) (xy 412.404052 -357.375968)
			(xy 413.267652 -357.375968) (xy 413.294927 -357.376368) (xy 413.348924 -357.384125) (xy 413.401266 -357.399489)
			(xy 413.450889 -357.422145) (xy 413.496783 -357.451634) (xy 413.538012 -357.487354) (xy 413.573737 -357.528579)
			(xy 413.603232 -357.574468) (xy 413.625894 -357.624089) (xy 413.641264 -357.676429) (xy 413.649028 -357.730425)
			(xy 413.649028 -357.784969) (xy 415.131731 -357.784969) (xy 415.131731 -357.730431) (xy 415.139493 -357.676447)
			(xy 415.154859 -357.624117) (xy 415.177516 -357.574507) (xy 415.207002 -357.528627) (xy 415.242718 -357.487409)
			(xy 415.283936 -357.451695) (xy 415.329818 -357.42221) (xy 415.379429 -357.399555) (xy 415.431759 -357.384191)
			(xy 415.485743 -357.376431) (xy 415.513012 -357.375968) (xy 416.376612 -357.375968) (xy 416.403883 -357.376395)
			(xy 416.457869 -357.384159) (xy 416.510202 -357.399527) (xy 416.559814 -357.422185) (xy 416.605697 -357.451674)
			(xy 416.646917 -357.487392) (xy 416.682633 -357.528612) (xy 416.712121 -357.574496) (xy 416.734778 -357.62411)
			(xy 416.750144 -357.676442) (xy 416.757906 -357.730429) (xy 416.757906 -357.784966) (xy 418.240754 -357.784966)
			(xy 418.240754 -357.730434) (xy 418.248515 -357.676457) (xy 418.263877 -357.624134) (xy 418.28653 -357.57453)
			(xy 418.316011 -357.528654) (xy 418.35172 -357.48744) (xy 418.392931 -357.451727) (xy 418.438805 -357.422243)
			(xy 418.488408 -357.399587) (xy 418.54073 -357.384221) (xy 418.594706 -357.376456) (xy 418.621972 -357.375968)
			(xy 419.485572 -357.375968) (xy 419.512846 -357.37637) (xy 419.566841 -357.384129) (xy 419.619181 -357.399494)
			(xy 419.668801 -357.422152) (xy 419.714692 -357.451641) (xy 419.755919 -357.487361) (xy 419.791642 -357.528585)
			(xy 419.821135 -357.574474) (xy 419.843796 -357.624093) (xy 419.859165 -357.676432) (xy 419.866928 -357.730426)
			(xy 419.866928 -357.78497) (xy 421.349632 -357.78497) (xy 421.349632 -357.73043) (xy 421.357394 -357.676444)
			(xy 421.372761 -357.624113) (xy 421.395419 -357.574502) (xy 421.424907 -357.52862) (xy 421.460625 -357.487402)
			(xy 421.501846 -357.451688) (xy 421.54773 -357.422203) (xy 421.597343 -357.399549) (xy 421.649676 -357.384187)
			(xy 421.703662 -357.376429) (xy 421.730932 -357.375968) (xy 422.594532 -357.375968) (xy 422.621802 -357.376397)
			(xy 422.675786 -357.384163) (xy 422.728116 -357.399532) (xy 422.777726 -357.422192) (xy 422.823607 -357.451681)
			(xy 422.864824 -357.487399) (xy 422.900538 -357.528619) (xy 422.930024 -357.574502) (xy 422.952679 -357.624114)
			(xy 422.968044 -357.676445) (xy 422.975806 -357.73043) (xy 422.975806 -357.784967) (xy 424.458654 -357.784967)
			(xy 424.458654 -357.730433) (xy 424.466415 -357.676454) (xy 424.481779 -357.62413) (xy 424.504433 -357.574524)
			(xy 424.533916 -357.528647) (xy 424.569627 -357.487433) (xy 424.610841 -357.45172) (xy 424.656717 -357.422237)
			(xy 424.706322 -357.399582) (xy 424.758647 -357.384217) (xy 424.812625 -357.376455) (xy 424.839892 -357.375968)
			(xy 425.703492 -357.375968) (xy 425.730766 -357.376371) (xy 425.784757 -357.384133) (xy 425.837095 -357.3995)
			(xy 425.886713 -357.422159) (xy 425.932602 -357.451648) (xy 425.973826 -357.487368) (xy 426.009547 -357.528592)
			(xy 426.039038 -357.57448) (xy 426.061698 -357.624097) (xy 426.077065 -357.676435) (xy 426.084828 -357.730426)
			(xy 426.084828 -357.784965) (xy 427.567654 -357.784965) (xy 427.567654 -357.730435) (xy 427.575414 -357.67646)
			(xy 427.590776 -357.624138) (xy 427.613427 -357.574535) (xy 427.642906 -357.52866) (xy 427.678613 -357.487447)
			(xy 427.719822 -357.451735) (xy 427.765693 -357.42225) (xy 427.815293 -357.399593) (xy 427.867613 -357.384224)
			(xy 427.921587 -357.376458) (xy 427.948852 -357.375968) (xy 428.812452 -357.375968) (xy 428.839727 -357.376368)
			(xy 428.893724 -357.384125) (xy 428.946066 -357.399489) (xy 428.995689 -357.422145) (xy 429.041583 -357.451634)
			(xy 429.082812 -357.487354) (xy 429.118537 -357.528579) (xy 429.148032 -357.574468) (xy 429.170694 -357.624089)
			(xy 429.186064 -357.676429) (xy 429.193828 -357.730425) (xy 429.193828 -357.784969) (xy 430.676531 -357.784969)
			(xy 430.676531 -357.730431) (xy 430.684293 -357.676447) (xy 430.699659 -357.624117) (xy 430.722316 -357.574507)
			(xy 430.751802 -357.528627) (xy 430.787518 -357.487409) (xy 430.828736 -357.451695) (xy 430.874618 -357.42221)
			(xy 430.924229 -357.399555) (xy 430.976559 -357.384191) (xy 431.030543 -357.376431) (xy 431.057812 -357.375968)
			(xy 431.921412 -357.375968) (xy 431.948683 -357.376395) (xy 432.002669 -357.384159) (xy 432.055002 -357.399527)
			(xy 432.104614 -357.422185) (xy 432.150497 -357.451674) (xy 432.191717 -357.487392) (xy 432.227433 -357.528612)
			(xy 432.256921 -357.574496) (xy 432.279578 -357.62411) (xy 432.294944 -357.676442) (xy 432.302706 -357.730429)
			(xy 432.302706 -357.784966) (xy 433.785554 -357.784966) (xy 433.785554 -357.730434) (xy 433.793315 -357.676457)
			(xy 433.808677 -357.624134) (xy 433.83133 -357.57453) (xy 433.860811 -357.528654) (xy 433.89652 -357.48744)
			(xy 433.937731 -357.451727) (xy 433.983605 -357.422243) (xy 434.033208 -357.399587) (xy 434.08553 -357.384221)
			(xy 434.139506 -357.376456) (xy 434.166772 -357.375968) (xy 435.030372 -357.375968) (xy 435.057646 -357.37637)
			(xy 435.111641 -357.384129) (xy 435.163981 -357.399494) (xy 435.213601 -357.422152) (xy 435.259492 -357.451641)
			(xy 435.300719 -357.487361) (xy 435.336442 -357.528585) (xy 435.365935 -357.574474) (xy 435.388596 -357.624093)
			(xy 435.403965 -357.676432) (xy 435.411728 -357.730426) (xy 435.411728 -357.78497) (xy 436.894432 -357.78497)
			(xy 436.894432 -357.73043) (xy 436.902194 -357.676444) (xy 436.917561 -357.624113) (xy 436.940219 -357.574502)
			(xy 436.969707 -357.52862) (xy 437.005425 -357.487402) (xy 437.046646 -357.451688) (xy 437.09253 -357.422203)
			(xy 437.142143 -357.399549) (xy 437.194476 -357.384187) (xy 437.248462 -357.376429) (xy 437.275732 -357.375968)
			(xy 438.139332 -357.375968) (xy 438.166602 -357.376397) (xy 438.220586 -357.384163) (xy 438.272916 -357.399532)
			(xy 438.322526 -357.422192) (xy 438.368407 -357.451681) (xy 438.409624 -357.487399) (xy 438.445338 -357.528619)
			(xy 438.474824 -357.574502) (xy 438.497479 -357.624114) (xy 438.512844 -357.676445) (xy 438.520606 -357.73043)
			(xy 438.520606 -357.784967) (xy 440.003454 -357.784967) (xy 440.003454 -357.730433) (xy 440.011215 -357.676454)
			(xy 440.026579 -357.62413) (xy 440.049233 -357.574524) (xy 440.078716 -357.528647) (xy 440.114427 -357.487433)
			(xy 440.155641 -357.45172) (xy 440.201517 -357.422237) (xy 440.251122 -357.399582) (xy 440.303447 -357.384217)
			(xy 440.357425 -357.376455) (xy 440.384692 -357.375968) (xy 441.248292 -357.375968) (xy 441.275566 -357.376371)
			(xy 441.329557 -357.384133) (xy 441.381895 -357.3995) (xy 441.431513 -357.422159) (xy 441.477402 -357.451648)
			(xy 441.518626 -357.487368) (xy 441.554347 -357.528592) (xy 441.583838 -357.57448) (xy 441.606498 -357.624097)
			(xy 441.621865 -357.676435) (xy 441.629628 -357.730426) (xy 441.629628 -357.784974) (xy 441.621865 -357.838965)
			(xy 441.606498 -357.891303) (xy 441.583838 -357.94092) (xy 441.554347 -357.986808) (xy 441.518626 -358.028032)
			(xy 441.477402 -358.063752) (xy 441.431513 -358.093241) (xy 441.381895 -358.1159) (xy 441.329557 -358.131267)
			(xy 441.275566 -358.139029) (xy 441.248292 -358.139492) (xy 440.384692 -358.139492) (xy 440.357425 -358.138945)
			(xy 440.303447 -358.131183) (xy 440.251122 -358.115818) (xy 440.201517 -358.093163) (xy 440.155641 -358.06368)
			(xy 440.114427 -358.027967) (xy 440.078716 -357.986753) (xy 440.049233 -357.940876) (xy 440.026579 -357.89127)
			(xy 440.011215 -357.838946) (xy 440.003454 -357.784967) (xy 438.520606 -357.784967) (xy 438.520606 -357.78497)
			(xy 438.512844 -357.838955) (xy 438.497479 -357.891286) (xy 438.474824 -357.940898) (xy 438.445338 -357.986781)
			(xy 438.409624 -358.028001) (xy 438.368407 -358.063719) (xy 438.322526 -358.093208) (xy 438.272916 -358.115868)
			(xy 438.220586 -358.131237) (xy 438.166602 -358.139003) (xy 438.139332 -358.139492) (xy 437.275732 -358.139492)
			(xy 437.248462 -358.138971) (xy 437.194476 -358.131213) (xy 437.142143 -358.115851) (xy 437.09253 -358.093197)
			(xy 437.046646 -358.063712) (xy 437.005425 -358.027998) (xy 436.969707 -357.98678) (xy 436.940219 -357.940898)
			(xy 436.917561 -357.891287) (xy 436.902194 -357.838956) (xy 436.894432 -357.78497) (xy 435.411728 -357.78497)
			(xy 435.411728 -357.784974) (xy 435.403965 -357.838968) (xy 435.388596 -357.891307) (xy 435.365935 -357.940926)
			(xy 435.336442 -357.986815) (xy 435.300719 -358.028039) (xy 435.259492 -358.063759) (xy 435.213601 -358.093248)
			(xy 435.163981 -358.115906) (xy 435.111641 -358.131271) (xy 435.057646 -358.13903) (xy 435.030372 -358.139492)
			(xy 434.166772 -358.139492) (xy 434.139506 -358.138944) (xy 434.08553 -358.131179) (xy 434.033208 -358.115813)
			(xy 433.983605 -358.093157) (xy 433.937731 -358.063673) (xy 433.89652 -358.02796) (xy 433.860811 -357.986746)
			(xy 433.83133 -357.94087) (xy 433.808677 -357.891266) (xy 433.793315 -357.838943) (xy 433.785554 -357.784966)
			(xy 432.302706 -357.784966) (xy 432.302706 -357.784971) (xy 432.294944 -357.838958) (xy 432.279578 -357.89129)
			(xy 432.256921 -357.940904) (xy 432.227433 -357.986788) (xy 432.191717 -358.028008) (xy 432.150497 -358.063726)
			(xy 432.104614 -358.093215) (xy 432.055002 -358.115873) (xy 432.002669 -358.131241) (xy 431.948683 -358.139005)
			(xy 431.921412 -358.139492) (xy 431.057812 -358.139492) (xy 431.030543 -358.138969) (xy 430.976559 -358.131209)
			(xy 430.924229 -358.115845) (xy 430.874618 -358.09319) (xy 430.828736 -358.063705) (xy 430.787518 -358.027991)
			(xy 430.751802 -357.986773) (xy 430.722316 -357.940893) (xy 430.699659 -357.891283) (xy 430.684293 -357.838953)
			(xy 430.676531 -357.784969) (xy 429.193828 -357.784969) (xy 429.193828 -357.784975) (xy 429.186064 -357.838971)
			(xy 429.170694 -357.891311) (xy 429.148032 -357.940932) (xy 429.118537 -357.986821) (xy 429.082812 -358.028046)
			(xy 429.041583 -358.063766) (xy 428.995689 -358.093255) (xy 428.946066 -358.115911) (xy 428.893724 -358.131275)
			(xy 428.839727 -358.139032) (xy 428.812452 -358.139492) (xy 427.948852 -358.139492) (xy 427.921587 -358.138942)
			(xy 427.867613 -358.131176) (xy 427.815293 -358.115807) (xy 427.765693 -358.09315) (xy 427.719822 -358.063665)
			(xy 427.678613 -358.027953) (xy 427.642906 -357.98674) (xy 427.613427 -357.940865) (xy 427.590776 -357.891262)
			(xy 427.575414 -357.83894) (xy 427.567654 -357.784965) (xy 426.084828 -357.784965) (xy 426.084828 -357.784974)
			(xy 426.077065 -357.838965) (xy 426.061698 -357.891303) (xy 426.039038 -357.94092) (xy 426.009547 -357.986808)
			(xy 425.973826 -358.028032) (xy 425.932602 -358.063752) (xy 425.886713 -358.093241) (xy 425.837095 -358.1159)
			(xy 425.784757 -358.131267) (xy 425.730766 -358.139029) (xy 425.703492 -358.139492) (xy 424.839892 -358.139492)
			(xy 424.812625 -358.138945) (xy 424.758647 -358.131183) (xy 424.706322 -358.115818) (xy 424.656717 -358.093163)
			(xy 424.610841 -358.06368) (xy 424.569627 -358.027967) (xy 424.533916 -357.986753) (xy 424.504433 -357.940876)
			(xy 424.481779 -357.89127) (xy 424.466415 -357.838946) (xy 424.458654 -357.784967) (xy 422.975806 -357.784967)
			(xy 422.975806 -357.78497) (xy 422.968044 -357.838955) (xy 422.952679 -357.891286) (xy 422.930024 -357.940898)
			(xy 422.900538 -357.986781) (xy 422.864824 -358.028001) (xy 422.823607 -358.063719) (xy 422.777726 -358.093208)
			(xy 422.728116 -358.115868) (xy 422.675786 -358.131237) (xy 422.621802 -358.139003) (xy 422.594532 -358.139492)
			(xy 421.730932 -358.139492) (xy 421.703662 -358.138971) (xy 421.649676 -358.131213) (xy 421.597343 -358.115851)
			(xy 421.54773 -358.093197) (xy 421.501846 -358.063712) (xy 421.460625 -358.027998) (xy 421.424907 -357.98678)
			(xy 421.395419 -357.940898) (xy 421.372761 -357.891287) (xy 421.357394 -357.838956) (xy 421.349632 -357.78497)
			(xy 419.866928 -357.78497) (xy 419.866928 -357.784974) (xy 419.859165 -357.838968) (xy 419.843796 -357.891307)
			(xy 419.821135 -357.940926) (xy 419.791642 -357.986815) (xy 419.755919 -358.028039) (xy 419.714692 -358.063759)
			(xy 419.668801 -358.093248) (xy 419.619181 -358.115906) (xy 419.566841 -358.131271) (xy 419.512846 -358.13903)
			(xy 419.485572 -358.139492) (xy 418.621972 -358.139492) (xy 418.594706 -358.138944) (xy 418.54073 -358.131179)
			(xy 418.488408 -358.115813) (xy 418.438805 -358.093157) (xy 418.392931 -358.063673) (xy 418.35172 -358.02796)
			(xy 418.316011 -357.986746) (xy 418.28653 -357.94087) (xy 418.263877 -357.891266) (xy 418.248515 -357.838943)
			(xy 418.240754 -357.784966) (xy 416.757906 -357.784966) (xy 416.757906 -357.784971) (xy 416.750144 -357.838958)
			(xy 416.734778 -357.89129) (xy 416.712121 -357.940904) (xy 416.682633 -357.986788) (xy 416.646917 -358.028008)
			(xy 416.605697 -358.063726) (xy 416.559814 -358.093215) (xy 416.510202 -358.115873) (xy 416.457869 -358.131241)
			(xy 416.403883 -358.139005) (xy 416.376612 -358.139492) (xy 415.513012 -358.139492) (xy 415.485743 -358.138969)
			(xy 415.431759 -358.131209) (xy 415.379429 -358.115845) (xy 415.329818 -358.09319) (xy 415.283936 -358.063705)
			(xy 415.242718 -358.027991) (xy 415.207002 -357.986773) (xy 415.177516 -357.940893) (xy 415.154859 -357.891283)
			(xy 415.139493 -357.838953) (xy 415.131731 -357.784969) (xy 413.649028 -357.784969) (xy 413.649028 -357.784975)
			(xy 413.641264 -357.838971) (xy 413.625894 -357.891311) (xy 413.603232 -357.940932) (xy 413.573737 -357.986821)
			(xy 413.538012 -358.028046) (xy 413.496783 -358.063766) (xy 413.450889 -358.093255) (xy 413.401266 -358.115911)
			(xy 413.348924 -358.131275) (xy 413.294927 -358.139032) (xy 413.267652 -358.139492) (xy 412.404052 -358.139492)
			(xy 412.376787 -358.138942) (xy 412.322813 -358.131176) (xy 412.270493 -358.115807) (xy 412.220893 -358.09315)
			(xy 412.175022 -358.063665) (xy 412.133813 -358.027953) (xy 412.098106 -357.98674) (xy 412.068627 -357.940865)
			(xy 412.045976 -357.891262) (xy 412.030614 -357.83894) (xy 412.022854 -357.784965) (xy 403.522528 -357.784965)
			(xy 403.522528 -357.784974) (xy 403.514765 -357.838967) (xy 403.499397 -357.891305) (xy 403.476736 -357.940924)
			(xy 403.447244 -357.986812) (xy 403.411522 -358.028036) (xy 403.370296 -358.063756) (xy 403.324406 -358.093245)
			(xy 403.274787 -358.115904) (xy 403.222447 -358.131269) (xy 403.168454 -358.13903) (xy 403.14118 -358.139492)
			(xy 402.27758 -358.139492) (xy 402.250314 -358.138944) (xy 402.196337 -358.131181) (xy 402.144013 -358.115815)
			(xy 402.09441 -358.093159) (xy 402.048535 -358.063675) (xy 402.007323 -358.027963) (xy 401.971613 -357.986749)
			(xy 401.942131 -357.940873) (xy 401.919478 -357.891268) (xy 401.904115 -357.838944) (xy 401.896354 -357.784966)
			(xy 400.413506 -357.784966) (xy 400.413506 -357.784971) (xy 400.405744 -357.838957) (xy 400.390378 -357.891289)
			(xy 400.367722 -357.940901) (xy 400.338235 -357.986785) (xy 400.30252 -358.028005) (xy 400.261301 -358.063723)
			(xy 400.215419 -358.093212) (xy 400.165807 -358.115871) (xy 400.113476 -358.13124) (xy 400.059491 -358.139004)
			(xy 400.03222 -358.139492) (xy 399.16862 -358.139492) (xy 399.14135 -358.13897) (xy 399.087365 -358.131211)
			(xy 399.035034 -358.115847) (xy 398.985423 -358.093193) (xy 398.93954 -358.063708) (xy 398.898321 -358.027993)
			(xy 398.862604 -357.986776) (xy 398.833117 -357.940895) (xy 398.81046 -357.891284) (xy 398.795094 -357.838954)
			(xy 398.787331 -357.78497) (xy 397.304628 -357.78497) (xy 397.304628 -357.784975) (xy 397.296865 -357.83897)
			(xy 397.281495 -357.89131) (xy 397.258833 -357.940929) (xy 397.229339 -357.986818) (xy 397.193615 -358.028043)
			(xy 397.152386 -358.063763) (xy 397.106494 -358.093252) (xy 397.056872 -358.115909) (xy 397.00453 -358.131273)
			(xy 396.950535 -358.139031) (xy 396.92326 -358.139492) (xy 396.05966 -358.139492) (xy 396.032395 -358.138943)
			(xy 395.97842 -358.131177) (xy 395.926099 -358.11581) (xy 395.876498 -358.093153) (xy 395.830625 -358.063668)
			(xy 395.789416 -358.027956) (xy 395.753708 -357.986742) (xy 395.724228 -357.940867) (xy 395.701576 -357.891263)
			(xy 395.686214 -357.838941) (xy 395.678454 -357.784965) (xy 394.195605 -357.784965) (xy 394.195605 -357.784972)
			(xy 394.187843 -357.838959) (xy 394.172477 -357.891293) (xy 394.149819 -357.940907) (xy 394.120331 -357.986792)
			(xy 394.084612 -358.028012) (xy 394.043392 -358.063731) (xy 393.997507 -358.093219) (xy 393.947893 -358.115877)
			(xy 393.895559 -358.131243) (xy 393.841572 -358.139005) (xy 393.8143 -358.139492) (xy 392.9507 -358.139492)
			(xy 392.923433 -358.138946) (xy 392.869453 -358.131185) (xy 392.817128 -358.11582) (xy 392.767522 -358.093166)
			(xy 392.721644 -358.063682) (xy 392.68043 -358.02797) (xy 392.644718 -357.986756) (xy 392.615234 -357.940878)
			(xy 392.59258 -357.891272) (xy 392.577215 -357.838947) (xy 392.569454 -357.784967) (xy 391.086606 -357.784967)
			(xy 391.086606 -357.78497) (xy 391.078844 -357.838954) (xy 391.06348 -357.891284) (xy 391.040825 -357.940896)
			(xy 391.01134 -357.986778) (xy 390.975627 -358.027998) (xy 390.934411 -358.063716) (xy 390.888531 -358.093206)
			(xy 390.838922 -358.115866) (xy 390.786593 -358.131236) (xy 390.73261 -358.139003) (xy 390.70534 -358.139492)
			(xy 389.84174 -358.139492) (xy 389.814469 -358.138971) (xy 389.760482 -358.131214) (xy 389.708149 -358.115853)
			(xy 389.658535 -358.093199) (xy 389.61265 -358.063715) (xy 389.571428 -358.028) (xy 389.535709 -357.986783)
			(xy 389.50622 -357.940901) (xy 389.483561 -357.891289) (xy 389.468194 -357.838957) (xy 389.460432 -357.784971)
			(xy 387.977728 -357.784971) (xy 387.977728 -357.784974) (xy 387.969965 -357.838967) (xy 387.954597 -357.891305)
			(xy 387.931936 -357.940924) (xy 387.902444 -357.986812) (xy 387.866722 -358.028036) (xy 387.825496 -358.063756)
			(xy 387.779606 -358.093245) (xy 387.729987 -358.115904) (xy 387.677647 -358.131269) (xy 387.623654 -358.13903)
			(xy 387.59638 -358.139492) (xy 386.73278 -358.139492) (xy 386.705514 -358.138944) (xy 386.651537 -358.131181)
			(xy 386.599213 -358.115815) (xy 386.54961 -358.093159) (xy 386.503735 -358.063675) (xy 386.462523 -358.027963)
			(xy 386.426813 -357.986749) (xy 386.397331 -357.940873) (xy 386.374678 -357.891268) (xy 386.359315 -357.838944)
			(xy 386.351554 -357.784966) (xy 384.868706 -357.784966) (xy 384.868706 -357.784971) (xy 384.860944 -357.838957)
			(xy 384.845578 -357.891289) (xy 384.822922 -357.940901) (xy 384.793435 -357.986785) (xy 384.75772 -358.028005)
			(xy 384.716501 -358.063723) (xy 384.670619 -358.093212) (xy 384.621007 -358.115871) (xy 384.568676 -358.13124)
			(xy 384.514691 -358.139004) (xy 384.48742 -358.139492) (xy 383.62382 -358.139492) (xy 383.59655 -358.13897)
			(xy 383.542565 -358.131211) (xy 383.490234 -358.115847) (xy 383.440623 -358.093193) (xy 383.39474 -358.063708)
			(xy 383.353521 -358.027993) (xy 383.317804 -357.986776) (xy 383.288317 -357.940895) (xy 383.26566 -357.891284)
			(xy 383.250294 -357.838954) (xy 383.242531 -357.78497) (xy 381.759828 -357.78497) (xy 381.759828 -357.784975)
			(xy 381.752065 -357.83897) (xy 381.736695 -357.89131) (xy 381.714033 -357.940929) (xy 381.684539 -357.986818)
			(xy 381.648815 -358.028043) (xy 381.607586 -358.063763) (xy 381.561694 -358.093252) (xy 381.512072 -358.115909)
			(xy 381.45973 -358.131273) (xy 381.405735 -358.139031) (xy 381.37846 -358.139492) (xy 380.51486 -358.139492)
			(xy 380.487595 -358.138943) (xy 380.43362 -358.131177) (xy 380.381299 -358.11581) (xy 380.331698 -358.093153)
			(xy 380.285825 -358.063668) (xy 380.244616 -358.027956) (xy 380.208908 -357.986742) (xy 380.179428 -357.940867)
			(xy 380.156776 -357.891263) (xy 380.141414 -357.838941) (xy 380.133654 -357.784965) (xy 378.650805 -357.784965)
			(xy 378.650805 -357.784972) (xy 378.643043 -357.838959) (xy 378.627677 -357.891293) (xy 378.605019 -357.940907)
			(xy 378.575531 -357.986792) (xy 378.539812 -358.028012) (xy 378.498592 -358.063731) (xy 378.452707 -358.093219)
			(xy 378.403093 -358.115877) (xy 378.350759 -358.131243) (xy 378.296772 -358.139005) (xy 378.2695 -358.139492)
			(xy 377.4059 -358.139492) (xy 377.378633 -358.138946) (xy 377.324653 -358.131185) (xy 377.272328 -358.11582)
			(xy 377.222722 -358.093166) (xy 377.176844 -358.063682) (xy 377.13563 -358.02797) (xy 377.099918 -357.986756)
			(xy 377.070434 -357.940878) (xy 377.04778 -357.891272) (xy 377.032415 -357.838947) (xy 377.024654 -357.784967)
			(xy 375.541806 -357.784967) (xy 375.541806 -357.78497) (xy 375.534044 -357.838954) (xy 375.51868 -357.891284)
			(xy 375.496025 -357.940896) (xy 375.46654 -357.986778) (xy 375.430827 -358.027998) (xy 375.389611 -358.063716)
			(xy 375.343731 -358.093206) (xy 375.294122 -358.115866) (xy 375.241793 -358.131236) (xy 375.18781 -358.139003)
			(xy 375.16054 -358.139492) (xy 374.29694 -358.139492) (xy 374.269669 -358.138971) (xy 374.215682 -358.131214)
			(xy 374.163349 -358.115853) (xy 374.113735 -358.093199) (xy 374.06785 -358.063715) (xy 374.026628 -358.028)
			(xy 373.990909 -357.986783) (xy 373.96142 -357.940901) (xy 373.938761 -357.891289) (xy 373.923394 -357.838957)
			(xy 373.915632 -357.784971) (xy 373.105997 -357.784971) (xy 374.94972 -359.628694) (xy 374.957119 -359.635538)
			(xy 374.975717 -359.643266) (xy 374.985788 -359.64368)
		)
		(stroke
			(width 0)
			(type solid)
		)
		(fill yes)
		(layer "B.Cu")
		(net "GND")
	)
	(gr_poly
		(pts
			(xy 299.98416 -79.904844) (xy 300.005387 -79.900223) (xy 300.048545 -79.895253) (xy 300.070266 -79.894938)
			(xy 300.091987 -79.89526) (xy 300.135144 -79.900228) (xy 300.156372 -79.904844) (xy 300.162214 -79.906114)
			(xy 304.682906 -79.906114) (xy 304.684684 -79.906114) (xy 304.694403 -79.905335) (xy 304.712208 -79.897433)
			(xy 304.725779 -79.883457) (xy 304.729896 -79.874618) (xy 304.741084 -79.848774) (xy 304.769948 -79.80042)
			(xy 304.805606 -79.756834) (xy 304.847283 -79.718963) (xy 304.894074 -79.687628) (xy 304.944963 -79.663512)
			(xy 304.998843 -79.647137) (xy 305.054545 -79.63886) (xy 305.110859 -79.63886) (xy 305.166561 -79.647137)
			(xy 305.220441 -79.663512) (xy 305.27133 -79.687628) (xy 305.318121 -79.718963) (xy 305.359798 -79.756834)
			(xy 305.395456 -79.80042) (xy 305.42432 -79.848774) (xy 305.435508 -79.874618) (xy 305.439608 -79.883469)
			(xy 305.453187 -79.897451) (xy 305.470996 -79.905372) (xy 305.48072 -79.906114) (xy 308.122574 -79.906114)
			(xy 308.132564 -79.905581) (xy 308.151004 -79.897876) (xy 308.158388 -79.891128) (xy 310.65597 -77.3938)
			(xy 310.663319 -77.387) (xy 310.681782 -77.379293) (xy 310.691784 -77.378814) (xy 311.319418 -77.378814)
			(xy 311.321196 -77.37856) (xy 311.371234 -77.377036) (xy 313.5884 -77.377036) (xy 313.588654 -77.377036)
			(xy 313.638692 -77.37856) (xy 313.64047 -77.378814) (xy 314.087256 -77.378814) (xy 314.097247 -77.379344)
			(xy 314.115689 -77.387048) (xy 314.12307 -77.3938) (xy 315.216209 -78.486762) (xy 320.503294 -78.486762)
			(xy 320.507365 -78.43114) (xy 320.519491 -78.376703) (xy 320.539414 -78.324612) (xy 320.56671 -78.275977)
			(xy 320.600796 -78.231834) (xy 320.640945 -78.193125) (xy 320.686303 -78.160674) (xy 320.735903 -78.135173)
			(xy 320.788687 -78.117166) (xy 320.84353 -78.107036) (xy 320.899264 -78.104999) (xy 320.954701 -78.111099)
			(xy 321.008658 -78.125205) (xy 321.059987 -78.147017) (xy 321.107593 -78.176071) (xy 321.150461 -78.211746)
			(xy 321.187678 -78.253283) (xy 321.218451 -78.299796) (xy 321.242123 -78.350293) (xy 321.258191 -78.4037)
			(xy 321.266311 -78.458876) (xy 321.26682 -78.486762) (xy 321.266311 -78.514648) (xy 321.258191 -78.569824)
			(xy 321.242123 -78.623231) (xy 321.218451 -78.673728) (xy 321.187678 -78.720241) (xy 321.150461 -78.761778)
			(xy 321.107593 -78.797453) (xy 321.059987 -78.826507) (xy 321.008658 -78.848319) (xy 320.954701 -78.862425)
			(xy 320.899264 -78.868525) (xy 320.84353 -78.866488) (xy 320.788687 -78.856358) (xy 320.735903 -78.838351)
			(xy 320.686303 -78.81285) (xy 320.640945 -78.780399) (xy 320.600796 -78.74169) (xy 320.56671 -78.697547)
			(xy 320.539414 -78.648912) (xy 320.519491 -78.596821) (xy 320.507365 -78.542384) (xy 320.503294 -78.486762)
			(xy 315.216209 -78.486762) (xy 315.695076 -78.965552) (xy 315.702423 -78.972356) (xy 315.720886 -78.980068)
			(xy 315.73089 -78.980538) (xy 327.032112 -78.980538) (xy 327.041764 -78.979522) (xy 327.049006 -78.977891)
			(xy 327.062169 -78.971043) (xy 327.067672 -78.96606) (xy 330.030582 -76.00315) (xy 330.037982 -75.996311)
			(xy 330.056581 -75.988598) (xy 330.06665 -75.988164) (xy 343.816432 -75.988164) (xy 343.826398 -75.988643)
			(xy 343.844834 -75.996218) (xy 343.852246 -76.002896) (xy 346.556076 -78.706726) (xy 346.561574 -78.711717)
			(xy 346.574738 -78.71857) (xy 346.581984 -78.720188) (xy 346.591636 -78.721204) (xy 404.994364 -78.721204)
			(xy 405.004429 -78.720769) (xy 405.023017 -78.713039) (xy 405.030432 -78.706218) (xy 405.101552 -78.635098)
			(xy 405.108953 -78.62826) (xy 405.127552 -78.620545) (xy 405.13762 -78.620112) (xy 431.430938 -78.620112)
			(xy 431.441005 -78.620542) (xy 431.459598 -78.628268) (xy 431.467006 -78.635098) (xy 431.538126 -78.706218)
			(xy 431.545522 -78.713069) (xy 431.564121 -78.720807) (xy 431.574194 -78.721204) (xy 461.72374 -78.721204)
			(xy 461.733392 -78.720188) (xy 461.740634 -78.718556) (xy 461.753797 -78.711709) (xy 461.7593 -78.706726)
			(xy 463.021172 -77.444854) (xy 463.026152 -77.439351) (xy 463.032981 -77.426182) (xy 463.034634 -77.418946)
			(xy 463.03565 -77.409294) (xy 463.03565 -67.41922) (xy 463.03548 -67.413211) (xy 463.032653 -67.401531)
			(xy 463.030062 -67.396106) (xy 463.028223 -67.392632) (xy 463.023629 -67.386253) (xy 463.020918 -67.383406)
			(xy 461.97901 -66.341498) (xy 461.975281 -66.337974) (xy 461.966709 -66.33234) (xy 461.961992 -66.330322)
			(xy 461.953356 -66.326766) (xy 376.759724 -66.326766) (xy 376.749661 -66.326328) (xy 376.731079 -66.318591)
			(xy 376.723656 -66.31178) (xy 376.697494 -66.285618) (xy 376.694642 -66.282913) (xy 376.688263 -66.278322)
			(xy 376.684794 -66.276474) (xy 376.679368 -66.273888) (xy 376.667688 -66.271057) (xy 376.66168 -66.270886)
			(xy 272.459196 -66.270886) (xy 272.449188 -66.271374) (xy 272.430695 -66.279034) (xy 272.41654 -66.293186)
			(xy 272.408876 -66.311678) (xy 272.408396 -66.321686) (xy 272.408396 -67.128953) (xy 272.566575 -67.128953)
			(xy 272.566575 -67.074447) (xy 272.574333 -67.020495) (xy 272.58969 -66.968197) (xy 272.612334 -66.918617)
			(xy 272.641804 -66.872765) (xy 272.6775 -66.831573) (xy 272.718695 -66.795881) (xy 272.764551 -66.766416)
			(xy 272.814133 -66.743777) (xy 272.866433 -66.728425) (xy 272.920385 -66.720673) (xy 272.947638 -66.720212)
			(xy 272.975007 -66.720711) (xy 273.029185 -66.728521) (xy 273.081688 -66.744002) (xy 273.131435 -66.766836)
			(xy 273.177403 -66.796554) (xy 273.198336 -66.814192) (xy 273.19859 -66.814446) (xy 273.205671 -66.82004)
			(xy 273.222592 -66.826281) (xy 273.23161 -66.826638) (xy 273.298666 -66.826638) (xy 273.30768 -66.826256)
			(xy 273.324597 -66.820025) (xy 273.331686 -66.814446) (xy 273.331686 -66.814192) (xy 273.33194 -66.814192)
			(xy 273.352883 -66.796566) (xy 273.398853 -66.766853) (xy 273.448598 -66.744014) (xy 273.501096 -66.72852)
			(xy 273.55527 -66.720688) (xy 273.582638 -66.720212) (xy 273.609889 -66.72066) (xy 273.663835 -66.728422)
			(xy 273.716128 -66.743781) (xy 273.765703 -66.766425) (xy 273.811551 -66.795894) (xy 273.852739 -66.831588)
			(xy 273.888428 -66.872779) (xy 273.917893 -66.91863) (xy 273.940532 -66.968207) (xy 273.955886 -67.020502)
			(xy 273.963642 -67.074449) (xy 273.963642 -67.128951) (xy 273.955886 -67.182898) (xy 273.940532 -67.235193)
			(xy 273.917893 -67.28477) (xy 273.888428 -67.330621) (xy 273.852739 -67.371812) (xy 273.811551 -67.407506)
			(xy 273.765703 -67.436975) (xy 273.716128 -67.459619) (xy 273.663835 -67.474978) (xy 273.609889 -67.48274)
			(xy 273.582638 -67.483228) (xy 273.555268 -67.482757) (xy 273.501088 -67.474943) (xy 273.448584 -67.459456)
			(xy 273.398837 -67.436615) (xy 273.352871 -67.40689) (xy 273.33194 -67.389248) (xy 273.331686 -67.388994)
			(xy 273.324608 -67.383395) (xy 273.307685 -67.377156) (xy 273.298666 -67.376802) (xy 273.23161 -67.376802)
			(xy 273.222594 -67.377163) (xy 273.205677 -67.383408) (xy 273.19859 -67.388994) (xy 273.19859 -67.389248)
			(xy 273.198336 -67.389248) (xy 273.177395 -67.406876) (xy 273.131425 -67.436591) (xy 273.08168 -67.45943)
			(xy 273.029181 -67.474924) (xy 272.975007 -67.482753) (xy 272.947638 -67.483228) (xy 272.920385 -67.482727)
			(xy 272.866433 -67.474975) (xy 272.814133 -67.459623) (xy 272.764551 -67.436984) (xy 272.718695 -67.407519)
			(xy 272.6775 -67.371827) (xy 272.641804 -67.330635) (xy 272.612334 -67.284783) (xy 272.58969 -67.235203)
			(xy 272.574333 -67.182905) (xy 272.566575 -67.128953) (xy 272.408396 -67.128953) (xy 272.408396 -68.586604)
			(xy 274.825206 -68.586604) (xy 274.825673 -68.559234) (xy 274.83349 -68.505055) (xy 274.848979 -68.452552)
			(xy 274.871821 -68.402805) (xy 274.901545 -68.356838) (xy 274.919186 -68.335906) (xy 274.91944 -68.335652)
			(xy 274.925016 -68.328558) (xy 274.931268 -68.311647) (xy 274.931632 -68.302632) (xy 274.931632 -68.235576)
			(xy 274.93128 -68.226559) (xy 274.925028 -68.209642) (xy 274.91944 -68.202556) (xy 274.919186 -68.202556)
			(xy 274.919186 -68.202302) (xy 274.901532 -68.181382) (xy 274.871823 -68.135406) (xy 274.84899 -68.085655)
			(xy 274.833503 -68.033152) (xy 274.825678 -67.978974) (xy 274.825206 -67.951604) (xy 274.825659 -67.924351)
			(xy 274.833416 -67.870399) (xy 274.848772 -67.8181) (xy 274.871415 -67.768519) (xy 274.900884 -67.722665)
			(xy 274.936579 -67.681472) (xy 274.977773 -67.645778) (xy 275.023627 -67.61631) (xy 275.073209 -67.593669)
			(xy 275.125508 -67.578314) (xy 275.179461 -67.570558) (xy 275.206714 -67.570096) (xy 275.233028 -67.570555)
			(xy 275.285157 -67.577792) (xy 275.3358 -67.592113) (xy 275.383999 -67.613247) (xy 275.428842 -67.640794)
			(xy 275.469482 -67.674234) (xy 275.487638 -67.693286) (xy 275.495145 -67.700704) (xy 275.514436 -67.70922)
			(xy 275.524976 -67.709796) (xy 275.599652 -67.709796) (xy 275.6102 -67.709256) (xy 275.629496 -67.700729)
			(xy 275.63699 -67.693286) (xy 275.655155 -67.67424) (xy 275.695783 -67.640782) (xy 275.740621 -67.613222)
			(xy 275.78882 -67.592082) (xy 275.839466 -67.577763) (xy 275.891598 -67.570536) (xy 275.917914 -67.570096)
			(xy 275.945284 -67.570555) (xy 275.999464 -67.578375) (xy 276.051967 -67.593865) (xy 276.101714 -67.616709)
			(xy 276.14768 -67.646434) (xy 276.168612 -67.664076) (xy 276.168866 -67.66433) (xy 276.175956 -67.669912)
			(xy 276.19287 -67.67616) (xy 276.201886 -67.676522) (xy 276.268942 -67.676522) (xy 276.277956 -67.676133)
			(xy 276.294873 -67.669907) (xy 276.301962 -67.66433) (xy 276.301962 -67.664076) (xy 276.302216 -67.664076)
			(xy 276.323166 -67.646459) (xy 276.369134 -67.616745) (xy 276.418877 -67.593905) (xy 276.471374 -67.578409)
			(xy 276.525546 -67.570574) (xy 276.552914 -67.570096) (xy 276.579003 -67.570511) (xy 276.630693 -67.577624)
			(xy 276.680932 -67.591714) (xy 276.728782 -67.61252) (xy 276.751288 -67.625722) (xy 276.763734 -67.633342)
			(xy 276.792182 -67.633088) (xy 276.893782 -67.569842) (xy 276.906482 -67.543934) (xy 276.905212 -67.52971)
			(xy 276.903434 -67.488054) (xy 276.903931 -67.458091) (xy 276.911759 -67.398677) (xy 276.927274 -67.340794)
			(xy 276.950212 -67.28543) (xy 276.980179 -67.233535) (xy 277.016664 -67.185994) (xy 277.059041 -67.143622)
			(xy 277.106587 -67.107144) (xy 277.158487 -67.077184) (xy 277.213853 -67.054254) (xy 277.271739 -67.038746)
			(xy 277.331153 -67.030927) (xy 277.39108 -67.030929) (xy 277.450494 -67.038753) (xy 277.508378 -67.054265)
			(xy 277.563743 -67.077199) (xy 277.615641 -67.107163) (xy 277.663184 -67.143644) (xy 277.705558 -67.186019)
			(xy 277.742039 -67.233562) (xy 277.772003 -67.28546) (xy 277.794937 -67.340825) (xy 277.810448 -67.39871)
			(xy 277.818271 -67.458124) (xy 277.818273 -67.518051) (xy 277.811758 -67.567552) (xy 278.196022 -67.567552)
			(xy 278.196022 -67.507616) (xy 278.203845 -67.448194) (xy 278.219358 -67.390301) (xy 278.242294 -67.334928)
			(xy 278.272261 -67.283022) (xy 278.308748 -67.235472) (xy 278.351128 -67.193092) (xy 278.398678 -67.156605)
			(xy 278.450584 -67.126638) (xy 278.505957 -67.103702) (xy 278.56385 -67.088189) (xy 278.623272 -67.080366)
			(xy 278.683208 -67.080366) (xy 278.74263 -67.088189) (xy 278.800523 -67.103702) (xy 278.855896 -67.126638)
			(xy 278.859899 -67.128949) (xy 298.566598 -67.128949) (xy 298.566598 -67.074451) (xy 298.574354 -67.020507)
			(xy 298.589708 -66.968216) (xy 298.612346 -66.918643) (xy 298.64181 -66.872796) (xy 298.677498 -66.831608)
			(xy 298.718684 -66.795918) (xy 298.76453 -66.766453) (xy 298.814103 -66.743812) (xy 298.866394 -66.728457)
			(xy 298.920337 -66.720699) (xy 298.947586 -66.720212) (xy 298.974956 -66.720683) (xy 299.029135 -66.728499)
			(xy 299.081638 -66.743987) (xy 299.131385 -66.766828) (xy 299.177352 -66.796551) (xy 299.198284 -66.814192)
			(xy 299.198538 -66.814446) (xy 299.205634 -66.820018) (xy 299.222544 -66.826272) (xy 299.231558 -66.826638)
			(xy 299.298614 -66.826638) (xy 299.307631 -66.82628) (xy 299.324547 -66.820032) (xy 299.331634 -66.814446)
			(xy 299.331634 -66.814192) (xy 299.331888 -66.814192) (xy 299.352813 -66.796544) (xy 299.398788 -66.766834)
			(xy 299.448537 -66.744) (xy 299.501039 -66.728511) (xy 299.555216 -66.720685) (xy 299.582586 -66.720212)
			(xy 299.609841 -66.720634) (xy 299.663796 -66.72839) (xy 299.716099 -66.743745) (xy 299.765683 -66.766388)
			(xy 299.811541 -66.795857) (xy 299.852737 -66.831553) (xy 299.888434 -66.872748) (xy 299.917905 -66.918605)
			(xy 299.94055 -66.968188) (xy 299.955907 -67.02049) (xy 299.963665 -67.074445) (xy 299.963665 -67.128955)
			(xy 299.955907 -67.18291) (xy 299.94055 -67.235212) (xy 299.917905 -67.284795) (xy 299.888434 -67.330652)
			(xy 299.852737 -67.371847) (xy 299.811541 -67.407543) (xy 299.765683 -67.437012) (xy 299.716099 -67.459655)
			(xy 299.663796 -67.47501) (xy 299.609841 -67.482766) (xy 299.582586 -67.483228) (xy 299.555215 -67.482788)
			(xy 299.501034 -67.474966) (xy 299.44853 -67.459472) (xy 299.398783 -67.436624) (xy 299.352818 -67.406893)
			(xy 299.331888 -67.389248) (xy 299.331634 -67.388994) (xy 299.324542 -67.383415) (xy 299.307629 -67.377164)
			(xy 299.298614 -67.376802) (xy 299.231558 -67.376802) (xy 299.222544 -67.377187) (xy 299.205627 -67.383415)
			(xy 299.198538 -67.388994) (xy 299.198538 -67.389248) (xy 299.198284 -67.389248) (xy 299.177324 -67.406853)
			(xy 299.13136 -67.436572) (xy 299.08162 -67.459415) (xy 299.029125 -67.474914) (xy 298.974953 -67.48275)
			(xy 298.947586 -67.483228) (xy 298.920337 -67.482701) (xy 298.866394 -67.474943) (xy 298.814103 -67.459588)
			(xy 298.76453 -67.436947) (xy 298.718684 -67.407482) (xy 298.677498 -67.371792) (xy 298.64181 -67.330604)
			(xy 298.612346 -67.284757) (xy 298.589708 -67.235184) (xy 298.574354 -67.182893) (xy 298.566598 -67.128949)
			(xy 278.859899 -67.128949) (xy 278.907802 -67.156605) (xy 278.955352 -67.193092) (xy 278.997732 -67.235472)
			(xy 279.034219 -67.283022) (xy 279.064186 -67.334928) (xy 279.087122 -67.390301) (xy 279.102635 -67.448194)
			(xy 279.110458 -67.507616) (xy 279.110948 -67.537584) (xy 279.110458 -67.567552) (xy 279.103168 -67.622924)
			(xy 279.470086 -67.622924) (xy 279.470086 -67.562988) (xy 279.477909 -67.503566) (xy 279.493422 -67.445673)
			(xy 279.516358 -67.3903) (xy 279.546325 -67.338394) (xy 279.582812 -67.290844) (xy 279.625192 -67.248464)
			(xy 279.672742 -67.211977) (xy 279.724648 -67.18201) (xy 279.780021 -67.159074) (xy 279.837914 -67.143561)
			(xy 279.897336 -67.135738) (xy 279.957272 -67.135738) (xy 280.016694 -67.143561) (xy 280.074587 -67.159074)
			(xy 280.12996 -67.18201) (xy 280.181866 -67.211977) (xy 280.229416 -67.248464) (xy 280.271796 -67.290844)
			(xy 280.308283 -67.338394) (xy 280.33825 -67.3903) (xy 280.361186 -67.445673) (xy 280.376699 -67.503566)
			(xy 280.384522 -67.562988) (xy 280.384556 -67.565051) (xy 282.646593 -67.565051) (xy 282.646593 -67.510549)
			(xy 282.65435 -67.456601) (xy 282.669706 -67.404306) (xy 282.692348 -67.354729) (xy 282.721816 -67.308879)
			(xy 282.757509 -67.267689) (xy 282.798701 -67.231999) (xy 282.844553 -67.202535) (xy 282.894132 -67.179896)
			(xy 282.946428 -67.164544) (xy 283.000377 -67.156791) (xy 283.027628 -67.15633) (xy 283.054999 -67.156772)
			(xy 283.10918 -67.164595) (xy 283.161683 -67.180089) (xy 283.21143 -67.202936) (xy 283.257395 -67.232666)
			(xy 283.278326 -67.25031) (xy 283.27858 -67.250564) (xy 283.285663 -67.256156) (xy 283.302583 -67.262398)
			(xy 283.3116 -67.262756) (xy 283.378656 -67.262756) (xy 283.387672 -67.262387) (xy 283.404589 -67.256149)
			(xy 283.411676 -67.250564) (xy 283.411676 -67.25031) (xy 283.41193 -67.25031) (xy 283.432879 -67.232692)
			(xy 283.478847 -67.202976) (xy 283.52859 -67.180136) (xy 283.581087 -67.16464) (xy 283.63526 -67.156807)
			(xy 283.662628 -67.15633) (xy 283.689881 -67.156742) (xy 283.743831 -67.164502) (xy 283.796127 -67.179861)
			(xy 283.845706 -67.202506) (xy 283.891557 -67.231976) (xy 283.932748 -67.267671) (xy 283.96844 -67.308865)
			(xy 283.997907 -67.354719) (xy 284.020548 -67.404299) (xy 284.035904 -67.456597) (xy 284.04366 -67.510547)
			(xy 284.04366 -67.565053) (xy 284.035904 -67.619003) (xy 284.020548 -67.671301) (xy 283.997907 -67.720881)
			(xy 283.96844 -67.766735) (xy 283.932748 -67.807929) (xy 283.891557 -67.843624) (xy 283.845706 -67.873094)
			(xy 283.796127 -67.895739) (xy 283.743831 -67.911098) (xy 283.689881 -67.918858) (xy 283.662628 -67.919346)
			(xy 283.635258 -67.918877) (xy 283.581078 -67.911062) (xy 283.528575 -67.895574) (xy 283.478828 -67.872733)
			(xy 283.432861 -67.843008) (xy 283.41193 -67.825366) (xy 283.411676 -67.825112) (xy 283.4046 -67.819511)
			(xy 283.387675 -67.813272) (xy 283.378656 -67.81292) (xy 283.3116 -67.81292) (xy 283.302583 -67.813273)
			(xy 283.285665 -67.819523) (xy 283.27858 -67.825112) (xy 283.27858 -67.825366) (xy 283.278326 -67.825366)
			(xy 283.257391 -67.843001) (xy 283.211419 -67.872715) (xy 283.161673 -67.895552) (xy 283.109172 -67.911044)
			(xy 283.054997 -67.918872) (xy 283.027628 -67.919346) (xy 283.000377 -67.918809) (xy 282.946428 -67.911056)
			(xy 282.894132 -67.895704) (xy 282.844553 -67.873065) (xy 282.798701 -67.843601) (xy 282.757509 -67.807911)
			(xy 282.721816 -67.766721) (xy 282.692348 -67.720871) (xy 282.669706 -67.671294) (xy 282.65435 -67.618999)
			(xy 282.646593 -67.565051) (xy 280.384556 -67.565051) (xy 280.385012 -67.592956) (xy 280.384522 -67.622924)
			(xy 280.376699 -67.682346) (xy 280.361186 -67.740239) (xy 280.33825 -67.795612) (xy 280.308283 -67.847518)
			(xy 280.271796 -67.895068) (xy 280.229416 -67.937448) (xy 280.181866 -67.973935) (xy 280.12996 -68.003902)
			(xy 280.074587 -68.026838) (xy 280.016694 -68.042351) (xy 279.957272 -68.050174) (xy 279.897336 -68.050174)
			(xy 279.837914 -68.042351) (xy 279.780021 -68.026838) (xy 279.724648 -68.003902) (xy 279.672742 -67.973935)
			(xy 279.625192 -67.937448) (xy 279.582812 -67.895068) (xy 279.546325 -67.847518) (xy 279.516358 -67.795612)
			(xy 279.493422 -67.740239) (xy 279.477909 -67.682346) (xy 279.470086 -67.622924) (xy 279.103168 -67.622924)
			(xy 279.102635 -67.626974) (xy 279.087122 -67.684867) (xy 279.064186 -67.74024) (xy 279.034219 -67.792146)
			(xy 278.997732 -67.839696) (xy 278.955352 -67.882076) (xy 278.907802 -67.918563) (xy 278.855896 -67.94853)
			(xy 278.800523 -67.971466) (xy 278.74263 -67.986979) (xy 278.683208 -67.994802) (xy 278.623272 -67.994802)
			(xy 278.56385 -67.986979) (xy 278.505957 -67.971466) (xy 278.450584 -67.94853) (xy 278.398678 -67.918563)
			(xy 278.351128 -67.882076) (xy 278.308748 -67.839696) (xy 278.272261 -67.792146) (xy 278.242294 -67.74024)
			(xy 278.219358 -67.684867) (xy 278.203845 -67.626974) (xy 278.196022 -67.567552) (xy 277.811758 -67.567552)
			(xy 277.810453 -67.577465) (xy 277.794945 -67.635351) (xy 277.772014 -67.690717) (xy 277.742053 -67.742616)
			(xy 277.705575 -67.790162) (xy 277.663203 -67.832539) (xy 277.615662 -67.869023) (xy 277.563766 -67.89899)
			(xy 277.508402 -67.921927) (xy 277.450519 -67.937442) (xy 277.391105 -67.945269) (xy 277.361142 -67.945762)
			(xy 277.332724 -67.945356) (xy 277.276324 -67.938322) (xy 277.221229 -67.924357) (xy 277.168289 -67.903676)
			(xy 277.118317 -67.876598) (xy 277.09495 -67.860418) (xy 277.083266 -67.852036) (xy 277.054818 -67.850004)
			(xy 276.9616 -67.899026) (xy 276.953513 -67.903753) (xy 276.941171 -67.917821) (xy 276.934706 -67.935384)
			(xy 276.934422 -67.944746) (xy 276.934422 -67.951604) (xy 276.933977 -67.978975) (xy 276.926157 -68.033156)
			(xy 276.910664 -68.08566) (xy 276.887817 -68.135407) (xy 276.858087 -68.181372) (xy 276.840442 -68.202302)
			(xy 276.840188 -68.202556) (xy 276.834612 -68.20965) (xy 276.828359 -68.226561) (xy 276.827996 -68.235576)
			(xy 276.827996 -68.302632) (xy 276.828339 -68.31165) (xy 276.834596 -68.328567) (xy 276.840188 -68.335652)
			(xy 276.840442 -68.335652) (xy 276.840442 -68.335906) (xy 276.858104 -68.356819) (xy 276.887811 -68.402798)
			(xy 276.910642 -68.45255) (xy 276.926128 -68.505055) (xy 276.933951 -68.559234) (xy 276.934422 -68.586604)
			(xy 276.933926 -68.613855) (xy 276.926169 -68.667801) (xy 276.910814 -68.720095) (xy 276.894175 -68.75653)
			(xy 280.37028 -68.75653) (xy 280.370744 -68.729159) (xy 280.378559 -68.67498) (xy 280.394048 -68.622476)
			(xy 280.416891 -68.572729) (xy 280.446617 -68.526763) (xy 280.46426 -68.505832) (xy 280.464514 -68.505578)
			(xy 280.470117 -68.498503) (xy 280.476354 -68.481577) (xy 280.476706 -68.472558) (xy 280.476706 -68.405502)
			(xy 280.476347 -68.396485) (xy 280.470101 -68.379568) (xy 280.464514 -68.372482) (xy 280.46426 -68.372482)
			(xy 280.46426 -68.372228) (xy 280.446614 -68.351302) (xy 280.416904 -68.305327) (xy 280.39407 -68.255578)
			(xy 280.378581 -68.203076) (xy 280.370753 -68.148899) (xy 280.37028 -68.12153) (xy 280.370783 -68.094278)
			(xy 280.378536 -68.04033) (xy 280.393887 -67.988033) (xy 280.416526 -67.938454) (xy 280.445989 -67.892601)
			(xy 280.481679 -67.851409) (xy 280.522868 -67.815714) (xy 280.568717 -67.786246) (xy 280.618294 -67.763602)
			(xy 280.670588 -67.748245) (xy 280.724536 -67.740486) (xy 280.751788 -67.740022) (xy 280.779158 -67.74049)
			(xy 280.833337 -67.748306) (xy 280.885841 -67.763795) (xy 280.935588 -67.786636) (xy 280.981554 -67.816361)
			(xy 281.002486 -67.834002) (xy 281.00274 -67.834256) (xy 281.009835 -67.83983) (xy 281.026745 -67.846083)
			(xy 281.03576 -67.846448) (xy 281.102816 -67.846448) (xy 281.111835 -67.84611) (xy 281.128752 -67.83985)
			(xy 281.135836 -67.834256) (xy 281.135836 -67.834002) (xy 281.13609 -67.834002) (xy 281.157015 -67.816354)
			(xy 281.20299 -67.786644) (xy 281.252739 -67.763809) (xy 281.305241 -67.74832) (xy 281.359418 -67.740495)
			(xy 281.386788 -67.740022) (xy 281.413102 -67.74049) (xy 281.465231 -67.747724) (xy 281.515874 -67.762042)
			(xy 281.564073 -67.783175) (xy 281.608916 -67.810721) (xy 281.649556 -67.84416) (xy 281.667712 -67.863212)
			(xy 281.675226 -67.870623) (xy 281.694512 -67.879142) (xy 281.70505 -67.879722) (xy 281.779726 -67.879722)
			(xy 281.790272 -67.87916) (xy 281.809567 -67.870647) (xy 281.817064 -67.863212) (xy 281.835198 -67.844135)
			(xy 281.875832 -67.810679) (xy 281.920677 -67.783123) (xy 281.968882 -67.761988) (xy 282.019533 -67.747676)
			(xy 282.071671 -67.740457) (xy 282.097988 -67.740022) (xy 282.125242 -67.740467) (xy 282.179195 -67.748223)
			(xy 282.231495 -67.763579) (xy 282.281077 -67.786222) (xy 282.326932 -67.815692) (xy 282.368125 -67.851387)
			(xy 282.403819 -67.892583) (xy 282.433287 -67.938439) (xy 282.455928 -67.988022) (xy 282.471281 -68.040323)
			(xy 282.479035 -68.094276) (xy 282.479496 -68.12153) (xy 282.479048 -68.148901) (xy 282.471226 -68.203081)
			(xy 282.455733 -68.255584) (xy 282.432887 -68.305331) (xy 282.403159 -68.351297) (xy 282.385516 -68.372228)
			(xy 282.385262 -68.372482) (xy 282.379673 -68.379566) (xy 282.373429 -68.396485) (xy 282.37307 -68.405502)
			(xy 282.37307 -68.472558) (xy 282.373454 -68.481572) (xy 282.379683 -68.498489) (xy 282.385262 -68.505578)
			(xy 282.385516 -68.505578) (xy 282.385516 -68.505832) (xy 282.403139 -68.526777) (xy 282.432853 -68.572746)
			(xy 282.439216 -68.586604) (xy 300.825154 -68.586604) (xy 300.825609 -68.559233) (xy 300.833428 -68.505053)
			(xy 300.848919 -68.452549) (xy 300.871763 -68.402803) (xy 300.901491 -68.356837) (xy 300.919134 -68.335906)
			(xy 300.919388 -68.335652) (xy 300.924958 -68.328554) (xy 300.931215 -68.311646) (xy 300.93158 -68.302632)
			(xy 300.93158 -68.235576) (xy 300.931239 -68.226557) (xy 300.924981 -68.20964) (xy 300.919388 -68.202556)
			(xy 300.919134 -68.202556) (xy 300.919134 -68.202302) (xy 300.901488 -68.181376) (xy 300.871776 -68.135402)
			(xy 300.848941 -68.085653) (xy 300.833451 -68.033151) (xy 300.825626 -67.978974) (xy 300.825154 -67.951604)
			(xy 300.825681 -67.924355) (xy 300.833436 -67.87041) (xy 300.848789 -67.818119) (xy 300.871427 -67.768544)
			(xy 300.900889 -67.722695) (xy 300.936576 -67.681506) (xy 300.977762 -67.645815) (xy 301.023607 -67.616347)
			(xy 301.073179 -67.593704) (xy 301.125469 -67.578345) (xy 301.179413 -67.570584) (xy 301.206662 -67.570096)
			(xy 301.232977 -67.570523) (xy 301.285108 -67.577767) (xy 301.335751 -67.592094) (xy 301.38395 -67.613234)
			(xy 301.428792 -67.640787) (xy 301.46943 -67.674232) (xy 301.487586 -67.693286) (xy 301.495113 -67.700681)
			(xy 301.514389 -67.70921) (xy 301.524924 -67.709796) (xy 301.5996 -67.709796) (xy 301.610151 -67.709281)
			(xy 301.629447 -67.700736) (xy 301.636938 -67.693286) (xy 301.655079 -67.674216) (xy 301.695712 -67.640761)
			(xy 301.740556 -67.613204) (xy 301.788759 -67.592068) (xy 301.839409 -67.577754) (xy 301.891545 -67.570533)
			(xy 301.917862 -67.570096) (xy 301.945231 -67.570585) (xy 301.999409 -67.578398) (xy 302.051912 -67.593881)
			(xy 302.101659 -67.616718) (xy 302.147627 -67.646437) (xy 302.16856 -67.664076) (xy 302.168814 -67.66433)
			(xy 302.17589 -67.669932) (xy 302.192815 -67.676168) (xy 302.201834 -67.676522) (xy 302.26889 -67.676522)
			(xy 302.277906 -67.676155) (xy 302.294823 -67.669914) (xy 302.30191 -67.66433) (xy 302.30191 -67.664076)
			(xy 302.302164 -67.664076) (xy 302.323096 -67.646437) (xy 302.369069 -67.616726) (xy 302.418817 -67.59389)
			(xy 302.471317 -67.578399) (xy 302.525493 -67.57057) (xy 302.552862 -67.570096) (xy 302.57895 -67.570535)
			(xy 302.63064 -67.57764) (xy 302.680879 -67.591724) (xy 302.72873 -67.612523) (xy 302.751236 -67.625722)
			(xy 302.763682 -67.633342) (xy 302.79213 -67.633088) (xy 302.89373 -67.569842) (xy 302.90643 -67.543934)
			(xy 302.90516 -67.52971) (xy 302.903382 -67.488054) (xy 302.903931 -67.45809) (xy 302.911759 -67.398675)
			(xy 302.927275 -67.34079) (xy 302.950214 -67.285426) (xy 302.980183 -67.233529) (xy 303.016669 -67.185988)
			(xy 303.059048 -67.143616) (xy 303.106596 -67.107138) (xy 303.158498 -67.077178) (xy 303.213866 -67.054249)
			(xy 303.271754 -67.038743) (xy 303.33117 -67.030926) (xy 303.391098 -67.03093) (xy 303.450513 -67.038757)
			(xy 303.508398 -67.054271) (xy 303.563763 -67.077209) (xy 303.615661 -67.107176) (xy 303.663203 -67.143661)
			(xy 303.705576 -67.186039) (xy 303.742055 -67.233586) (xy 303.772016 -67.285487) (xy 303.794947 -67.340855)
			(xy 303.810454 -67.398742) (xy 303.818274 -67.458158) (xy 303.818271 -67.518086) (xy 303.811756 -67.567552)
			(xy 304.19597 -67.567552) (xy 304.19597 -67.507616) (xy 304.203793 -67.448194) (xy 304.219306 -67.390301)
			(xy 304.242242 -67.334928) (xy 304.272209 -67.283022) (xy 304.308696 -67.235472) (xy 304.351076 -67.193092)
			(xy 304.398626 -67.156605) (xy 304.450532 -67.126638) (xy 304.505905 -67.103702) (xy 304.563798 -67.088189)
			(xy 304.62322 -67.080366) (xy 304.683156 -67.080366) (xy 304.742578 -67.088189) (xy 304.800471 -67.103702)
			(xy 304.855844 -67.126638) (xy 304.859854 -67.128953) (xy 324.566475 -67.128953) (xy 324.566475 -67.074447)
			(xy 324.574233 -67.020496) (xy 324.58959 -66.968198) (xy 324.612234 -66.918618) (xy 324.641703 -66.872766)
			(xy 324.677399 -66.831575) (xy 324.718593 -66.795883) (xy 324.764448 -66.766417) (xy 324.81403 -66.743778)
			(xy 324.866329 -66.728426) (xy 324.920281 -66.720673) (xy 324.947534 -66.720212) (xy 324.974905 -66.720655)
			(xy 325.029085 -66.728478) (xy 325.081589 -66.743972) (xy 325.131335 -66.766819) (xy 325.177301 -66.796549)
			(xy 325.198232 -66.814192) (xy 325.198486 -66.814446) (xy 325.205568 -66.820038) (xy 325.222489 -66.82628)
			(xy 325.231506 -66.826638) (xy 325.298562 -66.826638) (xy 325.307576 -66.826255) (xy 325.324493 -66.820024)
			(xy 325.331582 -66.814446) (xy 325.331582 -66.814192) (xy 325.331836 -66.814192) (xy 325.35278 -66.796568)
			(xy 325.39875 -66.766854) (xy 325.448494 -66.744016) (xy 325.500992 -66.728521) (xy 325.555166 -66.720688)
			(xy 325.582534 -66.720212) (xy 325.609785 -66.72066) (xy 325.663732 -66.728421) (xy 325.716025 -66.74378)
			(xy 325.765601 -66.766424) (xy 325.811449 -66.795893) (xy 325.852638 -66.831586) (xy 325.888328 -66.872778)
			(xy 325.917792 -66.918629) (xy 325.940432 -66.968207) (xy 325.955786 -67.020501) (xy 325.963542 -67.074449)
			(xy 325.963542 -67.128951) (xy 325.955786 -67.182899) (xy 325.940432 -67.235193) (xy 325.917792 -67.284771)
			(xy 325.888328 -67.330622) (xy 325.852638 -67.371814) (xy 325.811449 -67.407507) (xy 325.765601 -67.436976)
			(xy 325.716025 -67.45962) (xy 325.663732 -67.474979) (xy 325.609785 -67.48274) (xy 325.582534 -67.483228)
			(xy 325.555164 -67.48276) (xy 325.500984 -67.474945) (xy 325.44848 -67.459457) (xy 325.398733 -67.436616)
			(xy 325.352767 -67.40689) (xy 325.331836 -67.389248) (xy 325.331582 -67.388994) (xy 325.324505 -67.383393)
			(xy 325.307581 -67.377155) (xy 325.298562 -67.376802) (xy 325.231506 -67.376802) (xy 325.222489 -67.377161)
			(xy 325.205572 -67.383407) (xy 325.198486 -67.388994) (xy 325.198486 -67.389248) (xy 325.198232 -67.389248)
			(xy 325.177292 -67.406877) (xy 325.131322 -67.436593) (xy 325.081577 -67.459431) (xy 325.029078 -67.474924)
			(xy 324.974903 -67.482754) (xy 324.947534 -67.483228) (xy 324.920281 -67.482727) (xy 324.866329 -67.474974)
			(xy 324.81403 -67.459622) (xy 324.764448 -67.436983) (xy 324.718593 -67.407517) (xy 324.677399 -67.371825)
			(xy 324.641703 -67.330634) (xy 324.612234 -67.284782) (xy 324.58959 -67.235202) (xy 324.574233 -67.182904)
			(xy 324.566475 -67.128953) (xy 304.859854 -67.128953) (xy 304.90775 -67.156605) (xy 304.9553 -67.193092)
			(xy 304.99768 -67.235472) (xy 305.034167 -67.283022) (xy 305.064134 -67.334928) (xy 305.08707 -67.390301)
			(xy 305.102583 -67.448194) (xy 305.110406 -67.507616) (xy 305.110896 -67.537584) (xy 305.110406 -67.567552)
			(xy 305.103116 -67.622924) (xy 305.470034 -67.622924) (xy 305.470034 -67.562988) (xy 305.477857 -67.503566)
			(xy 305.49337 -67.445673) (xy 305.516306 -67.3903) (xy 305.546273 -67.338394) (xy 305.58276 -67.290844)
			(xy 305.62514 -67.248464) (xy 305.67269 -67.211977) (xy 305.724596 -67.18201) (xy 305.779969 -67.159074)
			(xy 305.837862 -67.143561) (xy 305.897284 -67.135738) (xy 305.95722 -67.135738) (xy 306.016642 -67.143561)
			(xy 306.074535 -67.159074) (xy 306.129908 -67.18201) (xy 306.181814 -67.211977) (xy 306.229364 -67.248464)
			(xy 306.271744 -67.290844) (xy 306.308231 -67.338394) (xy 306.338198 -67.3903) (xy 306.361134 -67.445673)
			(xy 306.376647 -67.503566) (xy 306.38447 -67.562988) (xy 306.384504 -67.565047) (xy 308.646616 -67.565047)
			(xy 308.646616 -67.510553) (xy 308.654371 -67.456612) (xy 308.669724 -67.404325) (xy 308.692361 -67.354754)
			(xy 308.721822 -67.30891) (xy 308.757507 -67.267724) (xy 308.79869 -67.232036) (xy 308.844533 -67.202572)
			(xy 308.894102 -67.179932) (xy 308.946389 -67.164576) (xy 309.000329 -67.156818) (xy 309.027576 -67.15633)
			(xy 309.054946 -67.156803) (xy 309.109125 -67.164618) (xy 309.161628 -67.180105) (xy 309.211375 -67.202945)
			(xy 309.257342 -67.232669) (xy 309.278274 -67.25031) (xy 309.278528 -67.250564) (xy 309.285626 -67.256134)
			(xy 309.302534 -67.262389) (xy 309.311548 -67.262756) (xy 309.378604 -67.262756) (xy 309.387622 -67.26241)
			(xy 309.404539 -67.256156) (xy 309.411624 -67.250564) (xy 309.411624 -67.25031) (xy 309.411878 -67.25031)
			(xy 309.432809 -67.232669) (xy 309.478782 -67.202957) (xy 309.52853 -67.180122) (xy 309.581031 -67.164631)
			(xy 309.635207 -67.156804) (xy 309.662576 -67.15633) (xy 309.689833 -67.156715) (xy 309.743792 -67.16447)
			(xy 309.796098 -67.179826) (xy 309.845686 -67.202469) (xy 309.891547 -67.23194) (xy 309.932746 -67.267637)
			(xy 309.968446 -67.308834) (xy 309.997919 -67.354693) (xy 310.020566 -67.40428) (xy 310.035925 -67.456585)
			(xy 310.043683 -67.510543) (xy 310.043683 -67.565057) (xy 310.035925 -67.619015) (xy 310.020566 -67.67132)
			(xy 309.997919 -67.720907) (xy 309.968446 -67.766766) (xy 309.932746 -67.807963) (xy 309.891547 -67.84366)
			(xy 309.845686 -67.873131) (xy 309.796098 -67.895774) (xy 309.743792 -67.91113) (xy 309.689833 -67.918885)
			(xy 309.662576 -67.919346) (xy 309.635205 -67.918907) (xy 309.581024 -67.911085) (xy 309.52852 -67.89559)
			(xy 309.478773 -67.872742) (xy 309.432808 -67.843011) (xy 309.411878 -67.825366) (xy 309.411624 -67.825112)
			(xy 309.404534 -67.819531) (xy 309.38762 -67.81328) (xy 309.378604 -67.81292) (xy 309.311548 -67.81292)
			(xy 309.302533 -67.813296) (xy 309.285616 -67.81953) (xy 309.278528 -67.825112) (xy 309.278528 -67.825366)
			(xy 309.278274 -67.825366) (xy 309.25732 -67.842979) (xy 309.211354 -67.872696) (xy 309.161612 -67.895537)
			(xy 309.109116 -67.911034) (xy 309.054944 -67.918869) (xy 309.027576 -67.919346) (xy 309.000329 -67.918782)
			(xy 308.946389 -67.911024) (xy 308.894102 -67.895668) (xy 308.844533 -67.873028) (xy 308.79869 -67.843564)
			(xy 308.757507 -67.807876) (xy 308.721822 -67.76669) (xy 308.692361 -67.720846) (xy 308.669724 -67.671275)
			(xy 308.654371 -67.618988) (xy 308.646616 -67.565047) (xy 306.384504 -67.565047) (xy 306.38496 -67.592956)
			(xy 306.38447 -67.622924) (xy 306.376647 -67.682346) (xy 306.361134 -67.740239) (xy 306.338198 -67.795612)
			(xy 306.308231 -67.847518) (xy 306.271744 -67.895068) (xy 306.229364 -67.937448) (xy 306.181814 -67.973935)
			(xy 306.129908 -68.003902) (xy 306.074535 -68.026838) (xy 306.016642 -68.042351) (xy 305.95722 -68.050174)
			(xy 305.897284 -68.050174) (xy 305.837862 -68.042351) (xy 305.779969 -68.026838) (xy 305.724596 -68.003902)
			(xy 305.67269 -67.973935) (xy 305.62514 -67.937448) (xy 305.58276 -67.895068) (xy 305.546273 -67.847518)
			(xy 305.516306 -67.795612) (xy 305.49337 -67.740239) (xy 305.477857 -67.682346) (xy 305.470034 -67.622924)
			(xy 305.103116 -67.622924) (xy 305.102583 -67.626974) (xy 305.08707 -67.684867) (xy 305.064134 -67.74024)
			(xy 305.034167 -67.792146) (xy 304.99768 -67.839696) (xy 304.9553 -67.882076) (xy 304.90775 -67.918563)
			(xy 304.855844 -67.94853) (xy 304.800471 -67.971466) (xy 304.742578 -67.986979) (xy 304.683156 -67.994802)
			(xy 304.62322 -67.994802) (xy 304.563798 -67.986979) (xy 304.505905 -67.971466) (xy 304.450532 -67.94853)
			(xy 304.398626 -67.918563) (xy 304.351076 -67.882076) (xy 304.308696 -67.839696) (xy 304.272209 -67.792146)
			(xy 304.242242 -67.74024) (xy 304.219306 -67.684867) (xy 304.203793 -67.626974) (xy 304.19597 -67.567552)
			(xy 303.811756 -67.567552) (xy 303.810446 -67.577501) (xy 303.794933 -67.635387) (xy 303.771997 -67.690752)
			(xy 303.742031 -67.742651) (xy 303.705547 -67.790194) (xy 303.66317 -67.832568) (xy 303.615624 -67.869048)
			(xy 303.563724 -67.899011) (xy 303.508357 -67.921943) (xy 303.45047 -67.937452) (xy 303.391054 -67.945273)
			(xy 303.36109 -67.945762) (xy 303.332672 -67.945331) (xy 303.276274 -67.938302) (xy 303.221179 -67.924343)
			(xy 303.168238 -67.903668) (xy 303.118266 -67.876595) (xy 303.094898 -67.860418) (xy 303.083214 -67.852036)
			(xy 303.054766 -67.850004) (xy 302.961548 -67.899026) (xy 302.953471 -67.903769) (xy 302.941124 -67.917828)
			(xy 302.934655 -67.935385) (xy 302.93437 -67.944746) (xy 302.93437 -67.951604) (xy 302.933914 -67.978975)
			(xy 302.926095 -68.033154) (xy 302.910604 -68.085658) (xy 302.88776 -68.135405) (xy 302.858033 -68.181371)
			(xy 302.84039 -68.202302) (xy 302.840136 -68.202556) (xy 302.834554 -68.209645) (xy 302.828306 -68.22656)
			(xy 302.827944 -68.235576) (xy 302.827944 -68.302632) (xy 302.828276 -68.311652) (xy 302.83454 -68.328569)
			(xy 302.840136 -68.335652) (xy 302.84039 -68.335652) (xy 302.84039 -68.335906) (xy 302.858044 -68.356826)
			(xy 302.887754 -68.402802) (xy 302.910587 -68.452553) (xy 302.926075 -68.505056) (xy 302.933898 -68.559234)
			(xy 302.93437 -68.586604) (xy 302.933948 -68.613859) (xy 302.92619 -68.667813) (xy 302.910831 -68.720114)
			(xy 302.894199 -68.75653) (xy 306.370228 -68.75653) (xy 306.370705 -68.72916) (xy 306.378519 -68.674981)
			(xy 306.394005 -68.622478) (xy 306.416845 -68.572731) (xy 306.446567 -68.526764) (xy 306.464208 -68.505832)
			(xy 306.464462 -68.505578) (xy 306.470071 -68.498507) (xy 306.476303 -68.481578) (xy 306.476654 -68.472558)
			(xy 306.476654 -68.405502) (xy 306.476306 -68.396484) (xy 306.470053 -68.379567) (xy 306.464462 -68.372482)
			(xy 306.464208 -68.372482) (xy 306.464208 -68.372228) (xy 306.44657 -68.351295) (xy 306.416858 -68.305323)
			(xy 306.394021 -68.255575) (xy 306.37853 -68.203075) (xy 306.370702 -68.148899) (xy 306.370228 -68.12153)
			(xy 306.370683 -68.094276) (xy 306.378437 -68.040323) (xy 306.393791 -67.988023) (xy 306.416433 -67.938441)
			(xy 306.445901 -67.892586) (xy 306.481596 -67.851392) (xy 306.52279 -67.815697) (xy 306.568646 -67.78623)
			(xy 306.618229 -67.763589) (xy 306.670529 -67.748236) (xy 306.724482 -67.740483) (xy 306.751736 -67.740022)
			(xy 306.779107 -67.740462) (xy 306.833288 -67.748285) (xy 306.885791 -67.76378) (xy 306.935538 -67.786628)
			(xy 306.981503 -67.816358) (xy 307.002434 -67.834002) (xy 307.002688 -67.834256) (xy 307.009769 -67.83985)
			(xy 307.02669 -67.846091) (xy 307.035708 -67.846448) (xy 307.102764 -67.846448) (xy 307.11178 -67.846085)
			(xy 307.128698 -67.839843) (xy 307.135784 -67.834256) (xy 307.135784 -67.834002) (xy 307.136038 -67.834002)
			(xy 307.156983 -67.816379) (xy 307.202952 -67.786665) (xy 307.252696 -67.763825) (xy 307.305194 -67.748331)
			(xy 307.359368 -67.740498) (xy 307.386736 -67.740022) (xy 307.413051 -67.740458) (xy 307.465181 -67.747699)
			(xy 307.515825 -67.762023) (xy 307.564024 -67.783162) (xy 307.608867 -67.810713) (xy 307.649505 -67.844158)
			(xy 307.66766 -67.863212) (xy 307.675193 -67.8706) (xy 307.694464 -67.879132) (xy 307.704998 -67.879722)
			(xy 307.779674 -67.879722) (xy 307.790223 -67.879186) (xy 307.809518 -67.870655) (xy 307.817012 -67.863212)
			(xy 307.835171 -67.84416) (xy 307.8758 -67.810702) (xy 307.920639 -67.783142) (xy 307.968839 -67.762003)
			(xy 308.019486 -67.747685) (xy 308.07162 -67.74046) (xy 308.097936 -67.740022) (xy 308.12519 -67.740444)
			(xy 308.179141 -67.748207) (xy 308.231439 -67.763568) (xy 308.281018 -67.786215) (xy 308.32687 -67.815688)
			(xy 308.36806 -67.851386) (xy 308.403751 -67.892583) (xy 308.433216 -67.93844) (xy 308.455855 -67.988023)
			(xy 308.471207 -68.040324) (xy 308.47896 -68.094276) (xy 308.479444 -68.12153) (xy 308.479009 -68.148902)
			(xy 308.471186 -68.203082) (xy 308.45569 -68.255586) (xy 308.432841 -68.305333) (xy 308.403109 -68.351298)
			(xy 308.385464 -68.372228) (xy 308.38521 -68.372482) (xy 308.379626 -68.37957) (xy 308.373377 -68.396486)
			(xy 308.373018 -68.405502) (xy 308.373018 -68.472558) (xy 308.373391 -68.481573) (xy 308.379627 -68.498491)
			(xy 308.38521 -68.505578) (xy 308.385464 -68.505578) (xy 308.385464 -68.505832) (xy 308.403079 -68.526784)
			(xy 308.432796 -68.57275) (xy 308.439157 -68.586604) (xy 326.825102 -68.586604) (xy 326.82557 -68.559234)
			(xy 326.833387 -68.505055) (xy 326.848876 -68.452552) (xy 326.871717 -68.402805) (xy 326.901441 -68.356838)
			(xy 326.919082 -68.335906) (xy 326.919336 -68.335652) (xy 326.924911 -68.328558) (xy 326.931164 -68.311647)
			(xy 326.931528 -68.302632) (xy 326.931528 -68.235576) (xy 326.931177 -68.226559) (xy 326.924925 -68.209642)
			(xy 326.919336 -68.202556) (xy 326.919082 -68.202556) (xy 326.919082 -68.202302) (xy 326.901428 -68.181382)
			(xy 326.871719 -68.135406) (xy 326.848886 -68.085655) (xy 326.833398 -68.033152) (xy 326.825574 -67.978974)
			(xy 326.825102 -67.951604) (xy 326.825559 -67.924351) (xy 326.833316 -67.870399) (xy 326.848672 -67.818101)
			(xy 326.871315 -67.76852) (xy 326.900783 -67.722666) (xy 326.936477 -67.681473) (xy 326.977671 -67.645779)
			(xy 327.023525 -67.616312) (xy 327.073106 -67.59367) (xy 327.125405 -67.578314) (xy 327.179357 -67.570559)
			(xy 327.20661 -67.570096) (xy 327.232924 -67.570558) (xy 327.285053 -67.577794) (xy 327.335696 -67.592114)
			(xy 327.383895 -67.613248) (xy 327.428738 -67.640795) (xy 327.469377 -67.674234) (xy 327.487534 -67.693286)
			(xy 327.495043 -67.700703) (xy 327.514333 -67.709219) (xy 327.524872 -67.709796) (xy 327.599548 -67.709796)
			(xy 327.610096 -67.709254) (xy 327.629392 -67.700728) (xy 327.636886 -67.693286) (xy 327.655053 -67.674242)
			(xy 327.69568 -67.640784) (xy 327.740518 -67.613224) (xy 327.788717 -67.592084) (xy 327.839362 -67.577764)
			(xy 327.891495 -67.570536) (xy 327.91781 -67.570096) (xy 327.94518 -67.570557) (xy 327.99936 -67.578376)
			(xy 328.051863 -67.593867) (xy 328.10161 -67.616709) (xy 328.147576 -67.646435) (xy 328.168508 -67.664076)
			(xy 328.168762 -67.66433) (xy 328.175853 -67.66991) (xy 328.192766 -67.67616) (xy 328.201782 -67.676522)
			(xy 328.268838 -67.676522) (xy 328.277856 -67.676179) (xy 328.294773 -67.669921) (xy 328.301858 -67.66433)
			(xy 328.301858 -67.664076) (xy 328.302112 -67.664076) (xy 328.323063 -67.646461) (xy 328.369031 -67.616746)
			(xy 328.418774 -67.593906) (xy 328.47127 -67.578409) (xy 328.525442 -67.570574) (xy 328.55281 -67.570096)
			(xy 328.578899 -67.570513) (xy 328.630589 -67.577625) (xy 328.680828 -67.591715) (xy 328.728678 -67.61252)
			(xy 328.751184 -67.625722) (xy 328.76363 -67.633342) (xy 328.792078 -67.633088) (xy 328.893678 -67.569842)
			(xy 328.906378 -67.543934) (xy 328.905108 -67.52971) (xy 328.90333 -67.488054) (xy 328.903831 -67.458091)
			(xy 328.911659 -67.398677) (xy 328.927174 -67.340793) (xy 328.950112 -67.28543) (xy 328.980079 -67.233534)
			(xy 329.016564 -67.185994) (xy 329.058942 -67.143622) (xy 329.106488 -67.107144) (xy 329.158388 -67.077183)
			(xy 329.213754 -67.054253) (xy 329.27164 -67.038746) (xy 329.331055 -67.030927) (xy 329.390981 -67.030929)
			(xy 329.450395 -67.038753) (xy 329.50828 -67.054265) (xy 329.563645 -67.077199) (xy 329.615542 -67.107164)
			(xy 329.663085 -67.143646) (xy 329.70546 -67.186021) (xy 329.741941 -67.233564) (xy 329.771904 -67.285462)
			(xy 329.794838 -67.340828) (xy 329.810348 -67.398712) (xy 329.818171 -67.458127) (xy 329.818173 -67.518053)
			(xy 329.811657 -67.567552) (xy 330.195918 -67.567552) (xy 330.195918 -67.507616) (xy 330.203741 -67.448194)
			(xy 330.219254 -67.390301) (xy 330.24219 -67.334928) (xy 330.272157 -67.283022) (xy 330.308644 -67.235472)
			(xy 330.351024 -67.193092) (xy 330.398574 -67.156605) (xy 330.45048 -67.126638) (xy 330.505853 -67.103702)
			(xy 330.563746 -67.088189) (xy 330.623168 -67.080366) (xy 330.683104 -67.080366) (xy 330.742526 -67.088189)
			(xy 330.800419 -67.103702) (xy 330.855792 -67.126638) (xy 330.907698 -67.156605) (xy 330.955248 -67.193092)
			(xy 330.997628 -67.235472) (xy 331.034115 -67.283022) (xy 331.064082 -67.334928) (xy 331.087018 -67.390301)
			(xy 331.102531 -67.448194) (xy 331.110354 -67.507616) (xy 331.110844 -67.537584) (xy 331.110354 -67.567552)
			(xy 331.103064 -67.622924) (xy 331.469982 -67.622924) (xy 331.469982 -67.562988) (xy 331.477805 -67.503566)
			(xy 331.493318 -67.445673) (xy 331.516254 -67.3903) (xy 331.546221 -67.338394) (xy 331.582708 -67.290844)
			(xy 331.625088 -67.248464) (xy 331.672638 -67.211977) (xy 331.724544 -67.18201) (xy 331.779917 -67.159074)
			(xy 331.83781 -67.143561) (xy 331.897232 -67.135738) (xy 331.957168 -67.135738) (xy 332.01659 -67.143561)
			(xy 332.074483 -67.159074) (xy 332.129856 -67.18201) (xy 332.181762 -67.211977) (xy 332.229312 -67.248464)
			(xy 332.271692 -67.290844) (xy 332.308179 -67.338394) (xy 332.338146 -67.3903) (xy 332.361082 -67.445673)
			(xy 332.376595 -67.503566) (xy 332.384418 -67.562988) (xy 332.384452 -67.565051) (xy 334.646493 -67.565051)
			(xy 334.646493 -67.510549) (xy 334.65425 -67.456601) (xy 334.669606 -67.404307) (xy 334.692248 -67.35473)
			(xy 334.721715 -67.30888) (xy 334.757408 -67.267691) (xy 334.798599 -67.232001) (xy 334.844451 -67.202536)
			(xy 334.894029 -67.179897) (xy 334.946325 -67.164545) (xy 335.000273 -67.156792) (xy 335.027524 -67.15633)
			(xy 335.054895 -67.156775) (xy 335.109075 -67.164597) (xy 335.161579 -67.18009) (xy 335.211326 -67.202937)
			(xy 335.257291 -67.232666) (xy 335.278222 -67.25031) (xy 335.278476 -67.250564) (xy 335.28556 -67.256154)
			(xy 335.302479 -67.262397) (xy 335.311496 -67.262756) (xy 335.378552 -67.262756) (xy 335.387568 -67.262386)
			(xy 335.404485 -67.256148) (xy 335.411572 -67.250564) (xy 335.411572 -67.25031) (xy 335.411826 -67.25031)
			(xy 335.432776 -67.232694) (xy 335.478744 -67.202978) (xy 335.528487 -67.180138) (xy 335.580984 -67.164641)
			(xy 335.635156 -67.156807) (xy 335.662524 -67.15633) (xy 335.689777 -67.156742) (xy 335.743727 -67.164502)
			(xy 335.796024 -67.17986) (xy 335.845604 -67.202505) (xy 335.891456 -67.231975) (xy 335.932647 -67.26767)
			(xy 335.968339 -67.308864) (xy 335.997806 -67.354718) (xy 336.003135 -67.366388) (xy 342.116408 -67.366388)
			(xy 342.120479 -67.310766) (xy 342.132605 -67.256329) (xy 342.152528 -67.204238) (xy 342.179824 -67.155603)
			(xy 342.21391 -67.11146) (xy 342.254059 -67.072751) (xy 342.299417 -67.0403) (xy 342.349017 -67.014799)
			(xy 342.401801 -66.996792) (xy 342.456644 -66.986662) (xy 342.512378 -66.984625) (xy 342.567815 -66.990725)
			(xy 342.621772 -67.004831) (xy 342.673101 -67.026643) (xy 342.720707 -67.055697) (xy 342.763575 -67.091372)
			(xy 342.797244 -67.128949) (xy 362.666798 -67.128949) (xy 362.666798 -67.074451) (xy 362.674554 -67.020507)
			(xy 362.689908 -66.968216) (xy 362.712547 -66.918642) (xy 362.74201 -66.872795) (xy 362.777699 -66.831607)
			(xy 362.818885 -66.795918) (xy 362.864732 -66.766452) (xy 362.914305 -66.743812) (xy 362.966595 -66.728457)
			(xy 363.020539 -66.720699) (xy 363.047788 -66.720212) (xy 363.075158 -66.720682) (xy 363.129337 -66.728499)
			(xy 363.18184 -66.743987) (xy 363.231587 -66.766827) (xy 363.277554 -66.796551) (xy 363.298486 -66.814192)
			(xy 363.29874 -66.814446) (xy 363.305836 -66.820019) (xy 363.322746 -66.826273) (xy 363.33176 -66.826638)
			(xy 363.398816 -66.826638) (xy 363.407833 -66.826281) (xy 363.424749 -66.820032) (xy 363.431836 -66.814446)
			(xy 363.431836 -66.814192) (xy 363.43209 -66.814192) (xy 363.453014 -66.796543) (xy 363.498989 -66.766833)
			(xy 363.548739 -66.743999) (xy 363.601241 -66.72851) (xy 363.655418 -66.720685) (xy 363.682788 -66.720212)
			(xy 363.710043 -66.720634) (xy 363.763998 -66.72839) (xy 363.8163 -66.743746) (xy 363.865884 -66.766389)
			(xy 363.911741 -66.795858) (xy 363.952938 -66.831554) (xy 363.988635 -66.872749) (xy 364.018105 -66.918605)
			(xy 364.04075 -66.968189) (xy 364.056107 -67.02049) (xy 364.063865 -67.074445) (xy 364.063865 -67.128955)
			(xy 364.056107 -67.18291) (xy 364.04075 -67.235211) (xy 364.018105 -67.284795) (xy 363.988635 -67.330651)
			(xy 363.952938 -67.371846) (xy 363.911741 -67.407542) (xy 363.865884 -67.437011) (xy 363.8163 -67.459654)
			(xy 363.763998 -67.47501) (xy 363.710043 -67.482766) (xy 363.682788 -67.483228) (xy 363.655417 -67.482787)
			(xy 363.601236 -67.474965) (xy 363.548732 -67.459472) (xy 363.498985 -67.436624) (xy 363.45302 -67.406893)
			(xy 363.43209 -67.389248) (xy 363.431836 -67.388994) (xy 363.424744 -67.383416) (xy 363.407831 -67.377164)
			(xy 363.398816 -67.376802) (xy 363.33176 -67.376802) (xy 363.322741 -67.37714) (xy 363.305824 -67.383401)
			(xy 363.29874 -67.388994) (xy 363.29874 -67.389248) (xy 363.298486 -67.389248) (xy 363.277526 -67.406852)
			(xy 363.231561 -67.436571) (xy 363.181821 -67.459415) (xy 363.129326 -67.474914) (xy 363.075155 -67.48275)
			(xy 363.047788 -67.483228) (xy 363.020539 -67.482701) (xy 362.966595 -67.474943) (xy 362.914305 -67.459588)
			(xy 362.864732 -67.436948) (xy 362.818885 -67.407482) (xy 362.777699 -67.371793) (xy 362.74201 -67.330605)
			(xy 362.712547 -67.284758) (xy 362.689908 -67.235184) (xy 362.674554 -67.182893) (xy 362.666798 -67.128949)
			(xy 342.797244 -67.128949) (xy 342.800792 -67.132909) (xy 342.831565 -67.179422) (xy 342.855237 -67.229919)
			(xy 342.871305 -67.283326) (xy 342.879425 -67.338502) (xy 342.879934 -67.366388) (xy 342.879425 -67.394274)
			(xy 342.871305 -67.44945) (xy 342.855237 -67.502857) (xy 342.831565 -67.553354) (xy 342.800792 -67.599867)
			(xy 342.763575 -67.641404) (xy 342.720707 -67.677079) (xy 342.673101 -67.706133) (xy 342.621772 -67.727945)
			(xy 342.567815 -67.742051) (xy 342.512378 -67.748151) (xy 342.456644 -67.746114) (xy 342.401801 -67.735984)
			(xy 342.349017 -67.717977) (xy 342.299417 -67.692476) (xy 342.254059 -67.660025) (xy 342.21391 -67.621316)
			(xy 342.179824 -67.577173) (xy 342.152528 -67.528538) (xy 342.132605 -67.476447) (xy 342.120479 -67.42201)
			(xy 342.116408 -67.366388) (xy 336.003135 -67.366388) (xy 336.020448 -67.404298) (xy 336.035804 -67.456596)
			(xy 336.04356 -67.510547) (xy 336.04356 -67.565053) (xy 336.035804 -67.619004) (xy 336.020448 -67.671302)
			(xy 335.997806 -67.720882) (xy 335.968339 -67.766736) (xy 335.932647 -67.80793) (xy 335.891456 -67.843625)
			(xy 335.845604 -67.873095) (xy 335.796024 -67.89574) (xy 335.743727 -67.911098) (xy 335.689777 -67.918858)
			(xy 335.662524 -67.919346) (xy 335.635154 -67.918879) (xy 335.580974 -67.911063) (xy 335.52847 -67.895575)
			(xy 335.478724 -67.872733) (xy 335.432757 -67.843008) (xy 335.411826 -67.825366) (xy 335.411572 -67.825112)
			(xy 335.404468 -67.819551) (xy 335.387565 -67.813288) (xy 335.378552 -67.81292) (xy 335.311496 -67.81292)
			(xy 335.302478 -67.813271) (xy 335.285561 -67.819522) (xy 335.278476 -67.825112) (xy 335.278476 -67.825366)
			(xy 335.278222 -67.825366) (xy 335.257288 -67.843003) (xy 335.211316 -67.872716) (xy 335.161569 -67.895553)
			(xy 335.109069 -67.911045) (xy 335.054893 -67.918872) (xy 335.027524 -67.919346) (xy 335.000273 -67.918808)
			(xy 334.946325 -67.911055) (xy 334.894029 -67.895703) (xy 334.844451 -67.873064) (xy 334.798599 -67.843599)
			(xy 334.757408 -67.807909) (xy 334.721715 -67.76672) (xy 334.692248 -67.72087) (xy 334.669606 -67.671293)
			(xy 334.65425 -67.618999) (xy 334.646493 -67.565051) (xy 332.384452 -67.565051) (xy 332.384908 -67.592956)
			(xy 332.384418 -67.622924) (xy 332.376595 -67.682346) (xy 332.361082 -67.740239) (xy 332.338146 -67.795612)
			(xy 332.308179 -67.847518) (xy 332.271692 -67.895068) (xy 332.229312 -67.937448) (xy 332.181762 -67.973935)
			(xy 332.129856 -68.003902) (xy 332.074483 -68.026838) (xy 332.01659 -68.042351) (xy 331.957168 -68.050174)
			(xy 331.897232 -68.050174) (xy 331.83781 -68.042351) (xy 331.779917 -68.026838) (xy 331.724544 -68.003902)
			(xy 331.672638 -67.973935) (xy 331.625088 -67.937448) (xy 331.582708 -67.895068) (xy 331.546221 -67.847518)
			(xy 331.516254 -67.795612) (xy 331.493318 -67.740239) (xy 331.477805 -67.682346) (xy 331.469982 -67.622924)
			(xy 331.103064 -67.622924) (xy 331.102531 -67.626974) (xy 331.087018 -67.684867) (xy 331.064082 -67.74024)
			(xy 331.034115 -67.792146) (xy 330.997628 -67.839696) (xy 330.955248 -67.882076) (xy 330.907698 -67.918563)
			(xy 330.855792 -67.94853) (xy 330.800419 -67.971466) (xy 330.742526 -67.986979) (xy 330.683104 -67.994802)
			(xy 330.623168 -67.994802) (xy 330.563746 -67.986979) (xy 330.505853 -67.971466) (xy 330.45048 -67.94853)
			(xy 330.398574 -67.918563) (xy 330.351024 -67.882076) (xy 330.308644 -67.839696) (xy 330.272157 -67.792146)
			(xy 330.24219 -67.74024) (xy 330.219254 -67.684867) (xy 330.203741 -67.626974) (xy 330.195918 -67.567552)
			(xy 329.811657 -67.567552) (xy 329.810352 -67.577468) (xy 329.794844 -67.635353) (xy 329.771913 -67.69072)
			(xy 329.741952 -67.742619) (xy 329.705473 -67.790164) (xy 329.6631 -67.832541) (xy 329.615559 -67.869025)
			(xy 329.563663 -67.898992) (xy 329.508299 -67.921929) (xy 329.450415 -67.937443) (xy 329.391001 -67.94527)
			(xy 329.361038 -67.945762) (xy 329.33262 -67.945358) (xy 329.27622 -67.938323) (xy 329.221125 -67.924358)
			(xy 329.168185 -67.903676) (xy 329.118213 -67.876598) (xy 329.094846 -67.860418) (xy 329.083162 -67.852036)
			(xy 329.054714 -67.850004) (xy 328.961496 -67.899026) (xy 328.953409 -67.903752) (xy 328.941067 -67.917821)
			(xy 328.934602 -67.935383) (xy 328.934318 -67.944746) (xy 328.934318 -67.951604) (xy 328.933874 -67.978975)
			(xy 328.926054 -68.033156) (xy 328.910561 -68.08566) (xy 328.887714 -68.135407) (xy 328.857983 -68.181372)
			(xy 328.840338 -68.202302) (xy 328.840084 -68.202556) (xy 328.834508 -68.20965) (xy 328.828255 -68.226561)
			(xy 328.827892 -68.235576) (xy 328.827892 -68.302632) (xy 328.828236 -68.31165) (xy 328.834493 -68.328567)
			(xy 328.840084 -68.335652) (xy 328.840338 -68.335652) (xy 328.840338 -68.335906) (xy 328.858 -68.35682)
			(xy 328.887707 -68.402798) (xy 328.910538 -68.45255) (xy 328.926024 -68.505055) (xy 328.933847 -68.559234)
			(xy 328.934318 -68.586604) (xy 328.933826 -68.613855) (xy 328.926069 -68.667802) (xy 328.910714 -68.720096)
			(xy 328.894075 -68.75653) (xy 332.370176 -68.75653) (xy 332.370641 -68.72916) (xy 332.378456 -68.67498)
			(xy 332.393945 -68.622476) (xy 332.416787 -68.572729) (xy 332.446513 -68.526763) (xy 332.464156 -68.505832)
			(xy 332.46441 -68.505578) (xy 332.470013 -68.498503) (xy 332.47625 -68.481577) (xy 332.476602 -68.472558)
			(xy 332.476602 -68.405502) (xy 332.476244 -68.396485) (xy 332.469997 -68.379568) (xy 332.46441 -68.372482)
			(xy 332.464156 -68.372482) (xy 332.464156 -68.372228) (xy 332.446509 -68.351302) (xy 332.4168 -68.305327)
			(xy 332.393966 -68.255578) (xy 332.378477 -68.203076) (xy 332.370649 -68.148899) (xy 332.370176 -68.12153)
			(xy 332.370683 -68.094279) (xy 332.378436 -68.04033) (xy 332.393787 -67.988034) (xy 332.416425 -67.938455)
			(xy 332.445888 -67.892603) (xy 332.481577 -67.85141) (xy 332.522766 -67.815716) (xy 332.568615 -67.786247)
			(xy 332.618191 -67.763603) (xy 332.670485 -67.748245) (xy 332.724433 -67.740486) (xy 332.751684 -67.740022)
			(xy 332.779054 -67.740492) (xy 332.833233 -67.748308) (xy 332.885737 -67.763796) (xy 332.935483 -67.786637)
			(xy 332.98145 -67.816361) (xy 333.002382 -67.834002) (xy 333.002636 -67.834256) (xy 333.009732 -67.839829)
			(xy 333.026642 -67.846082) (xy 333.035656 -67.846448) (xy 333.102712 -67.846448) (xy 333.111731 -67.846108)
			(xy 333.128648 -67.83985) (xy 333.135732 -67.834256) (xy 333.135732 -67.834002) (xy 333.135986 -67.834002)
			(xy 333.156913 -67.816356) (xy 333.202887 -67.786645) (xy 333.252636 -67.763811) (xy 333.305138 -67.748321)
			(xy 333.359314 -67.740495) (xy 333.386684 -67.740022) (xy 333.412998 -67.740493) (xy 333.465127 -67.747726)
			(xy 333.515769 -67.762044) (xy 333.563969 -67.783176) (xy 333.608812 -67.810722) (xy 333.649452 -67.84416)
			(xy 333.667608 -67.863212) (xy 333.675123 -67.870621) (xy 333.694408 -67.879141) (xy 333.704946 -67.879722)
			(xy 333.779622 -67.879722) (xy 333.790167 -67.879158) (xy 333.809463 -67.870647) (xy 333.81696 -67.863212)
			(xy 333.835096 -67.844137) (xy 333.875729 -67.810681) (xy 333.920574 -67.783124) (xy 333.968779 -67.761989)
			(xy 334.01943 -67.747676) (xy 334.071567 -67.740457) (xy 334.097884 -67.740022) (xy 334.125138 -67.74047)
			(xy 334.179091 -67.748226) (xy 334.231391 -67.763581) (xy 334.280973 -67.786224) (xy 334.326828 -67.815693)
			(xy 334.368021 -67.851389) (xy 334.403715 -67.892584) (xy 334.433183 -67.938439) (xy 334.455824 -67.988022)
			(xy 334.471177 -68.040323) (xy 334.478931 -68.094276) (xy 334.479392 -68.12153) (xy 334.478945 -68.148901)
			(xy 334.471123 -68.203081) (xy 334.45563 -68.255584) (xy 334.432784 -68.305331) (xy 334.403055 -68.351297)
			(xy 334.385412 -68.372228) (xy 334.385158 -68.372482) (xy 334.379568 -68.379566) (xy 334.373324 -68.396485)
			(xy 334.372966 -68.405502) (xy 334.372966 -68.472558) (xy 334.37335 -68.481572) (xy 334.37958 -68.498489)
			(xy 334.385158 -68.505578) (xy 334.385412 -68.505578) (xy 334.385412 -68.505832) (xy 334.403035 -68.526777)
			(xy 334.432748 -68.572747) (xy 334.455587 -68.622491) (xy 334.471082 -68.674989) (xy 334.478915 -68.729162)
			(xy 334.479392 -68.75653) (xy 334.47895 -68.783783) (xy 334.471189 -68.837733) (xy 334.455829 -68.890029)
			(xy 334.433183 -68.939608) (xy 334.403713 -68.985459) (xy 334.368017 -69.026649) (xy 334.326822 -69.06234)
			(xy 334.280967 -69.091806) (xy 334.231386 -69.114445) (xy 334.179088 -69.129799) (xy 334.125137 -69.137553)
			(xy 334.097884 -69.138038) (xy 334.071569 -69.137601) (xy 334.019438 -69.130363) (xy 333.968794 -69.116039)
			(xy 333.920595 -69.094901) (xy 333.875752 -69.067349) (xy 333.835115 -69.033903) (xy 333.81696 -69.014848)
			(xy 333.809449 -69.007434) (xy 333.790161 -68.998915) (xy 333.779622 -68.998338) (xy 333.704946 -68.998338)
			(xy 333.694396 -68.998867) (xy 333.6751 -69.007401) (xy 333.667608 -69.014848) (xy 333.649451 -69.033902)
			(xy 333.60882 -69.067357) (xy 333.56398 -69.094915) (xy 333.51578 -69.116054) (xy 333.465133 -69.130372)
			(xy 333.413 -69.137598) (xy 333.386684 -69.138038) (xy 333.359313 -69.137596) (xy 333.305132 -69.129775)
			(xy 333.252628 -69.114281) (xy 333.202881 -69.091433) (xy 333.156916 -69.061703) (xy 333.135986 -69.044058)
			(xy 333.135732 -69.043804) (xy 333.12864 -69.038225) (xy 333.111727 -69.031974) (xy 333.102712 -69.031612)
			(xy 333.035656 -69.031612) (xy 333.026642 -69.031993) (xy 333.009724 -69.038224) (xy 333.002636 -69.043804)
			(xy 333.002636 -69.044058) (xy 333.002382 -69.044058) (xy 332.981424 -69.061666) (xy 332.935459 -69.091384)
			(xy 332.885718 -69.114226) (xy 332.833223 -69.129725) (xy 332.779052 -69.13756) (xy 332.751684 -69.138038)
			(xy 332.724434 -69.137537) (xy 332.670488 -69.129779) (xy 332.618195 -69.114424) (xy 332.56862 -69.091783)
			(xy 332.522771 -69.062318) (xy 332.481582 -69.026628) (xy 332.445891 -68.98544) (xy 332.416424 -68.939592)
			(xy 332.393781 -68.890018) (xy 332.378424 -68.837726) (xy 332.370664 -68.78378) (xy 332.370176 -68.75653)
			(xy 328.894075 -68.75653) (xy 328.888073 -68.769672) (xy 328.858607 -68.815522) (xy 328.822917 -68.856712)
			(xy 328.781727 -68.892404) (xy 328.735878 -68.92187) (xy 328.686302 -68.944512) (xy 328.634008 -68.959868)
			(xy 328.580061 -68.967626) (xy 328.55281 -68.968112) (xy 328.52544 -68.967637) (xy 328.471262 -68.959821)
			(xy 328.418759 -68.944334) (xy 328.369012 -68.921494) (xy 328.323044 -68.891772) (xy 328.302112 -68.874132)
			(xy 328.301858 -68.873878) (xy 328.294761 -68.868307) (xy 328.277852 -68.862052) (xy 328.268838 -68.861686)
			(xy 328.201782 -68.861686) (xy 328.192765 -68.862038) (xy 328.175848 -68.868289) (xy 328.168762 -68.873878)
			(xy 328.168762 -68.874132) (xy 328.168508 -68.874132) (xy 328.147588 -68.891786) (xy 328.101611 -68.921494)
			(xy 328.051861 -68.944327) (xy 327.999358 -68.959815) (xy 327.94518 -68.96764) (xy 327.91781 -68.968112)
			(xy 327.891496 -68.967634) (xy 327.839369 -68.960401) (xy 327.788726 -68.946084) (xy 327.740527 -68.924953)
			(xy 327.695683 -68.897409) (xy 327.655043 -68.863972) (xy 327.636886 -68.844922) (xy 327.629369 -68.837515)
			(xy 327.610086 -68.828993) (xy 327.599548 -68.828412) (xy 327.524872 -68.828412) (xy 327.514325 -68.828963)
			(xy 327.495029 -68.837483) (xy 327.487534 -68.844922) (xy 327.469408 -68.864007) (xy 327.428771 -68.89746)
			(xy 327.383925 -68.925015) (xy 327.335718 -68.946148) (xy 327.285066 -68.960459) (xy 327.232928 -68.967677)
			(xy 327.20661 -68.968112) (xy 327.179358 -68.967635) (xy 327.125407 -68.95988) (xy 327.07311 -68.944525)
			(xy 327.02353 -68.921884) (xy 326.977677 -68.892418) (xy 326.936485 -68.856725) (xy 326.900791 -68.815534)
			(xy 326.871322 -68.769682) (xy 326.84868 -68.720103) (xy 326.833323 -68.667806) (xy 326.825566 -68.613856)
			(xy 326.825102 -68.586604) (xy 308.439157 -68.586604) (xy 308.455637 -68.622493) (xy 308.471133 -68.674989)
			(xy 308.478967 -68.729162) (xy 308.479444 -68.75653) (xy 308.47895 -68.78378) (xy 308.471191 -68.837726)
			(xy 308.455833 -68.890018) (xy 308.433191 -68.939593) (xy 308.403725 -68.985442) (xy 308.368035 -69.026631)
			(xy 308.326847 -69.062322) (xy 308.280999 -69.091789) (xy 308.231424 -69.114431) (xy 308.179132 -69.129789)
			(xy 308.125186 -69.13755) (xy 308.097936 -69.138038) (xy 308.07162 -69.137633) (xy 308.019488 -69.130388)
			(xy 307.968843 -69.116058) (xy 307.920644 -69.094914) (xy 307.875802 -69.067356) (xy 307.835166 -69.033905)
			(xy 307.817012 -69.014848) (xy 307.809481 -69.007457) (xy 307.790208 -68.998925) (xy 307.779674 -68.998338)
			(xy 307.704998 -68.998338) (xy 307.694445 -68.998841) (xy 307.675149 -69.007393) (xy 307.66766 -69.014848)
			(xy 307.649526 -69.033925) (xy 307.608891 -69.067378) (xy 307.564046 -69.094933) (xy 307.515841 -69.116068)
			(xy 307.46519 -69.130381) (xy 307.413053 -69.137602) (xy 307.386736 -69.138038) (xy 307.359366 -69.137566)
			(xy 307.305186 -69.129752) (xy 307.252683 -69.114265) (xy 307.202936 -69.091424) (xy 307.156969 -69.0617)
			(xy 307.136038 -69.044058) (xy 307.135784 -69.043804) (xy 307.128706 -69.038205) (xy 307.111783 -69.031966)
			(xy 307.102764 -69.031612) (xy 307.035708 -69.031612) (xy 307.026691 -69.03197) (xy 307.009774 -69.038217)
			(xy 307.002688 -69.043804) (xy 307.002688 -69.044058) (xy 307.002434 -69.044058) (xy 306.981495 -69.061688)
			(xy 306.935524 -69.091403) (xy 306.885779 -69.114241) (xy 306.83328 -69.129734) (xy 306.779105 -69.137564)
			(xy 306.751736 -69.138038) (xy 306.724485 -69.137511) (xy 306.670538 -69.12976) (xy 306.618243 -69.11441)
			(xy 306.568665 -69.091774) (xy 306.522814 -69.062312) (xy 306.481621 -69.026625) (xy 306.445927 -68.985439)
			(xy 306.416458 -68.939593) (xy 306.393813 -68.890018) (xy 306.378454 -68.837726) (xy 306.370693 -68.783781)
			(xy 306.370228 -68.75653) (xy 302.894199 -68.75653) (xy 302.888186 -68.769697) (xy 302.858714 -68.815552)
			(xy 302.823015 -68.856745) (xy 302.781818 -68.892439) (xy 302.73596 -68.921906) (xy 302.686375 -68.944546)
			(xy 302.634072 -68.959899) (xy 302.580117 -68.967651) (xy 302.552862 -68.968112) (xy 302.525493 -68.967607)
			(xy 302.471316 -68.959798) (xy 302.418813 -68.944318) (xy 302.369066 -68.921485) (xy 302.323097 -68.891769)
			(xy 302.302164 -68.874132) (xy 302.30191 -68.873878) (xy 302.294827 -68.868287) (xy 302.277907 -68.862044)
			(xy 302.26889 -68.861686) (xy 302.201834 -68.861686) (xy 302.192819 -68.862062) (xy 302.175902 -68.868297)
			(xy 302.168814 -68.873878) (xy 302.168814 -68.874132) (xy 302.16856 -68.874132) (xy 302.14762 -68.891761)
			(xy 302.101649 -68.921474) (xy 302.051903 -68.944311) (xy 301.999405 -68.959804) (xy 301.945231 -68.967636)
			(xy 301.917862 -68.968112) (xy 301.891547 -68.967666) (xy 301.839418 -68.960426) (xy 301.788775 -68.946103)
			(xy 301.740576 -68.924966) (xy 301.695733 -68.897417) (xy 301.655094 -68.863975) (xy 301.636938 -68.844922)
			(xy 301.629401 -68.837538) (xy 301.610133 -68.829003) (xy 301.5996 -68.828412) (xy 301.524924 -68.828412)
			(xy 301.514374 -68.828937) (xy 301.495078 -68.837475) (xy 301.487586 -68.844922) (xy 301.469435 -68.863982)
			(xy 301.428803 -68.897437) (xy 301.383962 -68.924995) (xy 301.335761 -68.946133) (xy 301.285113 -68.96045)
			(xy 301.232978 -68.967674) (xy 301.206662 -68.968112) (xy 301.17941 -68.967658) (xy 301.125461 -68.959896)
			(xy 301.073166 -68.944536) (xy 301.023589 -68.921891) (xy 300.977739 -68.892421) (xy 300.936549 -68.856726)
			(xy 300.900859 -68.815534) (xy 300.871393 -68.769681) (xy 300.848752 -68.720102) (xy 300.833397 -68.667805)
			(xy 300.82564 -68.613856) (xy 300.825154 -68.586604) (xy 282.439216 -68.586604) (xy 282.455692 -68.622491)
			(xy 282.471186 -68.674988) (xy 282.479019 -68.729162) (xy 282.479496 -68.75653) (xy 282.47905 -68.783783)
			(xy 282.471289 -68.837732) (xy 282.45593 -68.890029) (xy 282.433284 -68.939607) (xy 282.403814 -68.985457)
			(xy 282.368118 -69.026648) (xy 282.326924 -69.062339) (xy 282.28107 -69.091804) (xy 282.231489 -69.114444)
			(xy 282.179191 -69.129798) (xy 282.125241 -69.137553) (xy 282.097988 -69.138038) (xy 282.071673 -69.137598)
			(xy 282.019542 -69.130361) (xy 281.968898 -69.116037) (xy 281.920699 -69.0949) (xy 281.875856 -69.067348)
			(xy 281.835219 -69.033903) (xy 281.817064 -69.014848) (xy 281.809551 -69.007436) (xy 281.790265 -68.998916)
			(xy 281.779726 -68.998338) (xy 281.70505 -68.998338) (xy 281.6945 -68.998869) (xy 281.675204 -69.007402)
			(xy 281.667712 -69.014848) (xy 281.649553 -69.0339) (xy 281.608923 -69.067356) (xy 281.564083 -69.094914)
			(xy 281.515883 -69.116053) (xy 281.465237 -69.130371) (xy 281.413104 -69.137598) (xy 281.386788 -69.138038)
			(xy 281.359417 -69.137594) (xy 281.305236 -69.129773) (xy 281.252732 -69.11428) (xy 281.202986 -69.091433)
			(xy 281.15702 -69.061702) (xy 281.13609 -69.044058) (xy 281.135836 -69.043804) (xy 281.128743 -69.038227)
			(xy 281.111831 -69.031974) (xy 281.102816 -69.031612) (xy 281.03576 -69.031612) (xy 281.026741 -69.031947)
			(xy 281.009824 -69.03821) (xy 281.00274 -69.043804) (xy 281.00274 -69.044058) (xy 281.002486 -69.044058)
			(xy 280.981527 -69.061664) (xy 280.935562 -69.091382) (xy 280.885822 -69.114225) (xy 280.833327 -69.129724)
			(xy 280.779155 -69.13756) (xy 280.751788 -69.138038) (xy 280.724538 -69.137533) (xy 280.670592 -69.129776)
			(xy 280.6183 -69.114421) (xy 280.568724 -69.091781) (xy 280.522876 -69.062316) (xy 280.481686 -69.026626)
			(xy 280.445995 -68.985439) (xy 280.416528 -68.939591) (xy 280.393885 -68.890017) (xy 280.378528 -68.837725)
			(xy 280.370768 -68.78378) (xy 280.37028 -68.75653) (xy 276.894175 -68.75653) (xy 276.888174 -68.769671)
			(xy 276.858708 -68.815521) (xy 276.823018 -68.856711) (xy 276.781829 -68.892402) (xy 276.73598 -68.921869)
			(xy 276.686404 -68.944511) (xy 276.634111 -68.959867) (xy 276.580165 -68.967625) (xy 276.552914 -68.968112)
			(xy 276.525544 -68.967635) (xy 276.471366 -68.959819) (xy 276.418863 -68.944333) (xy 276.369116 -68.921493)
			(xy 276.323148 -68.891772) (xy 276.302216 -68.874132) (xy 276.301962 -68.873878) (xy 276.294864 -68.868309)
			(xy 276.277956 -68.862052) (xy 276.268942 -68.861686) (xy 276.201886 -68.861686) (xy 276.192869 -68.86204)
			(xy 276.175952 -68.86829) (xy 276.168866 -68.873878) (xy 276.168866 -68.874132) (xy 276.168612 -68.874132)
			(xy 276.14769 -68.891784) (xy 276.101714 -68.921493) (xy 276.051964 -68.944326) (xy 275.999461 -68.959814)
			(xy 275.945284 -68.967639) (xy 275.917914 -68.968112) (xy 275.891601 -68.967631) (xy 275.839473 -68.960399)
			(xy 275.78883 -68.946082) (xy 275.740631 -68.924952) (xy 275.695788 -68.897408) (xy 275.655147 -68.863972)
			(xy 275.63699 -68.844922) (xy 275.629471 -68.837517) (xy 275.610189 -68.828994) (xy 275.599652 -68.828412)
			(xy 275.524976 -68.828412) (xy 275.514429 -68.828965) (xy 275.495133 -68.837483) (xy 275.487638 -68.844922)
			(xy 275.46951 -68.864005) (xy 275.428874 -68.897459) (xy 275.384028 -68.925014) (xy 275.335822 -68.946147)
			(xy 275.285169 -68.960459) (xy 275.233032 -68.967677) (xy 275.206714 -68.968112) (xy 275.179462 -68.967632)
			(xy 275.125512 -68.959877) (xy 275.073214 -68.944523) (xy 275.023634 -68.921882) (xy 274.977781 -68.892416)
			(xy 274.936589 -68.856724) (xy 274.900895 -68.815533) (xy 274.871427 -68.769681) (xy 274.848784 -68.720103)
			(xy 274.833427 -68.667806) (xy 274.82567 -68.613856) (xy 274.825206 -68.586604) (xy 272.408396 -68.586604)
			(xy 272.408396 -68.796408) (xy 272.409412 -68.80606) (xy 272.41104 -68.813304) (xy 272.417881 -68.826473)
			(xy 272.422874 -68.831968) (xy 274.486624 -70.895718) (xy 340.004398 -70.895718) (xy 340.008469 -70.840096)
			(xy 340.020595 -70.785659) (xy 340.040518 -70.733568) (xy 340.067814 -70.684933) (xy 340.1019 -70.64079)
			(xy 340.142049 -70.602081) (xy 340.187407 -70.56963) (xy 340.237007 -70.544129) (xy 340.289791 -70.526122)
			(xy 340.344634 -70.515992) (xy 340.400368 -70.513955) (xy 340.455805 -70.520055) (xy 340.509762 -70.534161)
			(xy 340.561091 -70.555973) (xy 340.608697 -70.585027) (xy 340.651565 -70.620702) (xy 340.688782 -70.662239)
			(xy 340.719555 -70.708752) (xy 340.743227 -70.759249) (xy 340.759295 -70.812656) (xy 340.767415 -70.867832)
			(xy 340.767924 -70.895718) (xy 340.767669 -70.909684) (xy 340.92056 -70.909684) (xy 340.92056 -70.849748)
			(xy 340.928383 -70.790326) (xy 340.943896 -70.732433) (xy 340.966832 -70.67706) (xy 340.996799 -70.625154)
			(xy 341.033286 -70.577604) (xy 341.075666 -70.535224) (xy 341.123216 -70.498737) (xy 341.175122 -70.46877)
			(xy 341.230495 -70.445834) (xy 341.288388 -70.430321) (xy 341.34781 -70.422498) (xy 341.407746 -70.422498)
			(xy 341.467168 -70.430321) (xy 341.525061 -70.445834) (xy 341.580434 -70.46877) (xy 341.63234 -70.498737)
			(xy 341.67989 -70.535224) (xy 341.72227 -70.577604) (xy 341.758757 -70.625154) (xy 341.788724 -70.67706)
			(xy 341.81166 -70.732433) (xy 341.827173 -70.790326) (xy 341.834996 -70.849748) (xy 341.835486 -70.879716)
			(xy 341.834996 -70.909684) (xy 341.827173 -70.969106) (xy 341.81166 -71.026999) (xy 341.788724 -71.082372)
			(xy 341.758757 -71.134278) (xy 341.72227 -71.181828) (xy 341.67989 -71.224208) (xy 341.63234 -71.260695)
			(xy 341.580434 -71.290662) (xy 341.525061 -71.313598) (xy 341.467168 -71.329111) (xy 341.407746 -71.336934)
			(xy 341.34781 -71.336934) (xy 341.288388 -71.329111) (xy 341.230495 -71.313598) (xy 341.175122 -71.290662)
			(xy 341.123216 -71.260695) (xy 341.075666 -71.224208) (xy 341.033286 -71.181828) (xy 340.996799 -71.134278)
			(xy 340.966832 -71.082372) (xy 340.943896 -71.026999) (xy 340.928383 -70.969106) (xy 340.92056 -70.909684)
			(xy 340.767669 -70.909684) (xy 340.767415 -70.923604) (xy 340.759295 -70.97878) (xy 340.743227 -71.032187)
			(xy 340.719555 -71.082684) (xy 340.688782 -71.129197) (xy 340.651565 -71.170734) (xy 340.608697 -71.206409)
			(xy 340.561091 -71.235463) (xy 340.509762 -71.257275) (xy 340.455805 -71.271381) (xy 340.400368 -71.277481)
			(xy 340.344634 -71.275444) (xy 340.289791 -71.265314) (xy 340.237007 -71.247307) (xy 340.187407 -71.221806)
			(xy 340.142049 -71.189355) (xy 340.1019 -71.150646) (xy 340.067814 -71.106503) (xy 340.040518 -71.057868)
			(xy 340.020595 -71.005777) (xy 340.008469 -70.95134) (xy 340.004398 -70.895718) (xy 274.486624 -70.895718)
			(xy 275.176738 -71.585832) (xy 277.319214 -71.585832) (xy 277.319214 -71.525896) (xy 277.327037 -71.466474)
			(xy 277.34255 -71.408581) (xy 277.365486 -71.353208) (xy 277.395453 -71.301302) (xy 277.43194 -71.253752)
			(xy 277.47432 -71.211372) (xy 277.52187 -71.174885) (xy 277.573776 -71.144918) (xy 277.629149 -71.121982)
			(xy 277.687042 -71.106469) (xy 277.746464 -71.098646) (xy 277.8064 -71.098646) (xy 277.865822 -71.106469)
			(xy 277.923715 -71.121982) (xy 277.979088 -71.144918) (xy 278.030994 -71.174885) (xy 278.078544 -71.211372)
			(xy 278.120924 -71.253752) (xy 278.157411 -71.301302) (xy 278.187378 -71.353208) (xy 278.210314 -71.408581)
			(xy 278.225827 -71.466474) (xy 278.23365 -71.525896) (xy 278.23414 -71.555864) (xy 278.23365 -71.585832)
			(xy 278.225827 -71.645254) (xy 278.223645 -71.653396) (xy 278.828228 -71.653396) (xy 278.828228 -71.59346)
			(xy 278.836051 -71.534038) (xy 278.851564 -71.476145) (xy 278.8745 -71.420772) (xy 278.904467 -71.368866)
			(xy 278.940954 -71.321316) (xy 278.983334 -71.278936) (xy 279.030884 -71.242449) (xy 279.08279 -71.212482)
			(xy 279.138163 -71.189546) (xy 279.196056 -71.174033) (xy 279.255478 -71.16621) (xy 279.315414 -71.16621)
			(xy 279.374836 -71.174033) (xy 279.432729 -71.189546) (xy 279.488102 -71.212482) (xy 279.540008 -71.242449)
			(xy 279.587558 -71.278936) (xy 279.629938 -71.321316) (xy 279.666425 -71.368866) (xy 279.696392 -71.420772)
			(xy 279.719328 -71.476145) (xy 279.734841 -71.534038) (xy 279.74166 -71.585832) (xy 303.319162 -71.585832)
			(xy 303.319162 -71.525896) (xy 303.326985 -71.466474) (xy 303.342498 -71.408581) (xy 303.365434 -71.353208)
			(xy 303.395401 -71.301302) (xy 303.431888 -71.253752) (xy 303.474268 -71.211372) (xy 303.521818 -71.174885)
			(xy 303.573724 -71.144918) (xy 303.629097 -71.121982) (xy 303.68699 -71.106469) (xy 303.746412 -71.098646)
			(xy 303.806348 -71.098646) (xy 303.86577 -71.106469) (xy 303.923663 -71.121982) (xy 303.979036 -71.144918)
			(xy 304.030942 -71.174885) (xy 304.078492 -71.211372) (xy 304.120872 -71.253752) (xy 304.157359 -71.301302)
			(xy 304.187326 -71.353208) (xy 304.210262 -71.408581) (xy 304.225775 -71.466474) (xy 304.233598 -71.525896)
			(xy 304.234088 -71.555864) (xy 304.233598 -71.585832) (xy 304.225775 -71.645254) (xy 304.223593 -71.653396)
			(xy 304.828176 -71.653396) (xy 304.828176 -71.59346) (xy 304.835999 -71.534038) (xy 304.851512 -71.476145)
			(xy 304.874448 -71.420772) (xy 304.904415 -71.368866) (xy 304.940902 -71.321316) (xy 304.983282 -71.278936)
			(xy 305.030832 -71.242449) (xy 305.082738 -71.212482) (xy 305.138111 -71.189546) (xy 305.196004 -71.174033)
			(xy 305.255426 -71.16621) (xy 305.315362 -71.16621) (xy 305.374784 -71.174033) (xy 305.432677 -71.189546)
			(xy 305.48805 -71.212482) (xy 305.539956 -71.242449) (xy 305.587506 -71.278936) (xy 305.629886 -71.321316)
			(xy 305.666373 -71.368866) (xy 305.69634 -71.420772) (xy 305.69643 -71.42099) (xy 322.597016 -71.42099)
			(xy 322.601087 -71.365368) (xy 322.613213 -71.310931) (xy 322.633136 -71.25884) (xy 322.660432 -71.210205)
			(xy 322.694518 -71.166062) (xy 322.734667 -71.127353) (xy 322.780025 -71.094902) (xy 322.829625 -71.069401)
			(xy 322.882409 -71.051394) (xy 322.937252 -71.041264) (xy 322.992986 -71.039227) (xy 323.048423 -71.045327)
			(xy 323.10238 -71.059433) (xy 323.153709 -71.081245) (xy 323.201315 -71.110299) (xy 323.244183 -71.145974)
			(xy 323.2814 -71.187511) (xy 323.312173 -71.234024) (xy 323.335845 -71.284521) (xy 323.351913 -71.337928)
			(xy 323.360033 -71.393104) (xy 323.360542 -71.42099) (xy 323.360033 -71.448876) (xy 323.351913 -71.504052)
			(xy 323.335845 -71.557459) (xy 323.322544 -71.585832) (xy 329.31911 -71.585832) (xy 329.31911 -71.525896)
			(xy 329.326933 -71.466474) (xy 329.342446 -71.408581) (xy 329.365382 -71.353208) (xy 329.395349 -71.301302)
			(xy 329.431836 -71.253752) (xy 329.474216 -71.211372) (xy 329.521766 -71.174885) (xy 329.573672 -71.144918)
			(xy 329.629045 -71.121982) (xy 329.686938 -71.106469) (xy 329.74636 -71.098646) (xy 329.806296 -71.098646)
			(xy 329.865718 -71.106469) (xy 329.923611 -71.121982) (xy 329.978984 -71.144918) (xy 330.03089 -71.174885)
			(xy 330.07844 -71.211372) (xy 330.12082 -71.253752) (xy 330.157307 -71.301302) (xy 330.187274 -71.353208)
			(xy 330.21021 -71.408581) (xy 330.225723 -71.466474) (xy 330.233546 -71.525896) (xy 330.234036 -71.555864)
			(xy 330.233546 -71.585832) (xy 330.225723 -71.645254) (xy 330.223541 -71.653396) (xy 330.828124 -71.653396)
			(xy 330.828124 -71.59346) (xy 330.835947 -71.534038) (xy 330.85146 -71.476145) (xy 330.874396 -71.420772)
			(xy 330.904363 -71.368866) (xy 330.94085 -71.321316) (xy 330.98323 -71.278936) (xy 331.03078 -71.242449)
			(xy 331.082686 -71.212482) (xy 331.138059 -71.189546) (xy 331.195952 -71.174033) (xy 331.255374 -71.16621)
			(xy 331.31531 -71.16621) (xy 331.374732 -71.174033) (xy 331.432625 -71.189546) (xy 331.487998 -71.212482)
			(xy 331.539904 -71.242449) (xy 331.587454 -71.278936) (xy 331.629834 -71.321316) (xy 331.666321 -71.368866)
			(xy 331.696288 -71.420772) (xy 331.719224 -71.476145) (xy 331.734737 -71.534038) (xy 331.74256 -71.59346)
			(xy 331.74305 -71.623428) (xy 331.74256 -71.653396) (xy 331.734737 -71.712818) (xy 331.719224 -71.770711)
			(xy 331.696288 -71.826084) (xy 331.666321 -71.87799) (xy 331.629834 -71.92554) (xy 331.587454 -71.96792)
			(xy 331.539904 -72.004407) (xy 331.487998 -72.034374) (xy 331.432625 -72.05731) (xy 331.374732 -72.072823)
			(xy 331.31531 -72.080646) (xy 331.255374 -72.080646) (xy 331.195952 -72.072823) (xy 331.138059 -72.05731)
			(xy 331.082686 -72.034374) (xy 331.03078 -72.004407) (xy 330.98323 -71.96792) (xy 330.94085 -71.92554)
			(xy 330.904363 -71.87799) (xy 330.874396 -71.826084) (xy 330.85146 -71.770711) (xy 330.835947 -71.712818)
			(xy 330.828124 -71.653396) (xy 330.223541 -71.653396) (xy 330.21021 -71.703147) (xy 330.187274 -71.75852)
			(xy 330.157307 -71.810426) (xy 330.12082 -71.857976) (xy 330.07844 -71.900356) (xy 330.03089 -71.936843)
			(xy 329.978984 -71.96681) (xy 329.923611 -71.989746) (xy 329.865718 -72.005259) (xy 329.806296 -72.013082)
			(xy 329.74636 -72.013082) (xy 329.686938 -72.005259) (xy 329.629045 -71.989746) (xy 329.573672 -71.96681)
			(xy 329.521766 -71.936843) (xy 329.474216 -71.900356) (xy 329.431836 -71.857976) (xy 329.395349 -71.810426)
			(xy 329.365382 -71.75852) (xy 329.342446 -71.703147) (xy 329.326933 -71.645254) (xy 329.31911 -71.585832)
			(xy 323.322544 -71.585832) (xy 323.312173 -71.607956) (xy 323.2814 -71.654469) (xy 323.244183 -71.696006)
			(xy 323.201315 -71.731681) (xy 323.153709 -71.760735) (xy 323.10238 -71.782547) (xy 323.048423 -71.796653)
			(xy 322.992986 -71.802753) (xy 322.937252 -71.800716) (xy 322.882409 -71.790586) (xy 322.829625 -71.772579)
			(xy 322.780025 -71.747078) (xy 322.734667 -71.714627) (xy 322.694518 -71.675918) (xy 322.660432 -71.631775)
			(xy 322.633136 -71.58314) (xy 322.613213 -71.531049) (xy 322.601087 -71.476612) (xy 322.597016 -71.42099)
			(xy 305.69643 -71.42099) (xy 305.719276 -71.476145) (xy 305.734789 -71.534038) (xy 305.742612 -71.59346)
			(xy 305.743102 -71.623428) (xy 305.742612 -71.653396) (xy 305.734789 -71.712818) (xy 305.719276 -71.770711)
			(xy 305.69634 -71.826084) (xy 305.666373 -71.87799) (xy 305.629886 -71.92554) (xy 305.587506 -71.96792)
			(xy 305.539956 -72.004407) (xy 305.48805 -72.034374) (xy 305.432677 -72.05731) (xy 305.374784 -72.072823)
			(xy 305.315362 -72.080646) (xy 305.255426 -72.080646) (xy 305.196004 -72.072823) (xy 305.138111 -72.05731)
			(xy 305.082738 -72.034374) (xy 305.030832 -72.004407) (xy 304.983282 -71.96792) (xy 304.940902 -71.92554)
			(xy 304.904415 -71.87799) (xy 304.874448 -71.826084) (xy 304.851512 -71.770711) (xy 304.835999 -71.712818)
			(xy 304.828176 -71.653396) (xy 304.223593 -71.653396) (xy 304.210262 -71.703147) (xy 304.187326 -71.75852)
			(xy 304.157359 -71.810426) (xy 304.120872 -71.857976) (xy 304.078492 -71.900356) (xy 304.030942 -71.936843)
			(xy 303.979036 -71.96681) (xy 303.923663 -71.989746) (xy 303.86577 -72.005259) (xy 303.806348 -72.013082)
			(xy 303.746412 -72.013082) (xy 303.68699 -72.005259) (xy 303.629097 -71.989746) (xy 303.573724 -71.96681)
			(xy 303.521818 -71.936843) (xy 303.474268 -71.900356) (xy 303.431888 -71.857976) (xy 303.395401 -71.810426)
			(xy 303.365434 -71.75852) (xy 303.342498 -71.703147) (xy 303.326985 -71.645254) (xy 303.319162 -71.585832)
			(xy 279.74166 -71.585832) (xy 279.742664 -71.59346) (xy 279.743154 -71.623428) (xy 279.742664 -71.653396)
			(xy 279.734841 -71.712818) (xy 279.719328 -71.770711) (xy 279.696392 -71.826084) (xy 279.666425 -71.87799)
			(xy 279.629938 -71.92554) (xy 279.587558 -71.96792) (xy 279.540008 -72.004407) (xy 279.488102 -72.034374)
			(xy 279.432729 -72.05731) (xy 279.374836 -72.072823) (xy 279.315414 -72.080646) (xy 279.255478 -72.080646)
			(xy 279.196056 -72.072823) (xy 279.138163 -72.05731) (xy 279.08279 -72.034374) (xy 279.030884 -72.004407)
			(xy 278.983334 -71.96792) (xy 278.940954 -71.92554) (xy 278.904467 -71.87799) (xy 278.8745 -71.826084)
			(xy 278.851564 -71.770711) (xy 278.836051 -71.712818) (xy 278.828228 -71.653396) (xy 278.223645 -71.653396)
			(xy 278.210314 -71.703147) (xy 278.187378 -71.75852) (xy 278.157411 -71.810426) (xy 278.120924 -71.857976)
			(xy 278.078544 -71.900356) (xy 278.030994 -71.936843) (xy 277.979088 -71.96681) (xy 277.923715 -71.989746)
			(xy 277.865822 -72.005259) (xy 277.8064 -72.013082) (xy 277.746464 -72.013082) (xy 277.687042 -72.005259)
			(xy 277.629149 -71.989746) (xy 277.573776 -71.96681) (xy 277.52187 -71.936843) (xy 277.47432 -71.900356)
			(xy 277.43194 -71.857976) (xy 277.395453 -71.810426) (xy 277.365486 -71.75852) (xy 277.34255 -71.703147)
			(xy 277.327037 -71.645254) (xy 277.319214 -71.585832) (xy 275.176738 -71.585832) (xy 275.794216 -72.20331)
			(xy 275.80463 -72.20712) (xy 275.830377 -72.217081) (xy 275.878927 -72.243357) (xy 275.923183 -72.276356)
			(xy 275.96222 -72.31539) (xy 275.995224 -72.359643) (xy 276.021505 -72.40819) (xy 276.031452 -72.433942)
			(xy 276.035262 -72.444356) (xy 276.290786 -72.69988) (xy 344.768177 -72.69988) (xy 344.772183 -72.49714)
			(xy 344.784196 -72.294716) (xy 344.804197 -72.092925) (xy 344.832154 -71.892081) (xy 344.868023 -71.692499)
			(xy 344.91175 -71.49449) (xy 344.963265 -71.298362) (xy 345.022488 -71.104424) (xy 345.089327 -70.912976)
			(xy 345.163678 -70.724318) (xy 345.245423 -70.538745) (xy 345.334436 -70.356546) (xy 345.430577 -70.178006)
			(xy 345.533697 -70.003404) (xy 345.643634 -69.833011) (xy 345.760218 -69.667096) (xy 345.883264 -69.505915)
			(xy 346.012583 -69.349722) (xy 346.147971 -69.198759) (xy 346.289218 -69.053263) (xy 346.436102 -68.913461)
			(xy 346.588395 -68.77957) (xy 346.745858 -68.651801) (xy 346.908247 -68.530353) (xy 347.075306 -68.415414)
			(xy 347.246776 -68.307166) (xy 347.422389 -68.205776) (xy 347.60187 -68.111403) (xy 347.784939 -68.024194)
			(xy 347.971311 -67.944286) (xy 348.160694 -67.871803) (xy 348.352792 -67.806859) (xy 348.547307 -67.749554)
			(xy 348.743934 -67.699979) (xy 348.942365 -67.658211) (xy 349.142292 -67.624315) (xy 349.343402 -67.598343)
			(xy 349.545381 -67.580337) (xy 349.747913 -67.570325) (xy 349.950683 -67.568321) (xy 350.153374 -67.57433)
			(xy 350.35567 -67.588342) (xy 350.557253 -67.610335) (xy 350.757811 -67.640275) (xy 350.957029 -67.678115)
			(xy 351.154597 -67.723796) (xy 351.350205 -67.777246) (xy 351.54355 -67.838382) (xy 351.734328 -67.907109)
			(xy 351.922242 -67.983319) (xy 352.106998 -68.066894) (xy 352.288309 -68.157702) (xy 352.465891 -68.255603)
			(xy 352.639466 -68.360443) (xy 352.808763 -68.472058) (xy 352.968403 -68.586604) (xy 364.925356 -68.586604)
			(xy 364.925811 -68.559233) (xy 364.933629 -68.505053) (xy 364.94912 -68.452549) (xy 364.971965 -68.402803)
			(xy 365.001693 -68.356837) (xy 365.019336 -68.335906) (xy 365.01959 -68.335652) (xy 365.02516 -68.328554)
			(xy 365.031417 -68.311646) (xy 365.031782 -68.302632) (xy 365.031782 -68.235576) (xy 365.03144 -68.226557)
			(xy 365.025183 -68.20964) (xy 365.01959 -68.202556) (xy 365.019336 -68.202556) (xy 365.019336 -68.202302)
			(xy 365.00169 -68.181375) (xy 364.971978 -68.135402) (xy 364.949143 -68.085653) (xy 364.933653 -68.033151)
			(xy 364.925828 -67.978974) (xy 364.925356 -67.951604) (xy 364.925881 -67.924354) (xy 364.933636 -67.87041)
			(xy 364.948989 -67.818118) (xy 364.971627 -67.768543) (xy 365.00109 -67.722695) (xy 365.036777 -67.681505)
			(xy 365.077963 -67.645814) (xy 365.123808 -67.616346) (xy 365.173381 -67.593703) (xy 365.225671 -67.578345)
			(xy 365.279615 -67.570584) (xy 365.306864 -67.570096) (xy 365.333179 -67.570522) (xy 365.38531 -67.577766)
			(xy 365.435953 -67.592093) (xy 365.484152 -67.613233) (xy 365.528994 -67.640786) (xy 365.569632 -67.674231)
			(xy 365.587788 -67.693286) (xy 365.595314 -67.700682) (xy 365.614591 -67.70921) (xy 365.625126 -67.709796)
			(xy 365.699802 -67.709796) (xy 365.710354 -67.709282) (xy 365.729649 -67.700736) (xy 365.73714 -67.693286)
			(xy 365.75528 -67.674215) (xy 365.795914 -67.64076) (xy 365.840757 -67.613203) (xy 365.888961 -67.592068)
			(xy 365.939611 -67.577754) (xy 365.991747 -67.570533) (xy 366.018064 -67.570096) (xy 366.045433 -67.570584)
			(xy 366.099612 -67.578397) (xy 366.152114 -67.593881) (xy 366.201862 -67.616718) (xy 366.247829 -67.646437)
			(xy 366.268762 -67.664076) (xy 366.269016 -67.66433) (xy 366.276091 -67.669933) (xy 366.293017 -67.676169)
			(xy 366.302036 -67.676522) (xy 366.369092 -67.676522) (xy 366.378108 -67.676156) (xy 366.395025 -67.669914)
			(xy 366.402112 -67.66433) (xy 366.402112 -67.664076) (xy 366.402366 -67.664076) (xy 366.423297 -67.646436)
			(xy 366.46927 -67.616725) (xy 366.519018 -67.59389) (xy 366.571519 -67.578399) (xy 366.625695 -67.57057)
			(xy 366.653064 -67.570096) (xy 366.679152 -67.570534) (xy 366.730842 -67.57764) (xy 366.781081 -67.591723)
			(xy 366.828932 -67.612523) (xy 366.851438 -67.625722) (xy 366.863884 -67.633342) (xy 366.892332 -67.633088)
			(xy 366.993932 -67.569842) (xy 367.006632 -67.543934) (xy 367.005362 -67.52971) (xy 367.003584 -67.488054)
			(xy 367.004131 -67.45809) (xy 367.011959 -67.398675) (xy 367.027475 -67.34079) (xy 367.050414 -67.285426)
			(xy 367.080383 -67.23353) (xy 367.116869 -67.185988) (xy 367.159248 -67.143617) (xy 367.206796 -67.107139)
			(xy 367.258697 -67.077179) (xy 367.314066 -67.05425) (xy 367.371953 -67.038743) (xy 367.431369 -67.030926)
			(xy 367.491297 -67.03093) (xy 367.550712 -67.038756) (xy 367.608598 -67.054271) (xy 367.663962 -67.077208)
			(xy 367.71586 -67.107176) (xy 367.763402 -67.143661) (xy 367.805775 -67.186039) (xy 367.842254 -67.233585)
			(xy 367.872216 -67.285486) (xy 367.895146 -67.340854) (xy 367.910654 -67.398741) (xy 367.918473 -67.458157)
			(xy 367.918471 -67.518085) (xy 367.911956 -67.567552) (xy 368.296172 -67.567552) (xy 368.296172 -67.507616)
			(xy 368.303995 -67.448194) (xy 368.319508 -67.390301) (xy 368.342444 -67.334928) (xy 368.372411 -67.283022)
			(xy 368.408898 -67.235472) (xy 368.451278 -67.193092) (xy 368.498828 -67.156605) (xy 368.550734 -67.126638)
			(xy 368.606107 -67.103702) (xy 368.664 -67.088189) (xy 368.723422 -67.080366) (xy 368.783358 -67.080366)
			(xy 368.84278 -67.088189) (xy 368.900673 -67.103702) (xy 368.956046 -67.126638) (xy 368.960056 -67.128953)
			(xy 388.666675 -67.128953) (xy 388.666675 -67.074447) (xy 388.674433 -67.020496) (xy 388.68979 -66.968198)
			(xy 388.712434 -66.918618) (xy 388.741904 -66.872765) (xy 388.777599 -66.831574) (xy 388.818794 -66.795882)
			(xy 388.864649 -66.766417) (xy 388.914231 -66.743777) (xy 388.966531 -66.728425) (xy 389.020483 -66.720673)
			(xy 389.047736 -66.720212) (xy 389.075107 -66.720654) (xy 389.129287 -66.728477) (xy 389.181791 -66.743972)
			(xy 389.231537 -66.766819) (xy 389.277503 -66.796548) (xy 389.298434 -66.814192) (xy 389.298688 -66.814446)
			(xy 389.30577 -66.820039) (xy 389.32269 -66.826281) (xy 389.331708 -66.826638) (xy 389.398764 -66.826638)
			(xy 389.407778 -66.826255) (xy 389.424695 -66.820025) (xy 389.431784 -66.814446) (xy 389.431784 -66.814192)
			(xy 389.432038 -66.814192) (xy 389.452982 -66.796567) (xy 389.498951 -66.766854) (xy 389.548696 -66.744015)
			(xy 389.601194 -66.72852) (xy 389.655368 -66.720688) (xy 389.682736 -66.720212) (xy 389.709987 -66.72066)
			(xy 389.763934 -66.728421) (xy 389.816227 -66.74378) (xy 389.865802 -66.766425) (xy 389.91165 -66.795894)
			(xy 389.952838 -66.831587) (xy 389.988528 -66.872778) (xy 390.017992 -66.91863) (xy 390.040632 -66.968207)
			(xy 390.055986 -67.020502) (xy 390.063742 -67.074449) (xy 390.063742 -67.128951) (xy 390.055986 -67.182898)
			(xy 390.040632 -67.235193) (xy 390.017992 -67.28477) (xy 389.988528 -67.330622) (xy 389.952838 -67.371813)
			(xy 389.91165 -67.407506) (xy 389.865802 -67.436975) (xy 389.816227 -67.45962) (xy 389.763934 -67.474979)
			(xy 389.709987 -67.48274) (xy 389.682736 -67.483228) (xy 389.655366 -67.482758) (xy 389.601186 -67.474944)
			(xy 389.548682 -67.459457) (xy 389.498935 -67.436615) (xy 389.452969 -67.40689) (xy 389.432038 -67.389248)
			(xy 389.431784 -67.388994) (xy 389.424707 -67.383394) (xy 389.407783 -67.377156) (xy 389.398764 -67.376802)
			(xy 389.331708 -67.376802) (xy 389.322691 -67.377162) (xy 389.305774 -67.383408) (xy 389.298688 -67.388994)
			(xy 389.298688 -67.389248) (xy 389.298434 -67.389248) (xy 389.277493 -67.406877) (xy 389.231524 -67.436592)
			(xy 389.181778 -67.459431) (xy 389.129279 -67.474924) (xy 389.075105 -67.482754) (xy 389.047736 -67.483228)
			(xy 389.020483 -67.482727) (xy 388.966531 -67.474975) (xy 388.914231 -67.459623) (xy 388.864649 -67.436983)
			(xy 388.818794 -67.407518) (xy 388.777599 -67.371826) (xy 388.741904 -67.330635) (xy 388.712434 -67.284782)
			(xy 388.68979 -67.235202) (xy 388.674433 -67.182904) (xy 388.666675 -67.128953) (xy 368.960056 -67.128953)
			(xy 369.007952 -67.156605) (xy 369.055502 -67.193092) (xy 369.097882 -67.235472) (xy 369.134369 -67.283022)
			(xy 369.164336 -67.334928) (xy 369.187272 -67.390301) (xy 369.202785 -67.448194) (xy 369.210608 -67.507616)
			(xy 369.211098 -67.537584) (xy 369.210608 -67.567552) (xy 369.203318 -67.622924) (xy 369.570236 -67.622924)
			(xy 369.570236 -67.562988) (xy 369.578059 -67.503566) (xy 369.593572 -67.445673) (xy 369.616508 -67.3903)
			(xy 369.646475 -67.338394) (xy 369.682962 -67.290844) (xy 369.725342 -67.248464) (xy 369.772892 -67.211977)
			(xy 369.824798 -67.18201) (xy 369.880171 -67.159074) (xy 369.938064 -67.143561) (xy 369.997486 -67.135738)
			(xy 370.057422 -67.135738) (xy 370.116844 -67.143561) (xy 370.174737 -67.159074) (xy 370.23011 -67.18201)
			(xy 370.282016 -67.211977) (xy 370.329566 -67.248464) (xy 370.371946 -67.290844) (xy 370.408433 -67.338394)
			(xy 370.4384 -67.3903) (xy 370.461336 -67.445673) (xy 370.476849 -67.503566) (xy 370.484672 -67.562988)
			(xy 370.484706 -67.565048) (xy 372.746816 -67.565048) (xy 372.746816 -67.510553) (xy 372.754571 -67.456612)
			(xy 372.769924 -67.404324) (xy 372.792561 -67.354754) (xy 372.822022 -67.308909) (xy 372.857708 -67.267723)
			(xy 372.898891 -67.232035) (xy 372.944734 -67.202572) (xy 372.994304 -67.179931) (xy 373.046591 -67.164576)
			(xy 373.100531 -67.156818) (xy 373.127778 -67.15633) (xy 373.155148 -67.156802) (xy 373.209327 -67.164617)
			(xy 373.261831 -67.180104) (xy 373.311578 -67.202945) (xy 373.357544 -67.232669) (xy 373.378476 -67.25031)
			(xy 373.37873 -67.250564) (xy 373.385827 -67.256135) (xy 373.402736 -67.262389) (xy 373.41175 -67.262756)
			(xy 373.478806 -67.262756) (xy 373.487824 -67.262411) (xy 373.504742 -67.256156) (xy 373.511826 -67.250564)
			(xy 373.511826 -67.25031) (xy 373.51208 -67.25031) (xy 373.53301 -67.232668) (xy 373.578983 -67.202957)
			(xy 373.628731 -67.180121) (xy 373.681232 -67.164631) (xy 373.735409 -67.156803) (xy 373.762778 -67.15633)
			(xy 373.790035 -67.156715) (xy 373.843993 -67.164471) (xy 373.896299 -67.179826) (xy 373.945887 -67.20247)
			(xy 373.991748 -67.23194) (xy 374.032947 -67.267637) (xy 374.068647 -67.308835) (xy 374.09812 -67.354694)
			(xy 374.120766 -67.40428) (xy 374.136125 -67.456585) (xy 374.143883 -67.510543) (xy 374.143883 -67.565057)
			(xy 374.136125 -67.619015) (xy 374.120766 -67.67132) (xy 374.09812 -67.720906) (xy 374.068647 -67.766765)
			(xy 374.032947 -67.807963) (xy 373.991748 -67.84366) (xy 373.945887 -67.87313) (xy 373.896299 -67.895774)
			(xy 373.843993 -67.911129) (xy 373.790035 -67.918885) (xy 373.762778 -67.919346) (xy 373.735407 -67.918906)
			(xy 373.681226 -67.911084) (xy 373.628722 -67.895589) (xy 373.578976 -67.872742) (xy 373.53301 -67.843011)
			(xy 373.51208 -67.825366) (xy 373.511826 -67.825112) (xy 373.504735 -67.819532) (xy 373.487822 -67.813281)
			(xy 373.478806 -67.81292) (xy 373.41175 -67.81292) (xy 373.402735 -67.813297) (xy 373.385818 -67.81953)
			(xy 373.37873 -67.825112) (xy 373.37873 -67.825366) (xy 373.378476 -67.825366) (xy 373.357522 -67.842978)
			(xy 373.311556 -67.872695) (xy 373.261814 -67.895537) (xy 373.209318 -67.911034) (xy 373.155146 -67.918869)
			(xy 373.127778 -67.919346) (xy 373.100531 -67.918782) (xy 373.046591 -67.911024) (xy 372.994304 -67.895669)
			(xy 372.944734 -67.873028) (xy 372.898891 -67.843565) (xy 372.857708 -67.807877) (xy 372.822022 -67.766691)
			(xy 372.792561 -67.720846) (xy 372.769924 -67.671276) (xy 372.754571 -67.618988) (xy 372.746816 -67.565048)
			(xy 370.484706 -67.565048) (xy 370.485162 -67.592956) (xy 370.484672 -67.622924) (xy 370.476849 -67.682346)
			(xy 370.461336 -67.740239) (xy 370.4384 -67.795612) (xy 370.408433 -67.847518) (xy 370.371946 -67.895068)
			(xy 370.329566 -67.937448) (xy 370.282016 -67.973935) (xy 370.23011 -68.003902) (xy 370.174737 -68.026838)
			(xy 370.116844 -68.042351) (xy 370.057422 -68.050174) (xy 369.997486 -68.050174) (xy 369.938064 -68.042351)
			(xy 369.880171 -68.026838) (xy 369.824798 -68.003902) (xy 369.772892 -67.973935) (xy 369.725342 -67.937448)
			(xy 369.682962 -67.895068) (xy 369.646475 -67.847518) (xy 369.616508 -67.795612) (xy 369.593572 -67.740239)
			(xy 369.578059 -67.682346) (xy 369.570236 -67.622924) (xy 369.203318 -67.622924) (xy 369.202785 -67.626974)
			(xy 369.187272 -67.684867) (xy 369.164336 -67.74024) (xy 369.134369 -67.792146) (xy 369.097882 -67.839696)
			(xy 369.055502 -67.882076) (xy 369.007952 -67.918563) (xy 368.956046 -67.94853) (xy 368.900673 -67.971466)
			(xy 368.84278 -67.986979) (xy 368.783358 -67.994802) (xy 368.723422 -67.994802) (xy 368.664 -67.986979)
			(xy 368.606107 -67.971466) (xy 368.550734 -67.94853) (xy 368.498828 -67.918563) (xy 368.451278 -67.882076)
			(xy 368.408898 -67.839696) (xy 368.372411 -67.792146) (xy 368.342444 -67.74024) (xy 368.319508 -67.684867)
			(xy 368.303995 -67.626974) (xy 368.296172 -67.567552) (xy 367.911956 -67.567552) (xy 367.910646 -67.5775)
			(xy 367.895133 -67.635386) (xy 367.872197 -67.690751) (xy 367.842231 -67.742649) (xy 367.805748 -67.790192)
			(xy 367.763371 -67.832567) (xy 367.715826 -67.869047) (xy 367.663925 -67.89901) (xy 367.608558 -67.921942)
			(xy 367.550672 -67.937452) (xy 367.491256 -67.945273) (xy 367.461292 -67.945762) (xy 367.432874 -67.94533)
			(xy 367.376476 -67.938302) (xy 367.321381 -67.924343) (xy 367.26844 -67.903668) (xy 367.218468 -67.876595)
			(xy 367.1951 -67.860418) (xy 367.183416 -67.852036) (xy 367.154968 -67.850004) (xy 367.06175 -67.899026)
			(xy 367.053674 -67.90377) (xy 367.041326 -67.917828) (xy 367.034857 -67.935385) (xy 367.034572 -67.944746)
			(xy 367.034572 -67.951604) (xy 367.034115 -67.978975) (xy 367.026296 -68.033154) (xy 367.010805 -68.085658)
			(xy 366.987961 -68.135405) (xy 366.958234 -68.181371) (xy 366.940592 -68.202302) (xy 366.940338 -68.202556)
			(xy 366.934756 -68.209646) (xy 366.928508 -68.22656) (xy 366.928146 -68.235576) (xy 366.928146 -68.302632)
			(xy 366.928478 -68.311652) (xy 366.934742 -68.328569) (xy 366.940338 -68.335652) (xy 366.940592 -68.335652)
			(xy 366.940592 -68.335906) (xy 366.958246 -68.356826) (xy 366.987956 -68.402802) (xy 367.010789 -68.452553)
			(xy 367.026277 -68.505056) (xy 367.0341 -68.559234) (xy 367.034572 -68.586604) (xy 367.034148 -68.613859)
			(xy 367.02639 -68.667813) (xy 367.011031 -68.720114) (xy 366.994399 -68.75653) (xy 370.47043 -68.75653)
			(xy 370.470906 -68.72916) (xy 370.478721 -68.674981) (xy 370.494207 -68.622478) (xy 370.517046 -68.572731)
			(xy 370.546769 -68.526764) (xy 370.56441 -68.505832) (xy 370.564664 -68.505578) (xy 370.570273 -68.498507)
			(xy 370.576505 -68.481578) (xy 370.576856 -68.472558) (xy 370.576856 -68.405502) (xy 370.576507 -68.396484)
			(xy 370.570255 -68.379567) (xy 370.564664 -68.372482) (xy 370.56441 -68.372482) (xy 370.56441 -68.372228)
			(xy 370.546772 -68.351295) (xy 370.51706 -68.305323) (xy 370.494223 -68.255575) (xy 370.478732 -68.203075)
			(xy 370.470904 -68.148899) (xy 370.47043 -68.12153) (xy 370.470883 -68.094276) (xy 370.478637 -68.040323)
			(xy 370.493991 -67.988023) (xy 370.516633 -67.93844) (xy 370.546102 -67.892585) (xy 370.581797 -67.851391)
			(xy 370.622991 -67.815697) (xy 370.668847 -67.786229) (xy 370.71843 -67.763589) (xy 370.770731 -67.748236)
			(xy 370.824684 -67.740483) (xy 370.851938 -67.740022) (xy 370.879307 -67.740519) (xy 370.933485 -67.748329)
			(xy 370.985988 -67.76381) (xy 371.035736 -67.786645) (xy 371.081704 -67.816364) (xy 371.102636 -67.834002)
			(xy 371.10289 -67.834256) (xy 371.10997 -67.839851) (xy 371.126892 -67.846091) (xy 371.13591 -67.846448)
			(xy 371.202966 -67.846448) (xy 371.211983 -67.846086) (xy 371.2289 -67.839843) (xy 371.235986 -67.834256)
			(xy 371.235986 -67.834002) (xy 371.23624 -67.834002) (xy 371.257184 -67.816378) (xy 371.303154 -67.786664)
			(xy 371.352898 -67.763825) (xy 371.405396 -67.74833) (xy 371.45957 -67.740498) (xy 371.486938 -67.740022)
			(xy 371.513253 -67.740457) (xy 371.565383 -67.747698) (xy 371.616027 -67.762023) (xy 371.664226 -67.783161)
			(xy 371.709069 -67.810713) (xy 371.749707 -67.844158) (xy 371.767862 -67.863212) (xy 371.775394 -67.870601)
			(xy 371.794666 -67.879132) (xy 371.8052 -67.879722) (xy 371.879876 -67.879722) (xy 371.890425 -67.879187)
			(xy 371.90972 -67.870655) (xy 371.917214 -67.863212) (xy 371.935372 -67.844159) (xy 371.976001 -67.810701)
			(xy 372.020841 -67.783141) (xy 372.069041 -67.762002) (xy 372.119688 -67.747685) (xy 372.171822 -67.74046)
			(xy 372.198138 -67.740022) (xy 372.225392 -67.740443) (xy 372.279343 -67.748205) (xy 372.331641 -67.763566)
			(xy 372.38122 -67.786214) (xy 372.427072 -67.815687) (xy 372.468263 -67.851386) (xy 372.503954 -67.892583)
			(xy 372.533418 -67.938439) (xy 372.556057 -67.988023) (xy 372.571409 -68.040323) (xy 372.579162 -68.094276)
			(xy 372.579646 -68.12153) (xy 372.579211 -68.148901) (xy 372.571387 -68.203082) (xy 372.555892 -68.255586)
			(xy 372.533043 -68.305333) (xy 372.503311 -68.351298) (xy 372.485666 -68.372228) (xy 372.485412 -68.372482)
			(xy 372.479828 -68.379571) (xy 372.473579 -68.396486) (xy 372.47322 -68.405502) (xy 372.47322 -68.472558)
			(xy 372.473593 -68.481573) (xy 372.479829 -68.498491) (xy 372.485412 -68.505578) (xy 372.485666 -68.505578)
			(xy 372.485666 -68.505832) (xy 372.503281 -68.526783) (xy 372.532998 -68.57275) (xy 372.539359 -68.586604)
			(xy 390.925304 -68.586604) (xy 390.925771 -68.559234) (xy 390.933589 -68.505055) (xy 390.949077 -68.452552)
			(xy 390.971919 -68.402805) (xy 391.001643 -68.356838) (xy 391.019284 -68.335906) (xy 391.019538 -68.335652)
			(xy 391.025113 -68.328558) (xy 391.031366 -68.311647) (xy 391.03173 -68.302632) (xy 391.03173 -68.235576)
			(xy 391.031378 -68.226559) (xy 391.025126 -68.209642) (xy 391.019538 -68.202556) (xy 391.019284 -68.202556)
			(xy 391.019284 -68.202302) (xy 391.00163 -68.181382) (xy 390.971921 -68.135406) (xy 390.949088 -68.085655)
			(xy 390.9336 -68.033152) (xy 390.925776 -67.978974) (xy 390.925304 -67.951604) (xy 390.925759 -67.924351)
			(xy 390.933516 -67.870399) (xy 390.948872 -67.8181) (xy 390.971515 -67.768519) (xy 391.000984 -67.722666)
			(xy 391.036678 -67.681472) (xy 391.077872 -67.645779) (xy 391.123726 -67.616311) (xy 391.173308 -67.593669)
			(xy 391.225607 -67.578314) (xy 391.279559 -67.570559) (xy 391.306812 -67.570096) (xy 391.333126 -67.570557)
			(xy 391.385255 -67.577793) (xy 391.435898 -67.592114) (xy 391.484097 -67.613247) (xy 391.52894 -67.640795)
			(xy 391.569579 -67.674234) (xy 391.587736 -67.693286) (xy 391.595244 -67.700703) (xy 391.614534 -67.709219)
			(xy 391.625074 -67.709796) (xy 391.69975 -67.709796) (xy 391.710298 -67.709255) (xy 391.729594 -67.700728)
			(xy 391.737088 -67.693286) (xy 391.755254 -67.674241) (xy 391.795882 -67.640783) (xy 391.84072 -67.613223)
			(xy 391.888919 -67.592083) (xy 391.939564 -67.577763) (xy 391.991696 -67.570536) (xy 392.018012 -67.570096)
			(xy 392.045382 -67.570556) (xy 392.099562 -67.578375) (xy 392.152065 -67.593866) (xy 392.201812 -67.616709)
			(xy 392.247778 -67.646434) (xy 392.26871 -67.664076) (xy 392.268964 -67.66433) (xy 392.276054 -67.669911)
			(xy 392.292968 -67.67616) (xy 392.301984 -67.676522) (xy 392.36904 -67.676522) (xy 392.378058 -67.676179)
			(xy 392.394975 -67.669921) (xy 392.40206 -67.66433) (xy 392.40206 -67.664076) (xy 392.402314 -67.664076)
			(xy 392.423265 -67.64646) (xy 392.469233 -67.616746) (xy 392.518976 -67.593906) (xy 392.571472 -67.578409)
			(xy 392.625644 -67.570574) (xy 392.653012 -67.570096) (xy 392.679101 -67.570512) (xy 392.730791 -67.577624)
			(xy 392.78103 -67.591715) (xy 392.82888 -67.61252) (xy 392.851386 -67.625722) (xy 392.863832 -67.633342)
			(xy 392.89228 -67.633088) (xy 392.99388 -67.569842) (xy 393.00658 -67.543934) (xy 393.00531 -67.52971)
			(xy 393.003532 -67.488054) (xy 393.004031 -67.458091) (xy 393.011859 -67.398677) (xy 393.027374 -67.340794)
			(xy 393.050312 -67.28543) (xy 393.080279 -67.233534) (xy 393.116764 -67.185994) (xy 393.159142 -67.143622)
			(xy 393.206687 -67.107144) (xy 393.258587 -67.077184) (xy 393.313954 -67.054254) (xy 393.371839 -67.038746)
			(xy 393.431254 -67.030927) (xy 393.491181 -67.030929) (xy 393.550595 -67.038753) (xy 393.608479 -67.054265)
			(xy 393.663844 -67.077199) (xy 393.715742 -67.107163) (xy 393.763284 -67.143645) (xy 393.805659 -67.18602)
			(xy 393.84214 -67.233563) (xy 393.872104 -67.285461) (xy 393.895037 -67.340826) (xy 393.910548 -67.398711)
			(xy 393.918371 -67.458125) (xy 393.918373 -67.518052) (xy 393.911858 -67.567552) (xy 394.29612 -67.567552)
			(xy 394.29612 -67.507616) (xy 394.303943 -67.448194) (xy 394.319456 -67.390301) (xy 394.342392 -67.334928)
			(xy 394.372359 -67.283022) (xy 394.408846 -67.235472) (xy 394.451226 -67.193092) (xy 394.498776 -67.156605)
			(xy 394.550682 -67.126638) (xy 394.606055 -67.103702) (xy 394.663948 -67.088189) (xy 394.72337 -67.080366)
			(xy 394.783306 -67.080366) (xy 394.842728 -67.088189) (xy 394.900621 -67.103702) (xy 394.955994 -67.126638)
			(xy 394.959997 -67.128949) (xy 414.666698 -67.128949) (xy 414.666698 -67.074451) (xy 414.674454 -67.020508)
			(xy 414.689807 -66.968217) (xy 414.712446 -66.918643) (xy 414.741909 -66.872796) (xy 414.777597 -66.831609)
			(xy 414.818783 -66.795919) (xy 414.864629 -66.766454) (xy 414.914202 -66.743813) (xy 414.966492 -66.728457)
			(xy 415.020435 -66.720699) (xy 415.047684 -66.720212) (xy 415.075054 -66.720685) (xy 415.129233 -66.7285)
			(xy 415.181736 -66.743988) (xy 415.231483 -66.766828) (xy 415.27745 -66.796551) (xy 415.298382 -66.814192)
			(xy 415.298636 -66.814446) (xy 415.305733 -66.820017) (xy 415.322642 -66.826272) (xy 415.331656 -66.826638)
			(xy 415.398712 -66.826638) (xy 415.407728 -66.826279) (xy 415.424645 -66.820032) (xy 415.431732 -66.814446)
			(xy 415.431732 -66.814192) (xy 415.431986 -66.814192) (xy 415.452911 -66.796545) (xy 415.498886 -66.766834)
			(xy 415.548635 -66.744) (xy 415.601138 -66.728511) (xy 415.655314 -66.720685) (xy 415.682684 -66.720212)
			(xy 415.709939 -66.720634) (xy 415.763895 -66.728389) (xy 415.816197 -66.743745) (xy 415.865782 -66.766388)
			(xy 415.91164 -66.795857) (xy 415.952836 -66.831552) (xy 415.988534 -66.872748) (xy 416.018005 -66.918604)
			(xy 416.04065 -66.968188) (xy 416.056007 -67.02049) (xy 416.063765 -67.074445) (xy 416.063765 -67.128955)
			(xy 416.056007 -67.18291) (xy 416.04065 -67.235212) (xy 416.018005 -67.284796) (xy 415.988534 -67.330652)
			(xy 415.952836 -67.371848) (xy 415.91164 -67.407543) (xy 415.865782 -67.437012) (xy 415.816197 -67.459655)
			(xy 415.763895 -67.475011) (xy 415.709939 -67.482766) (xy 415.682684 -67.483228) (xy 415.655313 -67.482789)
			(xy 415.601132 -67.474967) (xy 415.548628 -67.459473) (xy 415.498881 -67.436625) (xy 415.452916 -67.406893)
			(xy 415.431986 -67.389248) (xy 415.431732 -67.388994) (xy 415.424641 -67.383414) (xy 415.407728 -67.377164)
			(xy 415.398712 -67.376802) (xy 415.331656 -67.376802) (xy 415.322642 -67.377186) (xy 415.305725 -67.383415)
			(xy 415.298636 -67.388994) (xy 415.298636 -67.389248) (xy 415.298382 -67.389248) (xy 415.277423 -67.406854)
			(xy 415.231459 -67.436573) (xy 415.181718 -67.459416) (xy 415.129223 -67.474914) (xy 415.075051 -67.48275)
			(xy 415.047684 -67.483228) (xy 415.020435 -67.482701) (xy 414.966492 -67.474943) (xy 414.914202 -67.459587)
			(xy 414.864629 -67.436946) (xy 414.818783 -67.407481) (xy 414.777597 -67.371791) (xy 414.741909 -67.330604)
			(xy 414.712446 -67.284757) (xy 414.689807 -67.235183) (xy 414.674454 -67.182892) (xy 414.666698 -67.128949)
			(xy 394.959997 -67.128949) (xy 395.0079 -67.156605) (xy 395.05545 -67.193092) (xy 395.09783 -67.235472)
			(xy 395.134317 -67.283022) (xy 395.164284 -67.334928) (xy 395.18722 -67.390301) (xy 395.202733 -67.448194)
			(xy 395.210556 -67.507616) (xy 395.211046 -67.537584) (xy 395.210556 -67.567552) (xy 395.203266 -67.622924)
			(xy 395.570184 -67.622924) (xy 395.570184 -67.562988) (xy 395.578007 -67.503566) (xy 395.59352 -67.445673)
			(xy 395.616456 -67.3903) (xy 395.646423 -67.338394) (xy 395.68291 -67.290844) (xy 395.72529 -67.248464)
			(xy 395.77284 -67.211977) (xy 395.824746 -67.18201) (xy 395.880119 -67.159074) (xy 395.938012 -67.143561)
			(xy 395.997434 -67.135738) (xy 396.05737 -67.135738) (xy 396.116792 -67.143561) (xy 396.174685 -67.159074)
			(xy 396.230058 -67.18201) (xy 396.281964 -67.211977) (xy 396.329514 -67.248464) (xy 396.371894 -67.290844)
			(xy 396.408381 -67.338394) (xy 396.438348 -67.3903) (xy 396.461284 -67.445673) (xy 396.476797 -67.503566)
			(xy 396.48462 -67.562988) (xy 396.484654 -67.565051) (xy 398.746693 -67.565051) (xy 398.746693 -67.510549)
			(xy 398.75445 -67.456601) (xy 398.769806 -67.404306) (xy 398.792448 -67.354729) (xy 398.821916 -67.308879)
			(xy 398.857609 -67.26769) (xy 398.8988 -67.232) (xy 398.944652 -67.202536) (xy 398.994231 -67.179897)
			(xy 399.046526 -67.164545) (xy 399.100475 -67.156791) (xy 399.127726 -67.15633) (xy 399.155097 -67.156774)
			(xy 399.209277 -67.164596) (xy 399.261781 -67.18009) (xy 399.311528 -67.202937) (xy 399.357493 -67.232666)
			(xy 399.378424 -67.25031) (xy 399.378678 -67.250564) (xy 399.385761 -67.256155) (xy 399.402681 -67.262397)
			(xy 399.411698 -67.262756) (xy 399.478754 -67.262756) (xy 399.48777 -67.262387) (xy 399.504687 -67.256149)
			(xy 399.511774 -67.250564) (xy 399.511774 -67.25031) (xy 399.512028 -67.25031) (xy 399.532978 -67.232693)
			(xy 399.578945 -67.202977) (xy 399.628689 -67.180137) (xy 399.681185 -67.164641) (xy 399.735358 -67.156807)
			(xy 399.762726 -67.15633) (xy 399.789979 -67.156742) (xy 399.843929 -67.164502) (xy 399.896226 -67.179861)
			(xy 399.945805 -67.202506) (xy 399.991656 -67.231976) (xy 400.032848 -67.267671) (xy 400.06854 -67.308864)
			(xy 400.098007 -67.354718) (xy 400.120648 -67.404299) (xy 400.136004 -67.456596) (xy 400.14376 -67.510547)
			(xy 400.14376 -67.565053) (xy 400.136004 -67.619004) (xy 400.120648 -67.671301) (xy 400.098007 -67.720882)
			(xy 400.06854 -67.766736) (xy 400.032848 -67.807929) (xy 399.991656 -67.843624) (xy 399.945805 -67.873094)
			(xy 399.896226 -67.895739) (xy 399.843929 -67.911098) (xy 399.789979 -67.918858) (xy 399.762726 -67.919346)
			(xy 399.735356 -67.918878) (xy 399.681176 -67.911063) (xy 399.628673 -67.895575) (xy 399.578926 -67.872733)
			(xy 399.532959 -67.843008) (xy 399.512028 -67.825366) (xy 399.511774 -67.825112) (xy 399.504669 -67.819552)
			(xy 399.487767 -67.813289) (xy 399.478754 -67.81292) (xy 399.411698 -67.81292) (xy 399.40268 -67.813272)
			(xy 399.385763 -67.819522) (xy 399.378678 -67.825112) (xy 399.378678 -67.825366) (xy 399.378424 -67.825366)
			(xy 399.357489 -67.843002) (xy 399.311518 -67.872715) (xy 399.261771 -67.895553) (xy 399.209271 -67.911044)
			(xy 399.155095 -67.918872) (xy 399.127726 -67.919346) (xy 399.100475 -67.918809) (xy 399.046526 -67.911055)
			(xy 398.994231 -67.895703) (xy 398.944652 -67.873064) (xy 398.8988 -67.8436) (xy 398.857609 -67.80791)
			(xy 398.821916 -67.766721) (xy 398.792448 -67.720871) (xy 398.769806 -67.671294) (xy 398.75445 -67.618999)
			(xy 398.746693 -67.565051) (xy 396.484654 -67.565051) (xy 396.48511 -67.592956) (xy 396.48462 -67.622924)
			(xy 396.476797 -67.682346) (xy 396.461284 -67.740239) (xy 396.438348 -67.795612) (xy 396.408381 -67.847518)
			(xy 396.371894 -67.895068) (xy 396.329514 -67.937448) (xy 396.281964 -67.973935) (xy 396.230058 -68.003902)
			(xy 396.174685 -68.026838) (xy 396.116792 -68.042351) (xy 396.05737 -68.050174) (xy 395.997434 -68.050174)
			(xy 395.938012 -68.042351) (xy 395.880119 -68.026838) (xy 395.824746 -68.003902) (xy 395.77284 -67.973935)
			(xy 395.72529 -67.937448) (xy 395.68291 -67.895068) (xy 395.646423 -67.847518) (xy 395.616456 -67.795612)
			(xy 395.59352 -67.740239) (xy 395.578007 -67.682346) (xy 395.570184 -67.622924) (xy 395.203266 -67.622924)
			(xy 395.202733 -67.626974) (xy 395.18722 -67.684867) (xy 395.164284 -67.74024) (xy 395.134317 -67.792146)
			(xy 395.09783 -67.839696) (xy 395.05545 -67.882076) (xy 395.0079 -67.918563) (xy 394.955994 -67.94853)
			(xy 394.900621 -67.971466) (xy 394.842728 -67.986979) (xy 394.783306 -67.994802) (xy 394.72337 -67.994802)
			(xy 394.663948 -67.986979) (xy 394.606055 -67.971466) (xy 394.550682 -67.94853) (xy 394.498776 -67.918563)
			(xy 394.451226 -67.882076) (xy 394.408846 -67.839696) (xy 394.372359 -67.792146) (xy 394.342392 -67.74024)
			(xy 394.319456 -67.684867) (xy 394.303943 -67.626974) (xy 394.29612 -67.567552) (xy 393.911858 -67.567552)
			(xy 393.910553 -67.577467) (xy 393.895044 -67.635352) (xy 393.872114 -67.690718) (xy 393.842153 -67.742618)
			(xy 393.805674 -67.790163) (xy 393.763301 -67.83254) (xy 393.715761 -67.869024) (xy 393.663864 -67.898991)
			(xy 393.608501 -67.921928) (xy 393.550617 -67.937443) (xy 393.491203 -67.94527) (xy 393.46124 -67.945762)
			(xy 393.432822 -67.945357) (xy 393.376422 -67.938322) (xy 393.321327 -67.924357) (xy 393.268387 -67.903676)
			(xy 393.218415 -67.876598) (xy 393.195048 -67.860418) (xy 393.183364 -67.852036) (xy 393.154916 -67.850004)
			(xy 393.061698 -67.899026) (xy 393.053611 -67.903753) (xy 393.041269 -67.917821) (xy 393.034804 -67.935384)
			(xy 393.03452 -67.944746) (xy 393.03452 -67.951604) (xy 393.034076 -67.978975) (xy 393.026256 -68.033156)
			(xy 393.010763 -68.08566) (xy 392.987915 -68.135407) (xy 392.958185 -68.181372) (xy 392.94054 -68.202302)
			(xy 392.940286 -68.202556) (xy 392.93471 -68.20965) (xy 392.928457 -68.226561) (xy 392.928094 -68.235576)
			(xy 392.928094 -68.302632) (xy 392.928437 -68.31165) (xy 392.934695 -68.328567) (xy 392.940286 -68.335652)
			(xy 392.94054 -68.335652) (xy 392.94054 -68.335906) (xy 392.958202 -68.35682) (xy 392.987909 -68.402798)
			(xy 393.01074 -68.45255) (xy 393.026226 -68.505055) (xy 393.034049 -68.559234) (xy 393.03452 -68.586604)
			(xy 393.034026 -68.613855) (xy 393.026269 -68.667802) (xy 393.010914 -68.720095) (xy 392.994275 -68.75653)
			(xy 396.470378 -68.75653) (xy 396.470843 -68.729159) (xy 396.478658 -68.67498) (xy 396.494146 -68.622476)
			(xy 396.516989 -68.572729) (xy 396.546715 -68.526763) (xy 396.564358 -68.505832) (xy 396.564612 -68.505578)
			(xy 396.570215 -68.498503) (xy 396.576452 -68.481577) (xy 396.576804 -68.472558) (xy 396.576804 -68.405502)
			(xy 396.576445 -68.396485) (xy 396.570199 -68.379568) (xy 396.564612 -68.372482) (xy 396.564358 -68.372482)
			(xy 396.564358 -68.372228) (xy 396.546712 -68.351302) (xy 396.517002 -68.305327) (xy 396.494168 -68.255578)
			(xy 396.478679 -68.203076) (xy 396.470851 -68.148899) (xy 396.470378 -68.12153) (xy 396.470883 -68.094279)
			(xy 396.478636 -68.04033) (xy 396.493987 -67.988034) (xy 396.516625 -67.938455) (xy 396.546089 -67.892602)
			(xy 396.581778 -67.851409) (xy 396.622967 -67.815715) (xy 396.668816 -67.786246) (xy 396.718392 -67.763603)
			(xy 396.770687 -67.748245) (xy 396.824635 -67.740486) (xy 396.851886 -67.740022) (xy 396.879256 -67.740491)
			(xy 396.933435 -67.748307) (xy 396.985939 -67.763795) (xy 397.035686 -67.786637) (xy 397.081652 -67.816361)
			(xy 397.102584 -67.834002) (xy 397.102838 -67.834256) (xy 397.109933 -67.839829) (xy 397.126844 -67.846083)
			(xy 397.135858 -67.846448) (xy 397.202914 -67.846448) (xy 397.211933 -67.846109) (xy 397.22885 -67.83985)
			(xy 397.235934 -67.834256) (xy 397.235934 -67.834002) (xy 397.236188 -67.834002) (xy 397.257114 -67.816355)
			(xy 397.303088 -67.786645) (xy 397.352837 -67.76381) (xy 397.40534 -67.748321) (xy 397.459516 -67.740495)
			(xy 397.486886 -67.740022) (xy 397.5132 -67.740492) (xy 397.565329 -67.747725) (xy 397.615972 -67.762043)
			(xy 397.664171 -67.783175) (xy 397.709014 -67.810721) (xy 397.749654 -67.84416) (xy 397.76781 -67.863212)
			(xy 397.775324 -67.870622) (xy 397.79461 -67.879141) (xy 397.805148 -67.879722) (xy 397.879824 -67.879722)
			(xy 397.89037 -67.879159) (xy 397.909665 -67.870647) (xy 397.917162 -67.863212) (xy 397.935297 -67.844136)
			(xy 397.975931 -67.81068) (xy 398.020775 -67.783123) (xy 398.06898 -67.761988) (xy 398.119631 -67.747676)
			(xy 398.171769 -67.740457) (xy 398.198086 -67.740022) (xy 398.22534 -67.740468) (xy 398.279293 -67.748224)
			(xy 398.331593 -67.76358) (xy 398.381175 -67.786223) (xy 398.42703 -67.815692) (xy 398.468223 -67.851388)
			(xy 398.503917 -67.892583) (xy 398.533385 -67.938439) (xy 398.556026 -67.988022) (xy 398.571379 -68.040323)
			(xy 398.579133 -68.094276) (xy 398.579594 -68.12153) (xy 398.579147 -68.148901) (xy 398.571325 -68.203081)
			(xy 398.555831 -68.255584) (xy 398.532985 -68.305331) (xy 398.503257 -68.351297) (xy 398.485614 -68.372228)
			(xy 398.48536 -68.372482) (xy 398.47977 -68.379566) (xy 398.473526 -68.396485) (xy 398.473168 -68.405502)
			(xy 398.473168 -68.472558) (xy 398.473552 -68.481572) (xy 398.479782 -68.498489) (xy 398.48536 -68.505578)
			(xy 398.485614 -68.505578) (xy 398.485614 -68.505832) (xy 398.503237 -68.526777) (xy 398.532951 -68.572747)
			(xy 398.539313 -68.586604) (xy 416.925252 -68.586604) (xy 416.925708 -68.559233) (xy 416.933526 -68.505053)
			(xy 416.949017 -68.45255) (xy 416.971861 -68.402803) (xy 417.001589 -68.356837) (xy 417.019232 -68.335906)
			(xy 417.019486 -68.335652) (xy 417.025055 -68.328554) (xy 417.031313 -68.311646) (xy 417.031678 -68.302632)
			(xy 417.031678 -68.235576) (xy 417.031337 -68.226557) (xy 417.025079 -68.20964) (xy 417.019486 -68.202556)
			(xy 417.019232 -68.202556) (xy 417.019232 -68.202302) (xy 417.001585 -68.181376) (xy 416.971874 -68.135402)
			(xy 416.949039 -68.085653) (xy 416.933549 -68.033151) (xy 416.925724 -67.978974) (xy 416.925252 -67.951604)
			(xy 416.925781 -67.924355) (xy 416.933536 -67.870411) (xy 416.948889 -67.818119) (xy 416.971527 -67.768545)
			(xy 417.000989 -67.722696) (xy 417.036676 -67.681507) (xy 417.077861 -67.645815) (xy 417.123706 -67.616348)
			(xy 417.173278 -67.593704) (xy 417.225568 -67.578346) (xy 417.279511 -67.570585) (xy 417.30676 -67.570096)
			(xy 417.333075 -67.570525) (xy 417.385205 -67.577768) (xy 417.435849 -67.592094) (xy 417.484048 -67.613234)
			(xy 417.52889 -67.640787) (xy 417.569528 -67.674232) (xy 417.587684 -67.693286) (xy 417.595212 -67.70068)
			(xy 417.614487 -67.709209) (xy 417.625022 -67.709796) (xy 417.699698 -67.709796) (xy 417.710249 -67.70928)
			(xy 417.729544 -67.700736) (xy 417.737036 -67.693286) (xy 417.755178 -67.674217) (xy 417.795811 -67.640762)
			(xy 417.840654 -67.613205) (xy 417.888858 -67.592069) (xy 417.939507 -67.577754) (xy 417.991643 -67.570533)
			(xy 418.01796 -67.570096) (xy 418.045329 -67.570586) (xy 418.099507 -67.578399) (xy 418.15201 -67.593882)
			(xy 418.201757 -67.616718) (xy 418.247725 -67.646437) (xy 418.268658 -67.664076) (xy 418.268912 -67.66433)
			(xy 418.275988 -67.669931) (xy 418.292913 -67.676168) (xy 418.301932 -67.676522) (xy 418.368988 -67.676522)
			(xy 418.378004 -67.676154) (xy 418.39492 -67.669914) (xy 418.402008 -67.66433) (xy 418.402008 -67.664076)
			(xy 418.402262 -67.664076) (xy 418.423194 -67.646438) (xy 418.469168 -67.616726) (xy 418.518915 -67.593891)
			(xy 418.571415 -67.578399) (xy 418.625591 -67.570571) (xy 418.65296 -67.570096) (xy 418.679048 -67.570536)
			(xy 418.730738 -67.577641) (xy 418.780977 -67.591724) (xy 418.828828 -67.612523) (xy 418.851334 -67.625722)
			(xy 418.86378 -67.633342) (xy 418.892228 -67.633088) (xy 418.993828 -67.569842) (xy 419.006528 -67.543934)
			(xy 419.005258 -67.52971) (xy 419.00348 -67.488054) (xy 419.004031 -67.45809) (xy 419.011859 -67.398675)
			(xy 419.027375 -67.34079) (xy 419.050314 -67.285426) (xy 419.080283 -67.233529) (xy 419.116769 -67.185988)
			(xy 419.159149 -67.143616) (xy 419.206696 -67.107138) (xy 419.258598 -67.077178) (xy 419.313967 -67.054249)
			(xy 419.371854 -67.038743) (xy 419.43127 -67.030926) (xy 419.491199 -67.03093) (xy 419.550614 -67.038757)
			(xy 419.608499 -67.054272) (xy 419.663864 -67.077209) (xy 419.715761 -67.107177) (xy 419.763303 -67.143662)
			(xy 419.805676 -67.18604) (xy 419.842156 -67.233587) (xy 419.872117 -67.285488) (xy 419.895047 -67.340856)
			(xy 419.910555 -67.398743) (xy 419.918374 -67.458159) (xy 419.918371 -67.518087) (xy 419.911856 -67.567552)
			(xy 420.296068 -67.567552) (xy 420.296068 -67.507616) (xy 420.303891 -67.448194) (xy 420.319404 -67.390301)
			(xy 420.34234 -67.334928) (xy 420.372307 -67.283022) (xy 420.408794 -67.235472) (xy 420.451174 -67.193092)
			(xy 420.498724 -67.156605) (xy 420.55063 -67.126638) (xy 420.606003 -67.103702) (xy 420.663896 -67.088189)
			(xy 420.723318 -67.080366) (xy 420.783254 -67.080366) (xy 420.842676 -67.088189) (xy 420.900569 -67.103702)
			(xy 420.955942 -67.126638) (xy 420.959952 -67.128953) (xy 440.666575 -67.128953) (xy 440.666575 -67.074447)
			(xy 440.674333 -67.020496) (xy 440.68969 -66.968199) (xy 440.712333 -66.918619) (xy 440.741803 -66.872767)
			(xy 440.777498 -66.831575) (xy 440.818692 -66.795883) (xy 440.864547 -66.766418) (xy 440.914129 -66.743778)
			(xy 440.966428 -66.728426) (xy 441.020379 -66.720673) (xy 441.047632 -66.720212) (xy 441.075003 -66.720656)
			(xy 441.129183 -66.728479) (xy 441.181687 -66.743973) (xy 441.231433 -66.76682) (xy 441.277399 -66.796549)
			(xy 441.29833 -66.814192) (xy 441.298584 -66.814446) (xy 441.305667 -66.820038) (xy 441.322587 -66.82628)
			(xy 441.331604 -66.826638) (xy 441.39866 -66.826638) (xy 441.407674 -66.826254) (xy 441.424591 -66.820024)
			(xy 441.43168 -66.814446) (xy 441.43168 -66.814192) (xy 441.431934 -66.814192) (xy 441.452879 -66.796569)
			(xy 441.498848 -66.766855) (xy 441.548593 -66.744016) (xy 441.60109 -66.728521) (xy 441.655264 -66.720689)
			(xy 441.682632 -66.720212) (xy 441.709883 -66.72066) (xy 441.76383 -66.728421) (xy 441.816124 -66.743779)
			(xy 441.8657 -66.766423) (xy 441.911549 -66.795892) (xy 441.952737 -66.831586) (xy 441.988427 -66.872777)
			(xy 442.017892 -66.918628) (xy 442.040532 -66.968206) (xy 442.055886 -67.020501) (xy 442.063642 -67.074449)
			(xy 442.063642 -67.128951) (xy 442.055886 -67.182899) (xy 442.040532 -67.235194) (xy 442.017892 -67.284772)
			(xy 441.988427 -67.330623) (xy 441.952737 -67.371814) (xy 441.911549 -67.407508) (xy 441.8657 -67.436977)
			(xy 441.816124 -67.459621) (xy 441.76383 -67.474979) (xy 441.709883 -67.48274) (xy 441.682632 -67.483228)
			(xy 441.655262 -67.482761) (xy 441.601082 -67.474946) (xy 441.548578 -67.459458) (xy 441.498831 -67.436616)
			(xy 441.452865 -67.40689) (xy 441.431934 -67.389248) (xy 441.43168 -67.388994) (xy 441.424604 -67.383392)
			(xy 441.407679 -67.377155) (xy 441.39866 -67.376802) (xy 441.331604 -67.376802) (xy 441.322587 -67.37716)
			(xy 441.30567 -67.383407) (xy 441.298584 -67.388994) (xy 441.298584 -67.389248) (xy 441.29833 -67.389248)
			(xy 441.277391 -67.406878) (xy 441.231421 -67.436593) (xy 441.181675 -67.459432) (xy 441.129176 -67.474925)
			(xy 441.075001 -67.482754) (xy 441.047632 -67.483228) (xy 441.020379 -67.482727) (xy 440.966428 -67.474974)
			(xy 440.914129 -67.459622) (xy 440.864547 -67.436982) (xy 440.818692 -67.407516) (xy 440.777498 -67.371825)
			(xy 440.741803 -67.330633) (xy 440.712333 -67.284781) (xy 440.68969 -67.235201) (xy 440.674333 -67.182904)
			(xy 440.666575 -67.128953) (xy 420.959952 -67.128953) (xy 421.007848 -67.156605) (xy 421.055398 -67.193092)
			(xy 421.097778 -67.235472) (xy 421.134265 -67.283022) (xy 421.164232 -67.334928) (xy 421.187168 -67.390301)
			(xy 421.202681 -67.448194) (xy 421.210504 -67.507616) (xy 421.210994 -67.537584) (xy 421.210504 -67.567552)
			(xy 421.203214 -67.622924) (xy 421.570132 -67.622924) (xy 421.570132 -67.562988) (xy 421.577955 -67.503566)
			(xy 421.593468 -67.445673) (xy 421.616404 -67.3903) (xy 421.646371 -67.338394) (xy 421.682858 -67.290844)
			(xy 421.725238 -67.248464) (xy 421.772788 -67.211977) (xy 421.824694 -67.18201) (xy 421.880067 -67.159074)
			(xy 421.93796 -67.143561) (xy 421.997382 -67.135738) (xy 422.057318 -67.135738) (xy 422.11674 -67.143561)
			(xy 422.174633 -67.159074) (xy 422.230006 -67.18201) (xy 422.281912 -67.211977) (xy 422.329462 -67.248464)
			(xy 422.371842 -67.290844) (xy 422.408329 -67.338394) (xy 422.438296 -67.3903) (xy 422.461232 -67.445673)
			(xy 422.476745 -67.503566) (xy 422.484568 -67.562988) (xy 422.484602 -67.565047) (xy 424.746716 -67.565047)
			(xy 424.746716 -67.510553) (xy 424.754471 -67.456613) (xy 424.769823 -67.404325) (xy 424.79246 -67.354755)
			(xy 424.821921 -67.30891) (xy 424.857606 -67.267725) (xy 424.898789 -67.232037) (xy 424.944632 -67.202573)
			(xy 424.994201 -67.179933) (xy 425.046487 -67.164577) (xy 425.100427 -67.156818) (xy 425.127674 -67.15633)
			(xy 425.155044 -67.156804) (xy 425.209223 -67.164619) (xy 425.261726 -67.180106) (xy 425.311473 -67.202946)
			(xy 425.35744 -67.232669) (xy 425.378372 -67.25031) (xy 425.378626 -67.250564) (xy 425.385724 -67.256133)
			(xy 425.402632 -67.262389) (xy 425.411646 -67.262756) (xy 425.478702 -67.262756) (xy 425.48772 -67.262409)
			(xy 425.504637 -67.256155) (xy 425.511722 -67.250564) (xy 425.511722 -67.25031) (xy 425.511976 -67.25031)
			(xy 425.532908 -67.23267) (xy 425.57888 -67.202958) (xy 425.628628 -67.180122) (xy 425.681129 -67.164631)
			(xy 425.735305 -67.156804) (xy 425.762674 -67.15633) (xy 425.789931 -67.156715) (xy 425.84389 -67.16447)
			(xy 425.896196 -67.179825) (xy 425.945785 -67.202469) (xy 425.991646 -67.231939) (xy 426.032846 -67.267636)
			(xy 426.068546 -67.308834) (xy 426.098019 -67.354693) (xy 426.120666 -67.404279) (xy 426.136025 -67.456585)
			(xy 426.143783 -67.510543) (xy 426.143783 -67.565057) (xy 426.136025 -67.619015) (xy 426.120666 -67.671321)
			(xy 426.098019 -67.720907) (xy 426.068546 -67.766766) (xy 426.032846 -67.807964) (xy 425.991646 -67.843661)
			(xy 425.945785 -67.873131) (xy 425.896196 -67.895775) (xy 425.84389 -67.91113) (xy 425.789931 -67.918885)
			(xy 425.762674 -67.919346) (xy 425.735303 -67.918908) (xy 425.681122 -67.911086) (xy 425.628618 -67.895591)
			(xy 425.578871 -67.872742) (xy 425.532906 -67.843011) (xy 425.511976 -67.825366) (xy 425.511722 -67.825112)
			(xy 425.504632 -67.81953) (xy 425.487718 -67.81328) (xy 425.478702 -67.81292) (xy 425.411646 -67.81292)
			(xy 425.402631 -67.813295) (xy 425.385714 -67.81953) (xy 425.378626 -67.825112) (xy 425.378626 -67.825366)
			(xy 425.378372 -67.825366) (xy 425.357419 -67.84298) (xy 425.311453 -67.872696) (xy 425.26171 -67.895538)
			(xy 425.209214 -67.911035) (xy 425.155042 -67.918869) (xy 425.127674 -67.919346) (xy 425.100427 -67.918782)
			(xy 425.046487 -67.911023) (xy 424.994201 -67.895667) (xy 424.944632 -67.873027) (xy 424.898789 -67.843563)
			(xy 424.857606 -67.807875) (xy 424.821921 -67.76669) (xy 424.79246 -67.720845) (xy 424.769823 -67.671275)
			(xy 424.754471 -67.618987) (xy 424.746716 -67.565047) (xy 422.484602 -67.565047) (xy 422.485058 -67.592956)
			(xy 422.484568 -67.622924) (xy 422.476745 -67.682346) (xy 422.461232 -67.740239) (xy 422.438296 -67.795612)
			(xy 422.408329 -67.847518) (xy 422.371842 -67.895068) (xy 422.329462 -67.937448) (xy 422.281912 -67.973935)
			(xy 422.230006 -68.003902) (xy 422.174633 -68.026838) (xy 422.11674 -68.042351) (xy 422.057318 -68.050174)
			(xy 421.997382 -68.050174) (xy 421.93796 -68.042351) (xy 421.880067 -68.026838) (xy 421.824694 -68.003902)
			(xy 421.772788 -67.973935) (xy 421.725238 -67.937448) (xy 421.682858 -67.895068) (xy 421.646371 -67.847518)
			(xy 421.616404 -67.795612) (xy 421.593468 -67.740239) (xy 421.577955 -67.682346) (xy 421.570132 -67.622924)
			(xy 421.203214 -67.622924) (xy 421.202681 -67.626974) (xy 421.187168 -67.684867) (xy 421.164232 -67.74024)
			(xy 421.134265 -67.792146) (xy 421.097778 -67.839696) (xy 421.055398 -67.882076) (xy 421.007848 -67.918563)
			(xy 420.955942 -67.94853) (xy 420.900569 -67.971466) (xy 420.842676 -67.986979) (xy 420.783254 -67.994802)
			(xy 420.723318 -67.994802) (xy 420.663896 -67.986979) (xy 420.606003 -67.971466) (xy 420.55063 -67.94853)
			(xy 420.498724 -67.918563) (xy 420.451174 -67.882076) (xy 420.408794 -67.839696) (xy 420.372307 -67.792146)
			(xy 420.34234 -67.74024) (xy 420.319404 -67.684867) (xy 420.303891 -67.626974) (xy 420.296068 -67.567552)
			(xy 419.911856 -67.567552) (xy 419.910545 -67.577503) (xy 419.895032 -67.635388) (xy 419.872096 -67.690754)
			(xy 419.84213 -67.742652) (xy 419.805646 -67.790195) (xy 419.763268 -67.832569) (xy 419.715723 -67.869049)
			(xy 419.663822 -67.899012) (xy 419.608455 -67.921944) (xy 419.550568 -67.937452) (xy 419.491152 -67.945273)
			(xy 419.461188 -67.945762) (xy 419.43277 -67.945332) (xy 419.376371 -67.938303) (xy 419.321277 -67.924344)
			(xy 419.268336 -67.903668) (xy 419.218363 -67.876595) (xy 419.194996 -67.860418) (xy 419.183312 -67.852036)
			(xy 419.154864 -67.850004) (xy 419.061646 -67.899026) (xy 419.053569 -67.903769) (xy 419.041222 -67.917828)
			(xy 419.034753 -67.935385) (xy 419.034468 -67.944746) (xy 419.034468 -67.951604) (xy 419.034012 -67.978975)
			(xy 419.026193 -68.033155) (xy 419.010702 -68.085658) (xy 418.987858 -68.135405) (xy 418.958131 -68.181371)
			(xy 418.940488 -68.202302) (xy 418.940234 -68.202556) (xy 418.934652 -68.209645) (xy 418.928404 -68.22656)
			(xy 418.928042 -68.235576) (xy 418.928042 -68.302632) (xy 418.928375 -68.311652) (xy 418.934638 -68.328569)
			(xy 418.940234 -68.335652) (xy 418.940488 -68.335652) (xy 418.940488 -68.335906) (xy 418.958141 -68.356827)
			(xy 418.987852 -68.402802) (xy 419.010685 -68.452553) (xy 419.026173 -68.505056) (xy 419.033996 -68.559234)
			(xy 419.034468 -68.586604) (xy 419.034048 -68.613859) (xy 419.02629 -68.667813) (xy 419.010931 -68.720114)
			(xy 418.994299 -68.75653) (xy 422.470326 -68.75653) (xy 422.470803 -68.72916) (xy 422.478617 -68.674981)
			(xy 422.494104 -68.622478) (xy 422.516943 -68.572731) (xy 422.546666 -68.526764) (xy 422.564306 -68.505832)
			(xy 422.56456 -68.505578) (xy 422.570169 -68.498507) (xy 422.576401 -68.481578) (xy 422.576752 -68.472558)
			(xy 422.576752 -68.405502) (xy 422.576404 -68.396484) (xy 422.570151 -68.379567) (xy 422.56456 -68.372482)
			(xy 422.564306 -68.372482) (xy 422.564306 -68.372228) (xy 422.546668 -68.351295) (xy 422.516955 -68.305323)
			(xy 422.494119 -68.255575) (xy 422.478628 -68.203075) (xy 422.4708 -68.148899) (xy 422.470326 -68.12153)
			(xy 422.470783 -68.094276) (xy 422.478537 -68.040323) (xy 422.493891 -67.988023) (xy 422.516533 -67.938441)
			(xy 422.546001 -67.892586) (xy 422.581695 -67.851392) (xy 422.622889 -67.815698) (xy 422.668745 -67.786231)
			(xy 422.718327 -67.76359) (xy 422.770627 -67.748236) (xy 422.82458 -67.740483) (xy 422.851834 -67.740022)
			(xy 422.879205 -67.740463) (xy 422.933386 -67.748286) (xy 422.985889 -67.763781) (xy 423.035636 -67.786628)
			(xy 423.081601 -67.816358) (xy 423.102532 -67.834002) (xy 423.102786 -67.834256) (xy 423.109868 -67.83985)
			(xy 423.126788 -67.846091) (xy 423.135806 -67.846448) (xy 423.202862 -67.846448) (xy 423.211878 -67.846084)
			(xy 423.228796 -67.839843) (xy 423.235882 -67.834256) (xy 423.235882 -67.834002) (xy 423.236136 -67.834002)
			(xy 423.257082 -67.81638) (xy 423.303051 -67.786665) (xy 423.352795 -67.763826) (xy 423.405292 -67.748331)
			(xy 423.459466 -67.740498) (xy 423.486834 -67.740022) (xy 423.513149 -67.74046) (xy 423.565279 -67.7477)
			(xy 423.615923 -67.762024) (xy 423.664122 -67.783162) (xy 423.708964 -67.810714) (xy 423.749603 -67.844158)
			(xy 423.767758 -67.863212) (xy 423.775292 -67.870599) (xy 423.794563 -67.879131) (xy 423.805096 -67.879722)
			(xy 423.879772 -67.879722) (xy 423.890321 -67.879185) (xy 423.909615 -67.870654) (xy 423.91711 -67.863212)
			(xy 423.93527 -67.844161) (xy 423.975899 -67.810703) (xy 424.020738 -67.783143) (xy 424.068938 -67.762004)
			(xy 424.119585 -67.747686) (xy 424.171718 -67.740461) (xy 424.198034 -67.740022) (xy 424.225287 -67.740446)
			(xy 424.279239 -67.748208) (xy 424.331537 -67.763569) (xy 424.381116 -67.786216) (xy 424.426968 -67.815689)
			(xy 424.468158 -67.851387) (xy 424.503849 -67.892584) (xy 424.533314 -67.93844) (xy 424.555953 -67.988023)
			(xy 424.571305 -68.040324) (xy 424.579058 -68.094276) (xy 424.579542 -68.12153) (xy 424.579108 -68.148902)
			(xy 424.571284 -68.203083) (xy 424.555789 -68.255587) (xy 424.532939 -68.305333) (xy 424.503207 -68.351298)
			(xy 424.485562 -68.372228) (xy 424.485308 -68.372482) (xy 424.479724 -68.37957) (xy 424.473475 -68.396486)
			(xy 424.473116 -68.405502) (xy 424.473116 -68.472558) (xy 424.47349 -68.481573) (xy 424.479725 -68.49849)
			(xy 424.485308 -68.505578) (xy 424.485562 -68.505578) (xy 424.485562 -68.505832) (xy 424.503177 -68.526784)
			(xy 424.532894 -68.572751) (xy 424.539255 -68.586604) (xy 442.9252 -68.586604) (xy 442.925668 -68.559234)
			(xy 442.933486 -68.505055) (xy 442.948974 -68.452552) (xy 442.971815 -68.402805) (xy 443.001539 -68.356838)
			(xy 443.01918 -68.335906) (xy 443.019434 -68.335652) (xy 443.025009 -68.328557) (xy 443.031261 -68.311647)
			(xy 443.031626 -68.302632) (xy 443.031626 -68.235576) (xy 443.031275 -68.226559) (xy 443.025023 -68.209642)
			(xy 443.019434 -68.202556) (xy 443.01918 -68.202556) (xy 443.01918 -68.202302) (xy 443.001525 -68.181383)
			(xy 442.971816 -68.135406) (xy 442.948984 -68.085655) (xy 442.933496 -68.033152) (xy 442.925672 -67.978974)
			(xy 442.9252 -67.951604) (xy 442.925659 -67.924351) (xy 442.933416 -67.870399) (xy 442.948772 -67.818101)
			(xy 442.971414 -67.76852) (xy 443.000883 -67.722667) (xy 443.036577 -67.681474) (xy 443.07777 -67.64578)
			(xy 443.123624 -67.616312) (xy 443.173205 -67.59367) (xy 443.225503 -67.578315) (xy 443.279455 -67.570559)
			(xy 443.306708 -67.570096) (xy 443.333022 -67.570559) (xy 443.385151 -67.577795) (xy 443.435793 -67.592115)
			(xy 443.483992 -67.613248) (xy 443.528836 -67.640795) (xy 443.569475 -67.674234) (xy 443.587632 -67.693286)
			(xy 443.595142 -67.700702) (xy 443.614431 -67.709218) (xy 443.62497 -67.709796) (xy 443.699646 -67.709796)
			(xy 443.710194 -67.709253) (xy 443.72949 -67.700728) (xy 443.736984 -67.693286) (xy 443.755152 -67.674243)
			(xy 443.795779 -67.640785) (xy 443.840617 -67.613225) (xy 443.888815 -67.592084) (xy 443.93946 -67.577764)
			(xy 443.991593 -67.570536) (xy 444.017908 -67.570096) (xy 444.045278 -67.570558) (xy 444.099458 -67.578377)
			(xy 444.151961 -67.593867) (xy 444.201707 -67.61671) (xy 444.247674 -67.646435) (xy 444.268606 -67.664076)
			(xy 444.26886 -67.66433) (xy 444.275951 -67.669909) (xy 444.292865 -67.676159) (xy 444.30188 -67.676522)
			(xy 444.368936 -67.676522) (xy 444.377954 -67.676178) (xy 444.394871 -67.669921) (xy 444.401956 -67.66433)
			(xy 444.401956 -67.664076) (xy 444.40221 -67.664076) (xy 444.423124 -67.646415) (xy 444.469102 -67.616707)
			(xy 444.518854 -67.593876) (xy 444.571359 -67.57839) (xy 444.625538 -67.570567) (xy 444.652908 -67.570096)
			(xy 444.678997 -67.570514) (xy 444.730687 -67.577626) (xy 444.780926 -67.591715) (xy 444.828776 -67.61252)
			(xy 444.851282 -67.625722) (xy 444.863728 -67.633342) (xy 444.892176 -67.633088) (xy 444.993776 -67.569842)
			(xy 445.006476 -67.543934) (xy 445.005206 -67.52971) (xy 445.003428 -67.488054) (xy 445.003931 -67.458091)
			(xy 445.011759 -67.398677) (xy 445.027274 -67.340793) (xy 445.050212 -67.28543) (xy 445.08018 -67.233534)
			(xy 445.116664 -67.185994) (xy 445.159042 -67.143622) (xy 445.206588 -67.107144) (xy 445.258488 -67.077183)
			(xy 445.313855 -67.054253) (xy 445.37174 -67.038746) (xy 445.431155 -67.030927) (xy 445.491082 -67.030929)
			(xy 445.550496 -67.038753) (xy 445.608381 -67.054265) (xy 445.663745 -67.0772) (xy 445.715643 -67.107164)
			(xy 445.763186 -67.143646) (xy 445.80556 -67.186022) (xy 445.842041 -67.233565) (xy 445.872005 -67.285463)
			(xy 445.894938 -67.340829) (xy 445.910449 -67.398714) (xy 445.918272 -67.458128) (xy 445.918273 -67.518055)
			(xy 445.911757 -67.567552) (xy 446.296016 -67.567552) (xy 446.296016 -67.507616) (xy 446.303839 -67.448194)
			(xy 446.319352 -67.390301) (xy 446.342288 -67.334928) (xy 446.372255 -67.283022) (xy 446.408742 -67.235472)
			(xy 446.451122 -67.193092) (xy 446.498672 -67.156605) (xy 446.550578 -67.126638) (xy 446.605951 -67.103702)
			(xy 446.663844 -67.088189) (xy 446.723266 -67.080366) (xy 446.783202 -67.080366) (xy 446.842624 -67.088189)
			(xy 446.900517 -67.103702) (xy 446.95589 -67.126638) (xy 447.007796 -67.156605) (xy 447.055346 -67.193092)
			(xy 447.097726 -67.235472) (xy 447.134213 -67.283022) (xy 447.16418 -67.334928) (xy 447.187116 -67.390301)
			(xy 447.202629 -67.448194) (xy 447.210452 -67.507616) (xy 447.210942 -67.537584) (xy 447.210452 -67.567552)
			(xy 447.203162 -67.622924) (xy 447.57008 -67.622924) (xy 447.57008 -67.562988) (xy 447.577903 -67.503566)
			(xy 447.593416 -67.445673) (xy 447.616352 -67.3903) (xy 447.646319 -67.338394) (xy 447.682806 -67.290844)
			(xy 447.725186 -67.248464) (xy 447.772736 -67.211977) (xy 447.824642 -67.18201) (xy 447.880015 -67.159074)
			(xy 447.937908 -67.143561) (xy 447.99733 -67.135738) (xy 448.057266 -67.135738) (xy 448.116688 -67.143561)
			(xy 448.174581 -67.159074) (xy 448.229954 -67.18201) (xy 448.28186 -67.211977) (xy 448.32941 -67.248464)
			(xy 448.37179 -67.290844) (xy 448.408277 -67.338394) (xy 448.438244 -67.3903) (xy 448.46118 -67.445673)
			(xy 448.476693 -67.503566) (xy 448.484516 -67.562988) (xy 448.48455 -67.565051) (xy 450.746593 -67.565051)
			(xy 450.746593 -67.510549) (xy 450.75435 -67.456601) (xy 450.769706 -67.404307) (xy 450.792348 -67.35473)
			(xy 450.821815 -67.308881) (xy 450.857507 -67.267692) (xy 450.898698 -67.232001) (xy 450.94455 -67.202537)
			(xy 450.994128 -67.179898) (xy 451.046423 -67.164545) (xy 451.100371 -67.156792) (xy 451.127622 -67.15633)
			(xy 451.154993 -67.156776) (xy 451.209173 -67.164597) (xy 451.261677 -67.180091) (xy 451.311423 -67.202937)
			(xy 451.357389 -67.232666) (xy 451.37832 -67.25031) (xy 451.378574 -67.250564) (xy 451.385658 -67.256153)
			(xy 451.402577 -67.262397) (xy 451.411594 -67.262756) (xy 451.47865 -67.262756) (xy 451.487666 -67.262385)
			(xy 451.504583 -67.256148) (xy 451.51167 -67.250564) (xy 451.51167 -67.25031) (xy 451.511924 -67.25031)
			(xy 451.532875 -67.232695) (xy 451.578843 -67.202979) (xy 451.628585 -67.180138) (xy 451.681082 -67.164642)
			(xy 451.735254 -67.156807) (xy 451.762622 -67.15633) (xy 451.789875 -67.156741) (xy 451.843826 -67.164501)
			(xy 451.896123 -67.17986) (xy 451.945702 -67.202504) (xy 451.991555 -67.231974) (xy 452.032746 -67.267669)
			(xy 452.068439 -67.308863) (xy 452.097906 -67.354717) (xy 452.120548 -67.404298) (xy 452.135903 -67.456596)
			(xy 452.14366 -67.510547) (xy 452.14366 -67.565053) (xy 452.135903 -67.619004) (xy 452.120548 -67.671302)
			(xy 452.097906 -67.720883) (xy 452.068439 -67.766737) (xy 452.032746 -67.807931) (xy 451.991555 -67.843626)
			(xy 451.945702 -67.873096) (xy 451.896123 -67.89574) (xy 451.843826 -67.911099) (xy 451.789875 -67.918859)
			(xy 451.762622 -67.919346) (xy 451.735252 -67.91888) (xy 451.681072 -67.911064) (xy 451.628568 -67.895576)
			(xy 451.578821 -67.872734) (xy 451.532855 -67.843008) (xy 451.511924 -67.825366) (xy 451.51167 -67.825112)
			(xy 451.504567 -67.81955) (xy 451.487663 -67.813288) (xy 451.47865 -67.81292) (xy 451.411594 -67.81292)
			(xy 451.402576 -67.81327) (xy 451.385659 -67.819522) (xy 451.378574 -67.825112) (xy 451.378574 -67.825366)
			(xy 451.37832 -67.825366) (xy 451.357387 -67.843004) (xy 451.311415 -67.872717) (xy 451.261668 -67.895554)
			(xy 451.209167 -67.911045) (xy 451.154991 -67.918873) (xy 451.127622 -67.919346) (xy 451.100371 -67.918808)
			(xy 451.046423 -67.911055) (xy 450.994128 -67.895702) (xy 450.94455 -67.873063) (xy 450.898698 -67.843599)
			(xy 450.857507 -67.807908) (xy 450.821815 -67.766719) (xy 450.792348 -67.72087) (xy 450.769706 -67.671293)
			(xy 450.75435 -67.618999) (xy 450.746593 -67.565051) (xy 448.48455 -67.565051) (xy 448.485006 -67.592956)
			(xy 448.484516 -67.622924) (xy 448.476693 -67.682346) (xy 448.46118 -67.740239) (xy 448.438244 -67.795612)
			(xy 448.408277 -67.847518) (xy 448.37179 -67.895068) (xy 448.32941 -67.937448) (xy 448.28186 -67.973935)
			(xy 448.229954 -68.003902) (xy 448.174581 -68.026838) (xy 448.116688 -68.042351) (xy 448.057266 -68.050174)
			(xy 447.99733 -68.050174) (xy 447.937908 -68.042351) (xy 447.880015 -68.026838) (xy 447.824642 -68.003902)
			(xy 447.772736 -67.973935) (xy 447.725186 -67.937448) (xy 447.682806 -67.895068) (xy 447.646319 -67.847518)
			(xy 447.616352 -67.795612) (xy 447.593416 -67.740239) (xy 447.577903 -67.682346) (xy 447.57008 -67.622924)
			(xy 447.203162 -67.622924) (xy 447.202629 -67.626974) (xy 447.187116 -67.684867) (xy 447.16418 -67.74024)
			(xy 447.134213 -67.792146) (xy 447.097726 -67.839696) (xy 447.055346 -67.882076) (xy 447.007796 -67.918563)
			(xy 446.95589 -67.94853) (xy 446.900517 -67.971466) (xy 446.842624 -67.986979) (xy 446.783202 -67.994802)
			(xy 446.723266 -67.994802) (xy 446.663844 -67.986979) (xy 446.605951 -67.971466) (xy 446.550578 -67.94853)
			(xy 446.498672 -67.918563) (xy 446.451122 -67.882076) (xy 446.408742 -67.839696) (xy 446.372255 -67.792146)
			(xy 446.342288 -67.74024) (xy 446.319352 -67.684867) (xy 446.303839 -67.626974) (xy 446.296016 -67.567552)
			(xy 445.911757 -67.567552) (xy 445.910452 -67.577469) (xy 445.894944 -67.635355) (xy 445.872012 -67.690721)
			(xy 445.842051 -67.74262) (xy 445.805572 -67.790165) (xy 445.763199 -67.832542) (xy 445.715658 -67.869026)
			(xy 445.663761 -67.898993) (xy 445.608397 -67.921929) (xy 445.550513 -67.937443) (xy 445.491099 -67.94527)
			(xy 445.461136 -67.945762) (xy 445.432717 -67.945359) (xy 445.376318 -67.938324) (xy 445.321223 -67.924358)
			(xy 445.268282 -67.903677) (xy 445.218311 -67.876598) (xy 445.194944 -67.860418) (xy 445.18326 -67.852036)
			(xy 445.154812 -67.850004) (xy 445.061594 -67.899026) (xy 445.053506 -67.903751) (xy 445.041165 -67.91782)
			(xy 445.0347 -67.935383) (xy 445.034416 -67.944746) (xy 445.034416 -67.951604) (xy 445.033973 -67.978975)
			(xy 445.026153 -68.033156) (xy 445.010659 -68.08566) (xy 444.987812 -68.135407) (xy 444.958081 -68.181372)
			(xy 444.940436 -68.202302) (xy 444.940182 -68.202556) (xy 444.934606 -68.20965) (xy 444.928353 -68.226561)
			(xy 444.92799 -68.235576) (xy 444.92799 -68.302632) (xy 444.928334 -68.31165) (xy 444.934591 -68.328567)
			(xy 444.940182 -68.335652) (xy 444.940436 -68.335652) (xy 444.940436 -68.335906) (xy 444.958097 -68.35682)
			(xy 444.987804 -68.402799) (xy 445.010635 -68.452551) (xy 445.026121 -68.505055) (xy 445.033945 -68.559234)
			(xy 445.034416 -68.586604) (xy 445.033926 -68.613855) (xy 445.026169 -68.667802) (xy 445.010814 -68.720096)
			(xy 444.994175 -68.75653) (xy 448.470274 -68.75653) (xy 448.47074 -68.72916) (xy 448.478555 -68.67498)
			(xy 448.494043 -68.622476) (xy 448.516885 -68.572729) (xy 448.546612 -68.526763) (xy 448.564254 -68.505832)
			(xy 448.564508 -68.505578) (xy 448.570111 -68.498503) (xy 448.576347 -68.481577) (xy 448.5767 -68.472558)
			(xy 448.5767 -68.405502) (xy 448.576342 -68.396485) (xy 448.570095 -68.379568) (xy 448.564508 -68.372482)
			(xy 448.564254 -68.372482) (xy 448.564254 -68.372228) (xy 448.546623 -68.351289) (xy 448.516908 -68.305319)
			(xy 448.49407 -68.255573) (xy 448.478577 -68.203074) (xy 448.470748 -68.148899) (xy 448.470274 -68.12153)
			(xy 448.470783 -68.094279) (xy 448.478536 -68.04033) (xy 448.493887 -67.988034) (xy 448.516525 -67.938456)
			(xy 448.545988 -67.892603) (xy 448.581677 -67.851411) (xy 448.622865 -67.815717) (xy 448.668713 -67.786248)
			(xy 448.718289 -67.763604) (xy 448.770583 -67.748246) (xy 448.824531 -67.740487) (xy 448.851782 -67.740022)
			(xy 448.879152 -67.740493) (xy 448.933331 -67.748309) (xy 448.985834 -67.763797) (xy 449.035581 -67.786637)
			(xy 449.081548 -67.816361) (xy 449.10248 -67.834002) (xy 449.102734 -67.834256) (xy 449.10983 -67.839828)
			(xy 449.12674 -67.846082) (xy 449.135754 -67.846448) (xy 449.20281 -67.846448) (xy 449.211829 -67.846107)
			(xy 449.228746 -67.839849) (xy 449.23583 -67.834256) (xy 449.23583 -67.834002) (xy 449.236084 -67.834002)
			(xy 449.257012 -67.816357) (xy 449.302986 -67.786646) (xy 449.352734 -67.763811) (xy 449.405236 -67.748322)
			(xy 449.459413 -67.740495) (xy 449.486782 -67.740022) (xy 449.513096 -67.740494) (xy 449.565224 -67.747727)
			(xy 449.615867 -67.762045) (xy 449.664067 -67.783176) (xy 449.70891 -67.810722) (xy 449.74955 -67.84416)
			(xy 449.767706 -67.863212) (xy 449.775222 -67.87062) (xy 449.794506 -67.879141) (xy 449.805044 -67.879722)
			(xy 449.87972 -67.879722) (xy 449.890265 -67.879157) (xy 449.909561 -67.870646) (xy 449.917058 -67.863212)
			(xy 449.935195 -67.844138) (xy 449.975828 -67.810682) (xy 450.020672 -67.783125) (xy 450.068877 -67.76199)
			(xy 450.119528 -67.747677) (xy 450.171665 -67.740457) (xy 450.197982 -67.740022) (xy 450.225236 -67.740472)
			(xy 450.279189 -67.748227) (xy 450.331489 -67.763583) (xy 450.381071 -67.786225) (xy 450.426925 -67.815694)
			(xy 450.468119 -67.851389) (xy 450.503813 -67.892584) (xy 450.53328 -67.93844) (xy 450.555921 -67.988023)
			(xy 450.571275 -68.040323) (xy 450.579029 -68.094276) (xy 450.57949 -68.12153) (xy 450.579044 -68.148901)
			(xy 450.571222 -68.203081) (xy 450.555728 -68.255584) (xy 450.532882 -68.305331) (xy 450.503153 -68.351297)
			(xy 450.48551 -68.372228) (xy 450.485256 -68.372482) (xy 450.479666 -68.379566) (xy 450.473422 -68.396485)
			(xy 450.473064 -68.405502) (xy 450.473064 -68.472558) (xy 450.473449 -68.481572) (xy 450.479678 -68.498489)
			(xy 450.485256 -68.505578) (xy 450.48551 -68.505578) (xy 450.48551 -68.505832) (xy 450.503132 -68.526778)
			(xy 450.532846 -68.572747) (xy 450.555685 -68.622491) (xy 450.57118 -68.674989) (xy 450.579013 -68.729162)
			(xy 450.57949 -68.75653) (xy 450.57905 -68.783783) (xy 450.571289 -68.837733) (xy 450.555929 -68.89003)
			(xy 450.533283 -68.939608) (xy 450.503812 -68.985459) (xy 450.468116 -69.02665) (xy 450.426921 -69.062341)
			(xy 450.381066 -69.091806) (xy 450.331485 -69.114446) (xy 450.279186 -69.129799) (xy 450.225235 -69.137553)
			(xy 450.197982 -69.138038) (xy 450.171667 -69.137602) (xy 450.119536 -69.130364) (xy 450.068892 -69.11604)
			(xy 450.020693 -69.094902) (xy 449.97585 -69.067349) (xy 449.935213 -69.033903) (xy 449.917058 -69.014848)
			(xy 449.909547 -69.007433) (xy 449.890259 -68.998915) (xy 449.87972 -68.998338) (xy 449.805044 -68.998338)
			(xy 449.794494 -68.998866) (xy 449.775198 -69.007401) (xy 449.767706 -69.014848) (xy 449.74955 -69.033903)
			(xy 449.708919 -69.067358) (xy 449.664079 -69.094916) (xy 449.615878 -69.116054) (xy 449.565231 -69.130372)
			(xy 449.513098 -69.137598) (xy 449.486782 -69.138038) (xy 449.459411 -69.137598) (xy 449.40523 -69.129776)
			(xy 449.352726 -69.114282) (xy 449.302979 -69.091434) (xy 449.257014 -69.061703) (xy 449.236084 -69.044058)
			(xy 449.23583 -69.043804) (xy 449.228739 -69.038224) (xy 449.211826 -69.031973) (xy 449.20281 -69.031612)
			(xy 449.135754 -69.031612) (xy 449.126739 -69.031992) (xy 449.109822 -69.038224) (xy 449.102734 -69.043804)
			(xy 449.102734 -69.044058) (xy 449.10248 -69.044058) (xy 449.081523 -69.061667) (xy 449.035558 -69.091384)
			(xy 448.985817 -69.114227) (xy 448.933321 -69.129725) (xy 448.87915 -69.13756) (xy 448.851782 -69.138038)
			(xy 448.824532 -69.137539) (xy 448.770586 -69.129781) (xy 448.718293 -69.114425) (xy 448.668718 -69.091784)
			(xy 448.622869 -69.062319) (xy 448.58168 -69.026629) (xy 448.545989 -68.98544) (xy 448.516522 -68.939593)
			(xy 448.493879 -68.890018) (xy 448.478522 -68.837726) (xy 448.470762 -68.78378) (xy 448.470274 -68.75653)
			(xy 444.994175 -68.75653) (xy 444.988173 -68.769673) (xy 444.958707 -68.815523) (xy 444.923016 -68.856713)
			(xy 444.881826 -68.892404) (xy 444.835977 -68.921871) (xy 444.7864 -68.944512) (xy 444.734106 -68.959868)
			(xy 444.680159 -68.967626) (xy 444.652908 -68.968112) (xy 444.625538 -68.967638) (xy 444.571359 -68.959822)
			(xy 444.518857 -68.944334) (xy 444.46911 -68.921494) (xy 444.423142 -68.891772) (xy 444.40221 -68.874132)
			(xy 444.401956 -68.873878) (xy 444.394859 -68.868306) (xy 444.37795 -68.862051) (xy 444.368936 -68.861686)
			(xy 444.30188 -68.861686) (xy 444.292863 -68.862037) (xy 444.275946 -68.868289) (xy 444.26886 -68.873878)
			(xy 444.26886 -68.874132) (xy 444.268606 -68.874132) (xy 444.247687 -68.891787) (xy 444.20171 -68.921495)
			(xy 444.151959 -68.944328) (xy 444.099456 -68.959815) (xy 444.045278 -68.96764) (xy 444.017908 -68.968112)
			(xy 443.991594 -68.967635) (xy 443.939466 -68.960402) (xy 443.888824 -68.946084) (xy 443.840625 -68.924954)
			(xy 443.795781 -68.897409) (xy 443.755141 -68.863973) (xy 443.736984 -68.844922) (xy 443.729467 -68.837515)
			(xy 443.710184 -68.828993) (xy 443.699646 -68.828412) (xy 443.62497 -68.828412) (xy 443.614423 -68.828962)
			(xy 443.595127 -68.837482) (xy 443.587632 -68.844922) (xy 443.569507 -68.864008) (xy 443.52887 -68.897461)
			(xy 443.484023 -68.925016) (xy 443.435817 -68.946149) (xy 443.385164 -68.96046) (xy 443.333026 -68.967677)
			(xy 443.306708 -68.968112) (xy 443.279456 -68.967637) (xy 443.225505 -68.959881) (xy 443.173208 -68.944527)
			(xy 443.123628 -68.921885) (xy 443.077775 -68.892419) (xy 443.036582 -68.856726) (xy 443.000889 -68.815535)
			(xy 442.97142 -68.769683) (xy 442.948778 -68.720103) (xy 442.933421 -68.667807) (xy 442.925664 -68.613856)
			(xy 442.9252 -68.586604) (xy 424.539255 -68.586604) (xy 424.555735 -68.622493) (xy 424.571231 -68.67499)
			(xy 424.579065 -68.729162) (xy 424.579542 -68.75653) (xy 424.57905 -68.78378) (xy 424.57129 -68.837726)
			(xy 424.555933 -68.890019) (xy 424.533291 -68.939594) (xy 424.503825 -68.985442) (xy 424.468134 -69.026631)
			(xy 424.426946 -69.062322) (xy 424.381097 -69.091789) (xy 424.331522 -69.114432) (xy 424.27923 -69.12979)
			(xy 424.225284 -69.13755) (xy 424.198034 -69.138038) (xy 424.171718 -69.137634) (xy 424.119586 -69.130389)
			(xy 424.068941 -69.116059) (xy 424.020742 -69.094915) (xy 423.9759 -69.067356) (xy 423.935264 -69.033906)
			(xy 423.91711 -69.014848) (xy 423.90958 -69.007456) (xy 423.890307 -68.998925) (xy 423.879772 -68.998338)
			(xy 423.805096 -68.998338) (xy 423.794543 -68.99884) (xy 423.775247 -69.007393) (xy 423.767758 -69.014848)
			(xy 423.749625 -69.033926) (xy 423.70899 -69.067379) (xy 423.664144 -69.094934) (xy 423.615939 -69.116068)
			(xy 423.565288 -69.130381) (xy 423.513151 -69.137602) (xy 423.486834 -69.138038) (xy 423.459464 -69.137567)
			(xy 423.405284 -69.129753) (xy 423.352781 -69.114266) (xy 423.303034 -69.091425) (xy 423.257067 -69.0617)
			(xy 423.236136 -69.044058) (xy 423.235882 -69.043804) (xy 423.228804 -69.038204) (xy 423.211881 -69.031965)
			(xy 423.202862 -69.031612) (xy 423.135806 -69.031612) (xy 423.126789 -69.031969) (xy 423.109872 -69.038216)
			(xy 423.102786 -69.043804) (xy 423.102786 -69.044058) (xy 423.102532 -69.044058) (xy 423.081593 -69.061689)
			(xy 423.035623 -69.091404) (xy 422.985877 -69.114242) (xy 422.933378 -69.129734) (xy 422.879203 -69.137564)
			(xy 422.851834 -69.138038) (xy 422.824583 -69.137513) (xy 422.770636 -69.129762) (xy 422.718341 -69.114411)
			(xy 422.668763 -69.091775) (xy 422.622911 -69.062313) (xy 422.581719 -69.026626) (xy 422.546025 -68.98544)
			(xy 422.516556 -68.939593) (xy 422.493911 -68.890019) (xy 422.478552 -68.837726) (xy 422.470791 -68.783781)
			(xy 422.470326 -68.75653) (xy 418.994299 -68.75653) (xy 418.988285 -68.769697) (xy 418.958813 -68.815552)
			(xy 418.923115 -68.856746) (xy 418.881917 -68.89244) (xy 418.836059 -68.921906) (xy 418.786473 -68.944547)
			(xy 418.73417 -68.959899) (xy 418.680215 -68.967651) (xy 418.65296 -68.968112) (xy 418.625591 -68.967608)
			(xy 418.571414 -68.959799) (xy 418.518911 -68.944318) (xy 418.469164 -68.921485) (xy 418.423195 -68.891769)
			(xy 418.402262 -68.874132) (xy 418.402008 -68.873878) (xy 418.394925 -68.868286) (xy 418.378005 -68.862043)
			(xy 418.368988 -68.861686) (xy 418.301932 -68.861686) (xy 418.292917 -68.862061) (xy 418.276 -68.868296)
			(xy 418.268912 -68.873878) (xy 418.268912 -68.874132) (xy 418.268658 -68.874132) (xy 418.247719 -68.891762)
			(xy 418.201748 -68.921474) (xy 418.152002 -68.944312) (xy 418.099503 -68.959805) (xy 418.045329 -68.967636)
			(xy 418.01796 -68.968112) (xy 417.991645 -68.967667) (xy 417.939516 -68.960427) (xy 417.888873 -68.946104)
			(xy 417.840674 -68.924967) (xy 417.795831 -68.897417) (xy 417.755192 -68.863975) (xy 417.737036 -68.844922)
			(xy 417.7295 -68.837537) (xy 417.710231 -68.829003) (xy 417.699698 -68.828412) (xy 417.625022 -68.828412)
			(xy 417.614472 -68.828936) (xy 417.595176 -68.837474) (xy 417.587684 -68.844922) (xy 417.569534 -68.863983)
			(xy 417.528902 -68.897438) (xy 417.484061 -68.924996) (xy 417.435859 -68.946134) (xy 417.385211 -68.96045)
			(xy 417.333076 -68.967674) (xy 417.30676 -68.968112) (xy 417.279508 -68.967659) (xy 417.225559 -68.959898)
			(xy 417.173264 -68.944538) (xy 417.123687 -68.921892) (xy 417.077837 -68.892422) (xy 417.036647 -68.856727)
			(xy 417.000956 -68.815534) (xy 416.971491 -68.769681) (xy 416.94885 -68.720102) (xy 416.933495 -68.667806)
			(xy 416.925738 -68.613856) (xy 416.925252 -68.586604) (xy 398.539313 -68.586604) (xy 398.555789 -68.622491)
			(xy 398.571284 -68.674988) (xy 398.579117 -68.729162) (xy 398.579594 -68.75653) (xy 398.57915 -68.783783)
			(xy 398.571389 -68.837733) (xy 398.556029 -68.890029) (xy 398.533384 -68.939607) (xy 398.503913 -68.985458)
			(xy 398.468217 -69.026648) (xy 398.427023 -69.062339) (xy 398.381169 -69.091805) (xy 398.331588 -69.114445)
			(xy 398.27929 -69.129798) (xy 398.225339 -69.137553) (xy 398.198086 -69.138038) (xy 398.171771 -69.1376)
			(xy 398.11964 -69.130362) (xy 398.068996 -69.116038) (xy 398.020797 -69.0949) (xy 397.975954 -69.067348)
			(xy 397.935317 -69.033903) (xy 397.917162 -69.014848) (xy 397.90965 -69.007435) (xy 397.890363 -68.998916)
			(xy 397.879824 -68.998338) (xy 397.805148 -68.998338) (xy 397.794598 -68.998868) (xy 397.775302 -69.007402)
			(xy 397.76781 -69.014848) (xy 397.749652 -69.033901) (xy 397.709022 -69.067356) (xy 397.664182 -69.094915)
			(xy 397.615982 -69.116053) (xy 397.565335 -69.130371) (xy 397.513202 -69.137598) (xy 397.486886 -69.138038)
			(xy 397.459515 -69.137595) (xy 397.405334 -69.129774) (xy 397.35283 -69.11428) (xy 397.303084 -69.091433)
			(xy 397.257118 -69.061702) (xy 397.236188 -69.044058) (xy 397.235934 -69.043804) (xy 397.228842 -69.038226)
			(xy 397.211929 -69.031974) (xy 397.202914 -69.031612) (xy 397.135858 -69.031612) (xy 397.126844 -69.031994)
			(xy 397.109926 -69.038224) (xy 397.102838 -69.043804) (xy 397.102838 -69.044058) (xy 397.102584 -69.044058)
			(xy 397.081626 -69.061665) (xy 397.035661 -69.091383) (xy 396.98592 -69.114226) (xy 396.933425 -69.129724)
			(xy 396.879253 -69.13756) (xy 396.851886 -69.138038) (xy 396.824636 -69.137535) (xy 396.77069 -69.129778)
			(xy 396.718398 -69.114422) (xy 396.668822 -69.091782) (xy 396.622973 -69.062317) (xy 396.581784 -69.026627)
			(xy 396.546093 -68.985439) (xy 396.516626 -68.939592) (xy 396.493983 -68.890017) (xy 396.478626 -68.837725)
			(xy 396.470866 -68.78378) (xy 396.470378 -68.75653) (xy 392.994275 -68.75653) (xy 392.988273 -68.769672)
			(xy 392.958808 -68.815522) (xy 392.923117 -68.856712) (xy 392.881928 -68.892403) (xy 392.836079 -68.92187)
			(xy 392.786503 -68.944511) (xy 392.734209 -68.959868) (xy 392.680263 -68.967625) (xy 392.653012 -68.968112)
			(xy 392.625642 -68.967636) (xy 392.571464 -68.95982) (xy 392.518961 -68.944333) (xy 392.469214 -68.921494)
			(xy 392.423246 -68.891772) (xy 392.402314 -68.874132) (xy 392.40206 -68.873878) (xy 392.394962 -68.868308)
			(xy 392.378054 -68.862052) (xy 392.36904 -68.861686) (xy 392.301984 -68.861686) (xy 392.292967 -68.862039)
			(xy 392.27605 -68.86829) (xy 392.268964 -68.873878) (xy 392.268964 -68.874132) (xy 392.26871 -68.874132)
			(xy 392.247789 -68.891785) (xy 392.201813 -68.921494) (xy 392.152062 -68.944326) (xy 392.099559 -68.959814)
			(xy 392.045382 -68.967639) (xy 392.018012 -68.968112) (xy 391.991698 -68.967633) (xy 391.939571 -68.9604)
			(xy 391.888928 -68.946083) (xy 391.840729 -68.924952) (xy 391.795886 -68.897409) (xy 391.755245 -68.863972)
			(xy 391.737088 -68.844922) (xy 391.72957 -68.837516) (xy 391.710287 -68.828993) (xy 391.69975 -68.828412)
			(xy 391.625074 -68.828412) (xy 391.614527 -68.828964) (xy 391.595231 -68.837483) (xy 391.587736 -68.844922)
			(xy 391.569609 -68.864006) (xy 391.528973 -68.89746) (xy 391.484126 -68.925014) (xy 391.43592 -68.946148)
			(xy 391.385268 -68.960459) (xy 391.33313 -68.967677) (xy 391.306812 -68.968112) (xy 391.27956 -68.967634)
			(xy 391.225609 -68.959878) (xy 391.173312 -68.944524) (xy 391.123732 -68.921883) (xy 391.077879 -68.892417)
			(xy 391.036687 -68.856725) (xy 391.000993 -68.815533) (xy 390.971525 -68.769682) (xy 390.948882 -68.720103)
			(xy 390.933525 -68.667806) (xy 390.925768 -68.613856) (xy 390.925304 -68.586604) (xy 372.539359 -68.586604)
			(xy 372.555839 -68.622493) (xy 372.571336 -68.674989) (xy 372.579169 -68.729162) (xy 372.579646 -68.75653)
			(xy 372.57915 -68.78378) (xy 372.571391 -68.837726) (xy 372.556034 -68.890018) (xy 372.533392 -68.939593)
			(xy 372.503926 -68.985441) (xy 372.468236 -69.02663) (xy 372.427048 -69.062321) (xy 372.3812 -69.091788)
			(xy 372.331625 -69.114431) (xy 372.279333 -69.129789) (xy 372.225388 -69.13755) (xy 372.198138 -69.138038)
			(xy 372.171822 -69.137632) (xy 372.11969 -69.130387) (xy 372.069045 -69.116057) (xy 372.020846 -69.094914)
			(xy 371.976004 -69.067356) (xy 371.935368 -69.033905) (xy 371.917214 -69.014848) (xy 371.909683 -69.007458)
			(xy 371.89041 -68.998925) (xy 371.879876 -68.998338) (xy 371.8052 -68.998338) (xy 371.794647 -68.998842)
			(xy 371.775351 -69.007394) (xy 371.767862 -69.014848) (xy 371.749727 -69.033924) (xy 371.709092 -69.067378)
			(xy 371.664247 -69.094933) (xy 371.616042 -69.116067) (xy 371.565392 -69.130381) (xy 371.513255 -69.137601)
			(xy 371.486938 -69.138038) (xy 371.459568 -69.137565) (xy 371.405388 -69.129751) (xy 371.352885 -69.114264)
			(xy 371.303138 -69.091424) (xy 371.257171 -69.061699) (xy 371.23624 -69.044058) (xy 371.235986 -69.043804)
			(xy 371.228907 -69.038206) (xy 371.211985 -69.031966) (xy 371.202966 -69.031612) (xy 371.13591 -69.031612)
			(xy 371.126893 -69.031971) (xy 371.109976 -69.038217) (xy 371.10289 -69.043804) (xy 371.10289 -69.044058)
			(xy 371.102636 -69.044058) (xy 371.081696 -69.061687) (xy 371.035726 -69.091402) (xy 370.985981 -69.11424)
			(xy 370.933481 -69.129734) (xy 370.879307 -69.137563) (xy 370.851938 -69.138038) (xy 370.824687 -69.137509)
			(xy 370.77074 -69.129758) (xy 370.718446 -69.114409) (xy 370.668868 -69.091773) (xy 370.623016 -69.062312)
			(xy 370.581823 -69.026625) (xy 370.546129 -68.985439) (xy 370.51666 -68.939592) (xy 370.494015 -68.890018)
			(xy 370.478656 -68.837726) (xy 370.470895 -68.78378) (xy 370.47043 -68.75653) (xy 366.994399 -68.75653)
			(xy 366.988386 -68.769696) (xy 366.958914 -68.815551) (xy 366.923216 -68.856745) (xy 366.882019 -68.892438)
			(xy 366.836161 -68.921905) (xy 366.786576 -68.944545) (xy 366.734274 -68.959898) (xy 366.680319 -68.967651)
			(xy 366.653064 -68.968112) (xy 366.625693 -68.967664) (xy 366.571513 -68.959841) (xy 366.51901 -68.944348)
			(xy 366.469264 -68.921502) (xy 366.423297 -68.891775) (xy 366.402366 -68.874132) (xy 366.402112 -68.873878)
			(xy 366.395028 -68.868288) (xy 366.378109 -68.862044) (xy 366.369092 -68.861686) (xy 366.302036 -68.861686)
			(xy 366.293021 -68.862063) (xy 366.276104 -68.868297) (xy 366.269016 -68.873878) (xy 366.269016 -68.874132)
			(xy 366.268762 -68.874132) (xy 366.247821 -68.89176) (xy 366.20185 -68.921473) (xy 366.152105 -68.94431)
			(xy 366.099606 -68.959804) (xy 366.045433 -68.967636) (xy 366.018064 -68.968112) (xy 365.991749 -68.967665)
			(xy 365.93962 -68.960425) (xy 365.888977 -68.946102) (xy 365.840778 -68.924966) (xy 365.795935 -68.897416)
			(xy 365.755296 -68.863975) (xy 365.73714 -68.844922) (xy 365.729603 -68.837539) (xy 365.710335 -68.829003)
			(xy 365.699802 -68.828412) (xy 365.625126 -68.828412) (xy 365.614576 -68.828938) (xy 365.59528 -68.837475)
			(xy 365.587788 -68.844922) (xy 365.569636 -68.863981) (xy 365.529005 -68.897437) (xy 365.484164 -68.924995)
			(xy 365.435962 -68.946132) (xy 365.385314 -68.960449) (xy 365.33318 -68.967674) (xy 365.306864 -68.968112)
			(xy 365.279612 -68.967656) (xy 365.225663 -68.959894) (xy 365.173368 -68.944535) (xy 365.123791 -68.92189)
			(xy 365.077941 -68.89242) (xy 365.036752 -68.856726) (xy 365.001061 -68.815533) (xy 364.971595 -68.769681)
			(xy 364.948954 -68.720102) (xy 364.933599 -68.667805) (xy 364.925842 -68.613856) (xy 364.925356 -68.586604)
			(xy 352.968403 -68.586604) (xy 352.973519 -68.590275) (xy 353.133476 -68.714908) (xy 353.288385 -68.845763)
			(xy 353.438003 -68.982636) (xy 353.582096 -69.125313) (xy 353.720441 -69.273571) (xy 353.85282 -69.42718)
			(xy 353.979027 -69.585898) (xy 354.098866 -69.749478) (xy 354.212148 -69.917665) (xy 354.318697 -70.090195)
			(xy 354.418347 -70.266801) (xy 354.510943 -70.447206) (xy 354.596339 -70.631128) (xy 354.674402 -70.81828)
			(xy 354.74501 -71.008369) (xy 354.808053 -71.2011) (xy 354.863433 -71.396172) (xy 354.909264 -71.585832)
			(xy 367.419364 -71.585832) (xy 367.419364 -71.525896) (xy 367.427187 -71.466474) (xy 367.4427 -71.408581)
			(xy 367.465636 -71.353208) (xy 367.495603 -71.301302) (xy 367.53209 -71.253752) (xy 367.57447 -71.211372)
			(xy 367.62202 -71.174885) (xy 367.673926 -71.144918) (xy 367.729299 -71.121982) (xy 367.787192 -71.106469)
			(xy 367.846614 -71.098646) (xy 367.90655 -71.098646) (xy 367.965972 -71.106469) (xy 368.023865 -71.121982)
			(xy 368.079238 -71.144918) (xy 368.131144 -71.174885) (xy 368.178694 -71.211372) (xy 368.221074 -71.253752)
			(xy 368.257561 -71.301302) (xy 368.287528 -71.353208) (xy 368.310464 -71.408581) (xy 368.325977 -71.466474)
			(xy 368.3338 -71.525896) (xy 368.33429 -71.555864) (xy 368.3338 -71.585832) (xy 368.325977 -71.645254)
			(xy 368.323795 -71.653396) (xy 368.928378 -71.653396) (xy 368.928378 -71.59346) (xy 368.936201 -71.534038)
			(xy 368.951714 -71.476145) (xy 368.97465 -71.420772) (xy 369.004617 -71.368866) (xy 369.041104 -71.321316)
			(xy 369.083484 -71.278936) (xy 369.131034 -71.242449) (xy 369.18294 -71.212482) (xy 369.238313 -71.189546)
			(xy 369.296206 -71.174033) (xy 369.355628 -71.16621) (xy 369.415564 -71.16621) (xy 369.474986 -71.174033)
			(xy 369.532879 -71.189546) (xy 369.588252 -71.212482) (xy 369.640158 -71.242449) (xy 369.687708 -71.278936)
			(xy 369.730088 -71.321316) (xy 369.766575 -71.368866) (xy 369.796542 -71.420772) (xy 369.819478 -71.476145)
			(xy 369.834991 -71.534038) (xy 369.84181 -71.585832) (xy 393.419312 -71.585832) (xy 393.419312 -71.525896)
			(xy 393.427135 -71.466474) (xy 393.442648 -71.408581) (xy 393.465584 -71.353208) (xy 393.495551 -71.301302)
			(xy 393.532038 -71.253752) (xy 393.574418 -71.211372) (xy 393.621968 -71.174885) (xy 393.673874 -71.144918)
			(xy 393.729247 -71.121982) (xy 393.78714 -71.106469) (xy 393.846562 -71.098646) (xy 393.906498 -71.098646)
			(xy 393.96592 -71.106469) (xy 394.023813 -71.121982) (xy 394.079186 -71.144918) (xy 394.131092 -71.174885)
			(xy 394.178642 -71.211372) (xy 394.221022 -71.253752) (xy 394.257509 -71.301302) (xy 394.287476 -71.353208)
			(xy 394.310412 -71.408581) (xy 394.325925 -71.466474) (xy 394.333748 -71.525896) (xy 394.334238 -71.555864)
			(xy 394.333748 -71.585832) (xy 394.325925 -71.645254) (xy 394.323743 -71.653396) (xy 394.928326 -71.653396)
			(xy 394.928326 -71.59346) (xy 394.936149 -71.534038) (xy 394.951662 -71.476145) (xy 394.974598 -71.420772)
			(xy 395.004565 -71.368866) (xy 395.041052 -71.321316) (xy 395.083432 -71.278936) (xy 395.130982 -71.242449)
			(xy 395.182888 -71.212482) (xy 395.238261 -71.189546) (xy 395.296154 -71.174033) (xy 395.355576 -71.16621)
			(xy 395.415512 -71.16621) (xy 395.474934 -71.174033) (xy 395.532827 -71.189546) (xy 395.5882 -71.212482)
			(xy 395.640106 -71.242449) (xy 395.687656 -71.278936) (xy 395.730036 -71.321316) (xy 395.766523 -71.368866)
			(xy 395.79649 -71.420772) (xy 395.819426 -71.476145) (xy 395.834939 -71.534038) (xy 395.841758 -71.585832)
			(xy 419.41926 -71.585832) (xy 419.41926 -71.525896) (xy 419.427083 -71.466474) (xy 419.442596 -71.408581)
			(xy 419.465532 -71.353208) (xy 419.495499 -71.301302) (xy 419.531986 -71.253752) (xy 419.574366 -71.211372)
			(xy 419.621916 -71.174885) (xy 419.673822 -71.144918) (xy 419.729195 -71.121982) (xy 419.787088 -71.106469)
			(xy 419.84651 -71.098646) (xy 419.906446 -71.098646) (xy 419.965868 -71.106469) (xy 420.023761 -71.121982)
			(xy 420.079134 -71.144918) (xy 420.13104 -71.174885) (xy 420.17859 -71.211372) (xy 420.22097 -71.253752)
			(xy 420.257457 -71.301302) (xy 420.287424 -71.353208) (xy 420.31036 -71.408581) (xy 420.325873 -71.466474)
			(xy 420.333696 -71.525896) (xy 420.334186 -71.555864) (xy 420.333696 -71.585832) (xy 420.325873 -71.645254)
			(xy 420.323691 -71.653396) (xy 420.928274 -71.653396) (xy 420.928274 -71.59346) (xy 420.936097 -71.534038)
			(xy 420.95161 -71.476145) (xy 420.974546 -71.420772) (xy 421.004513 -71.368866) (xy 421.041 -71.321316)
			(xy 421.08338 -71.278936) (xy 421.13093 -71.242449) (xy 421.182836 -71.212482) (xy 421.238209 -71.189546)
			(xy 421.296102 -71.174033) (xy 421.355524 -71.16621) (xy 421.41546 -71.16621) (xy 421.474882 -71.174033)
			(xy 421.532775 -71.189546) (xy 421.588148 -71.212482) (xy 421.640054 -71.242449) (xy 421.687604 -71.278936)
			(xy 421.729984 -71.321316) (xy 421.766471 -71.368866) (xy 421.796438 -71.420772) (xy 421.819374 -71.476145)
			(xy 421.834887 -71.534038) (xy 421.841706 -71.585832) (xy 445.419208 -71.585832) (xy 445.419208 -71.525896)
			(xy 445.427031 -71.466474) (xy 445.442544 -71.408581) (xy 445.46548 -71.353208) (xy 445.495447 -71.301302)
			(xy 445.531934 -71.253752) (xy 445.574314 -71.211372) (xy 445.621864 -71.174885) (xy 445.67377 -71.144918)
			(xy 445.729143 -71.121982) (xy 445.787036 -71.106469) (xy 445.846458 -71.098646) (xy 445.906394 -71.098646)
			(xy 445.965816 -71.106469) (xy 446.023709 -71.121982) (xy 446.079082 -71.144918) (xy 446.130988 -71.174885)
			(xy 446.178538 -71.211372) (xy 446.220918 -71.253752) (xy 446.257405 -71.301302) (xy 446.287372 -71.353208)
			(xy 446.310308 -71.408581) (xy 446.325821 -71.466474) (xy 446.333644 -71.525896) (xy 446.334134 -71.555864)
			(xy 446.333644 -71.585832) (xy 446.325821 -71.645254) (xy 446.323639 -71.653396) (xy 446.928222 -71.653396)
			(xy 446.928222 -71.59346) (xy 446.936045 -71.534038) (xy 446.951558 -71.476145) (xy 446.974494 -71.420772)
			(xy 447.004461 -71.368866) (xy 447.040948 -71.321316) (xy 447.083328 -71.278936) (xy 447.130878 -71.242449)
			(xy 447.182784 -71.212482) (xy 447.238157 -71.189546) (xy 447.29605 -71.174033) (xy 447.355472 -71.16621)
			(xy 447.415408 -71.16621) (xy 447.47483 -71.174033) (xy 447.532723 -71.189546) (xy 447.588096 -71.212482)
			(xy 447.640002 -71.242449) (xy 447.687552 -71.278936) (xy 447.729932 -71.321316) (xy 447.766419 -71.368866)
			(xy 447.796386 -71.420772) (xy 447.819322 -71.476145) (xy 447.834835 -71.534038) (xy 447.842658 -71.59346)
			(xy 447.843148 -71.623428) (xy 447.842658 -71.653396) (xy 447.834835 -71.712818) (xy 447.819322 -71.770711)
			(xy 447.796386 -71.826084) (xy 447.766419 -71.87799) (xy 447.729932 -71.92554) (xy 447.687552 -71.96792)
			(xy 447.640002 -72.004407) (xy 447.588096 -72.034374) (xy 447.532723 -72.05731) (xy 447.47483 -72.072823)
			(xy 447.415408 -72.080646) (xy 447.355472 -72.080646) (xy 447.29605 -72.072823) (xy 447.238157 -72.05731)
			(xy 447.182784 -72.034374) (xy 447.130878 -72.004407) (xy 447.083328 -71.96792) (xy 447.040948 -71.92554)
			(xy 447.004461 -71.87799) (xy 446.974494 -71.826084) (xy 446.951558 -71.770711) (xy 446.936045 -71.712818)
			(xy 446.928222 -71.653396) (xy 446.323639 -71.653396) (xy 446.310308 -71.703147) (xy 446.287372 -71.75852)
			(xy 446.257405 -71.810426) (xy 446.220918 -71.857976) (xy 446.178538 -71.900356) (xy 446.130988 -71.936843)
			(xy 446.079082 -71.96681) (xy 446.023709 -71.989746) (xy 445.965816 -72.005259) (xy 445.906394 -72.013082)
			(xy 445.846458 -72.013082) (xy 445.787036 -72.005259) (xy 445.729143 -71.989746) (xy 445.67377 -71.96681)
			(xy 445.621864 -71.936843) (xy 445.574314 -71.900356) (xy 445.531934 -71.857976) (xy 445.495447 -71.810426)
			(xy 445.46548 -71.75852) (xy 445.442544 -71.703147) (xy 445.427031 -71.645254) (xy 445.419208 -71.585832)
			(xy 421.841706 -71.585832) (xy 421.84271 -71.59346) (xy 421.8432 -71.623428) (xy 421.84271 -71.653396)
			(xy 421.834887 -71.712818) (xy 421.819374 -71.770711) (xy 421.796438 -71.826084) (xy 421.766471 -71.87799)
			(xy 421.729984 -71.92554) (xy 421.687604 -71.96792) (xy 421.640054 -72.004407) (xy 421.588148 -72.034374)
			(xy 421.532775 -72.05731) (xy 421.474882 -72.072823) (xy 421.41546 -72.080646) (xy 421.355524 -72.080646)
			(xy 421.296102 -72.072823) (xy 421.238209 -72.05731) (xy 421.182836 -72.034374) (xy 421.13093 -72.004407)
			(xy 421.08338 -71.96792) (xy 421.041 -71.92554) (xy 421.004513 -71.87799) (xy 420.974546 -71.826084)
			(xy 420.95161 -71.770711) (xy 420.936097 -71.712818) (xy 420.928274 -71.653396) (xy 420.323691 -71.653396)
			(xy 420.31036 -71.703147) (xy 420.287424 -71.75852) (xy 420.257457 -71.810426) (xy 420.22097 -71.857976)
			(xy 420.17859 -71.900356) (xy 420.13104 -71.936843) (xy 420.079134 -71.96681) (xy 420.023761 -71.989746)
			(xy 419.965868 -72.005259) (xy 419.906446 -72.013082) (xy 419.84651 -72.013082) (xy 419.787088 -72.005259)
			(xy 419.729195 -71.989746) (xy 419.673822 -71.96681) (xy 419.621916 -71.936843) (xy 419.574366 -71.900356)
			(xy 419.531986 -71.857976) (xy 419.495499 -71.810426) (xy 419.465532 -71.75852) (xy 419.442596 -71.703147)
			(xy 419.427083 -71.645254) (xy 419.41926 -71.585832) (xy 395.841758 -71.585832) (xy 395.842762 -71.59346)
			(xy 395.843252 -71.623428) (xy 395.842762 -71.653396) (xy 395.834939 -71.712818) (xy 395.819426 -71.770711)
			(xy 395.79649 -71.826084) (xy 395.766523 -71.87799) (xy 395.730036 -71.92554) (xy 395.687656 -71.96792)
			(xy 395.640106 -72.004407) (xy 395.5882 -72.034374) (xy 395.532827 -72.05731) (xy 395.474934 -72.072823)
			(xy 395.415512 -72.080646) (xy 395.355576 -72.080646) (xy 395.296154 -72.072823) (xy 395.238261 -72.05731)
			(xy 395.182888 -72.034374) (xy 395.130982 -72.004407) (xy 395.083432 -71.96792) (xy 395.041052 -71.92554)
			(xy 395.004565 -71.87799) (xy 394.974598 -71.826084) (xy 394.951662 -71.770711) (xy 394.936149 -71.712818)
			(xy 394.928326 -71.653396) (xy 394.323743 -71.653396) (xy 394.310412 -71.703147) (xy 394.287476 -71.75852)
			(xy 394.257509 -71.810426) (xy 394.221022 -71.857976) (xy 394.178642 -71.900356) (xy 394.131092 -71.936843)
			(xy 394.079186 -71.96681) (xy 394.023813 -71.989746) (xy 393.96592 -72.005259) (xy 393.906498 -72.013082)
			(xy 393.846562 -72.013082) (xy 393.78714 -72.005259) (xy 393.729247 -71.989746) (xy 393.673874 -71.96681)
			(xy 393.621968 -71.936843) (xy 393.574418 -71.900356) (xy 393.532038 -71.857976) (xy 393.495551 -71.810426)
			(xy 393.465584 -71.75852) (xy 393.442648 -71.703147) (xy 393.427135 -71.645254) (xy 393.419312 -71.585832)
			(xy 369.84181 -71.585832) (xy 369.842814 -71.59346) (xy 369.843304 -71.623428) (xy 369.842814 -71.653396)
			(xy 369.834991 -71.712818) (xy 369.819478 -71.770711) (xy 369.796542 -71.826084) (xy 369.766575 -71.87799)
			(xy 369.730088 -71.92554) (xy 369.687708 -71.96792) (xy 369.640158 -72.004407) (xy 369.588252 -72.034374)
			(xy 369.532879 -72.05731) (xy 369.474986 -72.072823) (xy 369.415564 -72.080646) (xy 369.355628 -72.080646)
			(xy 369.296206 -72.072823) (xy 369.238313 -72.05731) (xy 369.18294 -72.034374) (xy 369.131034 -72.004407)
			(xy 369.083484 -71.96792) (xy 369.041104 -71.92554) (xy 369.004617 -71.87799) (xy 368.97465 -71.826084)
			(xy 368.951714 -71.770711) (xy 368.936201 -71.712818) (xy 368.928378 -71.653396) (xy 368.323795 -71.653396)
			(xy 368.310464 -71.703147) (xy 368.287528 -71.75852) (xy 368.257561 -71.810426) (xy 368.221074 -71.857976)
			(xy 368.178694 -71.900356) (xy 368.131144 -71.936843) (xy 368.079238 -71.96681) (xy 368.023865 -71.989746)
			(xy 367.965972 -72.005259) (xy 367.90655 -72.013082) (xy 367.846614 -72.013082) (xy 367.787192 -72.005259)
			(xy 367.729299 -71.989746) (xy 367.673926 -71.96681) (xy 367.62202 -71.936843) (xy 367.57447 -71.900356)
			(xy 367.53209 -71.857976) (xy 367.495603 -71.810426) (xy 367.465636 -71.75852) (xy 367.4427 -71.703147)
			(xy 367.427187 -71.645254) (xy 367.419364 -71.585832) (xy 354.909264 -71.585832) (xy 354.911063 -71.593278)
			(xy 354.950869 -71.792113) (xy 354.982789 -71.992365) (xy 355.006772 -72.193721) (xy 355.022782 -72.395868)
			(xy 355.030793 -72.59849) (xy 355.031294 -72.69988) (xy 355.030793 -72.80127) (xy 355.022982 -72.998838)
			(xy 405.177496 -72.998838) (xy 405.181567 -72.943216) (xy 405.193693 -72.888779) (xy 405.213616 -72.836688)
			(xy 405.240912 -72.788053) (xy 405.274998 -72.74391) (xy 405.315147 -72.705201) (xy 405.360505 -72.67275)
			(xy 405.410105 -72.647249) (xy 405.462889 -72.629242) (xy 405.517732 -72.619112) (xy 405.573466 -72.617075)
			(xy 405.628903 -72.623175) (xy 405.68286 -72.637281) (xy 405.734189 -72.659093) (xy 405.781795 -72.688147)
			(xy 405.824663 -72.723822) (xy 405.86188 -72.765359) (xy 405.892653 -72.811872) (xy 405.916325 -72.862369)
			(xy 405.932393 -72.915776) (xy 405.940513 -72.970952) (xy 405.940665 -72.97928) (xy 432.334668 -72.97928)
			(xy 432.338739 -72.923658) (xy 432.350865 -72.869221) (xy 432.370788 -72.81713) (xy 432.398084 -72.768495)
			(xy 432.43217 -72.724352) (xy 432.472319 -72.685643) (xy 432.517677 -72.653192) (xy 432.567277 -72.627691)
			(xy 432.620061 -72.609684) (xy 432.674904 -72.599554) (xy 432.730638 -72.597517) (xy 432.786075 -72.603617)
			(xy 432.840032 -72.617723) (xy 432.891361 -72.639535) (xy 432.938967 -72.668589) (xy 432.981835 -72.704264)
			(xy 433.019052 -72.745801) (xy 433.049825 -72.792314) (xy 433.073497 -72.842811) (xy 433.089565 -72.896218)
			(xy 433.097685 -72.951394) (xy 433.098194 -72.97928) (xy 433.097685 -73.007166) (xy 433.089565 -73.062342)
			(xy 433.073497 -73.115749) (xy 433.049825 -73.166246) (xy 433.019052 -73.212759) (xy 432.981835 -73.254296)
			(xy 432.938967 -73.289971) (xy 432.891361 -73.319025) (xy 432.840032 -73.340837) (xy 432.786075 -73.354943)
			(xy 432.730638 -73.361043) (xy 432.674904 -73.359006) (xy 432.620061 -73.348876) (xy 432.567277 -73.330869)
			(xy 432.517677 -73.305368) (xy 432.472319 -73.272917) (xy 432.43217 -73.234208) (xy 432.398084 -73.190065)
			(xy 432.370788 -73.14143) (xy 432.350865 -73.089339) (xy 432.338739 -73.034902) (xy 432.334668 -72.97928)
			(xy 405.940665 -72.97928) (xy 405.941022 -72.998838) (xy 405.940513 -73.026724) (xy 405.932393 -73.0819)
			(xy 405.916325 -73.135307) (xy 405.892653 -73.185804) (xy 405.86188 -73.232317) (xy 405.824663 -73.273854)
			(xy 405.781795 -73.309529) (xy 405.734189 -73.338583) (xy 405.68286 -73.360395) (xy 405.628903 -73.374501)
			(xy 405.573466 -73.380601) (xy 405.517732 -73.378564) (xy 405.462889 -73.368434) (xy 405.410105 -73.350427)
			(xy 405.360505 -73.324926) (xy 405.315147 -73.292475) (xy 405.274998 -73.253766) (xy 405.240912 -73.209623)
			(xy 405.213616 -73.160988) (xy 405.193693 -73.108897) (xy 405.181567 -73.05446) (xy 405.177496 -72.998838)
			(xy 355.022982 -72.998838) (xy 355.022782 -73.003892) (xy 355.006772 -73.206039) (xy 354.982789 -73.407395)
			(xy 354.950869 -73.607647) (xy 354.911063 -73.806482) (xy 354.863433 -74.003588) (xy 354.808053 -74.19866)
			(xy 354.74501 -74.391391) (xy 354.688637 -74.543158) (xy 405.05202 -74.543158) (xy 405.056091 -74.487536)
			(xy 405.068217 -74.433099) (xy 405.08814 -74.381008) (xy 405.115436 -74.332373) (xy 405.149522 -74.28823)
			(xy 405.189671 -74.249521) (xy 405.235029 -74.21707) (xy 405.284629 -74.191569) (xy 405.337413 -74.173562)
			(xy 405.392256 -74.163432) (xy 405.44799 -74.161395) (xy 405.503427 -74.167495) (xy 405.557384 -74.181601)
			(xy 405.608713 -74.203413) (xy 405.60937 -74.203814) (xy 431.474624 -74.203814) (xy 431.478695 -74.148192)
			(xy 431.490821 -74.093755) (xy 431.510744 -74.041664) (xy 431.53804 -73.993029) (xy 431.572126 -73.948886)
			(xy 431.612275 -73.910177) (xy 431.657633 -73.877726) (xy 431.707233 -73.852225) (xy 431.760017 -73.834218)
			(xy 431.81486 -73.824088) (xy 431.870594 -73.822051) (xy 431.926031 -73.828151) (xy 431.979988 -73.842257)
			(xy 432.031317 -73.864069) (xy 432.078923 -73.893123) (xy 432.121791 -73.928798) (xy 432.159008 -73.970335)
			(xy 432.189781 -74.016848) (xy 432.213453 -74.067345) (xy 432.229521 -74.120752) (xy 432.237641 -74.175928)
			(xy 432.23815 -74.203814) (xy 432.237641 -74.2317) (xy 432.229521 -74.286876) (xy 432.213453 -74.340283)
			(xy 432.189781 -74.39078) (xy 432.159008 -74.437293) (xy 432.121791 -74.47883) (xy 432.078923 -74.514505)
			(xy 432.031317 -74.543559) (xy 431.979988 -74.565371) (xy 431.926031 -74.579477) (xy 431.870594 -74.585577)
			(xy 431.81486 -74.58354) (xy 431.760017 -74.57341) (xy 431.707233 -74.555403) (xy 431.657633 -74.529902)
			(xy 431.612275 -74.497451) (xy 431.572126 -74.458742) (xy 431.53804 -74.414599) (xy 431.510744 -74.365964)
			(xy 431.490821 -74.313873) (xy 431.478695 -74.259436) (xy 431.474624 -74.203814) (xy 405.60937 -74.203814)
			(xy 405.656319 -74.232467) (xy 405.699187 -74.268142) (xy 405.736404 -74.309679) (xy 405.767177 -74.356192)
			(xy 405.790849 -74.406689) (xy 405.806917 -74.460096) (xy 405.815037 -74.515272) (xy 405.815546 -74.543158)
			(xy 405.815037 -74.571044) (xy 405.806917 -74.62622) (xy 405.790849 -74.679627) (xy 405.767177 -74.730124)
			(xy 405.736404 -74.776637) (xy 405.728941 -74.784966) (xy 458.026514 -74.784966) (xy 458.030585 -74.729344)
			(xy 458.042711 -74.674907) (xy 458.062634 -74.622816) (xy 458.08993 -74.574181) (xy 458.124016 -74.530038)
			(xy 458.164165 -74.491329) (xy 458.209523 -74.458878) (xy 458.259123 -74.433377) (xy 458.311907 -74.41537)
			(xy 458.36675 -74.40524) (xy 458.422484 -74.403203) (xy 458.477921 -74.409303) (xy 458.531878 -74.423409)
			(xy 458.583207 -74.445221) (xy 458.630813 -74.474275) (xy 458.673681 -74.50995) (xy 458.710898 -74.551487)
			(xy 458.741671 -74.598) (xy 458.765343 -74.648497) (xy 458.781411 -74.701904) (xy 458.789531 -74.75708)
			(xy 458.79004 -74.784966) (xy 458.789531 -74.812852) (xy 458.781411 -74.868028) (xy 458.765343 -74.921435)
			(xy 458.741671 -74.971932) (xy 458.710898 -75.018445) (xy 458.673681 -75.059982) (xy 458.630813 -75.095657)
			(xy 458.583207 -75.124711) (xy 458.531878 -75.146523) (xy 458.477921 -75.160629) (xy 458.422484 -75.166729)
			(xy 458.36675 -75.164692) (xy 458.311907 -75.154562) (xy 458.259123 -75.136555) (xy 458.209523 -75.111054)
			(xy 458.164165 -75.078603) (xy 458.124016 -75.039894) (xy 458.08993 -74.995751) (xy 458.062634 -74.947116)
			(xy 458.042711 -74.895025) (xy 458.030585 -74.840588) (xy 458.026514 -74.784966) (xy 405.728941 -74.784966)
			(xy 405.699187 -74.818174) (xy 405.656319 -74.853849) (xy 405.608713 -74.882903) (xy 405.557384 -74.904715)
			(xy 405.503427 -74.918821) (xy 405.44799 -74.924921) (xy 405.392256 -74.922884) (xy 405.337413 -74.912754)
			(xy 405.284629 -74.894747) (xy 405.235029 -74.869246) (xy 405.189671 -74.836795) (xy 405.149522 -74.798086)
			(xy 405.115436 -74.753943) (xy 405.08814 -74.705308) (xy 405.068217 -74.653217) (xy 405.056091 -74.59878)
			(xy 405.05202 -74.543158) (xy 354.688637 -74.543158) (xy 354.674402 -74.58148) (xy 354.596339 -74.768632)
			(xy 354.510943 -74.952554) (xy 354.418347 -75.132959) (xy 354.407175 -75.152758) (xy 379.969266 -75.152758)
			(xy 379.973337 -75.097136) (xy 379.985463 -75.042699) (xy 380.005386 -74.990608) (xy 380.032682 -74.941973)
			(xy 380.066768 -74.89783) (xy 380.106917 -74.859121) (xy 380.152275 -74.82667) (xy 380.201875 -74.801169)
			(xy 380.254659 -74.783162) (xy 380.309502 -74.773032) (xy 380.365236 -74.770995) (xy 380.420673 -74.777095)
			(xy 380.47463 -74.791201) (xy 380.525959 -74.813013) (xy 380.573565 -74.842067) (xy 380.616433 -74.877742)
			(xy 380.65365 -74.919279) (xy 380.684423 -74.965792) (xy 380.708095 -75.016289) (xy 380.724088 -75.069446)
			(xy 381.604518 -75.069446) (xy 381.608589 -75.013824) (xy 381.620715 -74.959387) (xy 381.640638 -74.907296)
			(xy 381.667934 -74.858661) (xy 381.70202 -74.814518) (xy 381.742169 -74.775809) (xy 381.787527 -74.743358)
			(xy 381.837127 -74.717857) (xy 381.889911 -74.69985) (xy 381.944754 -74.68972) (xy 382.000488 -74.687683)
			(xy 382.055925 -74.693783) (xy 382.109882 -74.707889) (xy 382.161211 -74.729701) (xy 382.208817 -74.758755)
			(xy 382.251685 -74.79443) (xy 382.288902 -74.835967) (xy 382.319675 -74.88248) (xy 382.343347 -74.932977)
			(xy 382.359415 -74.986384) (xy 382.367535 -75.04156) (xy 382.368044 -75.069446) (xy 382.367535 -75.097332)
			(xy 382.359415 -75.152508) (xy 382.343347 -75.205915) (xy 382.319675 -75.256412) (xy 382.288902 -75.302925)
			(xy 382.251685 -75.344462) (xy 382.208817 -75.380137) (xy 382.161211 -75.409191) (xy 382.109882 -75.431003)
			(xy 382.055925 -75.445109) (xy 382.000488 -75.451209) (xy 381.944754 -75.449172) (xy 381.889911 -75.439042)
			(xy 381.837127 -75.421035) (xy 381.787527 -75.395534) (xy 381.742169 -75.363083) (xy 381.70202 -75.324374)
			(xy 381.667934 -75.280231) (xy 381.640638 -75.231596) (xy 381.620715 -75.179505) (xy 381.608589 -75.125068)
			(xy 381.604518 -75.069446) (xy 380.724088 -75.069446) (xy 380.724163 -75.069696) (xy 380.732283 -75.124872)
			(xy 380.732792 -75.152758) (xy 380.732283 -75.180644) (xy 380.724163 -75.23582) (xy 380.708095 -75.289227)
			(xy 380.684423 -75.339724) (xy 380.65365 -75.386237) (xy 380.616433 -75.427774) (xy 380.573565 -75.463449)
			(xy 380.525959 -75.492503) (xy 380.47463 -75.514315) (xy 380.420673 -75.528421) (xy 380.365236 -75.534521)
			(xy 380.309502 -75.532484) (xy 380.254659 -75.522354) (xy 380.201875 -75.504347) (xy 380.152275 -75.478846)
			(xy 380.106917 -75.446395) (xy 380.066768 -75.407686) (xy 380.032682 -75.363543) (xy 380.005386 -75.314908)
			(xy 379.985463 -75.262817) (xy 379.973337 -75.20838) (xy 379.969266 -75.152758) (xy 354.407175 -75.152758)
			(xy 354.318697 -75.309565) (xy 354.212148 -75.482095) (xy 354.098866 -75.650282) (xy 353.979027 -75.813862)
			(xy 353.85282 -75.97258) (xy 353.720441 -76.126189) (xy 353.582096 -76.274447) (xy 353.438003 -76.417124)
			(xy 353.411021 -76.441808) (xy 458.137766 -76.441808) (xy 458.141837 -76.386186) (xy 458.153963 -76.331749)
			(xy 458.173886 -76.279658) (xy 458.201182 -76.231023) (xy 458.235268 -76.18688) (xy 458.275417 -76.148171)
			(xy 458.320775 -76.11572) (xy 458.370375 -76.090219) (xy 458.423159 -76.072212) (xy 458.478002 -76.062082)
			(xy 458.533736 -76.060045) (xy 458.589173 -76.066145) (xy 458.64313 -76.080251) (xy 458.694459 -76.102063)
			(xy 458.742065 -76.131117) (xy 458.784933 -76.166792) (xy 458.82215 -76.208329) (xy 458.852923 -76.254842)
			(xy 458.876595 -76.305339) (xy 458.892663 -76.358746) (xy 458.900783 -76.413922) (xy 458.901292 -76.441808)
			(xy 458.900783 -76.469694) (xy 458.892663 -76.52487) (xy 458.876595 -76.578277) (xy 458.852923 -76.628774)
			(xy 458.82215 -76.675287) (xy 458.784933 -76.716824) (xy 458.742065 -76.752499) (xy 458.694459 -76.781553)
			(xy 458.64313 -76.803365) (xy 458.589173 -76.817471) (xy 458.533736 -76.823571) (xy 458.478002 -76.821534)
			(xy 458.423159 -76.811404) (xy 458.370375 -76.793397) (xy 458.320775 -76.767896) (xy 458.275417 -76.735445)
			(xy 458.235268 -76.696736) (xy 458.201182 -76.652593) (xy 458.173886 -76.603958) (xy 458.153963 -76.551867)
			(xy 458.141837 -76.49743) (xy 458.137766 -76.441808) (xy 353.411021 -76.441808) (xy 353.288385 -76.553997)
			(xy 353.133476 -76.684852) (xy 352.973519 -76.809485) (xy 352.808763 -76.927702) (xy 352.639466 -77.039317)
			(xy 352.465891 -77.144157) (xy 352.288309 -77.242058) (xy 352.106998 -77.332866) (xy 351.922242 -77.416441)
			(xy 351.734328 -77.492651) (xy 351.687213 -77.509624) (xy 391.980926 -77.509624) (xy 391.984997 -77.454002)
			(xy 391.997123 -77.399565) (xy 392.017046 -77.347474) (xy 392.044342 -77.298839) (xy 392.078428 -77.254696)
			(xy 392.118577 -77.215987) (xy 392.163935 -77.183536) (xy 392.213535 -77.158035) (xy 392.266319 -77.140028)
			(xy 392.321162 -77.129898) (xy 392.376896 -77.127861) (xy 392.432333 -77.133961) (xy 392.48629 -77.148067)
			(xy 392.537619 -77.169879) (xy 392.585225 -77.198933) (xy 392.628093 -77.234608) (xy 392.66531 -77.276145)
			(xy 392.696083 -77.322658) (xy 392.719755 -77.373155) (xy 392.735823 -77.426562) (xy 392.743943 -77.481738)
			(xy 392.744452 -77.509624) (xy 392.743943 -77.53751) (xy 392.743562 -77.5401) (xy 393.479256 -77.5401)
			(xy 393.479256 -77.480164) (xy 393.487079 -77.420742) (xy 393.502592 -77.362849) (xy 393.525528 -77.307476)
			(xy 393.555495 -77.25557) (xy 393.591982 -77.20802) (xy 393.634362 -77.16564) (xy 393.681912 -77.129153)
			(xy 393.733818 -77.099186) (xy 393.789191 -77.07625) (xy 393.847084 -77.060737) (xy 393.906506 -77.052914)
			(xy 393.966442 -77.052914) (xy 394.025864 -77.060737) (xy 394.083757 -77.07625) (xy 394.13913 -77.099186)
			(xy 394.191036 -77.129153) (xy 394.238586 -77.16564) (xy 394.279294 -77.206348) (xy 430.98415 -77.206348)
			(xy 430.988221 -77.150726) (xy 431.000347 -77.096289) (xy 431.02027 -77.044198) (xy 431.047566 -76.995563)
			(xy 431.081652 -76.95142) (xy 431.121801 -76.912711) (xy 431.167159 -76.88026) (xy 431.216759 -76.854759)
			(xy 431.269543 -76.836752) (xy 431.324386 -76.826622) (xy 431.38012 -76.824585) (xy 431.435557 -76.830685)
			(xy 431.489514 -76.844791) (xy 431.540843 -76.866603) (xy 431.588449 -76.895657) (xy 431.631317 -76.931332)
			(xy 431.668534 -76.972869) (xy 431.683189 -76.99502) (xy 453.687178 -76.99502) (xy 453.691249 -76.939398)
			(xy 453.703375 -76.884961) (xy 453.723298 -76.83287) (xy 453.750594 -76.784235) (xy 453.78468 -76.740092)
			(xy 453.824829 -76.701383) (xy 453.870187 -76.668932) (xy 453.919787 -76.643431) (xy 453.972571 -76.625424)
			(xy 454.027414 -76.615294) (xy 454.083148 -76.613257) (xy 454.138585 -76.619357) (xy 454.192542 -76.633463)
			(xy 454.243871 -76.655275) (xy 454.291477 -76.684329) (xy 454.334345 -76.720004) (xy 454.371562 -76.761541)
			(xy 454.402335 -76.808054) (xy 454.426007 -76.858551) (xy 454.442075 -76.911958) (xy 454.450195 -76.967134)
			(xy 454.450704 -76.99502) (xy 454.450195 -77.022906) (xy 454.446337 -77.049122) (xy 455.173078 -77.049122)
			(xy 455.177149 -76.9935) (xy 455.189275 -76.939063) (xy 455.209198 -76.886972) (xy 455.236494 -76.838337)
			(xy 455.27058 -76.794194) (xy 455.310729 -76.755485) (xy 455.356087 -76.723034) (xy 455.405687 -76.697533)
			(xy 455.458471 -76.679526) (xy 455.513314 -76.669396) (xy 455.569048 -76.667359) (xy 455.624485 -76.673459)
			(xy 455.678442 -76.687565) (xy 455.729771 -76.709377) (xy 455.777377 -76.738431) (xy 455.820245 -76.774106)
			(xy 455.857462 -76.815643) (xy 455.888235 -76.862156) (xy 455.911907 -76.912653) (xy 455.927975 -76.96606)
			(xy 455.936095 -77.021236) (xy 455.936604 -77.049122) (xy 455.936095 -77.077008) (xy 455.927975 -77.132184)
			(xy 455.911907 -77.185591) (xy 455.888235 -77.236088) (xy 455.857462 -77.282601) (xy 455.820245 -77.324138)
			(xy 455.777377 -77.359813) (xy 455.729771 -77.388867) (xy 455.678442 -77.410679) (xy 455.624485 -77.424785)
			(xy 455.569048 -77.430885) (xy 455.513314 -77.428848) (xy 455.458471 -77.418718) (xy 455.405687 -77.400711)
			(xy 455.356087 -77.37521) (xy 455.310729 -77.342759) (xy 455.27058 -77.30405) (xy 455.236494 -77.259907)
			(xy 455.209198 -77.211272) (xy 455.189275 -77.159181) (xy 455.177149 -77.104744) (xy 455.173078 -77.049122)
			(xy 454.446337 -77.049122) (xy 454.442075 -77.078082) (xy 454.426007 -77.131489) (xy 454.402335 -77.181986)
			(xy 454.371562 -77.228499) (xy 454.334345 -77.270036) (xy 454.291477 -77.305711) (xy 454.243871 -77.334765)
			(xy 454.192542 -77.356577) (xy 454.138585 -77.370683) (xy 454.083148 -77.376783) (xy 454.027414 -77.374746)
			(xy 453.972571 -77.364616) (xy 453.919787 -77.346609) (xy 453.870187 -77.321108) (xy 453.824829 -77.288657)
			(xy 453.78468 -77.249948) (xy 453.750594 -77.205805) (xy 453.723298 -77.15717) (xy 453.703375 -77.105079)
			(xy 453.691249 -77.050642) (xy 453.687178 -76.99502) (xy 431.683189 -76.99502) (xy 431.699307 -77.019382)
			(xy 431.722979 -77.069879) (xy 431.739047 -77.123286) (xy 431.747167 -77.178462) (xy 431.747676 -77.206348)
			(xy 431.747167 -77.234234) (xy 431.739047 -77.28941) (xy 431.722979 -77.342817) (xy 431.699307 -77.393314)
			(xy 431.668534 -77.439827) (xy 431.631317 -77.481364) (xy 431.588449 -77.517039) (xy 431.540843 -77.546093)
			(xy 431.489514 -77.567905) (xy 431.435557 -77.582011) (xy 431.38012 -77.588111) (xy 431.324386 -77.586074)
			(xy 431.269543 -77.575944) (xy 431.216759 -77.557937) (xy 431.167159 -77.532436) (xy 431.121801 -77.499985)
			(xy 431.081652 -77.461276) (xy 431.047566 -77.417133) (xy 431.02027 -77.368498) (xy 431.000347 -77.316407)
			(xy 430.988221 -77.26197) (xy 430.98415 -77.206348) (xy 394.279294 -77.206348) (xy 394.280966 -77.20802)
			(xy 394.317453 -77.25557) (xy 394.34742 -77.307476) (xy 394.370356 -77.362849) (xy 394.385869 -77.420742)
			(xy 394.393692 -77.480164) (xy 394.394182 -77.510132) (xy 394.393692 -77.5401) (xy 394.385869 -77.599522)
			(xy 394.370356 -77.657415) (xy 394.34742 -77.712788) (xy 394.317453 -77.764694) (xy 394.280966 -77.812244)
			(xy 394.238586 -77.854624) (xy 394.191036 -77.891111) (xy 394.13913 -77.921078) (xy 394.083757 -77.944014)
			(xy 394.025864 -77.959527) (xy 393.966442 -77.96735) (xy 393.906506 -77.96735) (xy 393.847084 -77.959527)
			(xy 393.789191 -77.944014) (xy 393.733818 -77.921078) (xy 393.681912 -77.891111) (xy 393.634362 -77.854624)
			(xy 393.591982 -77.812244) (xy 393.555495 -77.764694) (xy 393.525528 -77.712788) (xy 393.502592 -77.657415)
			(xy 393.487079 -77.599522) (xy 393.479256 -77.5401) (xy 392.743562 -77.5401) (xy 392.735823 -77.592686)
			(xy 392.719755 -77.646093) (xy 392.696083 -77.69659) (xy 392.66531 -77.743103) (xy 392.628093 -77.78464)
			(xy 392.585225 -77.820315) (xy 392.537619 -77.849369) (xy 392.48629 -77.871181) (xy 392.432333 -77.885287)
			(xy 392.376896 -77.891387) (xy 392.321162 -77.88935) (xy 392.266319 -77.87922) (xy 392.213535 -77.861213)
			(xy 392.163935 -77.835712) (xy 392.118577 -77.803261) (xy 392.078428 -77.764552) (xy 392.044342 -77.720409)
			(xy 392.017046 -77.671774) (xy 391.997123 -77.619683) (xy 391.984997 -77.565246) (xy 391.980926 -77.509624)
			(xy 351.687213 -77.509624) (xy 351.54355 -77.561378) (xy 351.350205 -77.622514) (xy 351.154597 -77.675964)
			(xy 350.957029 -77.721645) (xy 350.757811 -77.759485) (xy 350.557253 -77.789425) (xy 350.35567 -77.811418)
			(xy 350.153374 -77.82543) (xy 349.950683 -77.831439) (xy 349.747913 -77.829435) (xy 349.545381 -77.819423)
			(xy 349.343402 -77.801417) (xy 349.142292 -77.775445) (xy 348.942365 -77.741549) (xy 348.743934 -77.699781)
			(xy 348.547307 -77.650206) (xy 348.352792 -77.592901) (xy 348.160694 -77.527957) (xy 347.971311 -77.455474)
			(xy 347.784939 -77.375566) (xy 347.60187 -77.288357) (xy 347.422389 -77.193984) (xy 347.246776 -77.092594)
			(xy 347.075306 -76.984346) (xy 346.908247 -76.869407) (xy 346.745858 -76.747959) (xy 346.588395 -76.62019)
			(xy 346.436102 -76.486299) (xy 346.289218 -76.346497) (xy 346.147971 -76.201001) (xy 346.012583 -76.050038)
			(xy 345.883264 -75.893845) (xy 345.760218 -75.732664) (xy 345.643634 -75.566749) (xy 345.533697 -75.396356)
			(xy 345.430577 -75.221754) (xy 345.334436 -75.043214) (xy 345.245423 -74.861015) (xy 345.163678 -74.675442)
			(xy 345.089327 -74.486784) (xy 345.022488 -74.295336) (xy 344.963265 -74.101398) (xy 344.91175 -73.90527)
			(xy 344.868023 -73.707261) (xy 344.832154 -73.507679) (xy 344.804197 -73.306835) (xy 344.784196 -73.105044)
			(xy 344.772183 -72.90262) (xy 344.768177 -72.69988) (xy 276.290786 -72.69988) (xy 276.39772 -72.806814)
			(xy 276.400751 -72.8098) (xy 276.407648 -72.814782) (xy 276.411436 -72.81672) (xy 276.419056 -72.820276)
			(xy 276.427692 -72.821292) (xy 276.45594 -72.825044) (xy 276.510966 -72.839846) (xy 276.563178 -72.862668)
			(xy 276.611414 -72.893004) (xy 276.654601 -72.930177) (xy 276.691778 -72.973361) (xy 276.722117 -73.021595)
			(xy 276.744944 -73.073805) (xy 276.759751 -73.12883) (xy 276.76348 -73.15708) (xy 276.764496 -73.165716)
			(xy 276.768052 -73.173336) (xy 276.77003 -73.1771) (xy 276.775002 -73.183996) (xy 276.777958 -73.187052)
			(xy 281.047698 -77.456792) (xy 297.701968 -77.456792) (xy 297.706039 -77.40117) (xy 297.718165 -77.346733)
			(xy 297.738088 -77.294642) (xy 297.765384 -77.246007) (xy 297.79947 -77.201864) (xy 297.839619 -77.163155)
			(xy 297.884977 -77.130704) (xy 297.934577 -77.105203) (xy 297.987361 -77.087196) (xy 298.042204 -77.077066)
			(xy 298.097938 -77.075029) (xy 298.153375 -77.081129) (xy 298.207332 -77.095235) (xy 298.258661 -77.117047)
			(xy 298.306267 -77.146101) (xy 298.349135 -77.181776) (xy 298.386352 -77.223313) (xy 298.394955 -77.236316)
			(xy 314.808852 -77.236316) (xy 314.808852 -77.17638) (xy 314.816675 -77.116958) (xy 314.832188 -77.059065)
			(xy 314.855124 -77.003692) (xy 314.885091 -76.951786) (xy 314.921578 -76.904236) (xy 314.963958 -76.861856)
			(xy 315.011508 -76.825369) (xy 315.063414 -76.795402) (xy 315.118787 -76.772466) (xy 315.17668 -76.756953)
			(xy 315.236102 -76.74913) (xy 315.296038 -76.74913) (xy 315.35546 -76.756953) (xy 315.413353 -76.772466)
			(xy 315.468726 -76.795402) (xy 315.520632 -76.825369) (xy 315.568182 -76.861856) (xy 315.599746 -76.89342)
			(xy 320.334892 -76.89342) (xy 320.338963 -76.837798) (xy 320.351089 -76.783361) (xy 320.371012 -76.73127)
			(xy 320.398308 -76.682635) (xy 320.432394 -76.638492) (xy 320.472543 -76.599783) (xy 320.517901 -76.567332)
			(xy 320.567501 -76.541831) (xy 320.620285 -76.523824) (xy 320.675128 -76.513694) (xy 320.730862 -76.511657)
			(xy 320.786299 -76.517757) (xy 320.840256 -76.531863) (xy 320.891585 -76.553675) (xy 320.939191 -76.582729)
			(xy 320.982059 -76.618404) (xy 321.019276 -76.659941) (xy 321.050049 -76.706454) (xy 321.070658 -76.750418)
			(xy 321.42633 -76.750418) (xy 321.430401 -76.694796) (xy 321.442527 -76.640359) (xy 321.46245 -76.588268)
			(xy 321.489746 -76.539633) (xy 321.523832 -76.49549) (xy 321.563981 -76.456781) (xy 321.609339 -76.42433)
			(xy 321.658939 -76.398829) (xy 321.711723 -76.380822) (xy 321.766566 -76.370692) (xy 321.8223 -76.368655)
			(xy 321.877737 -76.374755) (xy 321.931694 -76.388861) (xy 321.983023 -76.410673) (xy 322.030629 -76.439727)
			(xy 322.073497 -76.475402) (xy 322.110714 -76.516939) (xy 322.141487 -76.563452) (xy 322.165159 -76.613949)
			(xy 322.181227 -76.667356) (xy 322.189347 -76.722532) (xy 322.189856 -76.750418) (xy 322.189347 -76.778304)
			(xy 322.181227 -76.83348) (xy 322.165159 -76.886887) (xy 322.141487 -76.937384) (xy 322.110714 -76.983897)
			(xy 322.073497 -77.025434) (xy 322.030629 -77.061109) (xy 321.983023 -77.090163) (xy 321.931694 -77.111975)
			(xy 321.877737 -77.126081) (xy 321.8223 -77.132181) (xy 321.766566 -77.130144) (xy 321.711723 -77.120014)
			(xy 321.658939 -77.102007) (xy 321.609339 -77.076506) (xy 321.563981 -77.044055) (xy 321.523832 -77.005346)
			(xy 321.489746 -76.961203) (xy 321.46245 -76.912568) (xy 321.442527 -76.860477) (xy 321.430401 -76.80604)
			(xy 321.42633 -76.750418) (xy 321.070658 -76.750418) (xy 321.073721 -76.756951) (xy 321.089789 -76.810358)
			(xy 321.097909 -76.865534) (xy 321.098418 -76.89342) (xy 321.097909 -76.921306) (xy 321.089789 -76.976482)
			(xy 321.073721 -77.029889) (xy 321.050049 -77.080386) (xy 321.019276 -77.126899) (xy 320.982059 -77.168436)
			(xy 320.939191 -77.204111) (xy 320.891585 -77.233165) (xy 320.840256 -77.254977) (xy 320.786299 -77.269083)
			(xy 320.730862 -77.275183) (xy 320.675128 -77.273146) (xy 320.620285 -77.263016) (xy 320.567501 -77.245009)
			(xy 320.517901 -77.219508) (xy 320.472543 -77.187057) (xy 320.432394 -77.148348) (xy 320.398308 -77.104205)
			(xy 320.371012 -77.05557) (xy 320.351089 -77.003479) (xy 320.338963 -76.949042) (xy 320.334892 -76.89342)
			(xy 315.599746 -76.89342) (xy 315.610562 -76.904236) (xy 315.647049 -76.951786) (xy 315.677016 -77.003692)
			(xy 315.699952 -77.059065) (xy 315.715465 -77.116958) (xy 315.723288 -77.17638) (xy 315.723778 -77.206348)
			(xy 315.723288 -77.236316) (xy 315.715465 -77.295738) (xy 315.699952 -77.353631) (xy 315.677016 -77.409004)
			(xy 315.647049 -77.46091) (xy 315.610562 -77.50846) (xy 315.568182 -77.55084) (xy 315.520632 -77.587327)
			(xy 315.468726 -77.617294) (xy 315.413353 -77.64023) (xy 315.35546 -77.655743) (xy 315.296038 -77.663566)
			(xy 315.236102 -77.663566) (xy 315.17668 -77.655743) (xy 315.118787 -77.64023) (xy 315.063414 -77.617294)
			(xy 315.011508 -77.587327) (xy 314.963958 -77.55084) (xy 314.921578 -77.50846) (xy 314.885091 -77.46091)
			(xy 314.855124 -77.409004) (xy 314.832188 -77.353631) (xy 314.816675 -77.295738) (xy 314.808852 -77.236316)
			(xy 298.394955 -77.236316) (xy 298.417125 -77.269826) (xy 298.440797 -77.320323) (xy 298.456865 -77.37373)
			(xy 298.464985 -77.428906) (xy 298.465494 -77.456792) (xy 298.464985 -77.484678) (xy 298.456865 -77.539854)
			(xy 298.440797 -77.593261) (xy 298.417125 -77.643758) (xy 298.386352 -77.690271) (xy 298.349135 -77.731808)
			(xy 298.306267 -77.767483) (xy 298.258661 -77.796537) (xy 298.210591 -77.816964) (xy 299.312836 -77.816964)
			(xy 299.316907 -77.761342) (xy 299.329033 -77.706905) (xy 299.348956 -77.654814) (xy 299.376252 -77.606179)
			(xy 299.410338 -77.562036) (xy 299.450487 -77.523327) (xy 299.495845 -77.490876) (xy 299.545445 -77.465375)
			(xy 299.598229 -77.447368) (xy 299.653072 -77.437238) (xy 299.708806 -77.435201) (xy 299.764243 -77.441301)
			(xy 299.8182 -77.455407) (xy 299.869529 -77.477219) (xy 299.917135 -77.506273) (xy 299.960003 -77.541948)
			(xy 299.99722 -77.583485) (xy 300.027993 -77.629998) (xy 300.051665 -77.680495) (xy 300.067733 -77.733902)
			(xy 300.075853 -77.789078) (xy 300.076362 -77.816964) (xy 300.075853 -77.84485) (xy 300.067733 -77.900026)
			(xy 300.051665 -77.953433) (xy 300.027993 -78.00393) (xy 299.99722 -78.050443) (xy 299.960003 -78.09198)
			(xy 299.917135 -78.127655) (xy 299.869529 -78.156709) (xy 299.8182 -78.178521) (xy 299.764243 -78.192627)
			(xy 299.708806 -78.198727) (xy 299.653072 -78.19669) (xy 299.598229 -78.18656) (xy 299.545445 -78.168553)
			(xy 299.495845 -78.143052) (xy 299.450487 -78.110601) (xy 299.410338 -78.071892) (xy 299.376252 -78.027749)
			(xy 299.348956 -77.979114) (xy 299.329033 -77.927023) (xy 299.316907 -77.872586) (xy 299.312836 -77.816964)
			(xy 298.210591 -77.816964) (xy 298.207332 -77.818349) (xy 298.153375 -77.832455) (xy 298.097938 -77.838555)
			(xy 298.042204 -77.836518) (xy 297.987361 -77.826388) (xy 297.934577 -77.808381) (xy 297.884977 -77.78288)
			(xy 297.839619 -77.750429) (xy 297.79947 -77.71172) (xy 297.765384 -77.667577) (xy 297.738088 -77.618942)
			(xy 297.718165 -77.566851) (xy 297.706039 -77.512414) (xy 297.701968 -77.456792) (xy 281.047698 -77.456792)
			(xy 282.36418 -78.773274) (xy 299.771306 -78.773274) (xy 299.775377 -78.717652) (xy 299.787503 -78.663215)
			(xy 299.807426 -78.611124) (xy 299.834722 -78.562489) (xy 299.868808 -78.518346) (xy 299.908957 -78.479637)
			(xy 299.954315 -78.447186) (xy 300.003915 -78.421685) (xy 300.056699 -78.403678) (xy 300.111542 -78.393548)
			(xy 300.167276 -78.391511) (xy 300.222713 -78.397611) (xy 300.27667 -78.411717) (xy 300.327999 -78.433529)
			(xy 300.375605 -78.462583) (xy 300.418473 -78.498258) (xy 300.45569 -78.539795) (xy 300.486463 -78.586308)
			(xy 300.510135 -78.636805) (xy 300.526203 -78.690212) (xy 300.534323 -78.745388) (xy 300.534832 -78.773274)
			(xy 300.534323 -78.80116) (xy 300.526203 -78.856336) (xy 300.510135 -78.909743) (xy 300.486463 -78.96024)
			(xy 300.45569 -79.006753) (xy 300.418473 -79.04829) (xy 300.375605 -79.083965) (xy 300.327999 -79.113019)
			(xy 300.27667 -79.134831) (xy 300.222713 -79.148937) (xy 300.167276 -79.155037) (xy 300.111542 -79.153)
			(xy 300.056699 -79.14287) (xy 300.003915 -79.124863) (xy 299.954315 -79.099362) (xy 299.908957 -79.066911)
			(xy 299.868808 -79.028202) (xy 299.834722 -78.984059) (xy 299.807426 -78.935424) (xy 299.787503 -78.883333)
			(xy 299.775377 -78.828896) (xy 299.771306 -78.773274) (xy 282.36418 -78.773274) (xy 282.387548 -78.796642)
			(xy 282.398724 -78.805024) (xy 288.28492 -78.805024) (xy 288.307972 -78.805162) (xy 288.353983 -78.808088)
			(xy 288.376868 -78.810866) (xy 288.38017 -78.811374) (xy 288.552382 -78.811374) (xy 288.562372 -78.811907)
			(xy 288.580811 -78.819613) (xy 288.588196 -78.82636) (xy 288.709862 -78.947772) (xy 288.712148 -78.949804)
			(xy 288.730409 -78.964031) (xy 288.765235 -78.994536) (xy 288.781744 -79.010764) (xy 289.613848 -79.842614)
			(xy 289.621245 -79.849462) (xy 289.639844 -79.857193) (xy 289.649916 -79.8576) (xy 291.837618 -79.8576)
			(xy 291.860674 -79.857808) (xy 291.906684 -79.86086) (xy 291.929566 -79.863696) (xy 291.932868 -79.864204)
			(xy 296.91711 -79.864204) (xy 296.923968 -79.863696) (xy 296.931556 -79.862243) (xy 296.945397 -79.855394)
			(xy 296.951146 -79.850234) (xy 297.072812 -79.728568) (xy 297.100802 -79.701373) (xy 297.161835 -79.652733)
			(xy 297.227924 -79.611224) (xy 297.29824 -79.577365) (xy 297.371902 -79.551582) (xy 297.447985 -79.534199)
			(xy 297.525534 -79.525433) (xy 297.564556 -79.52486) (xy 298.759626 -79.52486) (xy 298.770677 -79.523685)
			(xy 298.790284 -79.513272) (xy 298.797472 -79.504794) (xy 298.847764 -79.439008) (xy 298.850489 -79.434938)
			(xy 298.85445 -79.42598) (xy 298.855638 -79.421228) (xy 298.856654 -79.41564) (xy 298.858178 -79.407766)
			(xy 298.857416 -79.404718) (xy 298.85091 -79.38109) (xy 298.843267 -79.332681) (xy 298.842176 -79.308198)
			(xy 298.842176 -79.30769) (xy 298.841922 -79.299562) (xy 298.841922 -79.294736) (xy 298.842562 -79.267591)
			(xy 298.850579 -79.21389) (xy 298.86613 -79.161868) (xy 298.8889 -79.112577) (xy 298.918428 -79.067012)
			(xy 298.954119 -79.026094) (xy 298.99525 -78.99065) (xy 299.040992 -78.961397) (xy 299.090419 -78.938924)
			(xy 299.142534 -78.923686) (xy 299.196282 -78.915992) (xy 299.22343 -78.915514) (xy 299.249912 -78.915962)
			(xy 299.302369 -78.923277) (xy 299.353309 -78.937777) (xy 299.401755 -78.959182) (xy 299.446776 -78.987081)
			(xy 299.487505 -79.020939) (xy 299.52316 -79.060103) (xy 299.553057 -79.103823) (xy 299.57662 -79.151257)
			(xy 299.593396 -79.201494) (xy 299.603064 -79.253568) (xy 299.604684 -79.280004) (xy 299.605192 -79.292196)
			(xy 299.605192 -79.297022) (xy 299.604785 -79.322243) (xy 299.598139 -79.372246) (xy 299.584967 -79.420938)
			(xy 299.565498 -79.467471) (xy 299.54007 -79.511036) (xy 299.524928 -79.53121) (xy 299.518578 -79.539338)
			(xy 299.516038 -79.548228) (xy 299.514785 -79.553141) (xy 299.514014 -79.563249) (xy 299.514514 -79.568294)
			(xy 299.518832 -79.604108) (xy 299.52315 -79.639668) (xy 299.523882 -79.644675) (xy 299.527087 -79.65427)
			(xy 299.5295 -79.658718) (xy 299.534072 -79.666846) (xy 299.5422 -79.673196) (xy 299.558538 -79.686209)
			(xy 299.589801 -79.713914) (xy 299.604684 -79.728568) (xy 299.767244 -79.891382) (xy 299.76826 -79.892398)
			(xy 299.774402 -79.897748) (xy 299.789166 -79.90461) (xy 299.797216 -79.90586) (xy 299.803058 -79.906114)
			(xy 299.978318 -79.906114)
		)
		(stroke
			(width 0)
			(type solid)
		)
		(fill yes)
		(layer "B.Cu")
		(net "GND")
	)
	(gr_poly
		(pts
			(xy 41.223438 -78.721204) (xy 41.233775 -78.720723) (xy 41.252788 -78.712605) (xy 41.260268 -78.705456)
			(xy 41.311068 -78.651862) (xy 41.314478 -78.64812) (xy 41.319854 -78.639544) (xy 41.321736 -78.634844)
			(xy 41.325546 -78.62443) (xy 41.325038 -78.613762) (xy 41.324276 -78.58887) (xy 41.324766 -78.558902)
			(xy 41.332589 -78.49948) (xy 41.348102 -78.441587) (xy 41.371038 -78.386214) (xy 41.401005 -78.334308)
			(xy 41.437492 -78.286758) (xy 41.479872 -78.244378) (xy 41.527422 -78.207891) (xy 41.579328 -78.177924)
			(xy 41.634701 -78.154988) (xy 41.692594 -78.139475) (xy 41.752016 -78.131652) (xy 41.811952 -78.131652)
			(xy 41.871374 -78.139475) (xy 41.929267 -78.154988) (xy 41.98464 -78.177924) (xy 42.036546 -78.207891)
			(xy 42.084096 -78.244378) (xy 42.126476 -78.286758) (xy 42.162963 -78.334308) (xy 42.19293 -78.386214)
			(xy 42.215866 -78.441587) (xy 42.231379 -78.49948) (xy 42.239202 -78.558902) (xy 42.239692 -78.58887)
			(xy 42.23893 -78.613762) (xy 42.23893 -78.61427) (xy 42.238901 -78.62463) (xy 42.246121 -78.644026)
			(xy 42.2529 -78.651862) (xy 42.3037 -78.705456) (xy 42.311176 -78.712616) (xy 42.330189 -78.720751)
			(xy 42.34053 -78.721204) (xy 50.74793 -78.721204) (xy 50.757998 -78.720775) (xy 50.776595 -78.713054)
			(xy 50.783998 -78.706218) (xy 53.85816 -75.632056) (xy 53.865559 -75.625213) (xy 53.884158 -75.617491)
			(xy 53.894228 -75.61707) (xy 84.039964 -75.61707) (xy 84.050016 -75.617573) (xy 84.068581 -75.62529)
			(xy 84.076032 -75.632056) (xy 85.069426 -76.62545) (xy 204.32979 -76.62545) (xy 204.333861 -76.569828)
			(xy 204.345987 -76.515391) (xy 204.36591 -76.4633) (xy 204.393206 -76.414665) (xy 204.427292 -76.370522)
			(xy 204.467441 -76.331813) (xy 204.512799 -76.299362) (xy 204.562399 -76.273861) (xy 204.615183 -76.255854)
			(xy 204.670026 -76.245724) (xy 204.72576 -76.243687) (xy 204.781197 -76.249787) (xy 204.835154 -76.263893)
			(xy 204.886483 -76.285705) (xy 204.934089 -76.314759) (xy 204.976957 -76.350434) (xy 205.014174 -76.391971)
			(xy 205.044947 -76.438484) (xy 205.068619 -76.488981) (xy 205.084687 -76.542388) (xy 205.092807 -76.597564)
			(xy 205.093316 -76.62545) (xy 205.092807 -76.653336) (xy 205.084687 -76.708512) (xy 205.068619 -76.761919)
			(xy 205.044947 -76.812416) (xy 205.014174 -76.858929) (xy 204.976957 -76.900466) (xy 204.934089 -76.936141)
			(xy 204.886483 -76.965195) (xy 204.835154 -76.987007) (xy 204.781197 -77.001113) (xy 204.72576 -77.007213)
			(xy 204.670026 -77.005176) (xy 204.615183 -76.995046) (xy 204.562399 -76.977039) (xy 204.512799 -76.951538)
			(xy 204.467441 -76.919087) (xy 204.427292 -76.880378) (xy 204.393206 -76.836235) (xy 204.36591 -76.7876)
			(xy 204.345987 -76.735509) (xy 204.333861 -76.681072) (xy 204.32979 -76.62545) (xy 85.069426 -76.62545)
			(xy 85.809343 -77.365367) (xy 105.150162 -77.365367) (xy 105.150162 -77.305433) (xy 105.157985 -77.246011)
			(xy 105.173496 -77.188119) (xy 105.19643 -77.132746) (xy 105.226396 -77.08084) (xy 105.26288 -77.03329)
			(xy 105.305258 -76.990908) (xy 105.352805 -76.954419) (xy 105.404708 -76.924449) (xy 105.460079 -76.901509)
			(xy 105.51797 -76.885993) (xy 105.577391 -76.878165) (xy 105.607358 -76.877672) (xy 106.470958 -76.877672)
			(xy 106.500928 -76.878178) (xy 106.560354 -76.885997) (xy 106.618252 -76.901506) (xy 106.67363 -76.92444)
			(xy 106.72554 -76.954406) (xy 106.773095 -76.990892) (xy 106.81548 -77.033273) (xy 106.851971 -77.080825)
			(xy 106.881942 -77.132732) (xy 106.904881 -77.188108) (xy 106.920395 -77.246004) (xy 106.928219 -77.305431)
			(xy 106.928219 -77.365367) (xy 109.150162 -77.365367) (xy 109.150162 -77.305433) (xy 109.157984 -77.246012)
			(xy 109.173495 -77.18812) (xy 109.196429 -77.132748) (xy 109.226394 -77.080843) (xy 109.262878 -77.033292)
			(xy 109.305255 -76.990911) (xy 109.352801 -76.954422) (xy 109.404703 -76.924452) (xy 109.460073 -76.901511)
			(xy 109.517963 -76.885994) (xy 109.577383 -76.878165) (xy 109.60735 -76.877672) (xy 110.47095 -76.877672)
			(xy 110.50092 -76.878178) (xy 110.560347 -76.885996) (xy 110.618246 -76.901504) (xy 110.673625 -76.924437)
			(xy 110.725536 -76.954403) (xy 110.773092 -76.990889) (xy 110.815478 -77.03327) (xy 110.851969 -77.080822)
			(xy 110.881941 -77.13273) (xy 110.90488 -77.188107) (xy 110.920395 -77.246003) (xy 110.928219 -77.30543)
			(xy 110.928219 -77.36537) (xy 110.920395 -77.424797) (xy 110.90488 -77.482693) (xy 110.881941 -77.53807)
			(xy 110.881353 -77.539088) (xy 182.075834 -77.539088) (xy 182.079905 -77.483466) (xy 182.092031 -77.429029)
			(xy 182.111954 -77.376938) (xy 182.13925 -77.328303) (xy 182.173336 -77.28416) (xy 182.213485 -77.245451)
			(xy 182.258843 -77.213) (xy 182.308443 -77.187499) (xy 182.361227 -77.169492) (xy 182.41607 -77.159362)
			(xy 182.471804 -77.157325) (xy 182.527241 -77.163425) (xy 182.581198 -77.177531) (xy 182.632527 -77.199343)
			(xy 182.680133 -77.228397) (xy 182.689649 -77.236316) (xy 198.708754 -77.236316) (xy 198.708754 -77.17638)
			(xy 198.716577 -77.116958) (xy 198.73209 -77.059065) (xy 198.755026 -77.003692) (xy 198.784993 -76.951786)
			(xy 198.82148 -76.904236) (xy 198.86386 -76.861856) (xy 198.91141 -76.825369) (xy 198.963316 -76.795402)
			(xy 199.018689 -76.772466) (xy 199.076582 -76.756953) (xy 199.136004 -76.74913) (xy 199.19594 -76.74913)
			(xy 199.255362 -76.756953) (xy 199.313255 -76.772466) (xy 199.368628 -76.795402) (xy 199.420534 -76.825369)
			(xy 199.468084 -76.861856) (xy 199.510464 -76.904236) (xy 199.546951 -76.951786) (xy 199.576918 -77.003692)
			(xy 199.599854 -77.059065) (xy 199.615367 -77.116958) (xy 199.62319 -77.17638) (xy 199.62368 -77.206348)
			(xy 199.62319 -77.236316) (xy 199.615367 -77.295738) (xy 199.599854 -77.353631) (xy 199.576918 -77.409004)
			(xy 199.546951 -77.46091) (xy 199.510464 -77.50846) (xy 199.468084 -77.55084) (xy 199.420534 -77.587327)
			(xy 199.409946 -77.59344) (xy 205.153242 -77.59344) (xy 205.153242 -77.533504) (xy 205.161065 -77.474082)
			(xy 205.176578 -77.416189) (xy 205.199514 -77.360816) (xy 205.229481 -77.30891) (xy 205.265968 -77.26136)
			(xy 205.308348 -77.21898) (xy 205.355898 -77.182493) (xy 205.407804 -77.152526) (xy 205.463177 -77.12959)
			(xy 205.52107 -77.114077) (xy 205.580492 -77.106254) (xy 205.640428 -77.106254) (xy 205.69985 -77.114077)
			(xy 205.757743 -77.12959) (xy 205.813116 -77.152526) (xy 205.865022 -77.182493) (xy 205.912572 -77.21898)
			(xy 205.954952 -77.26136) (xy 205.991439 -77.30891) (xy 206.021406 -77.360816) (xy 206.044342 -77.416189)
			(xy 206.059855 -77.474082) (xy 206.067678 -77.533504) (xy 206.068168 -77.563472) (xy 206.067678 -77.59344)
			(xy 207.176606 -77.59344) (xy 207.176606 -77.533504) (xy 207.184429 -77.474082) (xy 207.199942 -77.416189)
			(xy 207.222878 -77.360816) (xy 207.252845 -77.30891) (xy 207.289332 -77.26136) (xy 207.331712 -77.21898)
			(xy 207.379262 -77.182493) (xy 207.431168 -77.152526) (xy 207.486541 -77.12959) (xy 207.544434 -77.114077)
			(xy 207.603856 -77.106254) (xy 207.663792 -77.106254) (xy 207.723214 -77.114077) (xy 207.781107 -77.12959)
			(xy 207.83648 -77.152526) (xy 207.888386 -77.182493) (xy 207.935936 -77.21898) (xy 207.978316 -77.26136)
			(xy 208.014803 -77.30891) (xy 208.04477 -77.360816) (xy 208.067706 -77.416189) (xy 208.083219 -77.474082)
			(xy 208.091042 -77.533504) (xy 208.091043 -77.533541) (xy 220.503432 -77.533541) (xy 220.511255 -77.474111)
			(xy 220.526768 -77.416211) (xy 220.549706 -77.360831) (xy 220.579676 -77.308919) (xy 220.616165 -77.261362)
			(xy 220.65855 -77.218976) (xy 220.706105 -77.182485) (xy 220.758016 -77.152513) (xy 220.813396 -77.129573)
			(xy 220.871295 -77.114058) (xy 220.930725 -77.106233) (xy 220.960696 -77.105764) (xy 220.961204 -77.105764)
			(xy 220.976876 -77.105904) (xy 221.008146 -77.108065) (xy 221.023688 -77.110082) (xy 221.036642 -77.11186)
			(xy 221.060772 -77.102716) (xy 221.133416 -77.018134) (xy 221.13875 -76.992734) (xy 221.135194 -76.980542)
			(xy 221.127741 -76.953918) (xy 221.119702 -76.899219) (xy 221.119192 -76.871576) (xy 221.119708 -76.844499)
			(xy 221.127376 -76.790891) (xy 221.14254 -76.738903) (xy 221.164898 -76.689579) (xy 221.193999 -76.643909)
			(xy 221.22926 -76.602808) (xy 221.269975 -76.5671) (xy 221.315325 -76.537503) (xy 221.339664 -76.525628)
			(xy 221.348808 -76.521564) (xy 221.36227 -76.507086) (xy 221.394528 -76.421488) (xy 221.39402 -76.40193)
			(xy 221.389956 -76.392532) (xy 221.377626 -76.363278) (xy 221.360215 -76.302229) (xy 221.351403 -76.239361)
			(xy 221.35084 -76.20762) (xy 221.35133 -76.177652) (xy 221.359153 -76.11823) (xy 221.374666 -76.060337)
			(xy 221.397602 -76.004964) (xy 221.427569 -75.953058) (xy 221.464056 -75.905508) (xy 221.506436 -75.863128)
			(xy 221.553986 -75.826641) (xy 221.605892 -75.796674) (xy 221.661265 -75.773738) (xy 221.719158 -75.758225)
			(xy 221.77858 -75.750402) (xy 221.838516 -75.750402) (xy 221.897938 -75.758225) (xy 221.955831 -75.773738)
			(xy 222.011204 -75.796674) (xy 222.06311 -75.826641) (xy 222.11066 -75.863128) (xy 222.15304 -75.905508)
			(xy 222.189527 -75.953058) (xy 222.219494 -76.004964) (xy 222.24243 -76.060337) (xy 222.257943 -76.11823)
			(xy 222.265766 -76.177652) (xy 222.266256 -76.20762) (xy 222.265832 -76.237023) (xy 222.258305 -76.295344)
			(xy 222.243366 -76.35222) (xy 222.22126 -76.406712) (xy 222.192352 -76.457922) (xy 222.15712 -76.505004)
			(xy 222.116143 -76.547182) (xy 222.070099 -76.58376) (xy 222.019747 -76.614136) (xy 221.965916 -76.637807)
			(xy 221.937834 -76.646532) (xy 221.93758 -76.646532) (xy 221.928378 -76.649799) (xy 221.913222 -76.662085)
			(xy 221.908116 -76.670408) (xy 221.868238 -76.741528) (xy 221.865952 -76.761086) (xy 221.868746 -76.770992)
			(xy 221.875057 -76.795592) (xy 221.881811 -76.845928) (xy 221.882208 -76.871322) (xy 221.882208 -76.871576)
			(xy 221.8817 -76.898815) (xy 221.873954 -76.95274) (xy 221.858614 -77.005014) (xy 221.835995 -77.054574)
			(xy 221.806554 -77.100412) (xy 221.770893 -77.141596) (xy 221.729735 -77.177288) (xy 221.683918 -77.206761)
			(xy 221.634374 -77.229417) (xy 221.582112 -77.244794) (xy 221.528193 -77.25258) (xy 221.500954 -77.253084)
			(xy 221.500446 -77.253084) (xy 221.483936 -77.25283) (xy 221.470982 -77.252322) (xy 221.447614 -77.263498)
			(xy 221.383352 -77.354684) (xy 221.380304 -77.380338) (xy 221.38513 -77.392276) (xy 221.395677 -77.41957)
			(xy 221.41049 -77.476178) (xy 221.417947 -77.534215) (xy 221.418404 -77.563472) (xy 222.62465 -77.563472)
			(xy 222.625214 -77.534544) (xy 222.633953 -77.477352) (xy 222.651228 -77.422136) (xy 222.676641 -77.37016)
			(xy 222.709611 -77.322618) (xy 222.749381 -77.280599) (xy 222.79504 -77.245066) (xy 222.84554 -77.216834)
			(xy 222.899723 -77.196551) (xy 222.927926 -77.190092) (xy 222.942126 -77.186685) (xy 222.967846 -77.172874)
			(xy 222.988617 -77.152358) (xy 223.002745 -77.126811) (xy 223.009079 -77.098312) (xy 223.007103 -77.069185)
			(xy 222.996978 -77.041803) (xy 222.988632 -77.029818) (xy 222.970842 -77.004942) (xy 222.942568 -76.950716)
			(xy 222.923305 -76.892674) (xy 222.913547 -76.832303) (xy 222.91294 -76.801726) (xy 222.913426 -76.774475)
			(xy 222.921182 -76.720527) (xy 222.936537 -76.668232) (xy 222.959179 -76.618655) (xy 222.988645 -76.572805)
			(xy 223.024336 -76.531614) (xy 223.065527 -76.495923) (xy 223.111377 -76.466457) (xy 223.160954 -76.443815)
			(xy 223.213249 -76.42846) (xy 223.267197 -76.420704) (xy 223.321699 -76.420704) (xy 223.375647 -76.42846)
			(xy 223.427942 -76.443815) (xy 223.477519 -76.466457) (xy 223.523369 -76.495923) (xy 223.56456 -76.531614)
			(xy 223.600251 -76.572805) (xy 223.629717 -76.618655) (xy 223.652359 -76.668232) (xy 223.667714 -76.720527)
			(xy 223.67547 -76.774475) (xy 223.675956 -76.801726) (xy 223.675386 -76.830654) (xy 223.666647 -76.887845)
			(xy 223.649373 -76.943061) (xy 223.62396 -76.995036) (xy 223.590991 -77.042578) (xy 223.551222 -77.084598)
			(xy 223.505564 -77.120131) (xy 223.455065 -77.148363) (xy 223.400882 -77.168647) (xy 223.37268 -77.175106)
			(xy 223.358481 -77.178519) (xy 223.332761 -77.192328) (xy 223.31199 -77.212843) (xy 223.297862 -77.238389)
			(xy 223.291528 -77.266887) (xy 223.293503 -77.296014) (xy 223.303628 -77.323395) (xy 223.311974 -77.33538)
			(xy 223.329764 -77.360257) (xy 223.358038 -77.414483) (xy 223.377301 -77.472524) (xy 223.387059 -77.532895)
			(xy 223.387666 -77.563472) (xy 223.38718 -77.590723) (xy 223.379424 -77.644671) (xy 223.364069 -77.696966)
			(xy 223.341427 -77.746543) (xy 223.311961 -77.792393) (xy 223.27627 -77.833584) (xy 223.235079 -77.869275)
			(xy 223.189229 -77.898741) (xy 223.139652 -77.921383) (xy 223.087357 -77.936738) (xy 223.033409 -77.944494)
			(xy 222.978907 -77.944494) (xy 222.924959 -77.936738) (xy 222.872664 -77.921383) (xy 222.823087 -77.898741)
			(xy 222.777237 -77.869275) (xy 222.736046 -77.833584) (xy 222.700355 -77.792393) (xy 222.670889 -77.746543)
			(xy 222.648247 -77.696966) (xy 222.632892 -77.644671) (xy 222.625136 -77.590723) (xy 222.62465 -77.563472)
			(xy 221.418404 -77.563472) (xy 221.417969 -77.593443) (xy 221.410148 -77.652873) (xy 221.394637 -77.710774)
			(xy 221.371702 -77.766155) (xy 221.341733 -77.818068) (xy 221.305245 -77.865626) (xy 221.262862 -77.908013)
			(xy 221.215308 -77.944506) (xy 221.163398 -77.97448) (xy 221.10802 -77.997422) (xy 221.05012 -78.012939)
			(xy 220.990691 -78.020766) (xy 220.930749 -78.020768) (xy 220.871319 -78.012947) (xy 220.813418 -77.997435)
			(xy 220.758038 -77.974498) (xy 220.706125 -77.944529) (xy 220.658568 -77.90804) (xy 220.616181 -77.865656)
			(xy 220.579689 -77.818101) (xy 220.549716 -77.766191) (xy 220.526776 -77.710812) (xy 220.51126 -77.652913)
			(xy 220.503434 -77.593483) (xy 220.503432 -77.533541) (xy 208.091043 -77.533541) (xy 208.091532 -77.563472)
			(xy 208.091042 -77.59344) (xy 208.083219 -77.652862) (xy 208.067706 -77.710755) (xy 208.04477 -77.766128)
			(xy 208.014803 -77.818034) (xy 207.978316 -77.865584) (xy 207.935936 -77.907964) (xy 207.888386 -77.944451)
			(xy 207.83648 -77.974418) (xy 207.781107 -77.997354) (xy 207.723214 -78.012867) (xy 207.663792 -78.02069)
			(xy 207.603856 -78.02069) (xy 207.544434 -78.012867) (xy 207.486541 -77.997354) (xy 207.431168 -77.974418)
			(xy 207.379262 -77.944451) (xy 207.331712 -77.907964) (xy 207.289332 -77.865584) (xy 207.252845 -77.818034)
			(xy 207.222878 -77.766128) (xy 207.199942 -77.710755) (xy 207.184429 -77.652862) (xy 207.176606 -77.59344)
			(xy 206.067678 -77.59344) (xy 206.059855 -77.652862) (xy 206.044342 -77.710755) (xy 206.021406 -77.766128)
			(xy 205.991439 -77.818034) (xy 205.954952 -77.865584) (xy 205.912572 -77.907964) (xy 205.865022 -77.944451)
			(xy 205.813116 -77.974418) (xy 205.757743 -77.997354) (xy 205.69985 -78.012867) (xy 205.640428 -78.02069)
			(xy 205.580492 -78.02069) (xy 205.52107 -78.012867) (xy 205.463177 -77.997354) (xy 205.407804 -77.974418)
			(xy 205.355898 -77.944451) (xy 205.308348 -77.907964) (xy 205.265968 -77.865584) (xy 205.229481 -77.818034)
			(xy 205.199514 -77.766128) (xy 205.176578 -77.710755) (xy 205.161065 -77.652862) (xy 205.153242 -77.59344)
			(xy 199.409946 -77.59344) (xy 199.368628 -77.617294) (xy 199.313255 -77.64023) (xy 199.255362 -77.655743)
			(xy 199.19594 -77.663566) (xy 199.136004 -77.663566) (xy 199.076582 -77.655743) (xy 199.018689 -77.64023)
			(xy 198.963316 -77.617294) (xy 198.91141 -77.587327) (xy 198.86386 -77.55084) (xy 198.82148 -77.50846)
			(xy 198.784993 -77.46091) (xy 198.755026 -77.409004) (xy 198.73209 -77.353631) (xy 198.716577 -77.295738)
			(xy 198.708754 -77.236316) (xy 182.689649 -77.236316) (xy 182.723001 -77.264072) (xy 182.760218 -77.305609)
			(xy 182.790991 -77.352122) (xy 182.814663 -77.402619) (xy 182.830731 -77.456026) (xy 182.838851 -77.511202)
			(xy 182.83936 -77.539088) (xy 182.838851 -77.566974) (xy 182.830731 -77.62215) (xy 182.814663 -77.675557)
			(xy 182.790991 -77.726054) (xy 182.760218 -77.772567) (xy 182.723001 -77.814104) (xy 182.680133 -77.849779)
			(xy 182.632527 -77.878833) (xy 182.581198 -77.900645) (xy 182.527241 -77.914751) (xy 182.471804 -77.920851)
			(xy 182.41607 -77.918814) (xy 182.361227 -77.908684) (xy 182.308443 -77.890677) (xy 182.258843 -77.865176)
			(xy 182.213485 -77.832725) (xy 182.173336 -77.794016) (xy 182.13925 -77.749873) (xy 182.111954 -77.701238)
			(xy 182.092031 -77.649147) (xy 182.079905 -77.59471) (xy 182.075834 -77.539088) (xy 110.881353 -77.539088)
			(xy 110.851969 -77.589978) (xy 110.815478 -77.63753) (xy 110.773092 -77.679911) (xy 110.725536 -77.716397)
			(xy 110.673625 -77.746363) (xy 110.618246 -77.769296) (xy 110.560347 -77.784804) (xy 110.50092 -77.792622)
			(xy 110.47095 -77.793088) (xy 109.60735 -77.793088) (xy 109.577383 -77.792635) (xy 109.517963 -77.784806)
			(xy 109.460073 -77.769289) (xy 109.404703 -77.746348) (xy 109.352801 -77.716378) (xy 109.305255 -77.679889)
			(xy 109.262878 -77.637508) (xy 109.226394 -77.589957) (xy 109.196429 -77.538052) (xy 109.173495 -77.48268)
			(xy 109.157984 -77.424788) (xy 109.150162 -77.365367) (xy 106.928219 -77.365367) (xy 106.928219 -77.365369)
			(xy 106.920395 -77.424796) (xy 106.904881 -77.482692) (xy 106.881942 -77.538068) (xy 106.851971 -77.589975)
			(xy 106.81548 -77.637527) (xy 106.773095 -77.679908) (xy 106.72554 -77.716394) (xy 106.67363 -77.74636)
			(xy 106.618252 -77.769294) (xy 106.560354 -77.784803) (xy 106.500928 -77.792622) (xy 106.470958 -77.793088)
			(xy 105.607358 -77.793088) (xy 105.577391 -77.792635) (xy 105.51797 -77.784807) (xy 105.460079 -77.769291)
			(xy 105.404708 -77.746351) (xy 105.352805 -77.716381) (xy 105.305258 -77.679892) (xy 105.26288 -77.63751)
			(xy 105.226396 -77.58996) (xy 105.19643 -77.538054) (xy 105.173496 -77.482681) (xy 105.157985 -77.424789)
			(xy 105.150162 -77.365367) (xy 85.809343 -77.365367) (xy 87.150194 -78.706218) (xy 87.157588 -78.713074)
			(xy 87.176187 -78.720824) (xy 87.186262 -78.721204) (xy 107.001056 -78.721204) (xy 107.02925 -78.696566)
			(xy 107.032044 -78.677516) (xy 107.036086 -78.652105) (xy 107.05012 -78.602602) (xy 107.070687 -78.555437)
			(xy 107.097411 -78.511468) (xy 107.129808 -78.471494) (xy 107.167287 -78.436241) (xy 107.188 -78.420976)
			(xy 107.195432 -78.415248) (xy 107.205744 -78.399587) (xy 107.208066 -78.390496) (xy 107.216956 -78.350872)
			(xy 107.214162 -78.332076) (xy 107.20959 -78.323948) (xy 107.195315 -78.297964) (xy 107.172835 -78.243103)
			(xy 107.157607 -78.185805) (xy 107.149885 -78.127023) (xy 107.149392 -78.09738) (xy 107.149883 -78.067424)
			(xy 107.157702 -78.008024) (xy 107.173206 -77.950152) (xy 107.196127 -77.894798) (xy 107.226075 -77.842907)
			(xy 107.262538 -77.795368) (xy 107.304892 -77.752993) (xy 107.352412 -77.716506) (xy 107.404287 -77.686531)
			(xy 107.45963 -77.663581) (xy 107.517494 -77.648048) (xy 107.57689 -77.640198) (xy 107.606846 -77.639672)
			(xy 108.470954 -77.639672) (xy 108.500929 -77.640159) (xy 108.560367 -77.647976) (xy 108.618276 -77.663482)
			(xy 108.673667 -77.686413) (xy 108.725592 -77.716376) (xy 108.773162 -77.752859) (xy 108.815565 -77.795237)
			(xy 108.852076 -77.842787) (xy 108.882069 -77.894694) (xy 108.905032 -77.950072) (xy 108.920572 -78.007972)
			(xy 108.928424 -78.067405) (xy 108.928916 -78.09738) (xy 108.928439 -78.127026) (xy 108.920759 -78.18582)
			(xy 108.905538 -78.243126) (xy 108.883032 -78.297982) (xy 108.868718 -78.323948) (xy 108.864146 -78.332076)
			(xy 108.861352 -78.350872) (xy 108.872274 -78.400148) (xy 108.882688 -78.415388) (xy 108.890308 -78.420976)
			(xy 108.910991 -78.436275) (xy 108.94845 -78.471539) (xy 108.980834 -78.511513) (xy 109.007557 -78.555474)
			(xy 109.028135 -78.602626) (xy 109.042195 -78.652113) (xy 109.046264 -78.677516) (xy 109.049058 -78.696566)
			(xy 109.077506 -78.721204) (xy 129.62636 -78.721204) (xy 129.630166 -78.721135) (xy 129.637691 -78.719983)
			(xy 129.641346 -78.718918) (xy 129.662682 -78.712314) (xy 129.668778 -78.70825) (xy 129.692007 -78.69333)
			(xy 129.741862 -78.66962) (xy 129.768092 -78.661006) (xy 129.793378 -78.653627) (xy 129.845356 -78.645091)
			(xy 129.898014 -78.64379) (xy 129.95035 -78.649746) (xy 130.001368 -78.662848) (xy 130.025902 -78.672436)
			(xy 130.043279 -78.679867) (xy 130.076615 -78.69768) (xy 130.09245 -78.707996) (xy 130.098546 -78.71206)
			(xy 130.127502 -78.721204) (xy 150.165562 -78.721204) (xy 150.175085 -78.720812) (xy 150.192838 -78.713907)
			(xy 150.200106 -78.707742) (xy 150.20036 -78.707488) (xy 150.206841 -78.700981) (xy 150.215063 -78.684574)
			(xy 150.216362 -78.675484) (xy 150.216362 -78.674214) (xy 150.219149 -78.647346) (xy 150.231331 -78.594721)
			(xy 150.250811 -78.54434) (xy 150.277201 -78.497209) (xy 150.309972 -78.45427) (xy 150.34847 -78.41638)
			(xy 150.391927 -78.384297) (xy 150.439472 -78.358662) (xy 150.490158 -78.339987) (xy 150.54297 -78.328646)
			(xy 150.596853 -78.324864) (xy 150.650732 -78.328717) (xy 150.703529 -78.340129) (xy 150.754189 -78.358871)
			(xy 150.801701 -78.384569) (xy 150.845115 -78.416709) (xy 150.883563 -78.45465) (xy 150.916277 -78.497633)
			(xy 150.942604 -78.544799) (xy 150.962018 -78.595206) (xy 150.97413 -78.647847) (xy 150.976838 -78.674722)
			(xy 150.9776 -78.684374) (xy 150.985728 -78.700884) (xy 150.993094 -78.707742) (xy 151.000352 -78.713929)
			(xy 151.018107 -78.720853) (xy 151.027638 -78.721204) (xy 205.147418 -78.721204) (xy 205.156855 -78.720716)
			(xy 205.174427 -78.713808) (xy 205.188332 -78.701036) (xy 205.192884 -78.692756) (xy 205.206513 -78.665928)
			(xy 205.239771 -78.615777) (xy 205.279312 -78.570416) (xy 205.324454 -78.530624) (xy 205.374419 -78.497088)
			(xy 205.428346 -78.470385) (xy 205.485306 -78.450977) (xy 205.544318 -78.439196) (xy 205.604364 -78.435246)
			(xy 205.66441 -78.439196) (xy 205.723422 -78.450977) (xy 205.780382 -78.470385) (xy 205.834309 -78.497088)
			(xy 205.884274 -78.530624) (xy 205.929416 -78.570416) (xy 205.968957 -78.615777) (xy 206.002215 -78.665928)
			(xy 206.015844 -78.692756) (xy 206.020335 -78.701086) (xy 206.034239 -78.713904) (xy 206.051855 -78.720782)
			(xy 206.06131 -78.721204) (xy 208.351374 -78.721204) (xy 208.361818 -78.720635) (xy 208.380952 -78.712235)
			(xy 208.388458 -78.704948) (xy 208.446624 -78.642464) (xy 208.453482 -78.622652) (xy 208.45272 -78.611984)
			(xy 208.45145 -78.579472) (xy 208.45194 -78.549504) (xy 208.459763 -78.490082) (xy 208.475276 -78.432189)
			(xy 208.498212 -78.376816) (xy 208.528179 -78.32491) (xy 208.564666 -78.27736) (xy 208.607046 -78.23498)
			(xy 208.654596 -78.198493) (xy 208.706502 -78.168526) (xy 208.761875 -78.14559) (xy 208.819768 -78.130077)
			(xy 208.87919 -78.122254) (xy 208.939126 -78.122254) (xy 208.998548 -78.130077) (xy 209.056441 -78.14559)
			(xy 209.111814 -78.168526) (xy 209.16372 -78.198493) (xy 209.21127 -78.23498) (xy 209.25365 -78.27736)
			(xy 209.290137 -78.32491) (xy 209.320104 -78.376816) (xy 209.34304 -78.432189) (xy 209.358553 -78.490082)
			(xy 209.366376 -78.549504) (xy 209.366866 -78.579472) (xy 209.365596 -78.611984) (xy 209.364834 -78.622652)
			(xy 209.371692 -78.642464) (xy 209.408776 -78.682342) (xy 209.429858 -78.704948) (xy 209.430874 -78.705964)
			(xy 209.431128 -78.706218) (xy 209.438524 -78.713069) (xy 209.457123 -78.720806) (xy 209.467196 -78.721204)
			(xy 218.753436 -78.721204) (xy 218.763884 -78.720642) (xy 218.783028 -78.712251) (xy 218.79052 -78.704948)
			(xy 218.848686 -78.642464) (xy 218.855544 -78.622652) (xy 218.854782 -78.611984) (xy 218.853512 -78.579472)
			(xy 218.854002 -78.549504) (xy 218.861825 -78.490082) (xy 218.877338 -78.432189) (xy 218.900274 -78.376816)
			(xy 218.930241 -78.32491) (xy 218.966728 -78.27736) (xy 219.009108 -78.23498) (xy 219.056658 -78.198493)
			(xy 219.108564 -78.168526) (xy 219.163937 -78.14559) (xy 219.22183 -78.130077) (xy 219.281252 -78.122254)
			(xy 219.341188 -78.122254) (xy 219.40061 -78.130077) (xy 219.458503 -78.14559) (xy 219.513876 -78.168526)
			(xy 219.565782 -78.198493) (xy 219.613332 -78.23498) (xy 219.655712 -78.27736) (xy 219.692199 -78.32491)
			(xy 219.722166 -78.376816) (xy 219.745102 -78.432189) (xy 219.760615 -78.490082) (xy 219.768438 -78.549504)
			(xy 219.768928 -78.579472) (xy 219.767658 -78.611984) (xy 219.766896 -78.622652) (xy 219.773754 -78.642464)
			(xy 219.810838 -78.682342) (xy 219.83192 -78.704948) (xy 219.832936 -78.705964) (xy 219.83319 -78.706218)
			(xy 219.840584 -78.713075) (xy 219.859183 -78.720826) (xy 219.869258 -78.721204) (xy 222.524828 -78.721204)
			(xy 222.535368 -78.720627) (xy 222.554658 -78.712112) (xy 222.562166 -78.704694) (xy 222.61957 -78.642464)
			(xy 222.626428 -78.622652) (xy 222.625666 -78.61173) (xy 222.624396 -78.579472) (xy 222.624884 -78.552203)
			(xy 222.632649 -78.49822) (xy 222.648016 -78.445891) (xy 222.670674 -78.396282) (xy 222.70016 -78.350402)
			(xy 222.735874 -78.309184) (xy 222.777091 -78.273468) (xy 222.82297 -78.24398) (xy 222.872578 -78.221321)
			(xy 222.924906 -78.205952) (xy 222.978889 -78.198185) (xy 223.006158 -78.19771) (xy 223.03378 -78.198196)
			(xy 223.088447 -78.206156) (xy 223.141395 -78.221916) (xy 223.191518 -78.245147) (xy 223.237766 -78.275362)
			(xy 223.279174 -78.311931) (xy 223.314876 -78.354089) (xy 223.344125 -78.400954) (xy 223.355662 -78.426056)
			(xy 223.361769 -78.438793) (xy 223.379783 -78.460535) (xy 223.40306 -78.476516) (xy 223.429822 -78.485517)
			(xy 223.458025 -78.48685) (xy 223.485517 -78.480413) (xy 223.510197 -78.466697) (xy 223.520508 -78.457044)
			(xy 225.07575 -76.901802) (xy 225.082433 -76.894391) (xy 225.090029 -76.875959) (xy 225.090026 -76.856024)
			(xy 225.082424 -76.837595) (xy 225.07575 -76.830174) (xy 225.05162 -76.806044) (xy 225.04478 -76.798643)
			(xy 225.037063 -76.780045) (xy 225.036634 -76.769976) (xy 225.036634 -74.9427) (xy 225.036209 -74.932631)
			(xy 225.028487 -74.914033) (xy 225.021648 -74.906632) (xy 224.521268 -74.406252) (xy 224.514422 -74.398854)
			(xy 224.506694 -74.380255) (xy 224.506282 -74.370184) (xy 224.506282 -70.393814) (xy 224.50672 -70.38375)
			(xy 224.514455 -70.365167) (xy 224.521268 -70.357746) (xy 226.179888 -68.699126) (xy 226.187285 -68.692275)
			(xy 226.205883 -68.684532) (xy 226.215956 -68.68414) (xy 226.424744 -68.68414) (xy 226.434809 -68.683707)
			(xy 226.453396 -68.675975) (xy 226.460812 -68.669154) (xy 226.723702 -68.406264) (xy 226.731097 -68.399411)
			(xy 226.749696 -68.391667) (xy 226.75977 -68.391278) (xy 227.698554 -68.391278) (xy 227.726494 -68.368418)
			(xy 227.73005 -68.350384) (xy 227.73555 -68.32471) (xy 227.752663 -68.27507) (xy 227.776427 -68.228249)
			(xy 227.806392 -68.185133) (xy 227.84199 -68.146536) (xy 227.882548 -68.11319) (xy 227.927299 -68.085726)
			(xy 227.975395 -68.064663) (xy 228.025927 -68.0504) (xy 228.077939 -68.043207) (xy 228.104192 -68.04279)
			(xy 228.136704 -68.04406) (xy 228.14534 -68.04406) (xy 228.179376 -68.042536) (xy 228.179884 -68.042536)
			(xy 228.201867 -68.042861) (xy 228.245537 -68.047958) (xy 228.267006 -68.052696) (xy 228.272086 -68.053458)
			(xy 228.287211 -68.054922) (xy 228.317168 -68.049934) (xy 228.344335 -68.036357) (xy 228.366308 -68.015392)
			(xy 228.374194 -68.002404) (xy 228.377242 -67.995546) (xy 228.37864 -67.991619) (xy 228.380306 -67.983452)
			(xy 228.380544 -67.97929) (xy 228.380544 -67.503548) (xy 228.380061 -67.493584) (xy 228.372482 -67.475152)
			(xy 228.365812 -67.467734) (xy 228.30028 -67.401948) (xy 228.293469 -67.394604) (xy 228.285743 -67.37614)
			(xy 228.285294 -67.366134) (xy 228.285294 -67.110864) (xy 228.28504 -67.098672) (xy 228.28504 -66.656712)
			(xy 228.285294 -66.64452) (xy 228.285294 -66.42608) (xy 228.284908 -66.417196) (xy 228.278838 -66.400497)
			(xy 228.267435 -66.38687) (xy 228.252067 -66.377953) (xy 228.243384 -66.376042) (xy 228.24313 -66.376042)
			(xy 228.219988 -66.37169) (xy 228.174928 -66.358014) (xy 228.131901 -66.338879) (xy 228.111558 -66.32702)
			(xy 228.097842 -66.326766) (xy 227.260912 -66.326766) (xy 227.252717 -66.327073) (xy 227.237167 -66.332249)
			(xy 227.230432 -66.336926) (xy 227.223066 -66.342514) (xy 227.21316 -66.357246) (xy 227.211128 -66.365882)
			(xy 227.206121 -66.385797) (xy 227.193022 -66.424718) (xy 227.184966 -66.443606) (xy 227.17182 -66.472087)
			(xy 227.138872 -66.525465) (xy 227.098942 -66.573843) (xy 227.052777 -66.616313) (xy 227.001245 -66.652079)
			(xy 226.945309 -66.680471) (xy 226.88602 -66.700956) (xy 226.824488 -66.71315) (xy 226.761868 -66.716825)
			(xy 226.73056 -66.714878) (xy 226.722686 -66.714878) (xy 226.690936 -66.716148) (xy 226.660387 -66.715636)
			(xy 226.599834 -66.7075) (xy 226.540901 -66.691381) (xy 226.484636 -66.667565) (xy 226.43204 -66.636477)
			(xy 226.384047 -66.598667) (xy 226.341509 -66.55481) (xy 226.305185 -66.505683) (xy 226.275718 -66.452161)
			(xy 226.253633 -66.395194) (xy 226.245928 -66.365628) (xy 226.242662 -66.354768) (xy 226.228396 -66.337175)
			(xy 226.207974 -66.32738) (xy 226.196652 -66.326766) (xy 224.790508 -66.326766) (xy 224.780439 -66.327189)
			(xy 224.761838 -66.334909) (xy 224.75444 -66.341752) (xy 224.748344 -66.347848) (xy 224.743264 -66.352928)
			(xy 224.700338 -66.430398) (xy 224.696273 -66.438441) (xy 224.693525 -66.45624) (xy 224.697135 -66.473883)
			(xy 224.701608 -66.481706) (xy 224.717784 -66.508905) (xy 224.743314 -66.566809) (xy 224.760629 -66.627677)
			(xy 224.769398 -66.690349) (xy 224.769934 -66.72199) (xy 224.769934 -66.722498) (xy 224.769444 -66.752482)
			(xy 224.761616 -66.811938) (xy 224.746095 -66.869863) (xy 224.723146 -66.925267) (xy 224.693162 -66.977201)
			(xy 224.656656 -67.024777) (xy 224.614251 -67.067182) (xy 224.566675 -67.103688) (xy 224.514741 -67.133672)
			(xy 224.459337 -67.156621) (xy 224.401412 -67.172142) (xy 224.341956 -67.17997) (xy 224.281988 -67.17997)
			(xy 224.222532 -67.172142) (xy 224.164607 -67.156621) (xy 224.109203 -67.133672) (xy 224.057269 -67.103688)
			(xy 224.009693 -67.067182) (xy 223.967288 -67.024777) (xy 223.930782 -66.977201) (xy 223.900798 -66.925267)
			(xy 223.877849 -66.869863) (xy 223.862328 -66.811938) (xy 223.8545 -66.752482) (xy 223.85401 -66.722498)
			(xy 223.854521 -66.691537) (xy 223.86286 -66.63018) (xy 223.879387 -66.570505) (xy 223.903801 -66.5136)
			(xy 223.919288 -66.486786) (xy 223.923098 -66.48069) (xy 223.926654 -66.466974) (xy 223.927924 -66.461386)
			(xy 223.927924 -66.46037) (xy 223.928836 -66.452132) (xy 223.925973 -66.435815) (xy 223.922336 -66.428366)
			(xy 223.88068 -66.352928) (xy 223.8756 -66.347848) (xy 223.869504 -66.341752) (xy 223.862108 -66.334899)
			(xy 223.84351 -66.327155) (xy 223.833436 -66.326766) (xy 9.178798 -66.326766) (xy 9.168801 -66.327262)
			(xy 9.15032 -66.334896) (xy 9.136125 -66.348978) (xy 9.131808 -66.358008) (xy 9.125712 -66.372486)
			(xy 9.131808 -66.402458) (xy 9.291574 -66.562224) (xy 9.291574 -66.562478) (xy 9.30783 -66.57848)
			(xy 9.308084 -66.578734) (xy 9.308338 -66.578988) (xy 9.315691 -66.585466) (xy 9.333853 -66.592778)
			(xy 9.343644 -66.593212) (xy 14.74851 -66.593212) (xy 14.778782 -66.593678) (xy 14.838891 -66.600927)
			(xy 14.897714 -66.61526) (xy 14.95442 -66.636476) (xy 15.008205 -66.664275) (xy 15.05831 -66.698262)
			(xy 15.104026 -66.737958) (xy 15.124684 -66.76009) (xy 15.125446 -66.761106) (xy 15.127224 -66.762884)
			(xy 15.133764 -66.768997) (xy 15.149961 -66.776593) (xy 15.167785 -66.778133) (xy 15.1765 -66.776092)
			(xy 15.189708 -66.772536) (xy 15.195296 -66.769488) (xy 15.216803 -66.757806) (xy 15.262156 -66.739403)
			(xy 15.309487 -66.726942) (xy 15.358022 -66.720628) (xy 15.382494 -66.720212) (xy 15.382748 -66.720212)
			(xy 15.410001 -66.720675) (xy 15.463952 -66.728432) (xy 15.51625 -66.743788) (xy 15.565831 -66.76643)
			(xy 15.611684 -66.795898) (xy 15.652877 -66.831592) (xy 15.688571 -66.872784) (xy 15.718039 -66.918638)
			(xy 15.740682 -66.968218) (xy 15.756038 -67.020516) (xy 15.763795 -67.074467) (xy 15.763795 -67.128973)
			(xy 15.756038 -67.182924) (xy 15.740682 -67.235222) (xy 15.718039 -67.284802) (xy 15.688571 -67.330656)
			(xy 15.652877 -67.371848) (xy 15.611684 -67.407542) (xy 15.565831 -67.43701) (xy 15.51625 -67.459652)
			(xy 15.463952 -67.475008) (xy 15.410001 -67.482765) (xy 15.382748 -67.483228) (xy 15.382494 -67.483228)
			(xy 15.357261 -67.482817) (xy 15.307236 -67.476165) (xy 15.25852 -67.462992) (xy 15.21196 -67.443525)
			(xy 15.189962 -67.431158) (xy 15.179604 -67.425763) (xy 15.156336 -67.424059) (xy 15.1347 -67.432783)
			(xy 15.126462 -67.441064) (xy 15.105807 -67.463448) (xy 15.060034 -67.503632) (xy 15.00979 -67.538061)
			(xy 14.955792 -67.566242) (xy 14.898815 -67.587772) (xy 14.839675 -67.602342) (xy 14.779217 -67.609744)
			(xy 14.748764 -67.610228) (xy 9.111742 -67.610228) (xy 9.078453 -67.609696) (xy 9.012446 -67.600982)
			(xy 8.948143 -67.583724) (xy 8.886644 -67.558217) (xy 8.829002 -67.524898) (xy 8.776204 -67.484337)
			(xy 8.752332 -67.46113) (xy 7.723124 -66.431922) (xy 7.720446 -66.429314) (xy 7.71445 -66.424853)
			(xy 7.711186 -66.423032) (xy 7.710932 -66.423032) (xy 7.705363 -66.420228) (xy 7.693287 -66.417143)
			(xy 7.687056 -66.416936) (xy 7.167372 -66.416936) (xy 7.162038 -66.41719) (xy 7.149592 -66.41846)
			(xy 7.139178 -66.425318) (xy 7.129526 -66.4337) (xy 7.079234 -66.489326) (xy 7.075729 -66.493356)
			(xy 7.070346 -66.502578) (xy 7.068566 -66.507614) (xy 7.06501 -66.518536) (xy 7.066026 -66.529204)
			(xy 7.068058 -66.56578) (xy 7.068058 -66.571114) (xy 7.067348 -66.598211) (xy 7.059212 -66.651802)
			(xy 7.043573 -66.703701) (xy 7.020746 -66.752865) (xy 6.99119 -66.798303) (xy 6.9555 -66.8391) (xy 6.914396 -66.874435)
			(xy 6.868704 -66.903597) (xy 6.819344 -66.925998) (xy 6.767311 -66.941187) (xy 6.713652 -66.948859)
			(xy 6.659448 -66.948859) (xy 6.605789 -66.941187) (xy 6.553756 -66.925998) (xy 6.504396 -66.903597)
			(xy 6.458704 -66.874435) (xy 6.4176 -66.8391) (xy 6.38191 -66.798303) (xy 6.352354 -66.752865) (xy 6.329527 -66.703701)
			(xy 6.313888 -66.651802) (xy 6.305752 -66.598211) (xy 6.305042 -66.571114) (xy 6.305042 -66.567812)
			(xy 6.307074 -66.529204) (xy 6.30809 -66.518536) (xy 6.304534 -66.507614) (xy 6.302717 -66.502596)
			(xy 6.297335 -66.493382) (xy 6.293866 -66.489326) (xy 6.243574 -66.4337) (xy 6.233922 -66.425318)
			(xy 6.2287 -66.422099) (xy 6.217145 -66.417989) (xy 6.211062 -66.41719) (xy 6.208268 -66.416936)
			(xy 4.46405 -66.416936) (xy 4.434813 -66.416499) (xy 4.37673 -66.409734) (xy 4.319808 -66.396345)
			(xy 4.2648 -66.376509) (xy 4.212433 -66.350489) (xy 4.187698 -66.334894) (xy 4.181416 -66.331106)
			(xy 4.167345 -66.326986) (xy 4.160012 -66.326766) (xy 3.15849 -66.326766) (xy 3.148422 -66.327193)
			(xy 3.129826 -66.334917) (xy 3.122422 -66.341752) (xy 2.233172 -67.231002) (xy 4.167106 -67.231002)
			(xy 4.167106 -67.171066) (xy 4.174929 -67.111644) (xy 4.190442 -67.053751) (xy 4.213378 -66.998378)
			(xy 4.243345 -66.946472) (xy 4.279832 -66.898922) (xy 4.322212 -66.856542) (xy 4.369762 -66.820055)
			(xy 4.421668 -66.790088) (xy 4.477041 -66.767152) (xy 4.534934 -66.751639) (xy 4.594356 -66.743816)
			(xy 4.654292 -66.743816) (xy 4.713714 -66.751639) (xy 4.771607 -66.767152) (xy 4.82698 -66.790088)
			(xy 4.878886 -66.820055) (xy 4.926436 -66.856542) (xy 4.968816 -66.898922) (xy 5.005303 -66.946472)
			(xy 5.03527 -66.998378) (xy 5.058206 -67.053751) (xy 5.073719 -67.111644) (xy 5.081542 -67.171066)
			(xy 5.082032 -67.201034) (xy 5.081542 -67.231002) (xy 5.073719 -67.290424) (xy 5.058206 -67.348317)
			(xy 5.03527 -67.40369) (xy 5.005303 -67.455596) (xy 4.968816 -67.503146) (xy 4.926436 -67.545526)
			(xy 4.878886 -67.582013) (xy 4.82698 -67.61198) (xy 4.771607 -67.634916) (xy 4.713714 -67.650429)
			(xy 4.654292 -67.658252) (xy 4.594356 -67.658252) (xy 4.534934 -67.650429) (xy 4.477041 -67.634916)
			(xy 4.421668 -67.61198) (xy 4.369762 -67.582013) (xy 4.322212 -67.545526) (xy 4.279832 -67.503146)
			(xy 4.243345 -67.455596) (xy 4.213378 -67.40369) (xy 4.190442 -67.348317) (xy 4.174929 -67.290424)
			(xy 4.167106 -67.231002) (xy 2.233172 -67.231002) (xy 1.678178 -67.785996) (xy 7.66521 -67.785996)
			(xy 7.669281 -67.730374) (xy 7.681407 -67.675937) (xy 7.70133 -67.623846) (xy 7.728626 -67.575211)
			(xy 7.762712 -67.531068) (xy 7.802861 -67.492359) (xy 7.848219 -67.459908) (xy 7.897819 -67.434407)
			(xy 7.950603 -67.4164) (xy 8.005446 -67.40627) (xy 8.06118 -67.404233) (xy 8.116617 -67.410333) (xy 8.170574 -67.424439)
			(xy 8.221903 -67.446251) (xy 8.269509 -67.475305) (xy 8.312377 -67.51098) (xy 8.349594 -67.552517)
			(xy 8.380367 -67.59903) (xy 8.404039 -67.649527) (xy 8.420107 -67.702934) (xy 8.428227 -67.75811)
			(xy 8.428736 -67.785996) (xy 8.428227 -67.813882) (xy 8.420107 -67.869058) (xy 8.404039 -67.922465)
			(xy 8.380367 -67.972962) (xy 8.349594 -68.019475) (xy 8.312377 -68.061012) (xy 8.269509 -68.096687)
			(xy 8.221903 -68.125741) (xy 8.170574 -68.147553) (xy 8.116617 -68.161659) (xy 8.06118 -68.167759)
			(xy 8.005446 -68.165722) (xy 7.950603 -68.155592) (xy 7.897819 -68.137585) (xy 7.848219 -68.112084)
			(xy 7.802861 -68.079633) (xy 7.762712 -68.040924) (xy 7.728626 -67.996781) (xy 7.70133 -67.948146)
			(xy 7.681407 -67.896055) (xy 7.669281 -67.841618) (xy 7.66521 -67.785996) (xy 1.678178 -67.785996)
			(xy 1.399794 -68.06438) (xy 1.392961 -68.071783) (xy 1.385257 -68.090381) (xy 1.384808 -68.100448)
			(xy 1.384808 -68.3834) (xy 3.501626 -68.3834) (xy 3.501626 -68.323464) (xy 3.509449 -68.264042) (xy 3.524962 -68.206149)
			(xy 3.547898 -68.150776) (xy 3.577865 -68.09887) (xy 3.614352 -68.05132) (xy 3.656732 -68.00894)
			(xy 3.704282 -67.972453) (xy 3.756188 -67.942486) (xy 3.811561 -67.91955) (xy 3.869454 -67.904037)
			(xy 3.928876 -67.896214) (xy 3.988812 -67.896214) (xy 4.048234 -67.904037) (xy 4.106127 -67.91955)
			(xy 4.1615 -67.942486) (xy 4.213406 -67.972453) (xy 4.260956 -68.00894) (xy 4.303336 -68.05132) (xy 4.339823 -68.09887)
			(xy 4.36979 -68.150776) (xy 4.392726 -68.206149) (xy 4.408239 -68.264042) (xy 4.416062 -68.323464)
			(xy 4.416552 -68.353432) (xy 4.416062 -68.3834) (xy 4.408239 -68.442822) (xy 4.392726 -68.500715)
			(xy 4.36979 -68.556088) (xy 4.352172 -68.586604) (xy 16.625316 -68.586604) (xy 16.625781 -68.559234)
			(xy 16.633598 -68.505054) (xy 16.649087 -68.452551) (xy 16.67193 -68.402804) (xy 16.701655 -68.356838)
			(xy 16.719296 -68.335906) (xy 16.71955 -68.335652) (xy 16.725127 -68.328559) (xy 16.731378 -68.311647)
			(xy 16.731742 -68.302632) (xy 16.731742 -68.235576) (xy 16.731409 -68.226556) (xy 16.725146 -68.209639)
			(xy 16.71955 -68.202556) (xy 16.719296 -68.202556) (xy 16.719296 -68.202302) (xy 16.701644 -68.181381)
			(xy 16.671934 -68.135405) (xy 16.649101 -68.085655) (xy 16.633613 -68.033152) (xy 16.625788 -67.978974)
			(xy 16.625316 -67.951604) (xy 16.625759 -67.92435) (xy 16.633516 -67.870397) (xy 16.648873 -67.818098)
			(xy 16.671517 -67.768516) (xy 16.700987 -67.722662) (xy 16.736682 -67.681468) (xy 16.777878 -67.645775)
			(xy 16.823733 -67.616307) (xy 16.873316 -67.593666) (xy 16.925617 -67.578312) (xy 16.97957 -67.570558)
			(xy 17.006824 -67.570096) (xy 17.033138 -67.570549) (xy 17.085268 -67.577787) (xy 17.13591 -67.592109)
			(xy 17.184109 -67.613244) (xy 17.228953 -67.640793) (xy 17.269592 -67.674233) (xy 17.287748 -67.693286)
			(xy 17.295252 -67.700709) (xy 17.314545 -67.709221) (xy 17.325086 -67.709796) (xy 17.399762 -67.709796)
			(xy 17.410311 -67.709261) (xy 17.429607 -67.70073) (xy 17.4371 -67.693286) (xy 17.45526 -67.674235)
			(xy 17.495889 -67.640778) (xy 17.540728 -67.613219) (xy 17.588928 -67.592079) (xy 17.639575 -67.577761)
			(xy 17.691708 -67.570535) (xy 17.718024 -67.570096) (xy 17.745395 -67.570549) (xy 17.799574 -67.57837)
			(xy 17.852078 -67.593862) (xy 17.901824 -67.616707) (xy 17.947791 -67.646434) (xy 17.968722 -67.664076)
			(xy 17.968976 -67.66433) (xy 17.976063 -67.669916) (xy 17.99298 -67.676162) (xy 18.001996 -67.676522)
			(xy 18.069052 -67.676522) (xy 18.078066 -67.676137) (xy 18.094983 -67.669908) (xy 18.102072 -67.66433)
			(xy 18.102072 -67.664076) (xy 18.102326 -67.664076) (xy 18.123272 -67.646454) (xy 18.169241 -67.616741)
			(xy 18.218985 -67.593902) (xy 18.271483 -67.578407) (xy 18.325656 -67.570573) (xy 18.353024 -67.570096)
			(xy 18.379113 -67.570507) (xy 18.430804 -67.577621) (xy 18.481043 -67.591712) (xy 18.528892 -67.612519)
			(xy 18.551398 -67.625722) (xy 18.563844 -67.633342) (xy 18.592292 -67.633088) (xy 18.693892 -67.569842)
			(xy 18.706592 -67.543934) (xy 18.705322 -67.52971) (xy 18.703544 -67.488054) (xy 18.704007 -67.458085)
			(xy 18.71183 -67.398659) (xy 18.727343 -67.340762) (xy 18.75028 -67.285386) (xy 18.780249 -67.233478)
			(xy 18.816737 -67.185925) (xy 18.859119 -67.143541) (xy 18.906671 -67.107053) (xy 18.95858 -67.077083)
			(xy 19.013955 -67.054145) (xy 19.071852 -67.038631) (xy 19.131277 -67.030807) (xy 19.191216 -67.030807)
			(xy 19.250642 -67.03863) (xy 19.308538 -67.054143) (xy 19.363914 -67.07708) (xy 19.415823 -67.107049)
			(xy 19.463376 -67.143537) (xy 19.505759 -67.18592) (xy 19.542248 -67.233472) (xy 19.572217 -67.28538)
			(xy 19.595155 -67.340756) (xy 19.610669 -67.398652) (xy 19.618493 -67.458078) (xy 19.618493 -67.518017)
			(xy 19.611972 -67.567552) (xy 19.996132 -67.567552) (xy 19.996132 -67.507616) (xy 20.003955 -67.448194)
			(xy 20.019468 -67.390301) (xy 20.042404 -67.334928) (xy 20.072371 -67.283022) (xy 20.108858 -67.235472)
			(xy 20.151238 -67.193092) (xy 20.198788 -67.156605) (xy 20.250694 -67.126638) (xy 20.306067 -67.103702)
			(xy 20.36396 -67.088189) (xy 20.423382 -67.080366) (xy 20.483318 -67.080366) (xy 20.54274 -67.088189)
			(xy 20.600633 -67.103702) (xy 20.656006 -67.126638) (xy 20.660011 -67.12895) (xy 40.366698 -67.12895)
			(xy 40.366698 -67.07445) (xy 40.374454 -67.020506) (xy 40.389808 -66.968214) (xy 40.412448 -66.91864)
			(xy 40.441912 -66.872792) (xy 40.477601 -66.831604) (xy 40.518789 -66.795915) (xy 40.564636 -66.76645)
			(xy 40.614211 -66.74381) (xy 40.666502 -66.728455) (xy 40.720446 -66.720699) (xy 40.747696 -66.720212)
			(xy 40.775066 -66.720677) (xy 40.829246 -66.728495) (xy 40.881749 -66.743984) (xy 40.931496 -66.766826)
			(xy 40.977462 -66.796551) (xy 40.998394 -66.814192) (xy 40.998648 -66.814446) (xy 41.005741 -66.820023)
			(xy 41.022653 -66.826274) (xy 41.031668 -66.826638) (xy 41.098724 -66.826638) (xy 41.107741 -66.826284)
			(xy 41.124658 -66.820034) (xy 41.131744 -66.814446) (xy 41.131744 -66.814192) (xy 41.131998 -66.814192)
			(xy 41.152919 -66.796539) (xy 41.198895 -66.76683) (xy 41.248645 -66.743996) (xy 41.301148 -66.728509)
			(xy 41.355326 -66.720684) (xy 41.382696 -66.720212) (xy 41.409951 -66.720635) (xy 41.463905 -66.728392)
			(xy 41.516206 -66.743748) (xy 41.565789 -66.766392) (xy 41.611645 -66.795861) (xy 41.652841 -66.831557)
			(xy 41.688537 -66.872752) (xy 41.718007 -66.918607) (xy 41.740651 -66.96819) (xy 41.756008 -67.020491)
			(xy 41.763765 -67.074446) (xy 41.763765 -67.128954) (xy 41.756008 -67.182909) (xy 41.740651 -67.23521)
			(xy 41.718007 -67.284793) (xy 41.688537 -67.330648) (xy 41.652841 -67.371843) (xy 41.611645 -67.407539)
			(xy 41.565789 -67.437008) (xy 41.516206 -67.459652) (xy 41.463905 -67.475008) (xy 41.409951 -67.482765)
			(xy 41.382696 -67.483228) (xy 41.355325 -67.482782) (xy 41.301144 -67.474962) (xy 41.24864 -67.459469)
			(xy 41.198894 -67.436623) (xy 41.152928 -67.406892) (xy 41.131998 -67.389248) (xy 41.131744 -67.388994)
			(xy 41.124649 -67.383419) (xy 41.107739 -67.377166) (xy 41.098724 -67.376802) (xy 41.031668 -67.376802)
			(xy 41.02265 -67.377143) (xy 41.005733 -67.383402) (xy 40.998648 -67.388994) (xy 40.998648 -67.389248)
			(xy 40.998394 -67.389248) (xy 40.977468 -67.406895) (xy 40.931495 -67.436608) (xy 40.881746 -67.459443)
			(xy 40.829243 -67.474932) (xy 40.775066 -67.482756) (xy 40.747696 -67.483228) (xy 40.720446 -67.482701)
			(xy 40.666502 -67.474945) (xy 40.614211 -67.45959) (xy 40.564636 -67.43695) (xy 40.518789 -67.407485)
			(xy 40.477601 -67.371796) (xy 40.441912 -67.330608) (xy 40.412448 -67.28476) (xy 40.389808 -67.235186)
			(xy 40.374454 -67.182894) (xy 40.366698 -67.12895) (xy 20.660011 -67.12895) (xy 20.707912 -67.156605)
			(xy 20.755462 -67.193092) (xy 20.797842 -67.235472) (xy 20.834329 -67.283022) (xy 20.864296 -67.334928)
			(xy 20.887232 -67.390301) (xy 20.902745 -67.448194) (xy 20.910568 -67.507616) (xy 20.911058 -67.537584)
			(xy 20.910568 -67.567552) (xy 20.903278 -67.622924) (xy 21.270196 -67.622924) (xy 21.270196 -67.562988)
			(xy 21.278019 -67.503566) (xy 21.293532 -67.445673) (xy 21.316468 -67.3903) (xy 21.346435 -67.338394)
			(xy 21.382922 -67.290844) (xy 21.425302 -67.248464) (xy 21.472852 -67.211977) (xy 21.524758 -67.18201)
			(xy 21.580131 -67.159074) (xy 21.638024 -67.143561) (xy 21.697446 -67.135738) (xy 21.757382 -67.135738)
			(xy 21.816804 -67.143561) (xy 21.874697 -67.159074) (xy 21.93007 -67.18201) (xy 21.981976 -67.211977)
			(xy 22.029526 -67.248464) (xy 22.071906 -67.290844) (xy 22.108393 -67.338394) (xy 22.13836 -67.3903)
			(xy 22.161296 -67.445673) (xy 22.176809 -67.503566) (xy 22.184632 -67.562988) (xy 22.184666 -67.565052)
			(xy 24.446693 -67.565052) (xy 24.446693 -67.510548) (xy 24.454451 -67.456599) (xy 24.469807 -67.404304)
			(xy 24.49245 -67.354726) (xy 24.521919 -67.308875) (xy 24.557613 -67.267686) (xy 24.598806 -67.231996)
			(xy 24.644659 -67.202532) (xy 24.694239 -67.179894) (xy 24.746536 -67.164542) (xy 24.800486 -67.156791)
			(xy 24.827738 -67.15633) (xy 24.855107 -67.156825) (xy 24.909285 -67.164635) (xy 24.961788 -67.180117)
			(xy 25.011536 -67.202952) (xy 25.057504 -67.232671) (xy 25.078436 -67.25031) (xy 25.07869 -67.250564)
			(xy 25.08577 -67.25616) (xy 25.102692 -67.262399) (xy 25.11171 -67.262756) (xy 25.178766 -67.262756)
			(xy 25.187782 -67.262392) (xy 25.2047 -67.25615) (xy 25.211786 -67.250564) (xy 25.211786 -67.25031)
			(xy 25.21204 -67.25031) (xy 25.232985 -67.232687) (xy 25.278954 -67.202973) (xy 25.328698 -67.180133)
			(xy 25.381196 -67.164638) (xy 25.43537 -67.156806) (xy 25.462738 -67.15633) (xy 25.48999 -67.156742)
			(xy 25.543939 -67.164504) (xy 25.596235 -67.179864) (xy 25.645812 -67.20251) (xy 25.691662 -67.23198)
			(xy 25.732852 -67.267675) (xy 25.768543 -67.308868) (xy 25.798009 -67.354721) (xy 25.820649 -67.404301)
			(xy 25.836004 -67.456598) (xy 25.84376 -67.510548) (xy 25.84376 -67.565052) (xy 25.836004 -67.619002)
			(xy 25.820649 -67.671299) (xy 25.798009 -67.720879) (xy 25.768543 -67.766732) (xy 25.732852 -67.807925)
			(xy 25.691662 -67.84362) (xy 25.645812 -67.87309) (xy 25.596235 -67.895736) (xy 25.543939 -67.911096)
			(xy 25.48999 -67.918858) (xy 25.462738 -67.919346) (xy 25.435368 -67.918871) (xy 25.381189 -67.911057)
			(xy 25.328685 -67.895571) (xy 25.278938 -67.872731) (xy 25.232971 -67.843007) (xy 25.21204 -67.825366)
			(xy 25.211786 -67.825112) (xy 25.204707 -67.819515) (xy 25.187784 -67.813274) (xy 25.178766 -67.81292)
			(xy 25.11171 -67.81292) (xy 25.102693 -67.813277) (xy 25.085776 -67.819524) (xy 25.07869 -67.825112)
			(xy 25.07869 -67.825366) (xy 25.078436 -67.825366) (xy 25.057497 -67.842996) (xy 25.011527 -67.872711)
			(xy 24.961781 -67.895549) (xy 24.909282 -67.911042) (xy 24.855107 -67.918871) (xy 24.827738 -67.919346)
			(xy 24.800486 -67.918809) (xy 24.746536 -67.911058) (xy 24.694239 -67.895706) (xy 24.644659 -67.873068)
			(xy 24.598806 -67.843604) (xy 24.557613 -67.807914) (xy 24.521919 -67.766725) (xy 24.49245 -67.720874)
			(xy 24.469807 -67.671296) (xy 24.454451 -67.619001) (xy 24.446693 -67.565052) (xy 22.184666 -67.565052)
			(xy 22.185122 -67.592956) (xy 22.184632 -67.622924) (xy 22.176809 -67.682346) (xy 22.161296 -67.740239)
			(xy 22.13836 -67.795612) (xy 22.108393 -67.847518) (xy 22.071906 -67.895068) (xy 22.029526 -67.937448)
			(xy 21.981976 -67.973935) (xy 21.93007 -68.003902) (xy 21.874697 -68.026838) (xy 21.816804 -68.042351)
			(xy 21.757382 -68.050174) (xy 21.697446 -68.050174) (xy 21.638024 -68.042351) (xy 21.580131 -68.026838)
			(xy 21.524758 -68.003902) (xy 21.472852 -67.973935) (xy 21.425302 -67.937448) (xy 21.382922 -67.895068)
			(xy 21.346435 -67.847518) (xy 21.316468 -67.795612) (xy 21.293532 -67.740239) (xy 21.278019 -67.682346)
			(xy 21.270196 -67.622924) (xy 20.903278 -67.622924) (xy 20.902745 -67.626974) (xy 20.887232 -67.684867)
			(xy 20.864296 -67.74024) (xy 20.834329 -67.792146) (xy 20.797842 -67.839696) (xy 20.755462 -67.882076)
			(xy 20.707912 -67.918563) (xy 20.656006 -67.94853) (xy 20.600633 -67.971466) (xy 20.54274 -67.986979)
			(xy 20.483318 -67.994802) (xy 20.423382 -67.994802) (xy 20.36396 -67.986979) (xy 20.306067 -67.971466)
			(xy 20.250694 -67.94853) (xy 20.198788 -67.918563) (xy 20.151238 -67.882076) (xy 20.108858 -67.839696)
			(xy 20.072371 -67.792146) (xy 20.042404 -67.74024) (xy 20.019468 -67.684867) (xy 20.003955 -67.626974)
			(xy 19.996132 -67.567552) (xy 19.611972 -67.567552) (xy 19.61067 -67.577443) (xy 19.595157 -67.635339)
			(xy 19.57222 -67.690715) (xy 19.542251 -67.742624) (xy 19.505763 -67.790176) (xy 19.46338 -67.83256)
			(xy 19.415827 -67.869048) (xy 19.363919 -67.899018) (xy 19.308543 -67.921955) (xy 19.250647 -67.937469)
			(xy 19.191221 -67.945293) (xy 19.161252 -67.945762) (xy 19.132834 -67.94535) (xy 19.076434 -67.938318)
			(xy 19.02134 -67.924354) (xy 18.968399 -67.903674) (xy 18.918427 -67.876597) (xy 18.89506 -67.860418)
			(xy 18.883376 -67.852036) (xy 18.854928 -67.850004) (xy 18.76171 -67.899026) (xy 18.753626 -67.903757)
			(xy 18.741283 -67.917823) (xy 18.734817 -67.935384) (xy 18.734532 -67.944746) (xy 18.734532 -67.951604)
			(xy 18.734085 -67.978975) (xy 18.726265 -68.033156) (xy 18.710772 -68.08566) (xy 18.687926 -68.135406)
			(xy 18.658196 -68.181372) (xy 18.640552 -68.202302) (xy 18.640298 -68.202556) (xy 18.634723 -68.209651)
			(xy 18.62847 -68.226561) (xy 18.628106 -68.235576) (xy 18.628106 -68.302632) (xy 18.628447 -68.311651)
			(xy 18.634705 -68.328567) (xy 18.640298 -68.335652) (xy 18.640552 -68.335652) (xy 18.640552 -68.335906)
			(xy 18.6582 -68.356831) (xy 18.687912 -68.402805) (xy 18.710747 -68.452554) (xy 18.726236 -68.505057)
			(xy 18.73406 -68.559234) (xy 18.734532 -68.586604) (xy 18.734026 -68.613854) (xy 18.72627 -68.6678)
			(xy 18.710915 -68.720093) (xy 18.694275 -68.75653) (xy 22.17039 -68.75653) (xy 22.170876 -68.729161)
			(xy 22.178689 -68.674982) (xy 22.194174 -68.62248) (xy 22.217011 -68.572732) (xy 22.246731 -68.526765)
			(xy 22.26437 -68.505832) (xy 22.264624 -68.505578) (xy 22.270229 -68.498504) (xy 22.276464 -68.481577)
			(xy 22.276816 -68.472558) (xy 22.276816 -68.405502) (xy 22.276454 -68.396486) (xy 22.27021 -68.379569)
			(xy 22.264624 -68.372482) (xy 22.26437 -68.372482) (xy 22.26437 -68.372228) (xy 22.246726 -68.3513)
			(xy 22.217016 -68.305326) (xy 22.194181 -68.255577) (xy 22.178691 -68.203076) (xy 22.170864 -68.148899)
			(xy 22.17039 -68.12153) (xy 22.170883 -68.094278) (xy 22.178636 -68.040328) (xy 22.193988 -67.988031)
			(xy 22.216627 -67.938451) (xy 22.246092 -67.892598) (xy 22.281782 -67.851405) (xy 22.322972 -67.815711)
			(xy 22.368823 -67.786242) (xy 22.418401 -67.763599) (xy 22.470697 -67.748243) (xy 22.524646 -67.740485)
			(xy 22.551898 -67.740022) (xy 22.579268 -67.740484) (xy 22.633448 -67.748302) (xy 22.685951 -67.763792)
			(xy 22.735698 -67.786634) (xy 22.781665 -67.81636) (xy 22.802596 -67.834002) (xy 22.80285 -67.834256)
			(xy 22.809942 -67.839834) (xy 22.826855 -67.846085) (xy 22.83587 -67.846448) (xy 22.902926 -67.846448)
			(xy 22.911946 -67.846115) (xy 22.928863 -67.839852) (xy 22.935946 -67.834256) (xy 22.935946 -67.834002)
			(xy 22.9362 -67.834002) (xy 22.957121 -67.81635) (xy 23.003097 -67.78664) (xy 23.052847 -67.763806)
			(xy 23.10535 -67.748318) (xy 23.159528 -67.740494) (xy 23.186898 -67.740022) (xy 23.213212 -67.740484)
			(xy 23.265341 -67.747719) (xy 23.315984 -67.762038) (xy 23.364184 -67.783172) (xy 23.409027 -67.810719)
			(xy 23.449666 -67.84416) (xy 23.467822 -67.863212) (xy 23.475332 -67.870627) (xy 23.494621 -67.879144)
			(xy 23.50516 -67.879722) (xy 23.579836 -67.879722) (xy 23.590382 -67.879165) (xy 23.609678 -67.870649)
			(xy 23.617174 -67.863212) (xy 23.635352 -67.844178) (xy 23.675976 -67.810719) (xy 23.720812 -67.783157)
			(xy 23.769008 -67.762014) (xy 23.819652 -67.747693) (xy 23.871783 -67.740463) (xy 23.898098 -67.740022)
			(xy 23.925352 -67.740457) (xy 23.979306 -67.748215) (xy 24.031606 -67.763572) (xy 24.081188 -67.786217)
			(xy 24.127043 -67.815687) (xy 24.168236 -67.851384) (xy 24.20393 -67.89258) (xy 24.233397 -67.938437)
			(xy 24.256038 -67.98802) (xy 24.271391 -68.040322) (xy 24.279145 -68.094276) (xy 24.279606 -68.12153)
			(xy 24.279156 -68.148901) (xy 24.271334 -68.203081) (xy 24.255841 -68.255584) (xy 24.232996 -68.30533)
			(xy 24.203268 -68.351297) (xy 24.185626 -68.372228) (xy 24.185372 -68.372482) (xy 24.179784 -68.379567)
			(xy 24.173539 -68.396485) (xy 24.17318 -68.405502) (xy 24.17318 -68.472558) (xy 24.173561 -68.481572)
			(xy 24.179792 -68.498489) (xy 24.185372 -68.505578) (xy 24.185626 -68.505578) (xy 24.185626 -68.505832)
			(xy 24.203251 -68.526776) (xy 24.232964 -68.572746) (xy 24.239326 -68.586604) (xy 42.625264 -68.586604)
			(xy 42.625717 -68.559233) (xy 42.633535 -68.505053) (xy 42.649027 -68.452549) (xy 42.671872 -68.402802)
			(xy 42.701601 -68.356837) (xy 42.719244 -68.335906) (xy 42.719498 -68.335652) (xy 42.725069 -68.328555)
			(xy 42.731325 -68.311646) (xy 42.73169 -68.302632) (xy 42.73169 -68.235576) (xy 42.731347 -68.226558)
			(xy 42.72509 -68.209641) (xy 42.719498 -68.202556) (xy 42.719244 -68.202556) (xy 42.719244 -68.202302)
			(xy 42.701599 -68.181374) (xy 42.671887 -68.135401) (xy 42.649051 -68.085652) (xy 42.633562 -68.033151)
			(xy 42.625736 -67.978974) (xy 42.625264 -67.951604) (xy 42.625781 -67.924354) (xy 42.633537 -67.870409)
			(xy 42.64889 -67.818117) (xy 42.671529 -67.768541) (xy 42.700992 -67.722692) (xy 42.73668 -67.681503)
			(xy 42.777866 -67.645811) (xy 42.823713 -67.616344) (xy 42.873287 -67.593701) (xy 42.925578 -67.578343)
			(xy 42.979522 -67.570584) (xy 43.006772 -67.570096) (xy 43.033088 -67.570517) (xy 43.085218 -67.577761)
			(xy 43.135862 -67.59209) (xy 43.18406 -67.613231) (xy 43.228903 -67.640785) (xy 43.269541 -67.674231)
			(xy 43.287696 -67.693286) (xy 43.295219 -67.700686) (xy 43.314498 -67.709212) (xy 43.325034 -67.709796)
			(xy 43.39971 -67.709796) (xy 43.410262 -67.709287) (xy 43.429557 -67.700738) (xy 43.437048 -67.693286)
			(xy 43.455184 -67.674212) (xy 43.495819 -67.640757) (xy 43.540663 -67.6132) (xy 43.588867 -67.592065)
			(xy 43.639518 -67.577752) (xy 43.691655 -67.570532) (xy 43.717972 -67.570096) (xy 43.745342 -67.570579)
			(xy 43.79952 -67.578393) (xy 43.852023 -67.593878) (xy 43.90177 -67.616716) (xy 43.947738 -67.646437)
			(xy 43.96867 -67.664076) (xy 43.968924 -67.66433) (xy 43.975997 -67.669936) (xy 43.992924 -67.67617)
			(xy 44.001944 -67.676522) (xy 44.069 -67.676522) (xy 44.078016 -67.67616) (xy 44.094933 -67.669915)
			(xy 44.10202 -67.66433) (xy 44.10202 -67.664076) (xy 44.102274 -67.664076) (xy 44.123202 -67.646432)
			(xy 44.169176 -67.616722) (xy 44.218925 -67.593887) (xy 44.271426 -67.578397) (xy 44.325603 -67.57057)
			(xy 44.352972 -67.570096) (xy 44.37906 -67.57053) (xy 44.43075 -67.577637) (xy 44.480989 -67.591722)
			(xy 44.52884 -67.612522) (xy 44.551346 -67.625722) (xy 44.563792 -67.633342) (xy 44.59224 -67.633088)
			(xy 44.69384 -67.569842) (xy 44.70654 -67.543934) (xy 44.70527 -67.52971) (xy 44.703492 -67.488054)
			(xy 44.704031 -67.45809) (xy 44.711859 -67.398676) (xy 44.727375 -67.340791) (xy 44.750313 -67.285427)
			(xy 44.780282 -67.23353) (xy 44.816768 -67.185989) (xy 44.859147 -67.143617) (xy 44.906694 -67.107139)
			(xy 44.958596 -67.07718) (xy 45.013964 -67.05425) (xy 45.071851 -67.038744) (xy 45.131267 -67.030926)
			(xy 45.191195 -67.03093) (xy 45.250609 -67.038756) (xy 45.308494 -67.05427) (xy 45.363859 -67.077207)
			(xy 45.415757 -67.107174) (xy 45.463299 -67.143658) (xy 45.505672 -67.186036) (xy 45.542152 -67.233581)
			(xy 45.572114 -67.285482) (xy 45.595045 -67.340849) (xy 45.610553 -67.398736) (xy 45.618373 -67.458151)
			(xy 45.618371 -67.518079) (xy 45.611856 -67.567552) (xy 45.99608 -67.567552) (xy 45.99608 -67.507616)
			(xy 46.003903 -67.448194) (xy 46.019416 -67.390301) (xy 46.042352 -67.334928) (xy 46.072319 -67.283022)
			(xy 46.108806 -67.235472) (xy 46.151186 -67.193092) (xy 46.198736 -67.156605) (xy 46.250642 -67.126638)
			(xy 46.306015 -67.103702) (xy 46.363908 -67.088189) (xy 46.42333 -67.080366) (xy 46.483266 -67.080366)
			(xy 46.542688 -67.088189) (xy 46.600581 -67.103702) (xy 46.655954 -67.126638) (xy 46.659964 -67.128953)
			(xy 66.366575 -67.128953) (xy 66.366575 -67.074447) (xy 66.374333 -67.020495) (xy 66.389691 -66.968196)
			(xy 66.412335 -66.918616) (xy 66.441806 -66.872763) (xy 66.477502 -66.831571) (xy 66.518698 -66.795879)
			(xy 66.564554 -66.766414) (xy 66.614137 -66.743775) (xy 66.666438 -66.728424) (xy 66.720391 -66.720672)
			(xy 66.747644 -66.720212) (xy 66.775013 -66.720708) (xy 66.829191 -66.728518) (xy 66.881694 -66.744)
			(xy 66.931441 -66.766835) (xy 66.977409 -66.796554) (xy 66.998342 -66.814192) (xy 66.998596 -66.814446)
			(xy 67.005676 -66.820043) (xy 67.022598 -66.826282) (xy 67.031616 -66.826638) (xy 67.098672 -66.826638)
			(xy 67.107686 -66.826259) (xy 67.124603 -66.820026) (xy 67.131692 -66.814446) (xy 67.131692 -66.814192)
			(xy 67.131946 -66.814192) (xy 67.152887 -66.796564) (xy 67.198857 -66.76685) (xy 67.248603 -66.744013)
			(xy 67.301101 -66.728519) (xy 67.355275 -66.720688) (xy 67.382644 -66.720212) (xy 67.409895 -66.720661)
			(xy 67.46384 -66.728423) (xy 67.516133 -66.743783) (xy 67.565707 -66.766427) (xy 67.611554 -66.795896)
			(xy 67.652741 -66.83159) (xy 67.68843 -66.872781) (xy 67.717894 -66.918632) (xy 67.740533 -66.968209)
			(xy 67.755887 -67.020503) (xy 67.763642 -67.074449) (xy 67.763642 -67.128951) (xy 67.755887 -67.182897)
			(xy 67.740533 -67.235191) (xy 67.717894 -67.284768) (xy 67.68843 -67.330619) (xy 67.652741 -67.37181)
			(xy 67.611554 -67.407504) (xy 67.565707 -67.436973) (xy 67.516133 -67.459617) (xy 67.46384 -67.474977)
			(xy 67.409895 -67.482739) (xy 67.382644 -67.483228) (xy 67.355274 -67.482754) (xy 67.301094 -67.474941)
			(xy 67.248591 -67.459454) (xy 67.198844 -67.436614) (xy 67.152877 -67.40689) (xy 67.131946 -67.389248)
			(xy 67.131692 -67.388994) (xy 67.124612 -67.383397) (xy 67.10769 -67.377157) (xy 67.098672 -67.376802)
			(xy 67.031616 -67.376802) (xy 67.0226 -67.377166) (xy 67.005683 -67.383409) (xy 66.998596 -67.388994)
			(xy 66.998596 -67.389248) (xy 66.998342 -67.389248) (xy 66.977398 -67.406873) (xy 66.931429 -67.436589)
			(xy 66.881685 -67.459428) (xy 66.829187 -67.474922) (xy 66.775013 -67.482753) (xy 66.747644 -67.483228)
			(xy 66.720391 -67.482728) (xy 66.666438 -67.474976) (xy 66.614137 -67.459625) (xy 66.564554 -67.436986)
			(xy 66.518698 -67.407521) (xy 66.477502 -67.371829) (xy 66.441806 -67.330637) (xy 66.412335 -67.284784)
			(xy 66.389691 -67.235204) (xy 66.374333 -67.182905) (xy 66.366575 -67.128953) (xy 46.659964 -67.128953)
			(xy 46.70786 -67.156605) (xy 46.75541 -67.193092) (xy 46.79779 -67.235472) (xy 46.834277 -67.283022)
			(xy 46.864244 -67.334928) (xy 46.88718 -67.390301) (xy 46.902693 -67.448194) (xy 46.910516 -67.507616)
			(xy 46.911006 -67.537584) (xy 46.910516 -67.567552) (xy 46.903226 -67.622924) (xy 47.270144 -67.622924)
			(xy 47.270144 -67.562988) (xy 47.277967 -67.503566) (xy 47.29348 -67.445673) (xy 47.316416 -67.3903)
			(xy 47.346383 -67.338394) (xy 47.38287 -67.290844) (xy 47.42525 -67.248464) (xy 47.4728 -67.211977)
			(xy 47.524706 -67.18201) (xy 47.580079 -67.159074) (xy 47.637972 -67.143561) (xy 47.697394 -67.135738)
			(xy 47.75733 -67.135738) (xy 47.816752 -67.143561) (xy 47.874645 -67.159074) (xy 47.930018 -67.18201)
			(xy 47.981924 -67.211977) (xy 48.029474 -67.248464) (xy 48.071854 -67.290844) (xy 48.108341 -67.338394)
			(xy 48.138308 -67.3903) (xy 48.161244 -67.445673) (xy 48.176757 -67.503566) (xy 48.18458 -67.562988)
			(xy 48.184614 -67.565048) (xy 50.446716 -67.565048) (xy 50.446716 -67.510552) (xy 50.454472 -67.456611)
			(xy 50.469824 -67.404323) (xy 50.492462 -67.354751) (xy 50.521924 -67.308906) (xy 50.557611 -67.267721)
			(xy 50.598795 -67.232033) (xy 50.644639 -67.202569) (xy 50.69421 -67.179929) (xy 50.746497 -67.164574)
			(xy 50.800438 -67.156817) (xy 50.827686 -67.15633) (xy 50.855056 -67.156797) (xy 50.909236 -67.164613)
			(xy 50.961739 -67.180102) (xy 51.011486 -67.202944) (xy 51.057453 -67.232668) (xy 51.078384 -67.25031)
			(xy 51.078638 -67.250564) (xy 51.085733 -67.256138) (xy 51.102643 -67.262391) (xy 51.111658 -67.262756)
			(xy 51.178714 -67.262756) (xy 51.187733 -67.262415) (xy 51.20465 -67.256158) (xy 51.211734 -67.250564)
			(xy 51.211734 -67.25031) (xy 51.211988 -67.25031) (xy 51.232915 -67.232665) (xy 51.278889 -67.202953)
			(xy 51.328638 -67.180118) (xy 51.38114 -67.164629) (xy 51.435316 -67.156803) (xy 51.462686 -67.15633)
			(xy 51.489942 -67.156716) (xy 51.5439 -67.164472) (xy 51.596205 -67.179828) (xy 51.645792 -67.202472)
			(xy 51.691651 -67.231943) (xy 51.73285 -67.26764) (xy 51.768549 -67.308837) (xy 51.798021 -67.354696)
			(xy 51.820667 -67.404282) (xy 51.836025 -67.456586) (xy 51.843783 -67.510544) (xy 51.843783 -67.565056)
			(xy 51.836025 -67.619014) (xy 51.820667 -67.671318) (xy 51.798021 -67.720904) (xy 51.768549 -67.766763)
			(xy 51.73285 -67.80796) (xy 51.691651 -67.843657) (xy 51.645792 -67.873128) (xy 51.596205 -67.895772)
			(xy 51.5439 -67.911128) (xy 51.489942 -67.918884) (xy 51.462686 -67.919346) (xy 51.435315 -67.918901)
			(xy 51.381134 -67.91108) (xy 51.32863 -67.895587) (xy 51.278884 -67.87274) (xy 51.232918 -67.84301)
			(xy 51.211988 -67.825366) (xy 51.211734 -67.825112) (xy 51.204641 -67.819535) (xy 51.187729 -67.813282)
			(xy 51.178714 -67.81292) (xy 51.111658 -67.81292) (xy 51.102643 -67.813301) (xy 51.085726 -67.819531)
			(xy 51.078638 -67.825112) (xy 51.078638 -67.825366) (xy 51.078384 -67.825366) (xy 51.057427 -67.842974)
			(xy 51.011461 -67.872692) (xy 50.96172 -67.895534) (xy 50.909225 -67.911032) (xy 50.855054 -67.918868)
			(xy 50.827686 -67.919346) (xy 50.800438 -67.918783) (xy 50.746497 -67.911026) (xy 50.69421 -67.895671)
			(xy 50.644639 -67.873031) (xy 50.598795 -67.843567) (xy 50.557611 -67.807879) (xy 50.521924 -67.766694)
			(xy 50.492462 -67.720849) (xy 50.469824 -67.671277) (xy 50.454472 -67.618989) (xy 50.446716 -67.565048)
			(xy 48.184614 -67.565048) (xy 48.18507 -67.592956) (xy 48.18458 -67.622924) (xy 48.176757 -67.682346)
			(xy 48.161244 -67.740239) (xy 48.138308 -67.795612) (xy 48.108341 -67.847518) (xy 48.071854 -67.895068)
			(xy 48.029474 -67.937448) (xy 47.981924 -67.973935) (xy 47.930018 -68.003902) (xy 47.874645 -68.026838)
			(xy 47.816752 -68.042351) (xy 47.75733 -68.050174) (xy 47.697394 -68.050174) (xy 47.637972 -68.042351)
			(xy 47.580079 -68.026838) (xy 47.524706 -68.003902) (xy 47.4728 -67.973935) (xy 47.42525 -67.937448)
			(xy 47.38287 -67.895068) (xy 47.346383 -67.847518) (xy 47.316416 -67.795612) (xy 47.29348 -67.740239)
			(xy 47.277967 -67.682346) (xy 47.270144 -67.622924) (xy 46.903226 -67.622924) (xy 46.902693 -67.626974)
			(xy 46.88718 -67.684867) (xy 46.864244 -67.74024) (xy 46.834277 -67.792146) (xy 46.79779 -67.839696)
			(xy 46.75541 -67.882076) (xy 46.70786 -67.918563) (xy 46.655954 -67.94853) (xy 46.600581 -67.971466)
			(xy 46.542688 -67.986979) (xy 46.483266 -67.994802) (xy 46.42333 -67.994802) (xy 46.363908 -67.986979)
			(xy 46.306015 -67.971466) (xy 46.250642 -67.94853) (xy 46.198736 -67.918563) (xy 46.151186 -67.882076)
			(xy 46.108806 -67.839696) (xy 46.072319 -67.792146) (xy 46.042352 -67.74024) (xy 46.019416 -67.684867)
			(xy 46.003903 -67.626974) (xy 45.99608 -67.567552) (xy 45.611856 -67.567552) (xy 45.610547 -67.577494)
			(xy 45.595035 -67.63538) (xy 45.5721 -67.690746) (xy 45.542135 -67.742644) (xy 45.505652 -67.790188)
			(xy 45.463276 -67.832562) (xy 45.415731 -67.869043) (xy 45.363832 -67.899007) (xy 45.308465 -67.92194)
			(xy 45.250579 -67.93745) (xy 45.191164 -67.945272) (xy 45.1612 -67.945762) (xy 45.132783 -67.945325)
			(xy 45.076384 -67.938299) (xy 45.02129 -67.924341) (xy 44.968349 -67.903666) (xy 44.918376 -67.876595)
			(xy 44.895008 -67.860418) (xy 44.883324 -67.852036) (xy 44.854876 -67.850004) (xy 44.761658 -67.899026)
			(xy 44.753583 -67.903773) (xy 44.741235 -67.917829) (xy 44.734765 -67.935386) (xy 44.73448 -67.944746)
			(xy 44.73448 -67.951604) (xy 44.734021 -67.978975) (xy 44.726202 -68.033154) (xy 44.710712 -68.085658)
			(xy 44.687868 -68.135404) (xy 44.658142 -68.181371) (xy 44.6405 -68.202302) (xy 44.640246 -68.202556)
			(xy 44.634665 -68.209646) (xy 44.628416 -68.22656) (xy 44.628054 -68.235576) (xy 44.628054 -68.302632)
			(xy 44.628384 -68.311652) (xy 44.634649 -68.328569) (xy 44.640246 -68.335652) (xy 44.6405 -68.335652)
			(xy 44.6405 -68.335906) (xy 44.658155 -68.356825) (xy 44.687865 -68.402801) (xy 44.710698 -68.452552)
			(xy 44.726185 -68.505056) (xy 44.734008 -68.559234) (xy 44.73448 -68.586604) (xy 44.734048 -68.613858)
			(xy 44.72629 -68.667812) (xy 44.710932 -68.720112) (xy 44.694299 -68.75653) (xy 48.170338 -68.75653)
			(xy 48.170812 -68.72916) (xy 48.178627 -68.674981) (xy 48.194113 -68.622477) (xy 48.216954 -68.57273)
			(xy 48.246677 -68.526764) (xy 48.264318 -68.505832) (xy 48.264572 -68.505578) (xy 48.270182 -68.498508)
			(xy 48.276413 -68.481578) (xy 48.276764 -68.472558) (xy 48.276764 -68.405502) (xy 48.276414 -68.396484)
			(xy 48.270162 -68.379567) (xy 48.264572 -68.372482) (xy 48.264318 -68.372482) (xy 48.264318 -68.372228)
			(xy 48.246681 -68.351294) (xy 48.216969 -68.305322) (xy 48.194132 -68.255575) (xy 48.17864 -68.203075)
			(xy 48.170812 -68.148899) (xy 48.170338 -68.12153) (xy 48.170783 -68.094276) (xy 48.178537 -68.040322)
			(xy 48.193892 -67.988021) (xy 48.216534 -67.938438) (xy 48.246004 -67.892582) (xy 48.281699 -67.851388)
			(xy 48.322895 -67.815694) (xy 48.368752 -67.786227) (xy 48.418336 -67.763586) (xy 48.470637 -67.748234)
			(xy 48.524592 -67.740482) (xy 48.551846 -67.740022) (xy 48.579215 -67.740514) (xy 48.633394 -67.748325)
			(xy 48.685897 -67.763808) (xy 48.735644 -67.786644) (xy 48.781612 -67.816363) (xy 48.802544 -67.834002)
			(xy 48.802798 -67.834256) (xy 48.809876 -67.839855) (xy 48.8268 -67.846093) (xy 48.835818 -67.846448)
			(xy 48.902874 -67.846448) (xy 48.911891 -67.84609) (xy 48.928809 -67.839844) (xy 48.935894 -67.834256)
			(xy 48.935894 -67.834002) (xy 48.936148 -67.834002) (xy 48.957089 -67.816374) (xy 49.003059 -67.786661)
			(xy 49.052805 -67.763822) (xy 49.105303 -67.748329) (xy 49.159477 -67.740498) (xy 49.186846 -67.740022)
			(xy 49.213161 -67.740452) (xy 49.265292 -67.747693) (xy 49.315935 -67.762019) (xy 49.364134 -67.783159)
			(xy 49.408977 -67.810712) (xy 49.449615 -67.844157) (xy 49.46777 -67.863212) (xy 49.475299 -67.870604)
			(xy 49.494574 -67.879134) (xy 49.505108 -67.879722) (xy 49.579784 -67.879722) (xy 49.590333 -67.879191)
			(xy 49.609628 -67.870657) (xy 49.617122 -67.863212) (xy 49.635276 -67.844155) (xy 49.675906 -67.810698)
			(xy 49.720746 -67.783138) (xy 49.768948 -67.762) (xy 49.819595 -67.747683) (xy 49.87173 -67.74046)
			(xy 49.898046 -67.740022) (xy 49.9253 -67.740435) (xy 49.979252 -67.748199) (xy 50.03155 -67.763561)
			(xy 50.081129 -67.78621) (xy 50.126981 -67.815684) (xy 50.168171 -67.851383) (xy 50.203862 -67.89258)
			(xy 50.233327 -67.938438) (xy 50.255965 -67.988022) (xy 50.271318 -68.040323) (xy 50.27907 -68.094276)
			(xy 50.279554 -68.12153) (xy 50.279117 -68.148901) (xy 50.271294 -68.203082) (xy 50.255798 -68.255586)
			(xy 50.23295 -68.305332) (xy 50.203219 -68.351298) (xy 50.185574 -68.372228) (xy 50.18532 -68.372482)
			(xy 50.179725 -68.379563) (xy 50.173486 -68.396484) (xy 50.173128 -68.405502) (xy 50.173128 -68.472558)
			(xy 50.173499 -68.481574) (xy 50.179736 -68.498491) (xy 50.18532 -68.505578) (xy 50.185574 -68.505578)
			(xy 50.185574 -68.505832) (xy 50.203191 -68.526782) (xy 50.232907 -68.57275) (xy 50.239268 -68.586604)
			(xy 68.625212 -68.586604) (xy 68.625677 -68.559234) (xy 68.633495 -68.505054) (xy 68.648984 -68.452551)
			(xy 68.671826 -68.402804) (xy 68.701551 -68.356838) (xy 68.719192 -68.335906) (xy 68.719446 -68.335652)
			(xy 68.725023 -68.328559) (xy 68.731274 -68.311647) (xy 68.731638 -68.302632) (xy 68.731638 -68.235576)
			(xy 68.731284 -68.226559) (xy 68.725034 -68.209642) (xy 68.719446 -68.202556) (xy 68.719192 -68.202556)
			(xy 68.719192 -68.202302) (xy 68.701539 -68.181381) (xy 68.67183 -68.135405) (xy 68.648996 -68.085655)
			(xy 68.633509 -68.033152) (xy 68.625684 -67.978974) (xy 68.625212 -67.951604) (xy 68.625659 -67.92435)
			(xy 68.633416 -67.870398) (xy 68.648773 -67.818098) (xy 68.671416 -67.768517) (xy 68.700886 -67.722663)
			(xy 68.736581 -67.68147) (xy 68.777776 -67.645776) (xy 68.823631 -67.616308) (xy 68.873213 -67.593667)
			(xy 68.925513 -67.578313) (xy 68.979466 -67.570558) (xy 69.00672 -67.570096) (xy 69.033034 -67.570551)
			(xy 69.085163 -67.577789) (xy 69.135806 -67.59211) (xy 69.184005 -67.613245) (xy 69.228848 -67.640793)
			(xy 69.269488 -67.674234) (xy 69.287644 -67.693286) (xy 69.295149 -67.700707) (xy 69.314442 -67.709221)
			(xy 69.324982 -67.709796) (xy 69.399658 -67.709796) (xy 69.410207 -67.709259) (xy 69.429502 -67.70073)
			(xy 69.436996 -67.693286) (xy 69.455158 -67.674237) (xy 69.495786 -67.64078) (xy 69.540626 -67.61322)
			(xy 69.588825 -67.592081) (xy 69.639471 -67.577762) (xy 69.691604 -67.570535) (xy 69.71792 -67.570096)
			(xy 69.745291 -67.570551) (xy 69.79947 -67.578372) (xy 69.851973 -67.593864) (xy 69.90172 -67.616708)
			(xy 69.947686 -67.646434) (xy 69.968618 -67.664076) (xy 69.968872 -67.66433) (xy 69.97596 -67.669914)
			(xy 69.992876 -67.676161) (xy 70.001892 -67.676522) (xy 70.068948 -67.676522) (xy 70.077962 -67.676135)
			(xy 70.094879 -67.669908) (xy 70.101968 -67.66433) (xy 70.101968 -67.664076) (xy 70.102222 -67.664076)
			(xy 70.12317 -67.646456) (xy 70.169139 -67.616742) (xy 70.218882 -67.593903) (xy 70.271379 -67.578407)
			(xy 70.325552 -67.570573) (xy 70.35292 -67.570096) (xy 70.379009 -67.570508) (xy 70.430699 -67.577622)
			(xy 70.480938 -67.591713) (xy 70.528788 -67.612519) (xy 70.551294 -67.625722) (xy 70.56374 -67.633342)
			(xy 70.592188 -67.633088) (xy 70.693788 -67.569842) (xy 70.706488 -67.543934) (xy 70.705218 -67.52971)
			(xy 70.70344 -67.488054) (xy 70.703931 -67.458091) (xy 70.711758 -67.398677) (xy 70.727274 -67.340794)
			(xy 70.750211 -67.285431) (xy 70.780179 -67.233535) (xy 70.816663 -67.185995) (xy 70.859041 -67.143623)
			(xy 70.906586 -67.107145) (xy 70.958485 -67.077185) (xy 71.013852 -67.054254) (xy 71.071737 -67.038747)
			(xy 71.131151 -67.030927) (xy 71.191078 -67.030929) (xy 71.250492 -67.038752) (xy 71.308376 -67.054264)
			(xy 71.363741 -67.077198) (xy 71.415639 -67.107161) (xy 71.463181 -67.143643) (xy 71.505556 -67.186017)
			(xy 71.542038 -67.23356) (xy 71.572002 -67.285457) (xy 71.594936 -67.340822) (xy 71.610447 -67.398706)
			(xy 71.618271 -67.45812) (xy 71.618273 -67.518047) (xy 71.611758 -67.567552) (xy 71.996028 -67.567552)
			(xy 71.996028 -67.507616) (xy 72.003851 -67.448194) (xy 72.019364 -67.390301) (xy 72.0423 -67.334928)
			(xy 72.072267 -67.283022) (xy 72.108754 -67.235472) (xy 72.151134 -67.193092) (xy 72.198684 -67.156605)
			(xy 72.25059 -67.126638) (xy 72.305963 -67.103702) (xy 72.363856 -67.088189) (xy 72.423278 -67.080366)
			(xy 72.483214 -67.080366) (xy 72.542636 -67.088189) (xy 72.600529 -67.103702) (xy 72.655902 -67.126638)
			(xy 72.659905 -67.128949) (xy 92.366598 -67.128949) (xy 92.366598 -67.074451) (xy 92.374354 -67.020506)
			(xy 92.389708 -66.968215) (xy 92.412347 -66.918641) (xy 92.441811 -66.872794) (xy 92.4775 -66.831606)
			(xy 92.518687 -66.795916) (xy 92.564534 -66.766451) (xy 92.614108 -66.743811) (xy 92.666399 -66.728456)
			(xy 92.720343 -66.720699) (xy 92.747592 -66.720212) (xy 92.774962 -66.72068) (xy 92.829141 -66.728497)
			(xy 92.881645 -66.743985) (xy 92.931391 -66.766827) (xy 92.977358 -66.796551) (xy 92.99829 -66.814192)
			(xy 92.998544 -66.814446) (xy 93.005638 -66.820021) (xy 93.022549 -66.826273) (xy 93.031564 -66.826638)
			(xy 93.09862 -66.826638) (xy 93.107637 -66.826282) (xy 93.124553 -66.820033) (xy 93.13164 -66.814446)
			(xy 93.13164 -66.814192) (xy 93.131894 -66.814192) (xy 93.152816 -66.796541) (xy 93.198792 -66.766831)
			(xy 93.248542 -66.743998) (xy 93.301045 -66.728509) (xy 93.355222 -66.720684) (xy 93.382592 -66.720212)
			(xy 93.409847 -66.720634) (xy 93.463801 -66.728391) (xy 93.516103 -66.743747) (xy 93.565687 -66.76639)
			(xy 93.611543 -66.79586) (xy 93.652739 -66.831555) (xy 93.688436 -66.87275) (xy 93.717906 -66.918606)
			(xy 93.74055 -66.96819) (xy 93.755907 -67.020491) (xy 93.763665 -67.074445) (xy 93.763665 -67.128955)
			(xy 93.755907 -67.182909) (xy 93.74055 -67.23521) (xy 93.717906 -67.284794) (xy 93.688436 -67.33065)
			(xy 93.652739 -67.371845) (xy 93.611543 -67.40754) (xy 93.565687 -67.43701) (xy 93.516103 -67.459653)
			(xy 93.463801 -67.475009) (xy 93.409847 -67.482766) (xy 93.382592 -67.483228) (xy 93.355221 -67.482784)
			(xy 93.30104 -67.474964) (xy 93.248536 -67.45947) (xy 93.198789 -67.436623) (xy 93.152824 -67.406892)
			(xy 93.131894 -67.389248) (xy 93.13164 -67.388994) (xy 93.124547 -67.383417) (xy 93.107635 -67.377165)
			(xy 93.09862 -67.376802) (xy 93.031564 -67.376802) (xy 93.022545 -67.377142) (xy 93.005629 -67.383401)
			(xy 92.998544 -67.388994) (xy 92.998544 -67.389248) (xy 92.99829 -67.389248) (xy 92.977366 -67.406897)
			(xy 92.931392 -67.436609) (xy 92.881642 -67.459444) (xy 92.82914 -67.474933) (xy 92.774962 -67.482757)
			(xy 92.747592 -67.483228) (xy 92.720343 -67.482701) (xy 92.666399 -67.474944) (xy 92.614108 -67.459589)
			(xy 92.564534 -67.436949) (xy 92.518687 -67.407484) (xy 92.4775 -67.371794) (xy 92.441811 -67.330606)
			(xy 92.412347 -67.284759) (xy 92.389708 -67.235185) (xy 92.374354 -67.182894) (xy 92.366598 -67.128949)
			(xy 72.659905 -67.128949) (xy 72.707808 -67.156605) (xy 72.755358 -67.193092) (xy 72.797738 -67.235472)
			(xy 72.834225 -67.283022) (xy 72.864192 -67.334928) (xy 72.887128 -67.390301) (xy 72.902641 -67.448194)
			(xy 72.910464 -67.507616) (xy 72.910954 -67.537584) (xy 72.910464 -67.567552) (xy 72.903174 -67.622924)
			(xy 73.270092 -67.622924) (xy 73.270092 -67.562988) (xy 73.277915 -67.503566) (xy 73.293428 -67.445673)
			(xy 73.316364 -67.3903) (xy 73.346331 -67.338394) (xy 73.382818 -67.290844) (xy 73.425198 -67.248464)
			(xy 73.472748 -67.211977) (xy 73.524654 -67.18201) (xy 73.580027 -67.159074) (xy 73.63792 -67.143561)
			(xy 73.697342 -67.135738) (xy 73.757278 -67.135738) (xy 73.8167 -67.143561) (xy 73.874593 -67.159074)
			(xy 73.929966 -67.18201) (xy 73.981872 -67.211977) (xy 74.029422 -67.248464) (xy 74.071802 -67.290844)
			(xy 74.108289 -67.338394) (xy 74.138256 -67.3903) (xy 74.161192 -67.445673) (xy 74.176705 -67.503566)
			(xy 74.184528 -67.562988) (xy 74.184562 -67.565052) (xy 76.446593 -67.565052) (xy 76.446593 -67.510548)
			(xy 76.45435 -67.4566) (xy 76.469707 -67.404304) (xy 76.492349 -67.354727) (xy 76.521818 -67.308877)
			(xy 76.557511 -67.267687) (xy 76.598704 -67.231997) (xy 76.644557 -67.202533) (xy 76.694136 -67.179895)
			(xy 76.746433 -67.164543) (xy 76.800382 -67.156791) (xy 76.827634 -67.15633) (xy 76.855005 -67.156769)
			(xy 76.909186 -67.164592) (xy 76.96169 -67.180087) (xy 77.011436 -67.202935) (xy 77.057401 -67.232666)
			(xy 77.078332 -67.25031) (xy 77.078586 -67.250564) (xy 77.085667 -67.256158) (xy 77.102588 -67.262399)
			(xy 77.111606 -67.262756) (xy 77.178662 -67.262756) (xy 77.187678 -67.26239) (xy 77.204596 -67.25615)
			(xy 77.211682 -67.250564) (xy 77.211682 -67.25031) (xy 77.211936 -67.25031) (xy 77.232883 -67.232689)
			(xy 77.278851 -67.202974) (xy 77.328595 -67.180135) (xy 77.381093 -67.164639) (xy 77.435266 -67.156806)
			(xy 77.462634 -67.15633) (xy 77.489886 -67.156742) (xy 77.543836 -67.164503) (xy 77.596132 -67.179863)
			(xy 77.64571 -67.202508) (xy 77.69156 -67.231978) (xy 77.732751 -67.267674) (xy 77.768442 -67.308867)
			(xy 77.797908 -67.35472) (xy 77.820549 -67.4043) (xy 77.835904 -67.456597) (xy 77.84366 -67.510548)
			(xy 77.84366 -67.565052) (xy 77.835904 -67.619003) (xy 77.820549 -67.6713) (xy 77.797908 -67.72088)
			(xy 77.768442 -67.766733) (xy 77.732751 -67.807926) (xy 77.69156 -67.843622) (xy 77.64571 -67.873092)
			(xy 77.596132 -67.895737) (xy 77.543836 -67.911097) (xy 77.489886 -67.918858) (xy 77.462634 -67.919346)
			(xy 77.435264 -67.918873) (xy 77.381085 -67.911059) (xy 77.328581 -67.895572) (xy 77.278834 -67.872732)
			(xy 77.232867 -67.843007) (xy 77.211936 -67.825366) (xy 77.211682 -67.825112) (xy 77.204604 -67.819513)
			(xy 77.187681 -67.813273) (xy 77.178662 -67.81292) (xy 77.111606 -67.81292) (xy 77.102589 -67.813275)
			(xy 77.085672 -67.819524) (xy 77.078586 -67.825112) (xy 77.078586 -67.825366) (xy 77.078332 -67.825366)
			(xy 77.057394 -67.842998) (xy 77.011424 -67.872712) (xy 76.961678 -67.89555) (xy 76.909178 -67.911043)
			(xy 76.855003 -67.918872) (xy 76.827634 -67.919346) (xy 76.800382 -67.918809) (xy 76.746433 -67.911057)
			(xy 76.694136 -67.895705) (xy 76.644557 -67.873067) (xy 76.598704 -67.843603) (xy 76.557511 -67.807913)
			(xy 76.521818 -67.766723) (xy 76.492349 -67.720873) (xy 76.469707 -67.671296) (xy 76.45435 -67.619)
			(xy 76.446593 -67.565052) (xy 74.184562 -67.565052) (xy 74.185018 -67.592956) (xy 74.184528 -67.622924)
			(xy 74.176705 -67.682346) (xy 74.161192 -67.740239) (xy 74.138256 -67.795612) (xy 74.108289 -67.847518)
			(xy 74.071802 -67.895068) (xy 74.029422 -67.937448) (xy 73.981872 -67.973935) (xy 73.929966 -68.003902)
			(xy 73.874593 -68.026838) (xy 73.8167 -68.042351) (xy 73.757278 -68.050174) (xy 73.697342 -68.050174)
			(xy 73.63792 -68.042351) (xy 73.580027 -68.026838) (xy 73.524654 -68.003902) (xy 73.472748 -67.973935)
			(xy 73.425198 -67.937448) (xy 73.382818 -67.895068) (xy 73.346331 -67.847518) (xy 73.316364 -67.795612)
			(xy 73.293428 -67.740239) (xy 73.277915 -67.682346) (xy 73.270092 -67.622924) (xy 72.903174 -67.622924)
			(xy 72.902641 -67.626974) (xy 72.887128 -67.684867) (xy 72.864192 -67.74024) (xy 72.834225 -67.792146)
			(xy 72.797738 -67.839696) (xy 72.755358 -67.882076) (xy 72.707808 -67.918563) (xy 72.655902 -67.94853)
			(xy 72.600529 -67.971466) (xy 72.542636 -67.986979) (xy 72.483214 -67.994802) (xy 72.423278 -67.994802)
			(xy 72.363856 -67.986979) (xy 72.305963 -67.971466) (xy 72.25059 -67.94853) (xy 72.198684 -67.918563)
			(xy 72.151134 -67.882076) (xy 72.108754 -67.839696) (xy 72.072267 -67.792146) (xy 72.0423 -67.74024)
			(xy 72.019364 -67.684867) (xy 72.003851 -67.626974) (xy 71.996028 -67.567552) (xy 71.611758 -67.567552)
			(xy 71.610454 -67.577461) (xy 71.594946 -67.635346) (xy 71.572016 -67.690713) (xy 71.542056 -67.742613)
			(xy 71.505578 -67.790158) (xy 71.463207 -67.832535) (xy 71.415666 -67.86902) (xy 71.363771 -67.898988)
			(xy 71.308408 -67.921926) (xy 71.250524 -67.937441) (xy 71.191111 -67.945269) (xy 71.161148 -67.945762)
			(xy 71.13273 -67.945352) (xy 71.07633 -67.938319) (xy 71.021236 -67.924355) (xy 70.968295 -67.903675)
			(xy 70.918323 -67.876597) (xy 70.894956 -67.860418) (xy 70.883272 -67.852036) (xy 70.854824 -67.850004)
			(xy 70.761606 -67.899026) (xy 70.753521 -67.903755) (xy 70.741178 -67.917822) (xy 70.734712 -67.935384)
			(xy 70.734428 -67.944746) (xy 70.734428 -67.951604) (xy 70.733982 -67.978975) (xy 70.726162 -68.033156)
			(xy 70.710669 -68.08566) (xy 70.687823 -68.135406) (xy 70.658092 -68.181372) (xy 70.640448 -68.202302)
			(xy 70.640194 -68.202556) (xy 70.634619 -68.209651) (xy 70.628366 -68.226561) (xy 70.628002 -68.235576)
			(xy 70.628002 -68.302632) (xy 70.628343 -68.31165) (xy 70.634602 -68.328567) (xy 70.640194 -68.335652)
			(xy 70.640448 -68.335652) (xy 70.640448 -68.335906) (xy 70.658095 -68.356832) (xy 70.687808 -68.402805)
			(xy 70.710643 -68.452554) (xy 70.726132 -68.505057) (xy 70.733956 -68.559234) (xy 70.734428 -68.586604)
			(xy 70.733926 -68.613854) (xy 70.726169 -68.667801) (xy 70.710815 -68.720094) (xy 70.694176 -68.75653)
			(xy 74.170286 -68.75653) (xy 74.170773 -68.729161) (xy 74.178586 -68.674983) (xy 74.194071 -68.62248)
			(xy 74.216908 -68.572733) (xy 74.246627 -68.526765) (xy 74.264266 -68.505832) (xy 74.26452 -68.505578)
			(xy 74.270124 -68.498504) (xy 74.27636 -68.481577) (xy 74.276712 -68.472558) (xy 74.276712 -68.405502)
			(xy 74.276351 -68.396486) (xy 74.270106 -68.379569) (xy 74.26452 -68.372482) (xy 74.264266 -68.372482)
			(xy 74.264266 -68.372228) (xy 74.246621 -68.351301) (xy 74.216911 -68.305326) (xy 74.194077 -68.255577)
			(xy 74.178587 -68.203076) (xy 74.17076 -68.148899) (xy 74.170286 -68.12153) (xy 74.170783 -68.094278)
			(xy 74.178536 -68.040329) (xy 74.193888 -67.988032) (xy 74.216526 -67.938452) (xy 74.245991 -67.892599)
			(xy 74.281681 -67.851406) (xy 74.32287 -67.815712) (xy 74.368721 -67.786244) (xy 74.418298 -67.7636)
			(xy 74.470594 -67.748244) (xy 74.524542 -67.740486) (xy 74.551794 -67.740022) (xy 74.579164 -67.740486)
			(xy 74.633344 -67.748304) (xy 74.685847 -67.763793) (xy 74.735594 -67.786635) (xy 74.781561 -67.81636)
			(xy 74.802492 -67.834002) (xy 74.802746 -67.834256) (xy 74.809839 -67.839833) (xy 74.826751 -67.846084)
			(xy 74.835766 -67.846448) (xy 74.902822 -67.846448) (xy 74.911841 -67.846113) (xy 74.928759 -67.839852)
			(xy 74.935842 -67.834256) (xy 74.935842 -67.834002) (xy 74.936096 -67.834002) (xy 74.957019 -67.816352)
			(xy 75.002994 -67.786641) (xy 75.052744 -67.763808) (xy 75.105247 -67.748319) (xy 75.159424 -67.740494)
			(xy 75.186794 -67.740022) (xy 75.213108 -67.740486) (xy 75.265237 -67.747721) (xy 75.31588 -67.76204)
			(xy 75.364079 -67.783173) (xy 75.408923 -67.81072) (xy 75.449562 -67.84416) (xy 75.467718 -67.863212)
			(xy 75.475229 -67.870625) (xy 75.494517 -67.879143) (xy 75.505056 -67.879722) (xy 75.579732 -67.879722)
			(xy 75.590278 -67.879163) (xy 75.609573 -67.870648) (xy 75.61707 -67.863212) (xy 75.63525 -67.84418)
			(xy 75.675874 -67.810721) (xy 75.720709 -67.783158) (xy 75.768905 -67.762015) (xy 75.819549 -67.747693)
			(xy 75.871679 -67.740463) (xy 75.897994 -67.740022) (xy 75.925248 -67.740461) (xy 75.979201 -67.748218)
			(xy 76.031502 -67.763575) (xy 76.081084 -67.786219) (xy 76.126938 -67.815689) (xy 76.168132 -67.851385)
			(xy 76.203826 -67.892581) (xy 76.233293 -67.938437) (xy 76.255934 -67.988021) (xy 76.271287 -68.040322)
			(xy 76.279041 -68.094276) (xy 76.279502 -68.12153) (xy 76.279053 -68.148901) (xy 76.271231 -68.203081)
			(xy 76.255738 -68.255584) (xy 76.232892 -68.30533) (xy 76.203165 -68.351297) (xy 76.185522 -68.372228)
			(xy 76.185268 -68.372482) (xy 76.179679 -68.379567) (xy 76.173435 -68.396485) (xy 76.173076 -68.405502)
			(xy 76.173076 -68.472558) (xy 76.173458 -68.481572) (xy 76.179689 -68.498489) (xy 76.185268 -68.505578)
			(xy 76.185522 -68.505578) (xy 76.185522 -68.505832) (xy 76.203146 -68.526776) (xy 76.232859 -68.572746)
			(xy 76.239222 -68.586604) (xy 94.62516 -68.586604) (xy 94.625614 -68.559233) (xy 94.633432 -68.505053)
			(xy 94.648923 -68.452549) (xy 94.671768 -68.402802) (xy 94.701497 -68.356837) (xy 94.71914 -68.335906)
			(xy 94.719394 -68.335652) (xy 94.724964 -68.328554) (xy 94.731221 -68.311646) (xy 94.731586 -68.302632)
			(xy 94.731586 -68.235576) (xy 94.731243 -68.226558) (xy 94.724986 -68.209641) (xy 94.719394 -68.202556)
			(xy 94.71914 -68.202556) (xy 94.71914 -68.202302) (xy 94.701495 -68.181375) (xy 94.671782 -68.135401)
			(xy 94.648947 -68.085653) (xy 94.633458 -68.033151) (xy 94.625632 -67.978974) (xy 94.62516 -67.951604)
			(xy 94.625681 -67.924354) (xy 94.633437 -67.87041) (xy 94.64879 -67.818117) (xy 94.671428 -67.768542)
			(xy 94.700891 -67.722693) (xy 94.736578 -67.681504) (xy 94.777765 -67.645812) (xy 94.823611 -67.616345)
			(xy 94.873184 -67.593702) (xy 94.925474 -67.578344) (xy 94.979418 -67.570584) (xy 95.006668 -67.570096)
			(xy 95.032983 -67.570519) (xy 95.085114 -67.577763) (xy 95.135757 -67.592091) (xy 95.183956 -67.613232)
			(xy 95.228799 -67.640786) (xy 95.269436 -67.674231) (xy 95.287592 -67.693286) (xy 95.295117 -67.700684)
			(xy 95.314394 -67.709211) (xy 95.32493 -67.709796) (xy 95.399606 -67.709796) (xy 95.410158 -67.709285)
			(xy 95.429453 -67.700737) (xy 95.436944 -67.693286) (xy 95.455082 -67.674213) (xy 95.495716 -67.640758)
			(xy 95.54056 -67.613202) (xy 95.588764 -67.592067) (xy 95.639415 -67.577753) (xy 95.691551 -67.570532)
			(xy 95.717868 -67.570096) (xy 95.745238 -67.570582) (xy 95.799416 -67.578395) (xy 95.851919 -67.59388)
			(xy 95.901666 -67.616717) (xy 95.947634 -67.646437) (xy 95.968566 -67.664076) (xy 95.96882 -67.66433)
			(xy 95.975894 -67.669934) (xy 95.992821 -67.676169) (xy 96.00184 -67.676522) (xy 96.068896 -67.676522)
			(xy 96.077912 -67.676158) (xy 96.094829 -67.669915) (xy 96.101916 -67.66433) (xy 96.101916 -67.664076)
			(xy 96.10217 -67.664076) (xy 96.123099 -67.646434) (xy 96.169073 -67.616723) (xy 96.218822 -67.593888)
			(xy 96.271323 -67.578398) (xy 96.325499 -67.57057) (xy 96.352868 -67.570096) (xy 96.378956 -67.570532)
			(xy 96.430646 -67.577638) (xy 96.480885 -67.591723) (xy 96.528736 -67.612522) (xy 96.551242 -67.625722)
			(xy 96.563688 -67.633342) (xy 96.592136 -67.633088) (xy 96.693736 -67.569842) (xy 96.706436 -67.543934)
			(xy 96.705166 -67.52971) (xy 96.703388 -67.488054) (xy 96.703931 -67.45809) (xy 96.711759 -67.398675)
			(xy 96.727275 -67.340791) (xy 96.750214 -67.285426) (xy 96.780182 -67.23353) (xy 96.816668 -67.185989)
			(xy 96.859048 -67.143617) (xy 96.906595 -67.107139) (xy 96.958497 -67.077179) (xy 97.013865 -67.05425)
			(xy 97.071752 -67.038744) (xy 97.131168 -67.030926) (xy 97.191096 -67.03093) (xy 97.250511 -67.038756)
			(xy 97.308396 -67.05427) (xy 97.363761 -67.077207) (xy 97.415658 -67.107175) (xy 97.463201 -67.143659)
			(xy 97.505574 -67.186037) (xy 97.542053 -67.233583) (xy 97.572015 -67.285484) (xy 97.594946 -67.340851)
			(xy 97.610454 -67.398738) (xy 97.618273 -67.458154) (xy 97.618271 -67.518082) (xy 97.611757 -67.567552)
			(xy 97.995976 -67.567552) (xy 97.995976 -67.507616) (xy 98.003799 -67.448194) (xy 98.019312 -67.390301)
			(xy 98.042248 -67.334928) (xy 98.072215 -67.283022) (xy 98.108702 -67.235472) (xy 98.151082 -67.193092)
			(xy 98.198632 -67.156605) (xy 98.250538 -67.126638) (xy 98.305911 -67.103702) (xy 98.363804 -67.088189)
			(xy 98.423226 -67.080366) (xy 98.483162 -67.080366) (xy 98.542584 -67.088189) (xy 98.600477 -67.103702)
			(xy 98.65585 -67.126638) (xy 98.659862 -67.128954) (xy 130.466775 -67.128954) (xy 130.466775 -67.074446)
			(xy 130.474533 -67.020494) (xy 130.489891 -66.968196) (xy 130.512535 -66.918615) (xy 130.542006 -66.872762)
			(xy 130.577703 -66.83157) (xy 130.618899 -66.795879) (xy 130.664755 -66.766413) (xy 130.714339 -66.743775)
			(xy 130.766639 -66.728423) (xy 130.820592 -66.720672) (xy 130.847846 -66.720212) (xy 130.875215 -66.720707)
			(xy 130.929393 -66.728517) (xy 130.981896 -66.743999) (xy 131.031643 -66.766835) (xy 131.077611 -66.796553)
			(xy 131.098544 -66.814192) (xy 131.098798 -66.814446) (xy 131.105877 -66.820043) (xy 131.1228 -66.826282)
			(xy 131.131818 -66.826638) (xy 131.198874 -66.826638) (xy 131.207889 -66.82626) (xy 131.224805 -66.820026)
			(xy 131.231894 -66.814446) (xy 131.231894 -66.814192) (xy 131.232148 -66.814192) (xy 131.253088 -66.796563)
			(xy 131.299059 -66.76685) (xy 131.348804 -66.744012) (xy 131.401303 -66.728519) (xy 131.455477 -66.720688)
			(xy 131.482846 -66.720212) (xy 131.510097 -66.720661) (xy 131.564042 -66.728423) (xy 131.616334 -66.743783)
			(xy 131.665908 -66.766428) (xy 131.711755 -66.795897) (xy 131.752942 -66.831591) (xy 131.78863 -66.872782)
			(xy 131.818094 -66.918632) (xy 131.840733 -66.968209) (xy 131.856087 -67.020503) (xy 131.863842 -67.074449)
			(xy 131.863842 -67.128951) (xy 131.856087 -67.182897) (xy 131.840733 -67.235191) (xy 131.818094 -67.284768)
			(xy 131.78863 -67.330618) (xy 131.752942 -67.371809) (xy 131.711755 -67.407503) (xy 131.665908 -67.436972)
			(xy 131.616334 -67.459617) (xy 131.564042 -67.474977) (xy 131.510097 -67.482739) (xy 131.482846 -67.483228)
			(xy 131.455476 -67.482753) (xy 131.401297 -67.47494) (xy 131.348793 -67.459454) (xy 131.299046 -67.436614)
			(xy 131.253079 -67.406889) (xy 131.232148 -67.389248) (xy 131.231894 -67.388994) (xy 131.224814 -67.383398)
			(xy 131.207892 -67.377157) (xy 131.198874 -67.376802) (xy 131.131818 -67.376802) (xy 131.122802 -67.377167)
			(xy 131.105885 -67.383409) (xy 131.098798 -67.388994) (xy 131.098798 -67.389248) (xy 131.098544 -67.389248)
			(xy 131.077599 -67.406872) (xy 131.031631 -67.436588) (xy 130.981887 -67.459427) (xy 130.929388 -67.474922)
			(xy 130.875214 -67.482753) (xy 130.847846 -67.483228) (xy 130.820592 -67.482728) (xy 130.766639 -67.474977)
			(xy 130.714339 -67.459625) (xy 130.664755 -67.436987) (xy 130.618899 -67.407521) (xy 130.577703 -67.37183)
			(xy 130.542006 -67.330638) (xy 130.512535 -67.284785) (xy 130.489891 -67.235204) (xy 130.474533 -67.182906)
			(xy 130.466775 -67.128954) (xy 98.659862 -67.128954) (xy 98.707756 -67.156605) (xy 98.755306 -67.193092)
			(xy 98.797686 -67.235472) (xy 98.834173 -67.283022) (xy 98.86414 -67.334928) (xy 98.887076 -67.390301)
			(xy 98.902589 -67.448194) (xy 98.910412 -67.507616) (xy 98.910902 -67.537584) (xy 98.910412 -67.567552)
			(xy 98.903122 -67.622924) (xy 99.27004 -67.622924) (xy 99.27004 -67.562988) (xy 99.277863 -67.503566)
			(xy 99.293376 -67.445673) (xy 99.316312 -67.3903) (xy 99.346279 -67.338394) (xy 99.382766 -67.290844)
			(xy 99.425146 -67.248464) (xy 99.472696 -67.211977) (xy 99.524602 -67.18201) (xy 99.579975 -67.159074)
			(xy 99.637868 -67.143561) (xy 99.69729 -67.135738) (xy 99.757226 -67.135738) (xy 99.816648 -67.143561)
			(xy 99.874541 -67.159074) (xy 99.929914 -67.18201) (xy 99.98182 -67.211977) (xy 100.02937 -67.248464)
			(xy 100.07175 -67.290844) (xy 100.108237 -67.338394) (xy 100.138204 -67.3903) (xy 100.16114 -67.445673)
			(xy 100.176653 -67.503566) (xy 100.184476 -67.562988) (xy 100.18451 -67.565048) (xy 102.446616 -67.565048)
			(xy 102.446616 -67.510552) (xy 102.454371 -67.456612) (xy 102.469724 -67.404324) (xy 102.492362 -67.354753)
			(xy 102.521823 -67.308908) (xy 102.557509 -67.267722) (xy 102.598693 -67.232034) (xy 102.644537 -67.20257)
			(xy 102.694107 -67.17993) (xy 102.746394 -67.164575) (xy 102.800334 -67.156817) (xy 102.827582 -67.15633)
			(xy 102.854952 -67.156799) (xy 102.909131 -67.164615) (xy 102.961635 -67.180103) (xy 103.011382 -67.202944)
			(xy 103.057348 -67.232669) (xy 103.07828 -67.25031) (xy 103.078534 -67.250564) (xy 103.08563 -67.256137)
			(xy 103.10254 -67.26239) (xy 103.111554 -67.262756) (xy 103.17861 -67.262756) (xy 103.187629 -67.262414)
			(xy 103.204546 -67.256157) (xy 103.21163 -67.250564) (xy 103.21163 -67.25031) (xy 103.211884 -67.25031)
			(xy 103.232813 -67.232667) (xy 103.278786 -67.202955) (xy 103.328535 -67.18012) (xy 103.381036 -67.16463)
			(xy 103.435213 -67.156803) (xy 103.462582 -67.15633) (xy 103.489838 -67.156716) (xy 103.543797 -67.164471)
			(xy 103.596102 -67.179827) (xy 103.645689 -67.202471) (xy 103.691549 -67.231942) (xy 103.732748 -67.267639)
			(xy 103.768448 -67.308836) (xy 103.79792 -67.354695) (xy 103.820566 -67.404281) (xy 103.835925 -67.456586)
			(xy 103.843683 -67.510544) (xy 103.843683 -67.565056) (xy 103.835925 -67.619014) (xy 103.820566 -67.671319)
			(xy 103.79792 -67.720905) (xy 103.768448 -67.766764) (xy 103.732748 -67.807961) (xy 103.691549 -67.843658)
			(xy 103.645689 -67.873129) (xy 103.596102 -67.895773) (xy 103.543797 -67.911129) (xy 103.489838 -67.918884)
			(xy 103.462582 -67.919346) (xy 103.435211 -67.918904) (xy 103.38103 -67.911082) (xy 103.328526 -67.895588)
			(xy 103.27878 -67.872741) (xy 103.232814 -67.84301) (xy 103.211884 -67.825366) (xy 103.21163 -67.825112)
			(xy 103.204538 -67.819533) (xy 103.187625 -67.813281) (xy 103.17861 -67.81292) (xy 103.111554 -67.81292)
			(xy 103.102539 -67.813299) (xy 103.085622 -67.819531) (xy 103.078534 -67.825112) (xy 103.078534 -67.825366)
			(xy 103.07828 -67.825366) (xy 103.057324 -67.842976) (xy 103.011358 -67.872693) (xy 102.961617 -67.895535)
			(xy 102.909121 -67.911033) (xy 102.85495 -67.918868) (xy 102.827582 -67.919346) (xy 102.800334 -67.918783)
			(xy 102.746394 -67.911025) (xy 102.694107 -67.89567) (xy 102.644537 -67.87303) (xy 102.598693 -67.843566)
			(xy 102.557509 -67.807878) (xy 102.521823 -67.766692) (xy 102.492362 -67.720847) (xy 102.469724 -67.671276)
			(xy 102.454371 -67.618988) (xy 102.446616 -67.565048) (xy 100.18451 -67.565048) (xy 100.184966 -67.592956)
			(xy 100.184476 -67.622924) (xy 100.176653 -67.682346) (xy 100.16114 -67.740239) (xy 100.138204 -67.795612)
			(xy 100.108237 -67.847518) (xy 100.07175 -67.895068) (xy 100.02937 -67.937448) (xy 99.98182 -67.973935)
			(xy 99.929914 -68.003902) (xy 99.874541 -68.026838) (xy 99.816648 -68.042351) (xy 99.757226 -68.050174)
			(xy 99.69729 -68.050174) (xy 99.637868 -68.042351) (xy 99.579975 -68.026838) (xy 99.524602 -68.003902)
			(xy 99.472696 -67.973935) (xy 99.425146 -67.937448) (xy 99.382766 -67.895068) (xy 99.346279 -67.847518)
			(xy 99.316312 -67.795612) (xy 99.293376 -67.740239) (xy 99.277863 -67.682346) (xy 99.27004 -67.622924)
			(xy 98.903122 -67.622924) (xy 98.902589 -67.626974) (xy 98.887076 -67.684867) (xy 98.86414 -67.74024)
			(xy 98.834173 -67.792146) (xy 98.797686 -67.839696) (xy 98.755306 -67.882076) (xy 98.707756 -67.918563)
			(xy 98.65585 -67.94853) (xy 98.600477 -67.971466) (xy 98.542584 -67.986979) (xy 98.483162 -67.994802)
			(xy 98.423226 -67.994802) (xy 98.363804 -67.986979) (xy 98.305911 -67.971466) (xy 98.250538 -67.94853)
			(xy 98.198632 -67.918563) (xy 98.151082 -67.882076) (xy 98.108702 -67.839696) (xy 98.072215 -67.792146)
			(xy 98.042248 -67.74024) (xy 98.019312 -67.684867) (xy 98.003799 -67.626974) (xy 97.995976 -67.567552)
			(xy 97.611757 -67.567552) (xy 97.610447 -67.577497) (xy 97.594934 -67.635383) (xy 97.571999 -67.690748)
			(xy 97.542033 -67.742647) (xy 97.50555 -67.79019) (xy 97.463173 -67.832565) (xy 97.415628 -67.869045)
			(xy 97.363729 -67.899009) (xy 97.308362 -67.921941) (xy 97.250476 -67.937451) (xy 97.19106 -67.945272)
			(xy 97.161096 -67.945762) (xy 97.132678 -67.945327) (xy 97.07628 -67.9383) (xy 97.021186 -67.924342)
			(xy 96.968245 -67.903667) (xy 96.918272 -67.876595) (xy 96.894904 -67.860418) (xy 96.88322 -67.852036)
			(xy 96.854772 -67.850004) (xy 96.761554 -67.899026) (xy 96.753478 -67.903771) (xy 96.74113 -67.917829)
			(xy 96.734661 -67.935385) (xy 96.734376 -67.944746) (xy 96.734376 -67.951604) (xy 96.733918 -67.978975)
			(xy 96.726099 -68.033154) (xy 96.710609 -68.085658) (xy 96.687765 -68.135404) (xy 96.658038 -68.181371)
			(xy 96.640396 -68.202302) (xy 96.640142 -68.202556) (xy 96.634561 -68.209646) (xy 96.628312 -68.22656)
			(xy 96.62795 -68.235576) (xy 96.62795 -68.302632) (xy 96.628281 -68.311652) (xy 96.634545 -68.328569)
			(xy 96.640142 -68.335652) (xy 96.640396 -68.335652) (xy 96.640396 -68.335906) (xy 96.658051 -68.356825)
			(xy 96.68776 -68.402802) (xy 96.710593 -68.452552) (xy 96.726081 -68.505056) (xy 96.733904 -68.559234)
			(xy 96.734376 -68.586604) (xy 96.733948 -68.613858) (xy 96.72619 -68.667812) (xy 96.710832 -68.720113)
			(xy 96.694199 -68.75653) (xy 100.170234 -68.75653) (xy 100.170709 -68.72916) (xy 100.178524 -68.674981)
			(xy 100.19401 -68.622478) (xy 100.21685 -68.572731) (xy 100.246573 -68.526764) (xy 100.264214 -68.505832)
			(xy 100.264468 -68.505578) (xy 100.270078 -68.498508) (xy 100.276309 -68.481578) (xy 100.27666 -68.472558)
			(xy 100.27666 -68.405502) (xy 100.27631 -68.396484) (xy 100.270059 -68.379567) (xy 100.264468 -68.372482)
			(xy 100.264214 -68.372482) (xy 100.264214 -68.372228) (xy 100.246577 -68.351294) (xy 100.216864 -68.305322)
			(xy 100.194028 -68.255575) (xy 100.178536 -68.203075) (xy 100.170708 -68.148899) (xy 100.170234 -68.12153)
			(xy 100.170683 -68.094276) (xy 100.178437 -68.040322) (xy 100.193792 -67.988022) (xy 100.216434 -67.938439)
			(xy 100.245903 -67.892584) (xy 100.281598 -67.851389) (xy 100.322793 -67.815695) (xy 100.368649 -67.786228)
			(xy 100.418233 -67.763587) (xy 100.470534 -67.748235) (xy 100.524488 -67.740482) (xy 100.551742 -67.740022)
			(xy 100.579111 -67.740517) (xy 100.633289 -67.748327) (xy 100.685792 -67.763809) (xy 100.73554 -67.786644)
			(xy 100.781508 -67.816363) (xy 100.80244 -67.834002) (xy 100.802694 -67.834256) (xy 100.809773 -67.839853)
			(xy 100.826696 -67.846092) (xy 100.835714 -67.846448) (xy 100.90277 -67.846448) (xy 100.911787 -67.846088)
			(xy 100.928704 -67.839844) (xy 100.93579 -67.834256) (xy 100.93579 -67.834002) (xy 100.936044 -67.834002)
			(xy 100.956987 -67.816376) (xy 101.002956 -67.786662) (xy 101.052701 -67.763824) (xy 101.1052 -67.74833)
			(xy 101.159374 -67.740498) (xy 101.186742 -67.740022) (xy 101.213057 -67.740454) (xy 101.265188 -67.747695)
			(xy 101.315831 -67.762021) (xy 101.36403 -67.78316) (xy 101.408873 -67.810712) (xy 101.449511 -67.844157)
			(xy 101.467666 -67.863212) (xy 101.475197 -67.870603) (xy 101.49447 -67.879133) (xy 101.505004 -67.879722)
			(xy 101.57968 -67.879722) (xy 101.590229 -67.879189) (xy 101.609524 -67.870656) (xy 101.617018 -67.863212)
			(xy 101.635174 -67.844157) (xy 101.675803 -67.810699) (xy 101.720644 -67.78314) (xy 101.768844 -67.762001)
			(xy 101.819492 -67.747684) (xy 101.871626 -67.74046) (xy 101.897942 -67.740022) (xy 101.925196 -67.740439)
			(xy 101.979147 -67.748202) (xy 102.031445 -67.763564) (xy 102.081025 -67.786212) (xy 102.126876 -67.815685)
			(xy 102.168067 -67.851384) (xy 102.203758 -67.892581) (xy 102.233223 -67.938439) (xy 102.255861 -67.988022)
			(xy 102.271213 -68.040323) (xy 102.278966 -68.094276) (xy 102.27945 -68.12153) (xy 102.279014 -68.148901)
			(xy 102.271191 -68.203082) (xy 102.255695 -68.255586) (xy 102.232847 -68.305333) (xy 102.203115 -68.351298)
			(xy 102.18547 -68.372228) (xy 102.185216 -68.372482) (xy 102.179633 -68.379571) (xy 102.173384 -68.396486)
			(xy 102.173024 -68.405502) (xy 102.173024 -68.472558) (xy 102.173396 -68.481573) (xy 102.179633 -68.498491)
			(xy 102.185216 -68.505578) (xy 102.18547 -68.505578) (xy 102.18547 -68.505832) (xy 102.203086 -68.526783)
			(xy 102.232802 -68.57275) (xy 102.239163 -68.586604) (xy 132.725414 -68.586604) (xy 132.725879 -68.559234)
			(xy 132.733697 -68.505054) (xy 132.749186 -68.452551) (xy 132.772028 -68.402804) (xy 132.801753 -68.356838)
			(xy 132.819394 -68.335906) (xy 132.819648 -68.335652) (xy 132.825225 -68.328559) (xy 132.831476 -68.311647)
			(xy 132.83184 -68.302632) (xy 132.83184 -68.235576) (xy 132.831507 -68.226556) (xy 132.825244 -68.209639)
			(xy 132.819648 -68.202556) (xy 132.819394 -68.202556) (xy 132.819394 -68.202302) (xy 132.801741 -68.181381)
			(xy 132.772032 -68.135405) (xy 132.749199 -68.085655) (xy 132.733711 -68.033152) (xy 132.725886 -67.978974)
			(xy 132.725414 -67.951604) (xy 132.725859 -67.92435) (xy 132.733616 -67.870398) (xy 132.748973 -67.818098)
			(xy 132.771616 -67.768516) (xy 132.801086 -67.722662) (xy 132.836782 -67.681469) (xy 132.877977 -67.645775)
			(xy 132.923832 -67.616308) (xy 132.973415 -67.593666) (xy 133.025715 -67.578312) (xy 133.079668 -67.570558)
			(xy 133.106922 -67.570096) (xy 133.133236 -67.57055) (xy 133.185365 -67.577788) (xy 133.236008 -67.59211)
			(xy 133.284207 -67.613245) (xy 133.32905 -67.640793) (xy 133.36969 -67.674234) (xy 133.387846 -67.693286)
			(xy 133.39535 -67.700708) (xy 133.414643 -67.709221) (xy 133.425184 -67.709796) (xy 133.49986 -67.709796)
			(xy 133.510409 -67.70926) (xy 133.529704 -67.70073) (xy 133.537198 -67.693286) (xy 133.555359 -67.674236)
			(xy 133.595988 -67.640779) (xy 133.640827 -67.613219) (xy 133.689027 -67.59208) (xy 133.739673 -67.577762)
			(xy 133.791806 -67.570535) (xy 133.818122 -67.570096) (xy 133.845493 -67.57055) (xy 133.899672 -67.578371)
			(xy 133.952175 -67.593863) (xy 134.001922 -67.616707) (xy 134.047889 -67.646434) (xy 134.06882 -67.664076)
			(xy 134.069074 -67.66433) (xy 134.076161 -67.669915) (xy 134.093078 -67.676162) (xy 134.102094 -67.676522)
			(xy 134.16915 -67.676522) (xy 134.178164 -67.676136) (xy 134.195081 -67.669908) (xy 134.20217 -67.66433)
			(xy 134.20217 -67.664076) (xy 134.202424 -67.664076) (xy 134.223371 -67.646455) (xy 134.26934 -67.616742)
			(xy 134.319084 -67.593902) (xy 134.371581 -67.578407) (xy 134.425754 -67.570573) (xy 134.453122 -67.570096)
			(xy 134.479211 -67.570508) (xy 134.530902 -67.577621) (xy 134.581141 -67.591713) (xy 134.62899 -67.612519)
			(xy 134.651496 -67.625722) (xy 134.663942 -67.633342) (xy 134.69239 -67.633088) (xy 134.79399 -67.569842)
			(xy 134.80669 -67.543934) (xy 134.80542 -67.52971) (xy 134.803642 -67.488054) (xy 134.804131 -67.458091)
			(xy 134.811958 -67.398678) (xy 134.827474 -67.340794) (xy 134.850411 -67.285431) (xy 134.880379 -67.233536)
			(xy 134.916863 -67.185995) (xy 134.95924 -67.143623) (xy 135.006785 -67.107145) (xy 135.058685 -67.077185)
			(xy 135.114051 -67.054254) (xy 135.171936 -67.038747) (xy 135.231351 -67.030927) (xy 135.291277 -67.030929)
			(xy 135.350691 -67.038752) (xy 135.408575 -67.054263) (xy 135.46394 -67.077197) (xy 135.515838 -67.107161)
			(xy 135.563381 -67.143642) (xy 135.605755 -67.186016) (xy 135.642237 -67.233559) (xy 135.672201 -67.285456)
			(xy 135.695135 -67.340821) (xy 135.710647 -67.398705) (xy 135.718471 -67.458119) (xy 135.718473 -67.518045)
			(xy 135.711958 -67.567552) (xy 136.09623 -67.567552) (xy 136.09623 -67.507616) (xy 136.104053 -67.448194)
			(xy 136.119566 -67.390301) (xy 136.142502 -67.334928) (xy 136.172469 -67.283022) (xy 136.208956 -67.235472)
			(xy 136.251336 -67.193092) (xy 136.298886 -67.156605) (xy 136.350792 -67.126638) (xy 136.406165 -67.103702)
			(xy 136.464058 -67.088189) (xy 136.52348 -67.080366) (xy 136.583416 -67.080366) (xy 136.642838 -67.088189)
			(xy 136.700731 -67.103702) (xy 136.756104 -67.126638) (xy 136.760109 -67.12895) (xy 156.466798 -67.12895)
			(xy 156.466798 -67.07445) (xy 156.474554 -67.020506) (xy 156.489908 -66.968215) (xy 156.512548 -66.918641)
			(xy 156.542012 -66.872793) (xy 156.577701 -66.831605) (xy 156.618888 -66.795915) (xy 156.664735 -66.766451)
			(xy 156.714309 -66.74381) (xy 156.7666 -66.728455) (xy 156.820544 -66.720699) (xy 156.847794 -66.720212)
			(xy 156.875164 -66.720679) (xy 156.929343 -66.728496) (xy 156.981847 -66.743985) (xy 157.031594 -66.766826)
			(xy 157.07756 -66.796551) (xy 157.098492 -66.814192) (xy 157.098746 -66.814446) (xy 157.10584 -66.820022)
			(xy 157.122751 -66.826274) (xy 157.131766 -66.826638) (xy 157.198822 -66.826638) (xy 157.207839 -66.826283)
			(xy 157.224756 -66.820033) (xy 157.231842 -66.814446) (xy 157.231842 -66.814192) (xy 157.232096 -66.814192)
			(xy 157.253018 -66.79654) (xy 157.298993 -66.76683) (xy 157.348744 -66.743997) (xy 157.401247 -66.728509)
			(xy 157.455424 -66.720684) (xy 157.482794 -66.720212) (xy 157.510049 -66.720634) (xy 157.564003 -66.728391)
			(xy 157.616304 -66.743748) (xy 157.665888 -66.766391) (xy 157.711744 -66.79586) (xy 157.75294 -66.831556)
			(xy 157.788636 -66.872751) (xy 157.818106 -66.918607) (xy 157.84075 -66.96819) (xy 157.856108 -67.020491)
			(xy 157.863865 -67.074445) (xy 157.863865 -67.128955) (xy 157.856108 -67.182909) (xy 157.84075 -67.23521)
			(xy 157.818106 -67.284793) (xy 157.788636 -67.330649) (xy 157.75294 -67.371844) (xy 157.711744 -67.40754)
			(xy 157.665888 -67.437009) (xy 157.616304 -67.459652) (xy 157.564003 -67.475009) (xy 157.510049 -67.482766)
			(xy 157.482794 -67.483228) (xy 157.455423 -67.482783) (xy 157.401242 -67.474963) (xy 157.348738 -67.45947)
			(xy 157.298991 -67.436623) (xy 157.253026 -67.406892) (xy 157.232096 -67.389248) (xy 157.231842 -67.388994)
			(xy 157.224748 -67.383418) (xy 157.207837 -67.377165) (xy 157.198822 -67.376802) (xy 157.131766 -67.376802)
			(xy 157.122747 -67.377142) (xy 157.105831 -67.383402) (xy 157.098746 -67.388994) (xy 157.098746 -67.389248)
			(xy 157.098492 -67.389248) (xy 157.077567 -67.406896) (xy 157.031593 -67.436608) (xy 156.981844 -67.459443)
			(xy 156.929341 -67.474932) (xy 156.875164 -67.482757) (xy 156.847794 -67.483228) (xy 156.820544 -67.482701)
			(xy 156.7666 -67.474945) (xy 156.714309 -67.45959) (xy 156.664735 -67.436949) (xy 156.618888 -67.407485)
			(xy 156.577701 -67.371795) (xy 156.542012 -67.330607) (xy 156.512548 -67.284759) (xy 156.489908 -67.235185)
			(xy 156.474554 -67.182894) (xy 156.466798 -67.12895) (xy 136.760109 -67.12895) (xy 136.80801 -67.156605)
			(xy 136.85556 -67.193092) (xy 136.89794 -67.235472) (xy 136.934427 -67.283022) (xy 136.964394 -67.334928)
			(xy 136.98733 -67.390301) (xy 137.002843 -67.448194) (xy 137.010666 -67.507616) (xy 137.011156 -67.537584)
			(xy 137.010666 -67.567552) (xy 137.003376 -67.622924) (xy 137.370294 -67.622924) (xy 137.370294 -67.562988)
			(xy 137.378117 -67.503566) (xy 137.39363 -67.445673) (xy 137.416566 -67.3903) (xy 137.446533 -67.338394)
			(xy 137.48302 -67.290844) (xy 137.5254 -67.248464) (xy 137.57295 -67.211977) (xy 137.624856 -67.18201)
			(xy 137.680229 -67.159074) (xy 137.738122 -67.143561) (xy 137.797544 -67.135738) (xy 137.85748 -67.135738)
			(xy 137.916902 -67.143561) (xy 137.974795 -67.159074) (xy 138.030168 -67.18201) (xy 138.082074 -67.211977)
			(xy 138.129624 -67.248464) (xy 138.172004 -67.290844) (xy 138.208491 -67.338394) (xy 138.238458 -67.3903)
			(xy 138.261394 -67.445673) (xy 138.276907 -67.503566) (xy 138.28473 -67.562988) (xy 138.284764 -67.565052)
			(xy 140.546793 -67.565052) (xy 140.546793 -67.510548) (xy 140.55455 -67.4566) (xy 140.569907 -67.404304)
			(xy 140.59255 -67.354726) (xy 140.622018 -67.308876) (xy 140.657712 -67.267687) (xy 140.698905 -67.231996)
			(xy 140.744758 -67.202532) (xy 140.794338 -67.179894) (xy 140.846635 -67.164543) (xy 140.900584 -67.156791)
			(xy 140.927836 -67.15633) (xy 140.955207 -67.156768) (xy 141.009388 -67.164591) (xy 141.061892 -67.180087)
			(xy 141.111638 -67.202935) (xy 141.157603 -67.232666) (xy 141.178534 -67.25031) (xy 141.178788 -67.250564)
			(xy 141.185868 -67.256159) (xy 141.20279 -67.262399) (xy 141.211808 -67.262756) (xy 141.278864 -67.262756)
			(xy 141.28788 -67.262391) (xy 141.304798 -67.25615) (xy 141.311884 -67.250564) (xy 141.311884 -67.25031)
			(xy 141.312138 -67.25031) (xy 141.333084 -67.232688) (xy 141.379053 -67.202973) (xy 141.428797 -67.180134)
			(xy 141.481294 -67.164639) (xy 141.535468 -67.156806) (xy 141.562836 -67.15633) (xy 141.590088 -67.156742)
			(xy 141.644037 -67.164504) (xy 141.696333 -67.179864) (xy 141.745911 -67.202509) (xy 141.791761 -67.231979)
			(xy 141.832951 -67.267674) (xy 141.868642 -67.308868) (xy 141.898108 -67.354721) (xy 141.920749 -67.404301)
			(xy 141.936104 -67.456598) (xy 141.94386 -67.510548) (xy 141.94386 -67.565052) (xy 141.936104 -67.619002)
			(xy 141.920749 -67.671299) (xy 141.898108 -67.720879) (xy 141.868642 -67.766732) (xy 141.832951 -67.807926)
			(xy 141.791761 -67.843621) (xy 141.745911 -67.873091) (xy 141.696333 -67.895736) (xy 141.644037 -67.911096)
			(xy 141.590088 -67.918858) (xy 141.562836 -67.919346) (xy 141.535466 -67.918872) (xy 141.481287 -67.911058)
			(xy 141.428783 -67.895572) (xy 141.379036 -67.872731) (xy 141.333069 -67.843007) (xy 141.312138 -67.825366)
			(xy 141.311884 -67.825112) (xy 141.304805 -67.819514) (xy 141.287883 -67.813274) (xy 141.278864 -67.81292)
			(xy 141.211808 -67.81292) (xy 141.202791 -67.813276) (xy 141.185874 -67.819524) (xy 141.178788 -67.825112)
			(xy 141.178788 -67.825366) (xy 141.178534 -67.825366) (xy 141.157596 -67.842997) (xy 141.111625 -67.872711)
			(xy 141.061879 -67.895549) (xy 141.00938 -67.911042) (xy 140.955205 -67.918872) (xy 140.927836 -67.919346)
			(xy 140.900584 -67.918809) (xy 140.846635 -67.911057) (xy 140.794338 -67.895706) (xy 140.744758 -67.873068)
			(xy 140.698905 -67.843604) (xy 140.657712 -67.807913) (xy 140.622018 -67.766724) (xy 140.59255 -67.720874)
			(xy 140.569907 -67.671296) (xy 140.55455 -67.619) (xy 140.546793 -67.565052) (xy 138.284764 -67.565052)
			(xy 138.28522 -67.592956) (xy 138.28473 -67.622924) (xy 138.276907 -67.682346) (xy 138.261394 -67.740239)
			(xy 138.238458 -67.795612) (xy 138.208491 -67.847518) (xy 138.172004 -67.895068) (xy 138.129624 -67.937448)
			(xy 138.082074 -67.973935) (xy 138.030168 -68.003902) (xy 137.974795 -68.026838) (xy 137.916902 -68.042351)
			(xy 137.85748 -68.050174) (xy 137.797544 -68.050174) (xy 137.738122 -68.042351) (xy 137.680229 -68.026838)
			(xy 137.624856 -68.003902) (xy 137.57295 -67.973935) (xy 137.5254 -67.937448) (xy 137.48302 -67.895068)
			(xy 137.446533 -67.847518) (xy 137.416566 -67.795612) (xy 137.39363 -67.740239) (xy 137.378117 -67.682346)
			(xy 137.370294 -67.622924) (xy 137.003376 -67.622924) (xy 137.002843 -67.626974) (xy 136.98733 -67.684867)
			(xy 136.964394 -67.74024) (xy 136.934427 -67.792146) (xy 136.89794 -67.839696) (xy 136.85556 -67.882076)
			(xy 136.80801 -67.918563) (xy 136.756104 -67.94853) (xy 136.700731 -67.971466) (xy 136.642838 -67.986979)
			(xy 136.583416 -67.994802) (xy 136.52348 -67.994802) (xy 136.464058 -67.986979) (xy 136.406165 -67.971466)
			(xy 136.350792 -67.94853) (xy 136.298886 -67.918563) (xy 136.251336 -67.882076) (xy 136.208956 -67.839696)
			(xy 136.172469 -67.792146) (xy 136.142502 -67.74024) (xy 136.119566 -67.684867) (xy 136.104053 -67.626974)
			(xy 136.09623 -67.567552) (xy 135.711958 -67.567552) (xy 135.710654 -67.57746) (xy 135.695147 -67.635345)
			(xy 135.672217 -67.690711) (xy 135.642257 -67.742611) (xy 135.605779 -67.790157) (xy 135.563408 -67.832534)
			(xy 135.515868 -67.869019) (xy 135.463972 -67.898987) (xy 135.40861 -67.921925) (xy 135.350726 -67.937441)
			(xy 135.291313 -67.945269) (xy 135.26135 -67.945762) (xy 135.232932 -67.945351) (xy 135.176532 -67.938318)
			(xy 135.121438 -67.924354) (xy 135.068497 -67.903675) (xy 135.018525 -67.876597) (xy 134.995158 -67.860418)
			(xy 134.983474 -67.852036) (xy 134.955026 -67.850004) (xy 134.861808 -67.899026) (xy 134.853723 -67.903756)
			(xy 134.84138 -67.917822) (xy 134.834914 -67.935384) (xy 134.83463 -67.944746) (xy 134.83463 -67.951604)
			(xy 134.834183 -67.978975) (xy 134.826363 -68.033156) (xy 134.810871 -68.08566) (xy 134.788024 -68.135406)
			(xy 134.758294 -68.181372) (xy 134.74065 -68.202302) (xy 134.740396 -68.202556) (xy 134.734821 -68.209651)
			(xy 134.728568 -68.226561) (xy 134.728204 -68.235576) (xy 134.728204 -68.302632) (xy 134.728545 -68.311651)
			(xy 134.734804 -68.328567) (xy 134.740396 -68.335652) (xy 134.74065 -68.335652) (xy 134.74065 -68.335906)
			(xy 134.758298 -68.356831) (xy 134.78801 -68.402805) (xy 134.810845 -68.452554) (xy 134.826334 -68.505057)
			(xy 134.834158 -68.559234) (xy 134.83463 -68.586604) (xy 134.834126 -68.613854) (xy 134.82637 -68.6678)
			(xy 134.811015 -68.720093) (xy 134.794375 -68.75653) (xy 138.270488 -68.75653) (xy 138.270975 -68.729161)
			(xy 138.278788 -68.674982) (xy 138.294272 -68.62248) (xy 138.317109 -68.572733) (xy 138.346829 -68.526765)
			(xy 138.364468 -68.505832) (xy 138.364722 -68.505578) (xy 138.370326 -68.498504) (xy 138.376562 -68.481577)
			(xy 138.376914 -68.472558) (xy 138.376914 -68.405502) (xy 138.376553 -68.396486) (xy 138.370308 -68.379569)
			(xy 138.364722 -68.372482) (xy 138.364468 -68.372482) (xy 138.364468 -68.372228) (xy 138.346824 -68.3513)
			(xy 138.317114 -68.305326) (xy 138.294279 -68.255577) (xy 138.278789 -68.203076) (xy 138.270962 -68.148899)
			(xy 138.270488 -68.12153) (xy 138.270983 -68.094278) (xy 138.278736 -68.040328) (xy 138.294088 -67.988031)
			(xy 138.316727 -67.938452) (xy 138.346191 -67.892599) (xy 138.381882 -67.851406) (xy 138.423071 -67.815712)
			(xy 138.468922 -67.786243) (xy 138.5185 -67.7636) (xy 138.570795 -67.748243) (xy 138.624744 -67.740486)
			(xy 138.651996 -67.740022) (xy 138.679366 -67.740485) (xy 138.733546 -67.748303) (xy 138.786049 -67.763792)
			(xy 138.835796 -67.786635) (xy 138.881763 -67.81636) (xy 138.902694 -67.834002) (xy 138.902948 -67.834256)
			(xy 138.91004 -67.839834) (xy 138.926953 -67.846084) (xy 138.935968 -67.846448) (xy 139.003024 -67.846448)
			(xy 139.012043 -67.846114) (xy 139.028961 -67.839852) (xy 139.036044 -67.834256) (xy 139.036044 -67.834002)
			(xy 139.036298 -67.834002) (xy 139.05722 -67.816351) (xy 139.103196 -67.786641) (xy 139.152946 -67.763807)
			(xy 139.205449 -67.748319) (xy 139.259626 -67.740494) (xy 139.286996 -67.740022) (xy 139.31331 -67.740485)
			(xy 139.365439 -67.74772) (xy 139.416082 -67.762039) (xy 139.464281 -67.783173) (xy 139.509125 -67.81072)
			(xy 139.549764 -67.84416) (xy 139.56792 -67.863212) (xy 139.575431 -67.870626) (xy 139.594719 -67.879143)
			(xy 139.605258 -67.879722) (xy 139.679934 -67.879722) (xy 139.69048 -67.879164) (xy 139.709776 -67.870649)
			(xy 139.717272 -67.863212) (xy 139.735451 -67.844179) (xy 139.776075 -67.81072) (xy 139.82091 -67.783157)
			(xy 139.869107 -67.762015) (xy 139.91975 -67.747693) (xy 139.971881 -67.740463) (xy 139.998196 -67.740022)
			(xy 140.02545 -67.740459) (xy 140.079404 -67.748216) (xy 140.131704 -67.763573) (xy 140.181286 -67.786218)
			(xy 140.22714 -67.815688) (xy 140.268334 -67.851385) (xy 140.304028 -67.89258) (xy 140.333495 -67.938437)
			(xy 140.356136 -67.988021) (xy 140.371489 -68.040322) (xy 140.379243 -68.094276) (xy 140.379704 -68.12153)
			(xy 140.379255 -68.148901) (xy 140.371433 -68.203081) (xy 140.35594 -68.255584) (xy 140.333094 -68.30533)
			(xy 140.303367 -68.351297) (xy 140.285724 -68.372228) (xy 140.28547 -68.372482) (xy 140.279881 -68.379567)
			(xy 140.273637 -68.396485) (xy 140.273278 -68.405502) (xy 140.273278 -68.472558) (xy 140.27366 -68.481572)
			(xy 140.279891 -68.498489) (xy 140.28547 -68.505578) (xy 140.285724 -68.505578) (xy 140.285724 -68.505832)
			(xy 140.303348 -68.526776) (xy 140.333062 -68.572746) (xy 140.339424 -68.586604) (xy 158.725362 -68.586604)
			(xy 158.725815 -68.559233) (xy 158.733634 -68.505053) (xy 158.749125 -68.452549) (xy 158.77197 -68.402802)
			(xy 158.801699 -68.356837) (xy 158.819342 -68.335906) (xy 158.819596 -68.335652) (xy 158.825167 -68.328554)
			(xy 158.831423 -68.311646) (xy 158.831788 -68.302632) (xy 158.831788 -68.235576) (xy 158.831445 -68.226558)
			(xy 158.825188 -68.209641) (xy 158.819596 -68.202556) (xy 158.819342 -68.202556) (xy 158.819342 -68.202302)
			(xy 158.801697 -68.181375) (xy 158.771985 -68.135401) (xy 158.749149 -68.085653) (xy 158.73366 -68.033151)
			(xy 158.725834 -67.978974) (xy 158.725362 -67.951604) (xy 158.725881 -67.924354) (xy 158.733637 -67.870409)
			(xy 158.74899 -67.818117) (xy 158.771628 -67.768542) (xy 158.801091 -67.722693) (xy 158.836779 -67.681503)
			(xy 158.877966 -67.645812) (xy 158.923812 -67.616345) (xy 158.973385 -67.593702) (xy 159.025676 -67.578344)
			(xy 159.07962 -67.570584) (xy 159.10687 -67.570096) (xy 159.133185 -67.570518) (xy 159.185316 -67.577762)
			(xy 159.235959 -67.59209) (xy 159.284158 -67.613231) (xy 159.329001 -67.640785) (xy 159.369639 -67.674231)
			(xy 159.387794 -67.693286) (xy 159.395318 -67.700685) (xy 159.414596 -67.709211) (xy 159.425132 -67.709796)
			(xy 159.499808 -67.709796) (xy 159.51036 -67.709286) (xy 159.529655 -67.700738) (xy 159.537146 -67.693286)
			(xy 159.555283 -67.674212) (xy 159.595917 -67.640757) (xy 159.640762 -67.613201) (xy 159.688966 -67.592066)
			(xy 159.739616 -67.577752) (xy 159.791753 -67.570532) (xy 159.81807 -67.570096) (xy 159.84544 -67.570581)
			(xy 159.899618 -67.578394) (xy 159.952121 -67.593879) (xy 160.001868 -67.616716) (xy 160.047836 -67.646437)
			(xy 160.068768 -67.664076) (xy 160.069022 -67.66433) (xy 160.076096 -67.669935) (xy 160.093022 -67.67617)
			(xy 160.102042 -67.676522) (xy 160.169098 -67.676522) (xy 160.178114 -67.676159) (xy 160.195031 -67.669915)
			(xy 160.202118 -67.66433) (xy 160.202118 -67.664076) (xy 160.202372 -67.664076) (xy 160.223301 -67.646433)
			(xy 160.269275 -67.616722) (xy 160.319023 -67.593888) (xy 160.371524 -67.578397) (xy 160.425701 -67.57057)
			(xy 160.45307 -67.570096) (xy 160.479158 -67.570531) (xy 160.530848 -67.577638) (xy 160.581087 -67.591722)
			(xy 160.628938 -67.612522) (xy 160.651444 -67.625722) (xy 160.66389 -67.633342) (xy 160.692338 -67.633088)
			(xy 160.793938 -67.569842) (xy 160.806638 -67.543934) (xy 160.805368 -67.52971) (xy 160.80359 -67.488054)
			(xy 160.804131 -67.45809) (xy 160.811959 -67.398675) (xy 160.827475 -67.340791) (xy 160.850414 -67.285427)
			(xy 160.880382 -67.23353) (xy 160.916868 -67.185989) (xy 160.959247 -67.143617) (xy 161.006794 -67.107139)
			(xy 161.058696 -67.077179) (xy 161.114064 -67.05425) (xy 161.171951 -67.038744) (xy 161.231367 -67.030926)
			(xy 161.291295 -67.03093) (xy 161.35071 -67.038756) (xy 161.408595 -67.05427) (xy 161.46396 -67.077207)
			(xy 161.515858 -67.107174) (xy 161.5634 -67.143659) (xy 161.605773 -67.186036) (xy 161.642253 -67.233582)
			(xy 161.672214 -67.285483) (xy 161.695145 -67.34085) (xy 161.710653 -67.398737) (xy 161.718473 -67.458153)
			(xy 161.718471 -67.518081) (xy 161.711956 -67.567552) (xy 162.096178 -67.567552) (xy 162.096178 -67.507616)
			(xy 162.104001 -67.448194) (xy 162.119514 -67.390301) (xy 162.14245 -67.334928) (xy 162.172417 -67.283022)
			(xy 162.208904 -67.235472) (xy 162.251284 -67.193092) (xy 162.298834 -67.156605) (xy 162.35074 -67.126638)
			(xy 162.406113 -67.103702) (xy 162.464006 -67.088189) (xy 162.523428 -67.080366) (xy 162.583364 -67.080366)
			(xy 162.642786 -67.088189) (xy 162.700679 -67.103702) (xy 162.756052 -67.126638) (xy 162.760062 -67.128953)
			(xy 182.466675 -67.128953) (xy 182.466675 -67.074447) (xy 182.474433 -67.020495) (xy 182.48979 -66.968196)
			(xy 182.512435 -66.918616) (xy 182.541905 -66.872763) (xy 182.577601 -66.831572) (xy 182.618797 -66.79588)
			(xy 182.664653 -66.766415) (xy 182.714236 -66.743776) (xy 182.766536 -66.728424) (xy 182.820489 -66.720672)
			(xy 182.847742 -66.720212) (xy 182.875111 -66.720709) (xy 182.929289 -66.728519) (xy 182.981792 -66.744001)
			(xy 183.031539 -66.766836) (xy 183.077507 -66.796554) (xy 183.09844 -66.814192) (xy 183.098694 -66.814446)
			(xy 183.105774 -66.820042) (xy 183.122696 -66.826282) (xy 183.131714 -66.826638) (xy 183.19877 -66.826638)
			(xy 183.207784 -66.826258) (xy 183.224701 -66.820026) (xy 183.23179 -66.814446) (xy 183.23179 -66.814192)
			(xy 183.232044 -66.814192) (xy 183.252985 -66.796564) (xy 183.298956 -66.766851) (xy 183.348701 -66.744013)
			(xy 183.401199 -66.728519) (xy 183.455373 -66.720688) (xy 183.482742 -66.720212) (xy 183.509993 -66.720661)
			(xy 183.563939 -66.728422) (xy 183.616231 -66.743782) (xy 183.665806 -66.766427) (xy 183.711653 -66.795896)
			(xy 183.752841 -66.831589) (xy 183.788529 -66.87278) (xy 183.817993 -66.918631) (xy 183.840633 -66.968208)
			(xy 183.855986 -67.020502) (xy 183.863742 -67.074449) (xy 183.863742 -67.128951) (xy 183.855986 -67.182898)
			(xy 183.840633 -67.235192) (xy 183.817993 -67.284769) (xy 183.788529 -67.33062) (xy 183.752841 -67.371811)
			(xy 183.711653 -67.407504) (xy 183.665806 -67.436973) (xy 183.616231 -67.459618) (xy 183.563939 -67.474978)
			(xy 183.509993 -67.482739) (xy 183.482742 -67.483228) (xy 183.455372 -67.482755) (xy 183.401192 -67.474941)
			(xy 183.348689 -67.459455) (xy 183.298942 -67.436614) (xy 183.252975 -67.40689) (xy 183.232044 -67.389248)
			(xy 183.23179 -67.388994) (xy 183.224711 -67.383396) (xy 183.207788 -67.377157) (xy 183.19877 -67.376802)
			(xy 183.131714 -67.376802) (xy 183.122698 -67.377165) (xy 183.105781 -67.383408) (xy 183.098694 -67.388994)
			(xy 183.098694 -67.389248) (xy 183.09844 -67.389248) (xy 183.077497 -67.406874) (xy 183.031528 -67.436589)
			(xy 182.981783 -67.459429) (xy 182.929285 -67.474923) (xy 182.875111 -67.482753) (xy 182.847742 -67.483228)
			(xy 182.820489 -67.482728) (xy 182.766536 -67.474976) (xy 182.714236 -67.459624) (xy 182.664653 -67.436985)
			(xy 182.618797 -67.40752) (xy 182.577601 -67.371828) (xy 182.541905 -67.330637) (xy 182.512435 -67.284784)
			(xy 182.48979 -67.235204) (xy 182.474433 -67.182905) (xy 182.466675 -67.128953) (xy 162.760062 -67.128953)
			(xy 162.807958 -67.156605) (xy 162.855508 -67.193092) (xy 162.897888 -67.235472) (xy 162.934375 -67.283022)
			(xy 162.964342 -67.334928) (xy 162.987278 -67.390301) (xy 163.002791 -67.448194) (xy 163.010614 -67.507616)
			(xy 163.011104 -67.537584) (xy 163.010614 -67.567552) (xy 163.003324 -67.622924) (xy 163.370242 -67.622924)
			(xy 163.370242 -67.562988) (xy 163.378065 -67.503566) (xy 163.393578 -67.445673) (xy 163.416514 -67.3903)
			(xy 163.446481 -67.338394) (xy 163.482968 -67.290844) (xy 163.525348 -67.248464) (xy 163.572898 -67.211977)
			(xy 163.624804 -67.18201) (xy 163.680177 -67.159074) (xy 163.73807 -67.143561) (xy 163.797492 -67.135738)
			(xy 163.857428 -67.135738) (xy 163.91685 -67.143561) (xy 163.974743 -67.159074) (xy 164.030116 -67.18201)
			(xy 164.082022 -67.211977) (xy 164.129572 -67.248464) (xy 164.171952 -67.290844) (xy 164.208439 -67.338394)
			(xy 164.238406 -67.3903) (xy 164.261342 -67.445673) (xy 164.276855 -67.503566) (xy 164.284678 -67.562988)
			(xy 164.284712 -67.565048) (xy 166.546816 -67.565048) (xy 166.546816 -67.510552) (xy 166.554571 -67.456611)
			(xy 166.569924 -67.404323) (xy 166.592562 -67.354752) (xy 166.622024 -67.308907) (xy 166.65771 -67.267721)
			(xy 166.698894 -67.232033) (xy 166.744738 -67.20257) (xy 166.794308 -67.17993) (xy 166.846596 -67.164575)
			(xy 166.900536 -67.156817) (xy 166.927784 -67.15633) (xy 166.955154 -67.156798) (xy 167.009334 -67.164614)
			(xy 167.061837 -67.180103) (xy 167.111584 -67.202944) (xy 167.157551 -67.232669) (xy 167.178482 -67.25031)
			(xy 167.178736 -67.250564) (xy 167.185831 -67.256137) (xy 167.202742 -67.26239) (xy 167.211756 -67.262756)
			(xy 167.278812 -67.262756) (xy 167.287831 -67.262414) (xy 167.304748 -67.256157) (xy 167.311832 -67.250564)
			(xy 167.311832 -67.25031) (xy 167.312086 -67.25031) (xy 167.333014 -67.232666) (xy 167.378988 -67.202954)
			(xy 167.428736 -67.180119) (xy 167.481238 -67.164629) (xy 167.535415 -67.156803) (xy 167.562784 -67.15633)
			(xy 167.59004 -67.156716) (xy 167.643998 -67.164472) (xy 167.696303 -67.179828) (xy 167.745891 -67.202472)
			(xy 167.79175 -67.231942) (xy 167.832949 -67.26764) (xy 167.868648 -67.308837) (xy 167.898121 -67.354695)
			(xy 167.920766 -67.404282) (xy 167.936125 -67.456586) (xy 167.943883 -67.510544) (xy 167.943883 -67.565056)
			(xy 167.936125 -67.619014) (xy 167.920766 -67.671318) (xy 167.898121 -67.720905) (xy 167.868648 -67.766763)
			(xy 167.832949 -67.80796) (xy 167.79175 -67.843658) (xy 167.745891 -67.873128) (xy 167.696303 -67.895772)
			(xy 167.643998 -67.911128) (xy 167.59004 -67.918884) (xy 167.562784 -67.919346) (xy 167.535413 -67.918902)
			(xy 167.481232 -67.911081) (xy 167.428728 -67.895588) (xy 167.378982 -67.872741) (xy 167.333016 -67.84301)
			(xy 167.312086 -67.825366) (xy 167.311832 -67.825112) (xy 167.304739 -67.819534) (xy 167.287827 -67.813282)
			(xy 167.278812 -67.81292) (xy 167.211756 -67.81292) (xy 167.202741 -67.8133) (xy 167.185824 -67.819531)
			(xy 167.178736 -67.825112) (xy 167.178736 -67.825366) (xy 167.178482 -67.825366) (xy 167.157525 -67.842975)
			(xy 167.11156 -67.872692) (xy 167.061819 -67.895535) (xy 167.009323 -67.911033) (xy 166.955152 -67.918868)
			(xy 166.927784 -67.919346) (xy 166.900536 -67.918783) (xy 166.846596 -67.911025) (xy 166.794308 -67.89567)
			(xy 166.744738 -67.87303) (xy 166.698894 -67.843567) (xy 166.65771 -67.807879) (xy 166.622024 -67.766693)
			(xy 166.592562 -67.720848) (xy 166.569924 -67.671277) (xy 166.554571 -67.618989) (xy 166.546816 -67.565048)
			(xy 164.284712 -67.565048) (xy 164.285168 -67.592956) (xy 164.284678 -67.622924) (xy 164.276855 -67.682346)
			(xy 164.261342 -67.740239) (xy 164.238406 -67.795612) (xy 164.208439 -67.847518) (xy 164.171952 -67.895068)
			(xy 164.129572 -67.937448) (xy 164.082022 -67.973935) (xy 164.030116 -68.003902) (xy 163.974743 -68.026838)
			(xy 163.91685 -68.042351) (xy 163.857428 -68.050174) (xy 163.797492 -68.050174) (xy 163.73807 -68.042351)
			(xy 163.680177 -68.026838) (xy 163.624804 -68.003902) (xy 163.572898 -67.973935) (xy 163.525348 -67.937448)
			(xy 163.482968 -67.895068) (xy 163.446481 -67.847518) (xy 163.416514 -67.795612) (xy 163.393578 -67.740239)
			(xy 163.378065 -67.682346) (xy 163.370242 -67.622924) (xy 163.003324 -67.622924) (xy 163.002791 -67.626974)
			(xy 162.987278 -67.684867) (xy 162.964342 -67.74024) (xy 162.934375 -67.792146) (xy 162.897888 -67.839696)
			(xy 162.855508 -67.882076) (xy 162.807958 -67.918563) (xy 162.756052 -67.94853) (xy 162.700679 -67.971466)
			(xy 162.642786 -67.986979) (xy 162.583364 -67.994802) (xy 162.523428 -67.994802) (xy 162.464006 -67.986979)
			(xy 162.406113 -67.971466) (xy 162.35074 -67.94853) (xy 162.298834 -67.918563) (xy 162.251284 -67.882076)
			(xy 162.208904 -67.839696) (xy 162.172417 -67.792146) (xy 162.14245 -67.74024) (xy 162.119514 -67.684867)
			(xy 162.104001 -67.626974) (xy 162.096178 -67.567552) (xy 161.711956 -67.567552) (xy 161.710647 -67.577496)
			(xy 161.695134 -67.635381) (xy 161.672199 -67.690747) (xy 161.642234 -67.742645) (xy 161.605751 -67.790189)
			(xy 161.563375 -67.832563) (xy 161.51583 -67.869044) (xy 161.46393 -67.899008) (xy 161.408564 -67.921941)
			(xy 161.350677 -67.93745) (xy 161.291262 -67.945272) (xy 161.261298 -67.945762) (xy 161.232881 -67.945326)
			(xy 161.176482 -67.938299) (xy 161.121388 -67.924341) (xy 161.068447 -67.903667) (xy 161.018474 -67.876595)
			(xy 160.995106 -67.860418) (xy 160.983422 -67.852036) (xy 160.954974 -67.850004) (xy 160.861756 -67.899026)
			(xy 160.853681 -67.903772) (xy 160.841333 -67.917829) (xy 160.834863 -67.935386) (xy 160.834578 -67.944746)
			(xy 160.834578 -67.951604) (xy 160.83412 -67.978975) (xy 160.826301 -68.033154) (xy 160.81081 -68.085658)
			(xy 160.787967 -68.135404) (xy 160.75824 -68.181371) (xy 160.740598 -68.202302) (xy 160.740344 -68.202556)
			(xy 160.734763 -68.209646) (xy 160.728514 -68.22656) (xy 160.728152 -68.235576) (xy 160.728152 -68.302632)
			(xy 160.728482 -68.311652) (xy 160.734747 -68.328569) (xy 160.740344 -68.335652) (xy 160.740598 -68.335652)
			(xy 160.740598 -68.335906) (xy 160.758253 -68.356825) (xy 160.787963 -68.402802) (xy 160.810795 -68.452552)
			(xy 160.826283 -68.505056) (xy 160.834106 -68.559234) (xy 160.834578 -68.586604) (xy 160.834148 -68.613858)
			(xy 160.82639 -68.667812) (xy 160.811032 -68.720112) (xy 160.794399 -68.75653) (xy 164.270436 -68.75653)
			(xy 164.270911 -68.72916) (xy 164.278725 -68.674981) (xy 164.294212 -68.622478) (xy 164.317052 -68.572731)
			(xy 164.346775 -68.526764) (xy 164.364416 -68.505832) (xy 164.36467 -68.505578) (xy 164.37028 -68.498508)
			(xy 164.376511 -68.481578) (xy 164.376862 -68.472558) (xy 164.376862 -68.405502) (xy 164.376512 -68.396484)
			(xy 164.37026 -68.379567) (xy 164.36467 -68.372482) (xy 164.364416 -68.372482) (xy 164.364416 -68.372228)
			(xy 164.346779 -68.351294) (xy 164.317066 -68.305322) (xy 164.29423 -68.255575) (xy 164.278738 -68.203075)
			(xy 164.27091 -68.148899) (xy 164.270436 -68.12153) (xy 164.270883 -68.094276) (xy 164.278637 -68.040322)
			(xy 164.293992 -67.988021) (xy 164.316634 -67.938438) (xy 164.346103 -67.892583) (xy 164.381799 -67.851389)
			(xy 164.422994 -67.815695) (xy 164.468851 -67.786227) (xy 164.518434 -67.763587) (xy 164.570736 -67.748234)
			(xy 164.62469 -67.740482) (xy 164.651944 -67.740022) (xy 164.679313 -67.740516) (xy 164.733491 -67.748326)
			(xy 164.785994 -67.763808) (xy 164.835742 -67.786644) (xy 164.88171 -67.816363) (xy 164.902642 -67.834002)
			(xy 164.902896 -67.834256) (xy 164.909975 -67.839854) (xy 164.926898 -67.846092) (xy 164.935916 -67.846448)
			(xy 165.002972 -67.846448) (xy 165.011989 -67.846089) (xy 165.028906 -67.839844) (xy 165.035992 -67.834256)
			(xy 165.035992 -67.834002) (xy 165.036246 -67.834002) (xy 165.057188 -67.816375) (xy 165.103158 -67.786661)
			(xy 165.152903 -67.763823) (xy 165.205401 -67.748329) (xy 165.259575 -67.740498) (xy 165.286944 -67.740022)
			(xy 165.313259 -67.740453) (xy 165.36539 -67.747694) (xy 165.416033 -67.76202) (xy 165.464232 -67.783159)
			(xy 165.509075 -67.810712) (xy 165.549713 -67.844157) (xy 165.567868 -67.863212) (xy 165.575398 -67.870603)
			(xy 165.594672 -67.879133) (xy 165.605206 -67.879722) (xy 165.679882 -67.879722) (xy 165.690431 -67.87919)
			(xy 165.709726 -67.870656) (xy 165.71722 -67.863212) (xy 165.735375 -67.844156) (xy 165.776005 -67.810698)
			(xy 165.820845 -67.783139) (xy 165.869046 -67.762001) (xy 165.919694 -67.747684) (xy 165.971828 -67.74046)
			(xy 165.998144 -67.740022) (xy 166.025398 -67.740437) (xy 166.07935 -67.7482) (xy 166.131647 -67.763562)
			(xy 166.181227 -67.786211) (xy 166.227078 -67.815685) (xy 166.268269 -67.851383) (xy 166.30396 -67.892581)
			(xy 166.333425 -67.938438) (xy 166.356063 -67.988022) (xy 166.371415 -68.040323) (xy 166.379168 -68.094276)
			(xy 166.379652 -68.12153) (xy 166.379215 -68.148901) (xy 166.371392 -68.203082) (xy 166.355897 -68.255586)
			(xy 166.333048 -68.305333) (xy 166.303317 -68.351298) (xy 166.285672 -68.372228) (xy 166.285418 -68.372482)
			(xy 166.279835 -68.379571) (xy 166.273586 -68.396486) (xy 166.273226 -68.405502) (xy 166.273226 -68.472558)
			(xy 166.273598 -68.481574) (xy 166.279834 -68.498491) (xy 166.285418 -68.505578) (xy 166.285672 -68.505578)
			(xy 166.285672 -68.505832) (xy 166.303288 -68.526782) (xy 166.333005 -68.57275) (xy 166.339366 -68.586604)
			(xy 184.72531 -68.586604) (xy 184.725776 -68.559234) (xy 184.733593 -68.505055) (xy 184.749082 -68.452551)
			(xy 184.771924 -68.402804) (xy 184.801649 -68.356838) (xy 184.81929 -68.335906) (xy 184.819544 -68.335652)
			(xy 184.82512 -68.328559) (xy 184.831372 -68.311647) (xy 184.831736 -68.302632) (xy 184.831736 -68.235576)
			(xy 184.831383 -68.226559) (xy 184.825132 -68.209642) (xy 184.819544 -68.202556) (xy 184.81929 -68.202556)
			(xy 184.81929 -68.202302) (xy 184.801637 -68.181381) (xy 184.771927 -68.135405) (xy 184.749094 -68.085655)
			(xy 184.733607 -68.033152) (xy 184.725782 -67.978974) (xy 184.72531 -67.951604) (xy 184.725759 -67.92435)
			(xy 184.733516 -67.870398) (xy 184.748872 -67.818099) (xy 184.771516 -67.768518) (xy 184.800985 -67.722664)
			(xy 184.83668 -67.68147) (xy 184.877875 -67.645777) (xy 184.92373 -67.616309) (xy 184.973312 -67.593668)
			(xy 185.025612 -67.578313) (xy 185.079564 -67.570558) (xy 185.106818 -67.570096) (xy 185.133132 -67.570553)
			(xy 185.185261 -67.57779) (xy 185.235904 -67.592111) (xy 185.284103 -67.613246) (xy 185.328946 -67.640794)
			(xy 185.369586 -67.674234) (xy 185.387742 -67.693286) (xy 185.395248 -67.700706) (xy 185.41454 -67.70922)
			(xy 185.42508 -67.709796) (xy 185.499756 -67.709796) (xy 185.510305 -67.709258) (xy 185.5296 -67.700729)
			(xy 185.537094 -67.693286) (xy 185.555257 -67.674238) (xy 185.595885 -67.64078) (xy 185.640724 -67.613221)
			(xy 185.688923 -67.592081) (xy 185.739569 -67.577762) (xy 185.791702 -67.570536) (xy 185.818018 -67.570096)
			(xy 185.845389 -67.570552) (xy 185.899568 -67.578373) (xy 185.952071 -67.593864) (xy 186.001818 -67.616708)
			(xy 186.047784 -67.646434) (xy 186.068716 -67.664076) (xy 186.06897 -67.66433) (xy 186.076059 -67.669913)
			(xy 186.092974 -67.676161) (xy 186.10199 -67.676522) (xy 186.169046 -67.676522) (xy 186.17806 -67.676135)
			(xy 186.194977 -67.669908) (xy 186.202066 -67.66433) (xy 186.202066 -67.664076) (xy 186.20232 -67.664076)
			(xy 186.223268 -67.646457) (xy 186.269237 -67.616743) (xy 186.31898 -67.593904) (xy 186.371477 -67.578408)
			(xy 186.42565 -67.570573) (xy 186.453018 -67.570096) (xy 186.479107 -67.570509) (xy 186.530797 -67.577622)
			(xy 186.581036 -67.591713) (xy 186.628886 -67.612519) (xy 186.651392 -67.625722) (xy 186.663838 -67.633342)
			(xy 186.692286 -67.633088) (xy 186.793886 -67.569842) (xy 186.806586 -67.543934) (xy 186.805316 -67.52971)
			(xy 186.803538 -67.488054) (xy 186.804031 -67.458091) (xy 186.811859 -67.398677) (xy 186.827374 -67.340794)
			(xy 186.850311 -67.285431) (xy 186.880279 -67.233535) (xy 186.916763 -67.185995) (xy 186.959141 -67.143623)
			(xy 187.006686 -67.107145) (xy 187.058586 -67.077184) (xy 187.113952 -67.054254) (xy 187.171838 -67.038747)
			(xy 187.231252 -67.030927) (xy 187.291179 -67.030929) (xy 187.350593 -67.038753) (xy 187.408477 -67.054264)
			(xy 187.463842 -67.077198) (xy 187.515739 -67.107162) (xy 187.563282 -67.143643) (xy 187.605657 -67.186018)
			(xy 187.642138 -67.233561) (xy 187.672102 -67.285458) (xy 187.695036 -67.340823) (xy 187.710547 -67.398707)
			(xy 187.718371 -67.458121) (xy 187.718373 -67.518048) (xy 187.711857 -67.567552) (xy 188.096126 -67.567552)
			(xy 188.096126 -67.507616) (xy 188.103949 -67.448194) (xy 188.119462 -67.390301) (xy 188.142398 -67.334928)
			(xy 188.172365 -67.283022) (xy 188.208852 -67.235472) (xy 188.251232 -67.193092) (xy 188.298782 -67.156605)
			(xy 188.350688 -67.126638) (xy 188.406061 -67.103702) (xy 188.463954 -67.088189) (xy 188.523376 -67.080366)
			(xy 188.583312 -67.080366) (xy 188.642734 -67.088189) (xy 188.700627 -67.103702) (xy 188.756 -67.126638)
			(xy 188.760003 -67.128949) (xy 208.466698 -67.128949) (xy 208.466698 -67.074451) (xy 208.474454 -67.020507)
			(xy 208.489808 -66.968216) (xy 208.512447 -66.918642) (xy 208.541911 -66.872794) (xy 208.577599 -66.831606)
			(xy 208.618786 -66.795917) (xy 208.664633 -66.766452) (xy 208.714206 -66.743811) (xy 208.766497 -66.728456)
			(xy 208.820441 -66.720699) (xy 208.84769 -66.720212) (xy 208.87506 -66.720681) (xy 208.929239 -66.728498)
			(xy 208.981742 -66.743986) (xy 209.031489 -66.766827) (xy 209.077456 -66.796551) (xy 209.098388 -66.814192)
			(xy 209.098642 -66.814446) (xy 209.105737 -66.82002) (xy 209.122647 -66.826273) (xy 209.131662 -66.826638)
			(xy 209.198718 -66.826638) (xy 209.207735 -66.826282) (xy 209.224651 -66.820033) (xy 209.231738 -66.814446)
			(xy 209.231738 -66.814192) (xy 209.231992 -66.814192) (xy 209.252915 -66.796542) (xy 209.298891 -66.766832)
			(xy 209.34864 -66.743998) (xy 209.401143 -66.72851) (xy 209.45532 -66.720684) (xy 209.48269 -66.720212)
			(xy 209.509945 -66.720634) (xy 209.5639 -66.72839) (xy 209.616202 -66.743746) (xy 209.665786 -66.76639)
			(xy 209.711642 -66.795859) (xy 209.752838 -66.831554) (xy 209.788535 -66.87275) (xy 209.818006 -66.918606)
			(xy 209.84065 -66.968189) (xy 209.856007 -67.020491) (xy 209.863765 -67.074445) (xy 209.863765 -67.128955)
			(xy 209.856007 -67.182909) (xy 209.84065 -67.235211) (xy 209.818006 -67.284794) (xy 209.788535 -67.33065)
			(xy 209.752838 -67.371846) (xy 209.711642 -67.407541) (xy 209.665786 -67.43701) (xy 209.616202 -67.459654)
			(xy 209.5639 -67.47501) (xy 209.509945 -67.482766) (xy 209.48269 -67.483228) (xy 209.455319 -67.482785)
			(xy 209.401138 -67.474965) (xy 209.348634 -67.459471) (xy 209.298887 -67.436624) (xy 209.252922 -67.406893)
			(xy 209.231992 -67.389248) (xy 209.231738 -67.388994) (xy 209.224645 -67.383417) (xy 209.207733 -67.377165)
			(xy 209.198718 -67.376802) (xy 209.131662 -67.376802) (xy 209.122643 -67.377141) (xy 209.105726 -67.383401)
			(xy 209.098642 -67.388994) (xy 209.098642 -67.389248) (xy 209.098388 -67.389248) (xy 209.077427 -67.406851)
			(xy 209.031463 -67.43657) (xy 208.981723 -67.459414) (xy 208.929228 -67.474913) (xy 208.875057 -67.48275)
			(xy 208.84769 -67.483228) (xy 208.820441 -67.482701) (xy 208.766497 -67.474944) (xy 208.714206 -67.459589)
			(xy 208.664633 -67.436948) (xy 208.618786 -67.407483) (xy 208.577599 -67.371794) (xy 208.541911 -67.330606)
			(xy 208.512447 -67.284758) (xy 208.489808 -67.235184) (xy 208.474454 -67.182893) (xy 208.466698 -67.128949)
			(xy 188.760003 -67.128949) (xy 188.807906 -67.156605) (xy 188.855456 -67.193092) (xy 188.897836 -67.235472)
			(xy 188.934323 -67.283022) (xy 188.96429 -67.334928) (xy 188.987226 -67.390301) (xy 189.002739 -67.448194)
			(xy 189.010562 -67.507616) (xy 189.011052 -67.537584) (xy 189.010562 -67.567552) (xy 189.003272 -67.622924)
			(xy 189.37019 -67.622924) (xy 189.37019 -67.562988) (xy 189.378013 -67.503566) (xy 189.393526 -67.445673)
			(xy 189.416462 -67.3903) (xy 189.446429 -67.338394) (xy 189.482916 -67.290844) (xy 189.525296 -67.248464)
			(xy 189.572846 -67.211977) (xy 189.624752 -67.18201) (xy 189.680125 -67.159074) (xy 189.738018 -67.143561)
			(xy 189.79744 -67.135738) (xy 189.857376 -67.135738) (xy 189.916798 -67.143561) (xy 189.974691 -67.159074)
			(xy 190.030064 -67.18201) (xy 190.08197 -67.211977) (xy 190.12952 -67.248464) (xy 190.1719 -67.290844)
			(xy 190.208387 -67.338394) (xy 190.238354 -67.3903) (xy 190.26129 -67.445673) (xy 190.276803 -67.503566)
			(xy 190.284626 -67.562988) (xy 190.28466 -67.565052) (xy 192.546693 -67.565052) (xy 192.546693 -67.510548)
			(xy 192.55445 -67.4566) (xy 192.569806 -67.404305) (xy 192.592449 -67.354728) (xy 192.621917 -67.308877)
			(xy 192.657611 -67.267688) (xy 192.698803 -67.231998) (xy 192.744656 -67.202534) (xy 192.794235 -67.179895)
			(xy 192.846531 -67.164544) (xy 192.90048 -67.156791) (xy 192.927732 -67.15633) (xy 192.955103 -67.15677)
			(xy 193.009284 -67.164593) (xy 193.061787 -67.180088) (xy 193.111534 -67.202935) (xy 193.157499 -67.232666)
			(xy 193.17843 -67.25031) (xy 193.178684 -67.250564) (xy 193.185765 -67.256158) (xy 193.202686 -67.262398)
			(xy 193.211704 -67.262756) (xy 193.27876 -67.262756) (xy 193.287776 -67.262389) (xy 193.304694 -67.25615)
			(xy 193.31178 -67.250564) (xy 193.31178 -67.25031) (xy 193.312034 -67.25031) (xy 193.332981 -67.23269)
			(xy 193.37895 -67.202975) (xy 193.428693 -67.180135) (xy 193.481191 -67.16464) (xy 193.535364 -67.156807)
			(xy 193.562732 -67.15633) (xy 193.589984 -67.156742) (xy 193.643934 -67.164503) (xy 193.69623 -67.179862)
			(xy 193.745808 -67.202508) (xy 193.791659 -67.231978) (xy 193.83285 -67.267673) (xy 193.868541 -67.308866)
			(xy 193.898008 -67.35472) (xy 193.920649 -67.4043) (xy 193.936004 -67.456597) (xy 193.94376 -67.510547)
			(xy 193.94376 -67.565053) (xy 193.936004 -67.619003) (xy 193.920649 -67.6713) (xy 193.898008 -67.72088)
			(xy 193.868541 -67.766734) (xy 193.83285 -67.807927) (xy 193.791659 -67.843622) (xy 193.745808 -67.873092)
			(xy 193.69623 -67.895738) (xy 193.643934 -67.911097) (xy 193.589984 -67.918858) (xy 193.562732 -67.919346)
			(xy 193.535362 -67.918874) (xy 193.481182 -67.91106) (xy 193.428679 -67.895573) (xy 193.378932 -67.872732)
			(xy 193.332965 -67.843007) (xy 193.312034 -67.825366) (xy 193.31178 -67.825112) (xy 193.304702 -67.819512)
			(xy 193.287779 -67.813273) (xy 193.27876 -67.81292) (xy 193.211704 -67.81292) (xy 193.202687 -67.813274)
			(xy 193.18577 -67.819523) (xy 193.178684 -67.825112) (xy 193.178684 -67.825366) (xy 193.17843 -67.825366)
			(xy 193.157493 -67.842999) (xy 193.111522 -67.872713) (xy 193.061776 -67.895551) (xy 193.009276 -67.911043)
			(xy 192.955101 -67.918872) (xy 192.927732 -67.919346) (xy 192.90048 -67.918809) (xy 192.846531 -67.911056)
			(xy 192.794235 -67.895705) (xy 192.744656 -67.873066) (xy 192.698803 -67.843602) (xy 192.657611 -67.807912)
			(xy 192.621917 -67.766723) (xy 192.592449 -67.720872) (xy 192.569806 -67.671295) (xy 192.55445 -67.619)
			(xy 192.546693 -67.565052) (xy 190.28466 -67.565052) (xy 190.285116 -67.592956) (xy 190.284626 -67.622924)
			(xy 190.276803 -67.682346) (xy 190.26129 -67.740239) (xy 190.238354 -67.795612) (xy 190.208387 -67.847518)
			(xy 190.1719 -67.895068) (xy 190.12952 -67.937448) (xy 190.08197 -67.973935) (xy 190.030064 -68.003902)
			(xy 189.974691 -68.026838) (xy 189.916798 -68.042351) (xy 189.857376 -68.050174) (xy 189.79744 -68.050174)
			(xy 189.738018 -68.042351) (xy 189.680125 -68.026838) (xy 189.624752 -68.003902) (xy 189.572846 -67.973935)
			(xy 189.525296 -67.937448) (xy 189.482916 -67.895068) (xy 189.446429 -67.847518) (xy 189.416462 -67.795612)
			(xy 189.393526 -67.740239) (xy 189.378013 -67.682346) (xy 189.37019 -67.622924) (xy 189.003272 -67.622924)
			(xy 189.002739 -67.626974) (xy 188.987226 -67.684867) (xy 188.96429 -67.74024) (xy 188.934323 -67.792146)
			(xy 188.897836 -67.839696) (xy 188.855456 -67.882076) (xy 188.807906 -67.918563) (xy 188.756 -67.94853)
			(xy 188.700627 -67.971466) (xy 188.642734 -67.986979) (xy 188.583312 -67.994802) (xy 188.523376 -67.994802)
			(xy 188.463954 -67.986979) (xy 188.406061 -67.971466) (xy 188.350688 -67.94853) (xy 188.298782 -67.918563)
			(xy 188.251232 -67.882076) (xy 188.208852 -67.839696) (xy 188.172365 -67.792146) (xy 188.142398 -67.74024)
			(xy 188.119462 -67.684867) (xy 188.103949 -67.626974) (xy 188.096126 -67.567552) (xy 187.711857 -67.567552)
			(xy 187.710553 -67.577462) (xy 187.695046 -67.635348) (xy 187.672116 -67.690714) (xy 187.642155 -67.742614)
			(xy 187.605677 -67.790159) (xy 187.563305 -67.832537) (xy 187.515765 -67.869021) (xy 187.463869 -67.898989)
			(xy 187.408506 -67.921926) (xy 187.350623 -67.937441) (xy 187.291209 -67.945269) (xy 187.261246 -67.945762)
			(xy 187.232828 -67.945353) (xy 187.176428 -67.93832) (xy 187.121334 -67.924356) (xy 187.068393 -67.903675)
			(xy 187.018421 -67.876597) (xy 186.995054 -67.860418) (xy 186.98337 -67.852036) (xy 186.954922 -67.850004)
			(xy 186.861704 -67.899026) (xy 186.853618 -67.903755) (xy 186.841276 -67.917822) (xy 186.83481 -67.935384)
			(xy 186.834526 -67.944746) (xy 186.834526 -67.951604) (xy 186.83408 -67.978975) (xy 186.82626 -68.033156)
			(xy 186.810767 -68.08566) (xy 186.787921 -68.135406) (xy 186.75819 -68.181372) (xy 186.740546 -68.202302)
			(xy 186.740292 -68.202556) (xy 186.734717 -68.20965) (xy 186.728464 -68.226561) (xy 186.7281 -68.235576)
			(xy 186.7281 -68.302632) (xy 186.728442 -68.31165) (xy 186.7347 -68.328567) (xy 186.740292 -68.335652)
			(xy 186.740546 -68.335652) (xy 186.740546 -68.335906) (xy 186.758193 -68.356832) (xy 186.787905 -68.402806)
			(xy 186.810741 -68.452555) (xy 186.82623 -68.505057) (xy 186.834054 -68.559234) (xy 186.834526 -68.586604)
			(xy 186.834026 -68.613855) (xy 186.826269 -68.667801) (xy 186.810915 -68.720094) (xy 186.794275 -68.75653)
			(xy 190.270384 -68.75653) (xy 190.270847 -68.729159) (xy 190.278663 -68.674979) (xy 190.294151 -68.622475)
			(xy 190.316994 -68.572729) (xy 190.346721 -68.526763) (xy 190.364364 -68.505832) (xy 190.364618 -68.505578)
			(xy 190.370222 -68.498503) (xy 190.376458 -68.481577) (xy 190.37681 -68.472558) (xy 190.37681 -68.405502)
			(xy 190.37645 -68.396486) (xy 190.370204 -68.379569) (xy 190.364618 -68.372482) (xy 190.364364 -68.372482)
			(xy 190.364364 -68.372228) (xy 190.346719 -68.351301) (xy 190.317009 -68.305326) (xy 190.294175 -68.255577)
			(xy 190.278685 -68.203076) (xy 190.270858 -68.148899) (xy 190.270384 -68.12153) (xy 190.270883 -68.094278)
			(xy 190.278636 -68.040329) (xy 190.293988 -67.988032) (xy 190.316626 -67.938453) (xy 190.34609 -67.8926)
			(xy 190.38178 -67.851407) (xy 190.422969 -67.815713) (xy 190.468819 -67.786244) (xy 190.518397 -67.763601)
			(xy 190.570692 -67.748244) (xy 190.62464 -67.740486) (xy 190.651892 -67.740022) (xy 190.679262 -67.740487)
			(xy 190.733442 -67.748305) (xy 190.785945 -67.763794) (xy 190.835692 -67.786636) (xy 190.881658 -67.81636)
			(xy 190.90259 -67.834002) (xy 190.902844 -67.834256) (xy 190.909938 -67.839832) (xy 190.926849 -67.846084)
			(xy 190.935864 -67.846448) (xy 191.00292 -67.846448) (xy 191.011939 -67.846112) (xy 191.028857 -67.839851)
			(xy 191.03594 -67.834256) (xy 191.03594 -67.834002) (xy 191.036194 -67.834002) (xy 191.057118 -67.816353)
			(xy 191.103093 -67.786642) (xy 191.152842 -67.763808) (xy 191.205345 -67.74832) (xy 191.259522 -67.740494)
			(xy 191.286892 -67.740022) (xy 191.313206 -67.740488) (xy 191.365335 -67.747722) (xy 191.415978 -67.762041)
			(xy 191.464177 -67.783174) (xy 191.509021 -67.81072) (xy 191.54966 -67.84416) (xy 191.567816 -67.863212)
			(xy 191.575328 -67.870625) (xy 191.594615 -67.879142) (xy 191.605154 -67.879722) (xy 191.67983 -67.879722)
			(xy 191.690376 -67.879162) (xy 191.709671 -67.870648) (xy 191.717168 -67.863212) (xy 191.7353 -67.844133)
			(xy 191.775934 -67.810677) (xy 191.82078 -67.783121) (xy 191.868985 -67.761987) (xy 191.919637 -67.747675)
			(xy 191.971774 -67.740457) (xy 191.998092 -67.740022) (xy 192.025346 -67.740463) (xy 192.079299 -67.74822)
			(xy 192.131599 -67.763576) (xy 192.181182 -67.78622) (xy 192.227036 -67.81569) (xy 192.26823 -67.851386)
			(xy 192.303923 -67.892582) (xy 192.333391 -67.938438) (xy 192.356032 -67.988021) (xy 192.371385 -68.040322)
			(xy 192.379139 -68.094276) (xy 192.3796 -68.12153) (xy 192.379152 -68.148901) (xy 192.371329 -68.203081)
			(xy 192.355836 -68.255584) (xy 192.332991 -68.305331) (xy 192.303263 -68.351297) (xy 192.28562 -68.372228)
			(xy 192.285366 -68.372482) (xy 192.279777 -68.379567) (xy 192.273533 -68.396485) (xy 192.273174 -68.405502)
			(xy 192.273174 -68.472558) (xy 192.273557 -68.481572) (xy 192.279787 -68.498489) (xy 192.285366 -68.505578)
			(xy 192.28562 -68.505578) (xy 192.28562 -68.505832) (xy 192.303244 -68.526776) (xy 192.332957 -68.572746)
			(xy 192.33932 -68.586604) (xy 210.725258 -68.586604) (xy 210.725712 -68.559233) (xy 210.733531 -68.505053)
			(xy 210.749022 -68.452549) (xy 210.771867 -68.402803) (xy 210.801595 -68.356837) (xy 210.819238 -68.335906)
			(xy 210.819492 -68.335652) (xy 210.825062 -68.328554) (xy 210.831319 -68.311646) (xy 210.831684 -68.302632)
			(xy 210.831684 -68.235576) (xy 210.831342 -68.226558) (xy 210.825084 -68.209641) (xy 210.819492 -68.202556)
			(xy 210.819238 -68.202556) (xy 210.819238 -68.202302) (xy 210.801592 -68.181375) (xy 210.77188 -68.135401)
			(xy 210.749045 -68.085653) (xy 210.733555 -68.033151) (xy 210.72573 -67.978974) (xy 210.725258 -67.951604)
			(xy 210.725781 -67.924354) (xy 210.733536 -67.87041) (xy 210.748889 -67.818118) (xy 210.771528 -67.768543)
			(xy 210.80099 -67.722694) (xy 210.836678 -67.681505) (xy 210.877864 -67.645813) (xy 210.923709 -67.616346)
			(xy 210.973282 -67.593703) (xy 211.025573 -67.578345) (xy 211.079516 -67.570584) (xy 211.106766 -67.570096)
			(xy 211.133081 -67.570521) (xy 211.185212 -67.577764) (xy 211.235855 -67.592092) (xy 211.284054 -67.613233)
			(xy 211.328896 -67.640786) (xy 211.369534 -67.674231) (xy 211.38769 -67.693286) (xy 211.395215 -67.700683)
			(xy 211.414492 -67.709211) (xy 211.425028 -67.709796) (xy 211.499704 -67.709796) (xy 211.510256 -67.709284)
			(xy 211.529551 -67.700737) (xy 211.537042 -67.693286) (xy 211.555181 -67.674214) (xy 211.595815 -67.640759)
			(xy 211.640659 -67.613203) (xy 211.688863 -67.592067) (xy 211.739513 -67.577753) (xy 211.791649 -67.570532)
			(xy 211.817966 -67.570096) (xy 211.845335 -67.570583) (xy 211.899514 -67.578396) (xy 211.952016 -67.59388)
			(xy 212.001764 -67.616717) (xy 212.047732 -67.646437) (xy 212.068664 -67.664076) (xy 212.068918 -67.66433)
			(xy 212.075993 -67.669934) (xy 212.092919 -67.676169) (xy 212.101938 -67.676522) (xy 212.168994 -67.676522)
			(xy 212.17801 -67.676157) (xy 212.194927 -67.669914) (xy 212.202014 -67.66433) (xy 212.202014 -67.664076)
			(xy 212.202268 -67.664076) (xy 212.223198 -67.646435) (xy 212.269172 -67.616724) (xy 212.31892 -67.593889)
			(xy 212.371421 -67.578398) (xy 212.425597 -67.57057) (xy 212.452966 -67.570096) (xy 212.479054 -67.570533)
			(xy 212.530744 -67.577639) (xy 212.580983 -67.591723) (xy 212.628834 -67.612523) (xy 212.65134 -67.625722)
			(xy 212.663786 -67.633342) (xy 212.692234 -67.633088) (xy 212.793834 -67.569842) (xy 212.806534 -67.543934)
			(xy 212.805264 -67.52971) (xy 212.803486 -67.488054) (xy 212.804031 -67.45809) (xy 212.811859 -67.398675)
			(xy 212.827375 -67.340791) (xy 212.850314 -67.285426) (xy 212.880283 -67.23353) (xy 212.916769 -67.185989)
			(xy 212.959148 -67.143617) (xy 213.006695 -67.107139) (xy 213.058597 -67.077179) (xy 213.113965 -67.05425)
			(xy 213.171852 -67.038744) (xy 213.231269 -67.030926) (xy 213.291197 -67.03093) (xy 213.350612 -67.038756)
			(xy 213.408497 -67.054271) (xy 213.463862 -67.077208) (xy 213.515759 -67.107175) (xy 213.563301 -67.14366)
			(xy 213.605674 -67.186038) (xy 213.642154 -67.233584) (xy 213.672115 -67.285485) (xy 213.695046 -67.340853)
			(xy 213.710554 -67.398739) (xy 213.718373 -67.458155) (xy 213.718371 -67.518083) (xy 213.711856 -67.567552)
			(xy 214.096074 -67.567552) (xy 214.096074 -67.507616) (xy 214.103897 -67.448194) (xy 214.11941 -67.390301)
			(xy 214.142346 -67.334928) (xy 214.172313 -67.283022) (xy 214.2088 -67.235472) (xy 214.25118 -67.193092)
			(xy 214.29873 -67.156605) (xy 214.350636 -67.126638) (xy 214.406009 -67.103702) (xy 214.463902 -67.088189)
			(xy 214.523324 -67.080366) (xy 214.58326 -67.080366) (xy 214.642682 -67.088189) (xy 214.700575 -67.103702)
			(xy 214.755948 -67.126638) (xy 214.807854 -67.156605) (xy 214.855404 -67.193092) (xy 214.897784 -67.235472)
			(xy 214.934271 -67.283022) (xy 214.964238 -67.334928) (xy 214.987174 -67.390301) (xy 215.002687 -67.448194)
			(xy 215.01051 -67.507616) (xy 215.011 -67.537584) (xy 215.01051 -67.567552) (xy 215.00322 -67.622924)
			(xy 215.370138 -67.622924) (xy 215.370138 -67.562988) (xy 215.377961 -67.503566) (xy 215.393474 -67.445673)
			(xy 215.41641 -67.3903) (xy 215.446377 -67.338394) (xy 215.482864 -67.290844) (xy 215.525244 -67.248464)
			(xy 215.572794 -67.211977) (xy 215.6247 -67.18201) (xy 215.680073 -67.159074) (xy 215.737966 -67.143561)
			(xy 215.797388 -67.135738) (xy 215.857324 -67.135738) (xy 215.916746 -67.143561) (xy 215.974639 -67.159074)
			(xy 216.030012 -67.18201) (xy 216.081918 -67.211977) (xy 216.129468 -67.248464) (xy 216.171848 -67.290844)
			(xy 216.208335 -67.338394) (xy 216.238302 -67.3903) (xy 216.261238 -67.445673) (xy 216.276751 -67.503566)
			(xy 216.284574 -67.562988) (xy 216.284608 -67.565048) (xy 218.546716 -67.565048) (xy 218.546716 -67.510552)
			(xy 218.554471 -67.456612) (xy 218.569824 -67.404324) (xy 218.592461 -67.354753) (xy 218.621923 -67.308908)
			(xy 218.657609 -67.267723) (xy 218.698792 -67.232035) (xy 218.744636 -67.202571) (xy 218.794205 -67.179931)
			(xy 218.846492 -67.164576) (xy 218.900432 -67.156818) (xy 218.92768 -67.15633) (xy 218.95505 -67.1568)
			(xy 219.009229 -67.164616) (xy 219.061733 -67.180104) (xy 219.11148 -67.202945) (xy 219.157446 -67.232669)
			(xy 219.178378 -67.25031) (xy 219.178632 -67.250564) (xy 219.185728 -67.256136) (xy 219.202638 -67.26239)
			(xy 219.211652 -67.262756) (xy 219.278708 -67.262756) (xy 219.287726 -67.262412) (xy 219.304644 -67.256156)
			(xy 219.311728 -67.250564) (xy 219.311728 -67.25031) (xy 219.311982 -67.25031) (xy 219.332911 -67.232667)
			(xy 219.378885 -67.202956) (xy 219.428633 -67.18012) (xy 219.481134 -67.16463) (xy 219.535311 -67.156803)
			(xy 219.56268 -67.15633) (xy 219.589937 -67.156716) (xy 219.643895 -67.164471) (xy 219.696201 -67.179827)
			(xy 219.745788 -67.20247) (xy 219.791648 -67.231941) (xy 219.832848 -67.267638) (xy 219.868547 -67.308836)
			(xy 219.89802 -67.354694) (xy 219.904985 -67.369944) (xy 226.983542 -67.369944) (xy 226.987613 -67.314322)
			(xy 226.999739 -67.259885) (xy 227.019662 -67.207794) (xy 227.046958 -67.159159) (xy 227.081044 -67.115016)
			(xy 227.121193 -67.076307) (xy 227.166551 -67.043856) (xy 227.216151 -67.018355) (xy 227.268935 -67.000348)
			(xy 227.323778 -66.990218) (xy 227.379512 -66.988181) (xy 227.434949 -66.994281) (xy 227.488906 -67.008387)
			(xy 227.540235 -67.030199) (xy 227.587841 -67.059253) (xy 227.630709 -67.094928) (xy 227.667926 -67.136465)
			(xy 227.698699 -67.182978) (xy 227.722371 -67.233475) (xy 227.738439 -67.286882) (xy 227.746559 -67.342058)
			(xy 227.747068 -67.369944) (xy 227.746559 -67.39783) (xy 227.738439 -67.453006) (xy 227.722371 -67.506413)
			(xy 227.698699 -67.55691) (xy 227.667926 -67.603423) (xy 227.630709 -67.64496) (xy 227.587841 -67.680635)
			(xy 227.540235 -67.709689) (xy 227.488906 -67.731501) (xy 227.434949 -67.745607) (xy 227.379512 -67.751707)
			(xy 227.323778 -67.74967) (xy 227.268935 -67.73954) (xy 227.216151 -67.721533) (xy 227.166551 -67.696032)
			(xy 227.121193 -67.663581) (xy 227.081044 -67.624872) (xy 227.046958 -67.580729) (xy 227.019662 -67.532094)
			(xy 226.999739 -67.480003) (xy 226.987613 -67.425566) (xy 226.983542 -67.369944) (xy 219.904985 -67.369944)
			(xy 219.920666 -67.404281) (xy 219.936025 -67.456585) (xy 219.943783 -67.510543) (xy 219.943783 -67.565057)
			(xy 219.936025 -67.619015) (xy 219.920666 -67.671319) (xy 219.89802 -67.720906) (xy 219.868547 -67.766764)
			(xy 219.832848 -67.807962) (xy 219.791648 -67.843659) (xy 219.745788 -67.87313) (xy 219.696201 -67.895773)
			(xy 219.643895 -67.911129) (xy 219.589937 -67.918884) (xy 219.56268 -67.919346) (xy 219.535309 -67.918905)
			(xy 219.481128 -67.911083) (xy 219.428624 -67.895589) (xy 219.378878 -67.872741) (xy 219.332912 -67.84301)
			(xy 219.311982 -67.825366) (xy 219.311728 -67.825112) (xy 219.304637 -67.819532) (xy 219.287724 -67.813281)
			(xy 219.278708 -67.81292) (xy 219.211652 -67.81292) (xy 219.202637 -67.813298) (xy 219.18572 -67.81953)
			(xy 219.178632 -67.825112) (xy 219.178632 -67.825366) (xy 219.178378 -67.825366) (xy 219.157423 -67.842977)
			(xy 219.111457 -67.872694) (xy 219.061715 -67.895536) (xy 219.00922 -67.911034) (xy 218.955048 -67.918869)
			(xy 218.92768 -67.919346) (xy 218.900432 -67.918782) (xy 218.846492 -67.911024) (xy 218.794205 -67.895669)
			(xy 218.744636 -67.873029) (xy 218.698792 -67.843565) (xy 218.657609 -67.807877) (xy 218.621923 -67.766692)
			(xy 218.592461 -67.720847) (xy 218.569824 -67.671276) (xy 218.554471 -67.618988) (xy 218.546716 -67.565048)
			(xy 216.284608 -67.565048) (xy 216.285064 -67.592956) (xy 216.284574 -67.622924) (xy 216.276751 -67.682346)
			(xy 216.261238 -67.740239) (xy 216.238302 -67.795612) (xy 216.208335 -67.847518) (xy 216.171848 -67.895068)
			(xy 216.129468 -67.937448) (xy 216.081918 -67.973935) (xy 216.030012 -68.003902) (xy 215.974639 -68.026838)
			(xy 215.916746 -68.042351) (xy 215.857324 -68.050174) (xy 215.797388 -68.050174) (xy 215.737966 -68.042351)
			(xy 215.680073 -68.026838) (xy 215.6247 -68.003902) (xy 215.572794 -67.973935) (xy 215.525244 -67.937448)
			(xy 215.482864 -67.895068) (xy 215.446377 -67.847518) (xy 215.41641 -67.795612) (xy 215.393474 -67.740239)
			(xy 215.377961 -67.682346) (xy 215.370138 -67.622924) (xy 215.00322 -67.622924) (xy 215.002687 -67.626974)
			(xy 214.987174 -67.684867) (xy 214.964238 -67.74024) (xy 214.934271 -67.792146) (xy 214.897784 -67.839696)
			(xy 214.855404 -67.882076) (xy 214.807854 -67.918563) (xy 214.755948 -67.94853) (xy 214.700575 -67.971466)
			(xy 214.642682 -67.986979) (xy 214.58326 -67.994802) (xy 214.523324 -67.994802) (xy 214.463902 -67.986979)
			(xy 214.406009 -67.971466) (xy 214.350636 -67.94853) (xy 214.29873 -67.918563) (xy 214.25118 -67.882076)
			(xy 214.2088 -67.839696) (xy 214.172313 -67.792146) (xy 214.142346 -67.74024) (xy 214.11941 -67.684867)
			(xy 214.103897 -67.626974) (xy 214.096074 -67.567552) (xy 213.711856 -67.567552) (xy 213.710546 -67.577499)
			(xy 213.695034 -67.635384) (xy 213.672098 -67.69075) (xy 213.642132 -67.742648) (xy 213.605649 -67.790191)
			(xy 213.563272 -67.832566) (xy 213.515727 -67.869046) (xy 213.463827 -67.899009) (xy 213.40846 -67.921942)
			(xy 213.350574 -67.937451) (xy 213.291158 -67.945272) (xy 213.261194 -67.945762) (xy 213.232776 -67.945328)
			(xy 213.176378 -67.938301) (xy 213.121284 -67.924342) (xy 213.068342 -67.903667) (xy 213.01837 -67.876595)
			(xy 212.995002 -67.860418) (xy 212.983318 -67.852036) (xy 212.95487 -67.850004) (xy 212.861652 -67.899026)
			(xy 212.853576 -67.903771) (xy 212.841228 -67.917828) (xy 212.834759 -67.935385) (xy 212.834474 -67.944746)
			(xy 212.834474 -67.951604) (xy 212.834017 -67.978975) (xy 212.826198 -68.033154) (xy 212.810707 -68.085658)
			(xy 212.787863 -68.135405) (xy 212.758136 -68.181371) (xy 212.740494 -68.202302) (xy 212.74024 -68.202556)
			(xy 212.734659 -68.209646) (xy 212.72841 -68.22656) (xy 212.728048 -68.235576) (xy 212.728048 -68.302632)
			(xy 212.728379 -68.311652) (xy 212.734643 -68.328569) (xy 212.74024 -68.335652) (xy 212.740494 -68.335652)
			(xy 212.740494 -68.335906) (xy 212.758148 -68.356826) (xy 212.787858 -68.402802) (xy 212.810691 -68.452552)
			(xy 212.826179 -68.505056) (xy 212.834002 -68.559234) (xy 212.834474 -68.586604) (xy 212.834048 -68.613858)
			(xy 212.82629 -68.667813) (xy 212.810932 -68.720113) (xy 212.794299 -68.75653) (xy 216.270332 -68.75653)
			(xy 216.270808 -68.72916) (xy 216.278622 -68.674981) (xy 216.294108 -68.622478) (xy 216.316948 -68.572731)
			(xy 216.346671 -68.526764) (xy 216.364312 -68.505832) (xy 216.364566 -68.505578) (xy 216.370176 -68.498508)
			(xy 216.376407 -68.481578) (xy 216.376758 -68.472558) (xy 216.376758 -68.405502) (xy 216.376409 -68.396484)
			(xy 216.370157 -68.379567) (xy 216.364566 -68.372482) (xy 216.364312 -68.372482) (xy 216.364312 -68.372228)
			(xy 216.346674 -68.351295) (xy 216.316962 -68.305322) (xy 216.294126 -68.255575) (xy 216.278634 -68.203075)
			(xy 216.270806 -68.148899) (xy 216.270332 -68.12153) (xy 216.270783 -68.094276) (xy 216.278537 -68.040323)
			(xy 216.293892 -67.988022) (xy 216.316533 -67.938439) (xy 216.346002 -67.892584) (xy 216.381697 -67.85139)
			(xy 216.422892 -67.815696) (xy 216.468748 -67.786229) (xy 216.518331 -67.763588) (xy 216.570632 -67.748235)
			(xy 216.624586 -67.740483) (xy 216.65184 -67.740022) (xy 216.679209 -67.740518) (xy 216.733387 -67.748328)
			(xy 216.78589 -67.76381) (xy 216.835638 -67.786645) (xy 216.881606 -67.816363) (xy 216.902538 -67.834002)
			(xy 216.902792 -67.834256) (xy 216.909872 -67.839852) (xy 216.926794 -67.846092) (xy 216.935812 -67.846448)
			(xy 217.002868 -67.846448) (xy 217.011885 -67.846087) (xy 217.028802 -67.839843) (xy 217.035888 -67.834256)
			(xy 217.035888 -67.834002) (xy 217.036142 -67.834002) (xy 217.057085 -67.816377) (xy 217.103055 -67.786663)
			(xy 217.1528 -67.763824) (xy 217.205298 -67.74833) (xy 217.259472 -67.740498) (xy 217.28684 -67.740022)
			(xy 217.313155 -67.740456) (xy 217.365285 -67.747696) (xy 217.415929 -67.762022) (xy 217.464128 -67.78316)
			(xy 217.508971 -67.810713) (xy 217.549609 -67.844158) (xy 217.567764 -67.863212) (xy 217.575295 -67.870602)
			(xy 217.594568 -67.879133) (xy 217.605102 -67.879722) (xy 217.679778 -67.879722) (xy 217.690327 -67.879188)
			(xy 217.709622 -67.870655) (xy 217.717116 -67.863212) (xy 217.735273 -67.844158) (xy 217.775902 -67.8107)
			(xy 217.820742 -67.783141) (xy 217.868943 -67.762002) (xy 217.91959 -67.747685) (xy 217.971724 -67.74046)
			(xy 217.99804 -67.740022) (xy 218.025294 -67.740441) (xy 218.079245 -67.748203) (xy 218.131543 -67.763565)
			(xy 218.181122 -67.786213) (xy 218.226974 -67.815686) (xy 218.268165 -67.851385) (xy 218.303856 -67.892582)
			(xy 218.33332 -67.938439) (xy 218.355959 -67.988023) (xy 218.371311 -68.040323) (xy 218.379064 -68.094276)
			(xy 218.379548 -68.12153) (xy 218.379112 -68.148901) (xy 218.371289 -68.203082) (xy 218.355794 -68.255586)
			(xy 218.332945 -68.305333) (xy 218.30545 -68.34784) (xy 224.712766 -68.34784) (xy 224.712766 -68.287904)
			(xy 224.720589 -68.228482) (xy 224.736102 -68.170589) (xy 224.759038 -68.115216) (xy 224.789005 -68.06331)
			(xy 224.825492 -68.01576) (xy 224.867872 -67.97338) (xy 224.915422 -67.936893) (xy 224.967328 -67.906926)
			(xy 225.022701 -67.88399) (xy 225.080594 -67.868477) (xy 225.140016 -67.860654) (xy 225.199952 -67.860654)
			(xy 225.259374 -67.868477) (xy 225.317267 -67.88399) (xy 225.37264 -67.906926) (xy 225.424546 -67.936893)
			(xy 225.472096 -67.97338) (xy 225.514476 -68.01576) (xy 225.550963 -68.06331) (xy 225.58093 -68.115216)
			(xy 225.603866 -68.170589) (xy 225.619379 -68.228482) (xy 225.627202 -68.287904) (xy 225.627692 -68.317872)
			(xy 225.627202 -68.34784) (xy 225.619379 -68.407262) (xy 225.603866 -68.465155) (xy 225.58093 -68.520528)
			(xy 225.550963 -68.572434) (xy 225.514476 -68.619984) (xy 225.472096 -68.662364) (xy 225.424546 -68.698851)
			(xy 225.37264 -68.728818) (xy 225.317267 -68.751754) (xy 225.259374 -68.767267) (xy 225.199952 -68.77509)
			(xy 225.140016 -68.77509) (xy 225.080594 -68.767267) (xy 225.022701 -68.751754) (xy 224.967328 -68.728818)
			(xy 224.915422 -68.698851) (xy 224.867872 -68.662364) (xy 224.825492 -68.619984) (xy 224.789005 -68.572434)
			(xy 224.759038 -68.520528) (xy 224.736102 -68.465155) (xy 224.720589 -68.407262) (xy 224.712766 -68.34784)
			(xy 218.30545 -68.34784) (xy 218.303213 -68.351298) (xy 218.285568 -68.372228) (xy 218.285314 -68.372482)
			(xy 218.27973 -68.379571) (xy 218.273481 -68.396486) (xy 218.273122 -68.405502) (xy 218.273122 -68.472558)
			(xy 218.273494 -68.481573) (xy 218.279731 -68.498491) (xy 218.285314 -68.505578) (xy 218.285568 -68.505578)
			(xy 218.285568 -68.505832) (xy 218.303184 -68.526783) (xy 218.3329 -68.57275) (xy 218.355741 -68.622493)
			(xy 218.371238 -68.674989) (xy 218.379071 -68.729162) (xy 218.379548 -68.75653) (xy 218.37905 -68.78378)
			(xy 218.371291 -68.837725) (xy 218.355934 -68.890017) (xy 218.333292 -68.939592) (xy 218.303826 -68.98544)
			(xy 218.268136 -69.026629) (xy 218.226948 -69.06232) (xy 218.181101 -69.091787) (xy 218.131527 -69.11443)
			(xy 218.079235 -69.129789) (xy 218.02529 -69.13755) (xy 217.99804 -69.138038) (xy 217.971724 -69.13763)
			(xy 217.919592 -69.130386) (xy 217.868947 -69.116057) (xy 217.820748 -69.094913) (xy 217.775906 -69.067355)
			(xy 217.73527 -69.033905) (xy 217.717116 -69.014848) (xy 217.709584 -69.007459) (xy 217.690312 -68.998926)
			(xy 217.679778 -68.998338) (xy 217.605102 -68.998338) (xy 217.594549 -68.998843) (xy 217.575253 -69.007394)
			(xy 217.567764 -69.014848) (xy 217.549628 -69.033923) (xy 217.508993 -69.067377) (xy 217.464148 -69.094932)
			(xy 217.415944 -69.116067) (xy 217.365294 -69.13038) (xy 217.313157 -69.137601) (xy 217.28684 -69.138038)
			(xy 217.25947 -69.137564) (xy 217.205291 -69.12975) (xy 217.152787 -69.114264) (xy 217.10304 -69.091424)
			(xy 217.057073 -69.061699) (xy 217.036142 -69.044058) (xy 217.035888 -69.043804) (xy 217.028809 -69.038207)
			(xy 217.011886 -69.031966) (xy 217.002868 -69.031612) (xy 216.935812 -69.031612) (xy 216.926795 -69.031972)
			(xy 216.909878 -69.038217) (xy 216.902792 -69.043804) (xy 216.902792 -69.044058) (xy 216.902538 -69.044058)
			(xy 216.881597 -69.061686) (xy 216.835627 -69.091401) (xy 216.785882 -69.11424) (xy 216.733383 -69.129733)
			(xy 216.679209 -69.137563) (xy 216.65184 -69.138038) (xy 216.624589 -69.137508) (xy 216.570643 -69.129757)
			(xy 216.518348 -69.114407) (xy 216.46877 -69.091772) (xy 216.422918 -69.062311) (xy 216.381726 -69.026624)
			(xy 216.346031 -68.985438) (xy 216.316562 -68.939592) (xy 216.293917 -68.890018) (xy 216.278558 -68.837726)
			(xy 216.270797 -68.78378) (xy 216.270332 -68.75653) (xy 212.794299 -68.75653) (xy 212.788286 -68.769696)
			(xy 212.758815 -68.81555) (xy 212.723117 -68.856744) (xy 212.68192 -68.892437) (xy 212.636062 -68.921904)
			(xy 212.586478 -68.944545) (xy 212.534175 -68.959898) (xy 212.480221 -68.967651) (xy 212.452966 -68.968112)
			(xy 212.425595 -68.967663) (xy 212.371416 -68.959841) (xy 212.318912 -68.944347) (xy 212.269166 -68.921502)
			(xy 212.223199 -68.891774) (xy 212.202268 -68.874132) (xy 212.202014 -68.873878) (xy 212.194929 -68.868289)
			(xy 212.178011 -68.862044) (xy 212.168994 -68.861686) (xy 212.101938 -68.861686) (xy 212.092923 -68.862064)
			(xy 212.076006 -68.868297) (xy 212.068918 -68.873878) (xy 212.068918 -68.874132) (xy 212.068664 -68.874132)
			(xy 212.047723 -68.89176) (xy 212.001752 -68.921472) (xy 211.952007 -68.94431) (xy 211.899508 -68.959804)
			(xy 211.845334 -68.967636) (xy 211.817966 -68.968112) (xy 211.791651 -68.967663) (xy 211.739522 -68.960424)
			(xy 211.688879 -68.946101) (xy 211.640681 -68.924965) (xy 211.595837 -68.897416) (xy 211.555198 -68.863975)
			(xy 211.537042 -68.844922) (xy 211.529504 -68.83754) (xy 211.510236 -68.829004) (xy 211.499704 -68.828412)
			(xy 211.425028 -68.828412) (xy 211.414478 -68.828939) (xy 211.395182 -68.837475) (xy 211.38769 -68.844922)
			(xy 211.369537 -68.86398) (xy 211.328906 -68.897436) (xy 211.284065 -68.924994) (xy 211.235864 -68.946132)
			(xy 211.185216 -68.960449) (xy 211.133082 -68.967673) (xy 211.106766 -68.968112) (xy 211.079514 -68.967654)
			(xy 211.025566 -68.959893) (xy 210.973271 -68.944534) (xy 210.923693 -68.921889) (xy 210.877843 -68.892419)
			(xy 210.836654 -68.856725) (xy 210.800963 -68.815532) (xy 210.771497 -68.76968) (xy 210.748856 -68.720101)
			(xy 210.733501 -68.667805) (xy 210.725744 -68.613856) (xy 210.725258 -68.586604) (xy 192.33932 -68.586604)
			(xy 192.355796 -68.622491) (xy 192.371291 -68.674988) (xy 192.379123 -68.729162) (xy 192.3796 -68.75653)
			(xy 192.37915 -68.783782) (xy 192.371389 -68.837732) (xy 192.35603 -68.890028) (xy 192.333385 -68.939606)
			(xy 192.303915 -68.985456) (xy 192.268219 -69.026646) (xy 192.227026 -69.062337) (xy 192.181172 -69.091803)
			(xy 192.131592 -69.114443) (xy 192.079295 -69.129797) (xy 192.025344 -69.137553) (xy 191.998092 -69.138038)
			(xy 191.971777 -69.137596) (xy 191.919647 -69.130358) (xy 191.869003 -69.116036) (xy 191.820803 -69.094899)
			(xy 191.77596 -69.067347) (xy 191.735323 -69.033903) (xy 191.717168 -69.014848) (xy 191.709654 -69.007437)
			(xy 191.690368 -68.998917) (xy 191.67983 -68.998338) (xy 191.605154 -68.998338) (xy 191.594605 -68.998872)
			(xy 191.575308 -69.007402) (xy 191.567816 -69.014848) (xy 191.549655 -69.033898) (xy 191.509025 -69.067354)
			(xy 191.464186 -69.094912) (xy 191.415986 -69.116051) (xy 191.36534 -69.13037) (xy 191.313208 -69.137598)
			(xy 191.286892 -69.138038) (xy 191.259521 -69.137592) (xy 191.20534 -69.129771) (xy 191.152836 -69.114279)
			(xy 191.10309 -69.091432) (xy 191.057124 -69.061702) (xy 191.036194 -69.044058) (xy 191.03594 -69.043804)
			(xy 191.028846 -69.038228) (xy 191.011935 -69.031975) (xy 191.00292 -69.031612) (xy 190.935864 -69.031612)
			(xy 190.926845 -69.031949) (xy 190.909928 -69.03821) (xy 190.902844 -69.043804) (xy 190.902844 -69.044058)
			(xy 190.90259 -69.044058) (xy 190.881667 -69.061709) (xy 190.835692 -69.09142) (xy 190.785943 -69.114255)
			(xy 190.73344 -69.129743) (xy 190.679262 -69.137567) (xy 190.651892 -69.138038) (xy 190.624642 -69.13753)
			(xy 190.570697 -69.129773) (xy 190.518404 -69.114418) (xy 190.468829 -69.091778) (xy 190.42298 -69.062314)
			(xy 190.381791 -69.026625) (xy 190.346099 -68.985438) (xy 190.316632 -68.939591) (xy 190.293989 -68.890017)
			(xy 190.278632 -68.837725) (xy 190.270872 -68.78378) (xy 190.270384 -68.75653) (xy 186.794275 -68.75653)
			(xy 186.788274 -68.76967) (xy 186.758809 -68.81552) (xy 186.723119 -68.856709) (xy 186.681931 -68.892401)
			(xy 186.636083 -68.921868) (xy 186.586507 -68.94451) (xy 186.534215 -68.959866) (xy 186.480269 -68.967625)
			(xy 186.453018 -68.968112) (xy 186.425648 -68.967632) (xy 186.37147 -68.959817) (xy 186.318967 -68.944331)
			(xy 186.26922 -68.921493) (xy 186.223252 -68.891772) (xy 186.20232 -68.874132) (xy 186.202066 -68.873878)
			(xy 186.194966 -68.86831) (xy 186.17806 -68.862053) (xy 186.169046 -68.861686) (xy 186.10199 -68.861686)
			(xy 186.092973 -68.862041) (xy 186.076056 -68.868291) (xy 186.06897 -68.873878) (xy 186.06897 -68.874132)
			(xy 186.068716 -68.874132) (xy 186.047793 -68.891782) (xy 186.001817 -68.921491) (xy 185.952067 -68.944324)
			(xy 185.899565 -68.959813) (xy 185.845388 -68.967639) (xy 185.818018 -68.968112) (xy 185.791705 -68.967629)
			(xy 185.739577 -68.960397) (xy 185.688935 -68.94608) (xy 185.640736 -68.924951) (xy 185.595892 -68.897408)
			(xy 185.555251 -68.863972) (xy 185.537094 -68.844922) (xy 185.529574 -68.837519) (xy 185.510293 -68.828995)
			(xy 185.499756 -68.828412) (xy 185.42508 -68.828412) (xy 185.414533 -68.828967) (xy 185.395237 -68.837484)
			(xy 185.387742 -68.844922) (xy 185.369612 -68.864003) (xy 185.328976 -68.897457) (xy 185.28413 -68.925012)
			(xy 185.235925 -68.946146) (xy 185.185273 -68.960458) (xy 185.133136 -68.967677) (xy 185.106818 -68.968112)
			(xy 185.079566 -68.967628) (xy 185.025616 -68.959874) (xy 184.973319 -68.94452) (xy 184.923739 -68.92188)
			(xy 184.877886 -68.892414) (xy 184.836693 -68.856723) (xy 184.800999 -68.815532) (xy 184.771531 -68.769681)
			(xy 184.748888 -68.720102) (xy 184.733531 -68.667806) (xy 184.725774 -68.613856) (xy 184.72531 -68.586604)
			(xy 166.339366 -68.586604) (xy 166.355845 -68.622493) (xy 166.371342 -68.674989) (xy 166.379175 -68.729162)
			(xy 166.379652 -68.75653) (xy 166.37915 -68.78378) (xy 166.371391 -68.837725) (xy 166.356034 -68.890017)
			(xy 166.333393 -68.939591) (xy 166.303927 -68.985439) (xy 166.268238 -69.026628) (xy 166.22705 -69.062319)
			(xy 166.181203 -69.091786) (xy 166.13163 -69.114429) (xy 166.079339 -69.129788) (xy 166.025394 -69.137549)
			(xy 165.998144 -69.138038) (xy 165.971828 -69.137628) (xy 165.919696 -69.130384) (xy 165.869051 -69.116055)
			(xy 165.820852 -69.094912) (xy 165.77601 -69.067355) (xy 165.735374 -69.033905) (xy 165.71722 -69.014848)
			(xy 165.709686 -69.00746) (xy 165.690416 -68.998926) (xy 165.679882 -68.998338) (xy 165.605206 -68.998338)
			(xy 165.594653 -68.998846) (xy 165.575358 -69.007395) (xy 165.567868 -69.014848) (xy 165.54973 -69.033921)
			(xy 165.509096 -69.067375) (xy 165.464251 -69.09493) (xy 165.416047 -69.116065) (xy 165.365397 -69.130379)
			(xy 165.313261 -69.137601) (xy 165.286944 -69.138038) (xy 165.259574 -69.137561) (xy 165.205395 -69.129748)
			(xy 165.152891 -69.114263) (xy 165.103144 -69.091423) (xy 165.057177 -69.061699) (xy 165.036246 -69.044058)
			(xy 165.035992 -69.043804) (xy 165.028912 -69.038208) (xy 165.01199 -69.031967) (xy 165.002972 -69.031612)
			(xy 164.935916 -69.031612) (xy 164.9269 -69.031974) (xy 164.909982 -69.038218) (xy 164.902896 -69.043804)
			(xy 164.902896 -69.044058) (xy 164.902642 -69.044058) (xy 164.8817 -69.061684) (xy 164.83573 -69.0914)
			(xy 164.785985 -69.114239) (xy 164.733487 -69.129733) (xy 164.679313 -69.137563) (xy 164.651944 -69.138038)
			(xy 164.624694 -69.137504) (xy 164.570747 -69.129754) (xy 164.518452 -69.114405) (xy 164.468874 -69.09177)
			(xy 164.423022 -69.062309) (xy 164.38183 -69.026623) (xy 164.346135 -68.985437) (xy 164.316666 -68.939591)
			(xy 164.294021 -68.890017) (xy 164.278662 -68.837726) (xy 164.270901 -68.78378) (xy 164.270436 -68.75653)
			(xy 160.794399 -68.75653) (xy 160.788387 -68.769694) (xy 160.758916 -68.815549) (xy 160.723218 -68.856742)
			(xy 160.682022 -68.892436) (xy 160.636165 -68.921903) (xy 160.58658 -68.944544) (xy 160.534279 -68.959897)
			(xy 160.480324 -68.967651) (xy 160.45307 -68.968112) (xy 160.425699 -68.967661) (xy 160.37152 -68.959839)
			(xy 160.319017 -68.944346) (xy 160.26927 -68.921501) (xy 160.223304 -68.891774) (xy 160.202372 -68.874132)
			(xy 160.202118 -68.873878) (xy 160.195032 -68.86829) (xy 160.178115 -68.862045) (xy 160.169098 -68.861686)
			(xy 160.102042 -68.861686) (xy 160.093028 -68.862066) (xy 160.076111 -68.868298) (xy 160.069022 -68.873878)
			(xy 160.069022 -68.874132) (xy 160.068768 -68.874132) (xy 160.047825 -68.891758) (xy 160.001855 -68.92147)
			(xy 159.95211 -68.944308) (xy 159.899612 -68.959803) (xy 159.845438 -68.967635) (xy 159.81807 -68.968112)
			(xy 159.791756 -68.967661) (xy 159.739626 -68.960422) (xy 159.688984 -68.9461) (xy 159.640785 -68.924964)
			(xy 159.595942 -68.897415) (xy 159.555302 -68.863974) (xy 159.537146 -68.844922) (xy 159.529643 -68.837498)
			(xy 159.510349 -68.828986) (xy 159.499808 -68.828412) (xy 159.425132 -68.828412) (xy 159.414582 -68.828941)
			(xy 159.395287 -68.837476) (xy 159.387794 -68.844922) (xy 159.369639 -68.863978) (xy 159.329008 -68.897434)
			(xy 159.284168 -68.924992) (xy 159.235967 -68.946131) (xy 159.18532 -68.960448) (xy 159.133186 -68.967673)
			(xy 159.10687 -68.968112) (xy 159.079618 -68.96765) (xy 159.02567 -68.95989) (xy 158.973375 -68.944531)
			(xy 158.923798 -68.921887) (xy 158.877948 -68.892418) (xy 158.836758 -68.856724) (xy 158.801067 -68.815531)
			(xy 158.771601 -68.769679) (xy 158.74896 -68.720101) (xy 158.733605 -68.667805) (xy 158.725848 -68.613856)
			(xy 158.725362 -68.586604) (xy 140.339424 -68.586604) (xy 140.3559 -68.62249) (xy 140.371395 -68.674988)
			(xy 140.379227 -68.729162) (xy 140.379704 -68.75653) (xy 140.37925 -68.783782) (xy 140.371489 -68.837731)
			(xy 140.35613 -68.890027) (xy 140.333485 -68.939604) (xy 140.304016 -68.985455) (xy 140.268321 -69.026645)
			(xy 140.227128 -69.062336) (xy 140.181275 -69.091802) (xy 140.131695 -69.114442) (xy 140.079398 -69.129797)
			(xy 140.025448 -69.137553) (xy 139.998196 -69.138038) (xy 139.971881 -69.137593) (xy 139.919751 -69.130356)
			(xy 139.869107 -69.116034) (xy 139.820907 -69.094898) (xy 139.776065 -69.067347) (xy 139.735427 -69.033902)
			(xy 139.717272 -69.014848) (xy 139.709756 -69.007439) (xy 139.690472 -68.998917) (xy 139.679934 -68.998338)
			(xy 139.605258 -68.998338) (xy 139.594709 -68.998874) (xy 139.575413 -69.007403) (xy 139.56792 -69.014848)
			(xy 139.549757 -69.033896) (xy 139.509128 -69.067352) (xy 139.464289 -69.094911) (xy 139.41609 -69.11605)
			(xy 139.365444 -69.13037) (xy 139.313312 -69.137597) (xy 139.286996 -69.138038) (xy 139.259625 -69.137589)
			(xy 139.205445 -69.12977) (xy 139.152941 -69.114277) (xy 139.103194 -69.091431) (xy 139.057229 -69.061702)
			(xy 139.036298 -69.044058) (xy 139.036044 -69.043804) (xy 139.028949 -69.03823) (xy 139.012039 -69.031976)
			(xy 139.003024 -69.031612) (xy 138.935968 -69.031612) (xy 138.926949 -69.031951) (xy 138.910032 -69.038211)
			(xy 138.902948 -69.043804) (xy 138.902948 -69.044058) (xy 138.902694 -69.044058) (xy 138.88177 -69.061707)
			(xy 138.835795 -69.091419) (xy 138.786046 -69.114253) (xy 138.733543 -69.129742) (xy 138.679366 -69.137566)
			(xy 138.651996 -69.138038) (xy 138.624746 -69.137526) (xy 138.570801 -69.12977) (xy 138.518508 -69.114416)
			(xy 138.468933 -69.091776) (xy 138.423084 -69.062312) (xy 138.381895 -69.026624) (xy 138.346203 -68.985437)
			(xy 138.316736 -68.93959) (xy 138.294093 -68.890016) (xy 138.278736 -68.837725) (xy 138.270976 -68.78378)
			(xy 138.270488 -68.75653) (xy 134.794375 -68.75653) (xy 134.788375 -68.769669) (xy 134.75891 -68.815518)
			(xy 134.723221 -68.856708) (xy 134.682033 -68.8924) (xy 134.636185 -68.921866) (xy 134.58661 -68.944509)
			(xy 134.534318 -68.959866) (xy 134.480372 -68.967625) (xy 134.453122 -68.968112) (xy 134.425752 -68.96763)
			(xy 134.371574 -68.959816) (xy 134.319071 -68.94433) (xy 134.269324 -68.921492) (xy 134.223356 -68.891771)
			(xy 134.202424 -68.874132) (xy 134.20217 -68.873878) (xy 134.195069 -68.868312) (xy 134.178163 -68.862054)
			(xy 134.16915 -68.861686) (xy 134.102094 -68.861686) (xy 134.093077 -68.862043) (xy 134.07616 -68.868291)
			(xy 134.069074 -68.873878) (xy 134.069074 -68.874132) (xy 134.06882 -68.874132) (xy 134.047895 -68.89178)
			(xy 134.00192 -68.92149) (xy 133.952171 -68.944323) (xy 133.899668 -68.959812) (xy 133.845492 -68.967639)
			(xy 133.818122 -68.968112) (xy 133.791809 -68.967626) (xy 133.739681 -68.960394) (xy 133.689039 -68.946079)
			(xy 133.64084 -68.92495) (xy 133.595996 -68.897407) (xy 133.555355 -68.863972) (xy 133.537198 -68.844922)
			(xy 133.529676 -68.837521) (xy 133.510396 -68.828995) (xy 133.49986 -68.828412) (xy 133.425184 -68.828412)
			(xy 133.414631 -68.828915) (xy 133.395336 -68.837468) (xy 133.387846 -68.844922) (xy 133.369714 -68.864001)
			(xy 133.329079 -68.897455) (xy 133.284233 -68.925011) (xy 133.236028 -68.946145) (xy 133.185377 -68.960457)
			(xy 133.133239 -68.967676) (xy 133.106922 -68.968112) (xy 133.07967 -68.967624) (xy 133.02572 -68.95987)
			(xy 132.973423 -68.944517) (xy 132.923843 -68.921878) (xy 132.87799 -68.892412) (xy 132.836797 -68.856721)
			(xy 132.801103 -68.815531) (xy 132.771635 -68.76968) (xy 132.748992 -68.720102) (xy 132.733635 -68.667805)
			(xy 132.725878 -68.613856) (xy 132.725414 -68.586604) (xy 102.239163 -68.586604) (xy 102.255643 -68.622493)
			(xy 102.27114 -68.674989) (xy 102.278973 -68.729162) (xy 102.27945 -68.75653) (xy 102.27895 -68.78378)
			(xy 102.271191 -68.837725) (xy 102.255834 -68.890017) (xy 102.233192 -68.939592) (xy 102.203727 -68.98544)
			(xy 102.168037 -69.026629) (xy 102.126849 -69.06232) (xy 102.081002 -69.091787) (xy 102.031428 -69.11443)
			(xy 101.979137 -69.129788) (xy 101.925192 -69.137549) (xy 101.897942 -69.138038) (xy 101.871626 -69.137629)
			(xy 101.819494 -69.130385) (xy 101.768849 -69.116056) (xy 101.72065 -69.094913) (xy 101.675808 -69.067355)
			(xy 101.635172 -69.033905) (xy 101.617018 -69.014848) (xy 101.609485 -69.00746) (xy 101.590214 -68.998926)
			(xy 101.57968 -68.998338) (xy 101.505004 -68.998338) (xy 101.494451 -68.998844) (xy 101.475156 -69.007394)
			(xy 101.467666 -69.014848) (xy 101.449529 -69.033922) (xy 101.408895 -69.067376) (xy 101.36405 -69.094931)
			(xy 101.315846 -69.116066) (xy 101.265195 -69.13038) (xy 101.213059 -69.137601) (xy 101.186742 -69.138038)
			(xy 101.159372 -69.137562) (xy 101.105193 -69.129749) (xy 101.052689 -69.114263) (xy 101.002942 -69.091423)
			(xy 100.956975 -69.061699) (xy 100.936044 -69.044058) (xy 100.93579 -69.043804) (xy 100.92871 -69.038208)
			(xy 100.911788 -69.031967) (xy 100.90277 -69.031612) (xy 100.835714 -69.031612) (xy 100.826697 -69.031973)
			(xy 100.80978 -69.038217) (xy 100.802694 -69.043804) (xy 100.802694 -69.044058) (xy 100.80244 -69.044058)
			(xy 100.781498 -69.061685) (xy 100.735529 -69.0914) (xy 100.685784 -69.114239) (xy 100.633285 -69.129733)
			(xy 100.579111 -69.137563) (xy 100.551742 -69.138038) (xy 100.524492 -69.137506) (xy 100.470545 -69.129755)
			(xy 100.41825 -69.114406) (xy 100.368672 -69.091771) (xy 100.32282 -69.06231) (xy 100.281628 -69.026623)
			(xy 100.245933 -68.985438) (xy 100.216464 -68.939591) (xy 100.193819 -68.890018) (xy 100.17846 -68.837726)
			(xy 100.170699 -68.78378) (xy 100.170234 -68.75653) (xy 96.694199 -68.75653) (xy 96.688186 -68.769695)
			(xy 96.658715 -68.81555) (xy 96.623018 -68.856743) (xy 96.581821 -68.892437) (xy 96.535963 -68.921904)
			(xy 96.486379 -68.944544) (xy 96.434077 -68.959898) (xy 96.380122 -68.967651) (xy 96.352868 -68.968112)
			(xy 96.325497 -68.967662) (xy 96.271318 -68.95984) (xy 96.218814 -68.944347) (xy 96.169068 -68.921502)
			(xy 96.123101 -68.891774) (xy 96.10217 -68.874132) (xy 96.101916 -68.873878) (xy 96.094831 -68.86829)
			(xy 96.077913 -68.862045) (xy 96.068896 -68.861686) (xy 96.00184 -68.861686) (xy 95.992825 -68.862065)
			(xy 95.975908 -68.868298) (xy 95.96882 -68.873878) (xy 95.96882 -68.874132) (xy 95.968566 -68.874132)
			(xy 95.947624 -68.891759) (xy 95.901653 -68.921471) (xy 95.851908 -68.944309) (xy 95.79941 -68.959803)
			(xy 95.745236 -68.967636) (xy 95.717868 -68.968112) (xy 95.691553 -68.967662) (xy 95.639424 -68.960423)
			(xy 95.588781 -68.9461) (xy 95.540583 -68.924965) (xy 95.49574 -68.897416) (xy 95.4551 -68.863975)
			(xy 95.436944 -68.844922) (xy 95.429405 -68.837541) (xy 95.410138 -68.829004) (xy 95.399606 -68.828412)
			(xy 95.32493 -68.828412) (xy 95.31438 -68.82894) (xy 95.295085 -68.837476) (xy 95.287592 -68.844922)
			(xy 95.269438 -68.863979) (xy 95.228807 -68.897435) (xy 95.183966 -68.924993) (xy 95.135766 -68.946131)
			(xy 95.085118 -68.960448) (xy 95.032984 -68.967673) (xy 95.006668 -68.968112) (xy 94.979416 -68.967652)
			(xy 94.925468 -68.959891) (xy 94.873173 -68.944532) (xy 94.823596 -68.921888) (xy 94.777746 -68.892418)
			(xy 94.736556 -68.856724) (xy 94.700865 -68.815532) (xy 94.671399 -68.76968) (xy 94.648758 -68.720101)
			(xy 94.633403 -68.667805) (xy 94.625646 -68.613856) (xy 94.62516 -68.586604) (xy 76.239222 -68.586604)
			(xy 76.255698 -68.62249) (xy 76.271193 -68.674988) (xy 76.279025 -68.729162) (xy 76.279502 -68.75653)
			(xy 76.27905 -68.783782) (xy 76.271289 -68.837732) (xy 76.25593 -68.890027) (xy 76.233285 -68.939605)
			(xy 76.203815 -68.985456) (xy 76.16812 -69.026646) (xy 76.126927 -69.062337) (xy 76.081073 -69.091802)
			(xy 76.031493 -69.114443) (xy 75.979196 -69.129797) (xy 75.925246 -69.137553) (xy 75.897994 -69.138038)
			(xy 75.871679 -69.137594) (xy 75.819549 -69.130357) (xy 75.768905 -69.116035) (xy 75.720705 -69.094898)
			(xy 75.675863 -69.067347) (xy 75.635225 -69.033903) (xy 75.61707 -69.014848) (xy 75.609555 -69.007438)
			(xy 75.59027 -68.998917) (xy 75.579732 -68.998338) (xy 75.505056 -68.998338) (xy 75.494507 -68.998873)
			(xy 75.475211 -69.007403) (xy 75.467718 -69.014848) (xy 75.449556 -69.033897) (xy 75.408927 -69.067353)
			(xy 75.364087 -69.094912) (xy 75.315888 -69.116051) (xy 75.265242 -69.13037) (xy 75.21311 -69.137598)
			(xy 75.186794 -69.138038) (xy 75.159423 -69.137591) (xy 75.105242 -69.129771) (xy 75.052739 -69.114278)
			(xy 75.002992 -69.091432) (xy 74.957026 -69.061702) (xy 74.936096 -69.044058) (xy 74.935842 -69.043804)
			(xy 74.928747 -69.038229) (xy 74.911837 -69.031975) (xy 74.902822 -69.031612) (xy 74.835766 -69.031612)
			(xy 74.826747 -69.03195) (xy 74.80983 -69.038211) (xy 74.802746 -69.043804) (xy 74.802746 -69.044058)
			(xy 74.802492 -69.044058) (xy 74.781568 -69.061708) (xy 74.735594 -69.091419) (xy 74.685844 -69.114254)
			(xy 74.633342 -69.129742) (xy 74.579164 -69.137567) (xy 74.551794 -69.138038) (xy 74.524544 -69.137528)
			(xy 74.470599 -69.129771) (xy 74.418306 -69.114417) (xy 74.368731 -69.091777) (xy 74.322882 -69.062313)
			(xy 74.281693 -69.026624) (xy 74.246001 -68.985437) (xy 74.216534 -68.93959) (xy 74.193891 -68.890016)
			(xy 74.178534 -68.837725) (xy 74.170774 -68.78378) (xy 74.170286 -68.75653) (xy 70.694176 -68.75653)
			(xy 70.688175 -68.76967) (xy 70.65871 -68.815519) (xy 70.62302 -68.856709) (xy 70.581832 -68.8924)
			(xy 70.535984 -68.921867) (xy 70.486409 -68.944509) (xy 70.434116 -68.959866) (xy 70.38017 -68.967625)
			(xy 70.35292 -68.968112) (xy 70.32555 -68.967631) (xy 70.271372 -68.959817) (xy 70.218869 -68.944331)
			(xy 70.169122 -68.921492) (xy 70.123154 -68.891771) (xy 70.102222 -68.874132) (xy 70.101968 -68.873878)
			(xy 70.094868 -68.868311) (xy 70.077961 -68.862053) (xy 70.068948 -68.861686) (xy 70.001892 -68.861686)
			(xy 69.992875 -68.862042) (xy 69.975958 -68.868291) (xy 69.968872 -68.873878) (xy 69.968872 -68.874132)
			(xy 69.968618 -68.874132) (xy 69.947694 -68.891781) (xy 69.901719 -68.92149) (xy 69.851969 -68.944324)
			(xy 69.799467 -68.959813) (xy 69.74529 -68.967639) (xy 69.71792 -68.968112) (xy 69.691607 -68.967627)
			(xy 69.639479 -68.960396) (xy 69.588837 -68.94608) (xy 69.540638 -68.92495) (xy 69.495794 -68.897407)
			(xy 69.455153 -68.863972) (xy 69.436996 -68.844922) (xy 69.429475 -68.83752) (xy 69.410195 -68.828995)
			(xy 69.399658 -68.828412) (xy 69.324982 -68.828412) (xy 69.314435 -68.828968) (xy 69.295139 -68.837484)
			(xy 69.287644 -68.844922) (xy 69.269513 -68.864002) (xy 69.228878 -68.897456) (xy 69.184032 -68.925011)
			(xy 69.135826 -68.946145) (xy 69.085175 -68.960458) (xy 69.033037 -68.967677) (xy 69.00672 -68.968112)
			(xy 68.979468 -68.967626) (xy 68.925518 -68.959872) (xy 68.873221 -68.944519) (xy 68.823641 -68.921879)
			(xy 68.777788 -68.892413) (xy 68.736595 -68.856722) (xy 68.700901 -68.815531) (xy 68.671433 -68.76968)
			(xy 68.64879 -68.720102) (xy 68.633433 -68.667806) (xy 68.625676 -68.613856) (xy 68.625212 -68.586604)
			(xy 50.239268 -68.586604) (xy 50.255747 -68.622492) (xy 50.271244 -68.674989) (xy 50.279077 -68.729162)
			(xy 50.279554 -68.75653) (xy 50.27905 -68.78378) (xy 50.271291 -68.837725) (xy 50.255934 -68.890016)
			(xy 50.233293 -68.93959) (xy 50.203828 -68.985438) (xy 50.168138 -69.026627) (xy 50.126951 -69.062318)
			(xy 50.081105 -69.091785) (xy 50.031531 -69.114429) (xy 49.97924 -69.129787) (xy 49.925296 -69.137549)
			(xy 49.898046 -69.138038) (xy 49.87173 -69.137626) (xy 49.819598 -69.130383) (xy 49.768954 -69.116054)
			(xy 49.720754 -69.094911) (xy 49.675912 -69.067355) (xy 49.635276 -69.033905) (xy 49.617122 -69.014848)
			(xy 49.609588 -69.007461) (xy 49.590318 -68.998927) (xy 49.579784 -68.998338) (xy 49.505108 -68.998338)
			(xy 49.494556 -68.998847) (xy 49.47526 -69.007395) (xy 49.46777 -69.014848) (xy 49.449631 -69.03392)
			(xy 49.408997 -69.067374) (xy 49.364153 -69.09493) (xy 49.315949 -69.116065) (xy 49.265299 -69.130379)
			(xy 49.213163 -69.137601) (xy 49.186846 -69.138038) (xy 49.159476 -69.13756) (xy 49.105297 -69.129747)
			(xy 49.052793 -69.114262) (xy 49.003046 -69.091422) (xy 48.957079 -69.061699) (xy 48.936148 -69.044058)
			(xy 48.935894 -69.043804) (xy 48.928813 -69.038209) (xy 48.911892 -69.031967) (xy 48.902874 -69.031612)
			(xy 48.835818 -69.031612) (xy 48.826802 -69.031975) (xy 48.809884 -69.038218) (xy 48.802798 -69.043804)
			(xy 48.802798 -69.044058) (xy 48.802544 -69.044058) (xy 48.781601 -69.061683) (xy 48.735632 -69.091399)
			(xy 48.685887 -69.114238) (xy 48.633389 -69.129732) (xy 48.579215 -69.137563) (xy 48.551846 -69.138038)
			(xy 48.524596 -69.137502) (xy 48.470649 -69.129752) (xy 48.418354 -69.114403) (xy 48.368776 -69.091768)
			(xy 48.322924 -69.062308) (xy 48.281732 -69.026622) (xy 48.246038 -68.985437) (xy 48.216568 -68.939591)
			(xy 48.193923 -68.890017) (xy 48.178564 -68.837725) (xy 48.170803 -68.78378) (xy 48.170338 -68.75653)
			(xy 44.694299 -68.75653) (xy 44.688287 -68.769694) (xy 44.658816 -68.815548) (xy 44.623119 -68.856742)
			(xy 44.581923 -68.892435) (xy 44.536066 -68.921902) (xy 44.486482 -68.944543) (xy 44.43418 -68.959897)
			(xy 44.380226 -68.967651) (xy 44.352972 -68.968112) (xy 44.325601 -68.967659) (xy 44.271422 -68.959838)
			(xy 44.218919 -68.944345) (xy 44.169172 -68.921501) (xy 44.123206 -68.891774) (xy 44.102274 -68.874132)
			(xy 44.10202 -68.873878) (xy 44.094934 -68.868291) (xy 44.078017 -68.862045) (xy 44.069 -68.861686)
			(xy 44.001944 -68.861686) (xy 43.99293 -68.862067) (xy 43.976013 -68.868298) (xy 43.968924 -68.873878)
			(xy 43.968924 -68.874132) (xy 43.96867 -68.874132) (xy 43.947726 -68.891757) (xy 43.901756 -68.92147)
			(xy 43.852012 -68.944308) (xy 43.799514 -68.959802) (xy 43.74534 -68.967635) (xy 43.717972 -68.968112)
			(xy 43.691658 -68.967659) (xy 43.639529 -68.960421) (xy 43.588886 -68.946099) (xy 43.540687 -68.924963)
			(xy 43.495844 -68.897415) (xy 43.455204 -68.863974) (xy 43.437048 -68.844922) (xy 43.429545 -68.837499)
			(xy 43.410251 -68.828986) (xy 43.39971 -68.828412) (xy 43.325034 -68.828412) (xy 43.314484 -68.828942)
			(xy 43.295189 -68.837476) (xy 43.287696 -68.844922) (xy 43.26954 -68.863977) (xy 43.22891 -68.897433)
			(xy 43.184069 -68.924992) (xy 43.135869 -68.94613) (xy 43.085222 -68.960448) (xy 43.033088 -68.967673)
			(xy 43.006772 -68.968112) (xy 42.97952 -68.967648) (xy 42.925572 -68.959888) (xy 42.873277 -68.94453)
			(xy 42.8237 -68.921885) (xy 42.77785 -68.892417) (xy 42.73666 -68.856723) (xy 42.700969 -68.815531)
			(xy 42.671503 -68.769679) (xy 42.648862 -68.7201) (xy 42.633507 -68.667805) (xy 42.62575 -68.613856)
			(xy 42.625264 -68.586604) (xy 24.239326 -68.586604) (xy 24.255802 -68.62249) (xy 24.271297 -68.674988)
			(xy 24.279129 -68.729162) (xy 24.279606 -68.75653) (xy 24.27915 -68.783782) (xy 24.271389 -68.837731)
			(xy 24.25603 -68.890026) (xy 24.233386 -68.939604) (xy 24.203916 -68.985454) (xy 24.168221 -69.026644)
			(xy 24.127029 -69.062335) (xy 24.081176 -69.091801) (xy 24.031596 -69.114442) (xy 23.9793 -69.129796)
			(xy 23.92535 -69.137552) (xy 23.898098 -69.138038) (xy 23.871783 -69.137592) (xy 23.819653 -69.130355)
			(xy 23.769009 -69.116033) (xy 23.72081 -69.094897) (xy 23.675967 -69.067346) (xy 23.635329 -69.033902)
			(xy 23.617174 -69.014848) (xy 23.609657 -69.00744) (xy 23.590374 -68.998918) (xy 23.579836 -68.998338)
			(xy 23.50516 -68.998338) (xy 23.494611 -68.998875) (xy 23.475315 -69.007403) (xy 23.467822 -69.014848)
			(xy 23.449658 -69.033895) (xy 23.409029 -69.067351) (xy 23.36419 -69.09491) (xy 23.315991 -69.11605)
			(xy 23.265346 -69.130369) (xy 23.213213 -69.137597) (xy 23.186898 -69.138038) (xy 23.159527 -69.137588)
			(xy 23.105347 -69.129769) (xy 23.052843 -69.114277) (xy 23.003096 -69.091431) (xy 22.957131 -69.061702)
			(xy 22.9362 -69.044058) (xy 22.935946 -69.043804) (xy 22.92885 -69.038231) (xy 22.911941 -69.031976)
			(xy 22.902926 -69.031612) (xy 22.83587 -69.031612) (xy 22.826851 -69.031952) (xy 22.809934 -69.038211)
			(xy 22.80285 -69.043804) (xy 22.80285 -69.044058) (xy 22.802596 -69.044058) (xy 22.781671 -69.061706)
			(xy 22.735697 -69.091418) (xy 22.685948 -69.114253) (xy 22.633445 -69.129742) (xy 22.579268 -69.137566)
			(xy 22.551898 -69.138038) (xy 22.524648 -69.137524) (xy 22.470703 -69.129768) (xy 22.418411 -69.114414)
			(xy 22.368835 -69.091775) (xy 22.322986 -69.062311) (xy 22.281797 -69.026623) (xy 22.246105 -68.985436)
			(xy 22.216638 -68.939589) (xy 22.193995 -68.890016) (xy 22.178638 -68.837724) (xy 22.170878 -68.78378)
			(xy 22.17039 -68.75653) (xy 18.694275 -68.75653) (xy 18.688275 -68.769669) (xy 18.658811 -68.815518)
			(xy 18.623122 -68.856707) (xy 18.581934 -68.892399) (xy 18.536086 -68.921866) (xy 18.486512 -68.944508)
			(xy 18.43422 -68.959865) (xy 18.380274 -68.967625) (xy 18.353024 -68.968112) (xy 18.325654 -68.967629)
			(xy 18.271476 -68.959815) (xy 18.218973 -68.944329) (xy 18.169226 -68.921492) (xy 18.123258 -68.891771)
			(xy 18.102326 -68.874132) (xy 18.102072 -68.873878) (xy 18.094971 -68.868313) (xy 18.078065 -68.862054)
			(xy 18.069052 -68.861686) (xy 18.001996 -68.861686) (xy 17.992979 -68.862044) (xy 17.976063 -68.868291)
			(xy 17.968976 -68.873878) (xy 17.968976 -68.874132) (xy 17.968722 -68.874132) (xy 17.947797 -68.891779)
			(xy 17.901821 -68.921489) (xy 17.852072 -68.944323) (xy 17.79957 -68.959812) (xy 17.745394 -68.967639)
			(xy 17.718024 -68.968112) (xy 17.691711 -68.967625) (xy 17.639583 -68.960393) (xy 17.588941 -68.946078)
			(xy 17.540742 -68.924949) (xy 17.495898 -68.897407) (xy 17.455257 -68.863972) (xy 17.4371 -68.844922)
			(xy 17.429577 -68.837522) (xy 17.410298 -68.828996) (xy 17.399762 -68.828412) (xy 17.325086 -68.828412)
			(xy 17.314533 -68.828916) (xy 17.295238 -68.837468) (xy 17.287748 -68.844922) (xy 17.269615 -68.864)
			(xy 17.22898 -68.897454) (xy 17.184135 -68.92501) (xy 17.13593 -68.946144) (xy 17.085278 -68.960457)
			(xy 17.033141 -68.967676) (xy 17.006824 -68.968112) (xy 16.979572 -68.967622) (xy 16.925622 -68.959869)
			(xy 16.873325 -68.944516) (xy 16.823745 -68.921877) (xy 16.777892 -68.892411) (xy 16.736699 -68.85672)
			(xy 16.701005 -68.81553) (xy 16.671537 -68.769679) (xy 16.648894 -68.720101) (xy 16.633537 -68.667805)
			(xy 16.62578 -68.613856) (xy 16.625316 -68.586604) (xy 4.352172 -68.586604) (xy 4.339823 -68.607994)
			(xy 4.303336 -68.655544) (xy 4.260956 -68.697924) (xy 4.213406 -68.734411) (xy 4.1615 -68.764378)
			(xy 4.106127 -68.787314) (xy 4.048234 -68.802827) (xy 3.988812 -68.81065) (xy 3.928876 -68.81065)
			(xy 3.869454 -68.802827) (xy 3.811561 -68.787314) (xy 3.756188 -68.764378) (xy 3.704282 -68.734411)
			(xy 3.656732 -68.697924) (xy 3.614352 -68.655544) (xy 3.577865 -68.607994) (xy 3.547898 -68.556088)
			(xy 3.524962 -68.500715) (xy 3.509449 -68.442822) (xy 3.501626 -68.3834) (xy 1.384808 -68.3834) (xy 1.384808 -68.804028)
			(xy 1.385211 -68.813513) (xy 1.392113 -68.831186) (xy 1.404937 -68.845169) (xy 1.413256 -68.849748)
			(xy 1.465326 -68.875148) (xy 1.495552 -68.889626) (xy 1.502015 -68.892485) (xy 1.515931 -68.894922)
			(xy 1.522984 -68.894452) (xy 1.530092 -68.89346) (xy 1.543377 -68.888052) (xy 1.549146 -68.883784)
			(xy 1.569493 -68.868118) (xy 1.613592 -68.841807) (xy 1.660821 -68.821646) (xy 1.710326 -68.808)
			(xy 1.761214 -68.801113) (xy 1.78689 -68.800726) (xy 1.787144 -68.800726) (xy 1.814395 -68.801212)
			(xy 1.868342 -68.808969) (xy 1.920636 -68.824325) (xy 1.970213 -68.846966) (xy 2.016062 -68.876432)
			(xy 2.057252 -68.912124) (xy 2.092942 -68.953314) (xy 2.122408 -68.999164) (xy 2.145048 -69.048741)
			(xy 2.160403 -69.101036) (xy 2.168159 -69.154983) (xy 2.168652 -69.182234) (xy 2.16815 -69.209972)
			(xy 2.16011 -69.264861) (xy 2.144208 -69.318008) (xy 2.12078 -69.368294) (xy 2.090319 -69.414658)
			(xy 2.053467 -69.456124) (xy 2.011 -69.491818) (xy 1.963813 -69.520988) (xy 1.912901 -69.54302) (xy 1.859335 -69.557449)
			(xy 1.831848 -69.561202) (xy 1.81737 -69.562726) (xy 1.787144 -69.563996) (xy 1.786636 -69.563996)
			(xy 1.760978 -69.563547) (xy 1.710131 -69.556606) (xy 1.660674 -69.542911) (xy 1.6135 -69.522709)
			(xy 1.569459 -69.496366) (xy 1.549146 -69.480684) (xy 1.537716 -69.47154) (xy 1.508506 -69.468492)
			(xy 1.41351 -69.51472) (xy 1.405114 -69.519224) (xy 1.392183 -69.533198) (xy 1.385228 -69.550921)
			(xy 1.384808 -69.56044) (xy 1.384808 -70.234044) (xy 6.032228 -70.234044) (xy 6.032228 -70.174108)
			(xy 6.040051 -70.114686) (xy 6.055564 -70.056793) (xy 6.0785 -70.00142) (xy 6.108467 -69.949514)
			(xy 6.144954 -69.901964) (xy 6.187334 -69.859584) (xy 6.234884 -69.823097) (xy 6.28679 -69.79313)
			(xy 6.342163 -69.770194) (xy 6.400056 -69.754681) (xy 6.459478 -69.746858) (xy 6.519414 -69.746858)
			(xy 6.578836 -69.754681) (xy 6.636729 -69.770194) (xy 6.692102 -69.79313) (xy 6.744008 -69.823097)
			(xy 6.791558 -69.859584) (xy 6.833938 -69.901964) (xy 6.870425 -69.949514) (xy 6.900392 -70.00142)
			(xy 6.923328 -70.056793) (xy 6.938841 -70.114686) (xy 6.946664 -70.174108) (xy 6.947154 -70.204076)
			(xy 6.946664 -70.234044) (xy 6.938841 -70.293466) (xy 6.923328 -70.351359) (xy 6.900392 -70.406732)
			(xy 6.870425 -70.458638) (xy 6.833938 -70.506188) (xy 6.791558 -70.548568) (xy 6.744008 -70.585055)
			(xy 6.692102 -70.615022) (xy 6.636729 -70.637958) (xy 6.578836 -70.653471) (xy 6.519414 -70.661294)
			(xy 6.459478 -70.661294) (xy 6.400056 -70.653471) (xy 6.342163 -70.637958) (xy 6.28679 -70.615022)
			(xy 6.234884 -70.585055) (xy 6.187334 -70.548568) (xy 6.144954 -70.506188) (xy 6.108467 -70.458638)
			(xy 6.0785 -70.406732) (xy 6.055564 -70.351359) (xy 6.040051 -70.293466) (xy 6.032228 -70.234044)
			(xy 1.384808 -70.234044) (xy 1.384808 -71.31837) (xy 1.659872 -71.31837) (xy 1.659872 -71.258434)
			(xy 1.667695 -71.199012) (xy 1.683208 -71.141119) (xy 1.706144 -71.085746) (xy 1.736111 -71.03384)
			(xy 1.772598 -70.98629) (xy 1.814978 -70.94391) (xy 1.862528 -70.907423) (xy 1.914434 -70.877456)
			(xy 1.969807 -70.85452) (xy 2.0277 -70.839007) (xy 2.087122 -70.831184) (xy 2.147058 -70.831184)
			(xy 2.20648 -70.839007) (xy 2.264373 -70.85452) (xy 2.319746 -70.877456) (xy 2.371652 -70.907423)
			(xy 2.419202 -70.94391) (xy 2.461582 -70.98629) (xy 2.498069 -71.03384) (xy 2.528036 -71.085746)
			(xy 2.550972 -71.141119) (xy 2.566485 -71.199012) (xy 2.574308 -71.258434) (xy 2.574798 -71.288402)
			(xy 2.574308 -71.31837) (xy 2.566485 -71.377792) (xy 2.550972 -71.435685) (xy 2.528036 -71.491058)
			(xy 2.498069 -71.542964) (xy 2.461582 -71.590514) (xy 2.419202 -71.632894) (xy 2.371652 -71.669381)
			(xy 2.319746 -71.699348) (xy 2.308655 -71.703942) (xy 3.30376 -71.703942) (xy 3.30376 -71.644006)
			(xy 3.311583 -71.584584) (xy 3.327096 -71.526691) (xy 3.350032 -71.471318) (xy 3.379999 -71.419412)
			(xy 3.416486 -71.371862) (xy 3.458866 -71.329482) (xy 3.506416 -71.292995) (xy 3.558322 -71.263028)
			(xy 3.613695 -71.240092) (xy 3.671588 -71.224579) (xy 3.73101 -71.216756) (xy 3.790946 -71.216756)
			(xy 3.850368 -71.224579) (xy 3.908261 -71.240092) (xy 3.963634 -71.263028) (xy 4.01554 -71.292995)
			(xy 4.06309 -71.329482) (xy 4.10547 -71.371862) (xy 4.141957 -71.419412) (xy 4.151958 -71.436734)
			(xy 6.938246 -71.436734) (xy 6.938246 -71.376798) (xy 6.946069 -71.317376) (xy 6.961582 -71.259483)
			(xy 6.984518 -71.20411) (xy 7.014485 -71.152204) (xy 7.050972 -71.104654) (xy 7.093352 -71.062274)
			(xy 7.140902 -71.025787) (xy 7.192808 -70.99582) (xy 7.248181 -70.972884) (xy 7.306074 -70.957371)
			(xy 7.365496 -70.949548) (xy 7.425432 -70.949548) (xy 7.484854 -70.957371) (xy 7.542747 -70.972884)
			(xy 7.59812 -70.99582) (xy 7.650026 -71.025787) (xy 7.697576 -71.062274) (xy 7.739956 -71.104654)
			(xy 7.772973 -71.147682) (xy 8.9705 -71.147682) (xy 8.9705 -71.087746) (xy 8.978323 -71.028324) (xy 8.993836 -70.970431)
			(xy 9.016772 -70.915058) (xy 9.046739 -70.863152) (xy 9.083226 -70.815602) (xy 9.125606 -70.773222)
			(xy 9.173156 -70.736735) (xy 9.225062 -70.706768) (xy 9.280435 -70.683832) (xy 9.338328 -70.668319)
			(xy 9.39775 -70.660496) (xy 9.457686 -70.660496) (xy 9.517108 -70.668319) (xy 9.575001 -70.683832)
			(xy 9.630374 -70.706768) (xy 9.68228 -70.736735) (xy 9.72983 -70.773222) (xy 9.77221 -70.815602)
			(xy 9.808697 -70.863152) (xy 9.838664 -70.915058) (xy 9.8616 -70.970431) (xy 9.877113 -71.028324)
			(xy 9.884936 -71.087746) (xy 9.885426 -71.117714) (xy 9.884936 -71.147682) (xy 9.877113 -71.207104)
			(xy 9.8616 -71.264997) (xy 9.838664 -71.32037) (xy 9.808697 -71.372276) (xy 9.77221 -71.419826) (xy 9.72983 -71.462206)
			(xy 9.68228 -71.498693) (xy 9.630374 -71.52866) (xy 9.575001 -71.551596) (xy 9.517108 -71.567109)
			(xy 9.457686 -71.574932) (xy 9.39775 -71.574932) (xy 9.338328 -71.567109) (xy 9.280435 -71.551596)
			(xy 9.225062 -71.52866) (xy 9.173156 -71.498693) (xy 9.125606 -71.462206) (xy 9.083226 -71.419826)
			(xy 9.046739 -71.372276) (xy 9.016772 -71.32037) (xy 8.993836 -71.264997) (xy 8.978323 -71.207104)
			(xy 8.9705 -71.147682) (xy 7.772973 -71.147682) (xy 7.776443 -71.152204) (xy 7.80641 -71.20411) (xy 7.829346 -71.259483)
			(xy 7.844859 -71.317376) (xy 7.852682 -71.376798) (xy 7.853172 -71.406766) (xy 7.852682 -71.436734)
			(xy 7.844859 -71.496156) (xy 7.829346 -71.554049) (xy 7.816181 -71.585832) (xy 19.119324 -71.585832)
			(xy 19.119324 -71.525896) (xy 19.127147 -71.466474) (xy 19.14266 -71.408581) (xy 19.165596 -71.353208)
			(xy 19.195563 -71.301302) (xy 19.23205 -71.253752) (xy 19.27443 -71.211372) (xy 19.32198 -71.174885)
			(xy 19.373886 -71.144918) (xy 19.429259 -71.121982) (xy 19.487152 -71.106469) (xy 19.546574 -71.098646)
			(xy 19.60651 -71.098646) (xy 19.665932 -71.106469) (xy 19.723825 -71.121982) (xy 19.779198 -71.144918)
			(xy 19.831104 -71.174885) (xy 19.878654 -71.211372) (xy 19.921034 -71.253752) (xy 19.957521 -71.301302)
			(xy 19.987488 -71.353208) (xy 20.010424 -71.408581) (xy 20.025937 -71.466474) (xy 20.03376 -71.525896)
			(xy 20.03425 -71.555864) (xy 20.03376 -71.585832) (xy 20.025937 -71.645254) (xy 20.023755 -71.653396)
			(xy 20.628338 -71.653396) (xy 20.628338 -71.59346) (xy 20.636161 -71.534038) (xy 20.651674 -71.476145)
			(xy 20.67461 -71.420772) (xy 20.704577 -71.368866) (xy 20.741064 -71.321316) (xy 20.783444 -71.278936)
			(xy 20.830994 -71.242449) (xy 20.8829 -71.212482) (xy 20.938273 -71.189546) (xy 20.996166 -71.174033)
			(xy 21.055588 -71.16621) (xy 21.115524 -71.16621) (xy 21.174946 -71.174033) (xy 21.232839 -71.189546)
			(xy 21.288212 -71.212482) (xy 21.340118 -71.242449) (xy 21.387668 -71.278936) (xy 21.430048 -71.321316)
			(xy 21.466535 -71.368866) (xy 21.496502 -71.420772) (xy 21.519438 -71.476145) (xy 21.534951 -71.534038)
			(xy 21.54177 -71.585832) (xy 45.119272 -71.585832) (xy 45.119272 -71.525896) (xy 45.127095 -71.466474)
			(xy 45.142608 -71.408581) (xy 45.165544 -71.353208) (xy 45.195511 -71.301302) (xy 45.231998 -71.253752)
			(xy 45.274378 -71.211372) (xy 45.321928 -71.174885) (xy 45.373834 -71.144918) (xy 45.429207 -71.121982)
			(xy 45.4871 -71.106469) (xy 45.546522 -71.098646) (xy 45.606458 -71.098646) (xy 45.66588 -71.106469)
			(xy 45.723773 -71.121982) (xy 45.779146 -71.144918) (xy 45.831052 -71.174885) (xy 45.878602 -71.211372)
			(xy 45.920982 -71.253752) (xy 45.957469 -71.301302) (xy 45.987436 -71.353208) (xy 46.010372 -71.408581)
			(xy 46.025885 -71.466474) (xy 46.033708 -71.525896) (xy 46.034198 -71.555864) (xy 46.033708 -71.585832)
			(xy 46.025885 -71.645254) (xy 46.023703 -71.653396) (xy 46.628286 -71.653396) (xy 46.628286 -71.59346)
			(xy 46.636109 -71.534038) (xy 46.651622 -71.476145) (xy 46.674558 -71.420772) (xy 46.704525 -71.368866)
			(xy 46.741012 -71.321316) (xy 46.783392 -71.278936) (xy 46.830942 -71.242449) (xy 46.882848 -71.212482)
			(xy 46.938221 -71.189546) (xy 46.996114 -71.174033) (xy 47.055536 -71.16621) (xy 47.115472 -71.16621)
			(xy 47.174894 -71.174033) (xy 47.232787 -71.189546) (xy 47.28816 -71.212482) (xy 47.340066 -71.242449)
			(xy 47.387616 -71.278936) (xy 47.429996 -71.321316) (xy 47.466483 -71.368866) (xy 47.49645 -71.420772)
			(xy 47.519386 -71.476145) (xy 47.534899 -71.534038) (xy 47.541718 -71.585832) (xy 71.11922 -71.585832)
			(xy 71.11922 -71.525896) (xy 71.127043 -71.466474) (xy 71.142556 -71.408581) (xy 71.165492 -71.353208)
			(xy 71.195459 -71.301302) (xy 71.231946 -71.253752) (xy 71.274326 -71.211372) (xy 71.321876 -71.174885)
			(xy 71.373782 -71.144918) (xy 71.429155 -71.121982) (xy 71.487048 -71.106469) (xy 71.54647 -71.098646)
			(xy 71.606406 -71.098646) (xy 71.665828 -71.106469) (xy 71.723721 -71.121982) (xy 71.779094 -71.144918)
			(xy 71.831 -71.174885) (xy 71.87855 -71.211372) (xy 71.92093 -71.253752) (xy 71.957417 -71.301302)
			(xy 71.987384 -71.353208) (xy 72.01032 -71.408581) (xy 72.025833 -71.466474) (xy 72.033656 -71.525896)
			(xy 72.034146 -71.555864) (xy 72.033656 -71.585832) (xy 72.025833 -71.645254) (xy 72.023651 -71.653396)
			(xy 72.628234 -71.653396) (xy 72.628234 -71.59346) (xy 72.636057 -71.534038) (xy 72.65157 -71.476145)
			(xy 72.674506 -71.420772) (xy 72.704473 -71.368866) (xy 72.74096 -71.321316) (xy 72.78334 -71.278936)
			(xy 72.83089 -71.242449) (xy 72.882796 -71.212482) (xy 72.938169 -71.189546) (xy 72.996062 -71.174033)
			(xy 73.055484 -71.16621) (xy 73.11542 -71.16621) (xy 73.174842 -71.174033) (xy 73.232735 -71.189546)
			(xy 73.288108 -71.212482) (xy 73.340014 -71.242449) (xy 73.387564 -71.278936) (xy 73.429944 -71.321316)
			(xy 73.466431 -71.368866) (xy 73.496398 -71.420772) (xy 73.519334 -71.476145) (xy 73.534847 -71.534038)
			(xy 73.541666 -71.585832) (xy 97.119168 -71.585832) (xy 97.119168 -71.525896) (xy 97.126991 -71.466474)
			(xy 97.142504 -71.408581) (xy 97.16544 -71.353208) (xy 97.195407 -71.301302) (xy 97.231894 -71.253752)
			(xy 97.274274 -71.211372) (xy 97.321824 -71.174885) (xy 97.37373 -71.144918) (xy 97.429103 -71.121982)
			(xy 97.486996 -71.106469) (xy 97.546418 -71.098646) (xy 97.606354 -71.098646) (xy 97.665776 -71.106469)
			(xy 97.723669 -71.121982) (xy 97.779042 -71.144918) (xy 97.830948 -71.174885) (xy 97.878498 -71.211372)
			(xy 97.920878 -71.253752) (xy 97.957365 -71.301302) (xy 97.987332 -71.353208) (xy 98.010268 -71.408581)
			(xy 98.025781 -71.466474) (xy 98.033604 -71.525896) (xy 98.034094 -71.555864) (xy 98.033604 -71.585832)
			(xy 98.025781 -71.645254) (xy 98.023599 -71.653396) (xy 98.628182 -71.653396) (xy 98.628182 -71.59346)
			(xy 98.636005 -71.534038) (xy 98.651518 -71.476145) (xy 98.674454 -71.420772) (xy 98.704421 -71.368866)
			(xy 98.740908 -71.321316) (xy 98.783288 -71.278936) (xy 98.830838 -71.242449) (xy 98.882744 -71.212482)
			(xy 98.938117 -71.189546) (xy 98.99601 -71.174033) (xy 99.055432 -71.16621) (xy 99.115368 -71.16621)
			(xy 99.17479 -71.174033) (xy 99.232683 -71.189546) (xy 99.288056 -71.212482) (xy 99.339962 -71.242449)
			(xy 99.387512 -71.278936) (xy 99.429892 -71.321316) (xy 99.466379 -71.368866) (xy 99.496346 -71.420772)
			(xy 99.519282 -71.476145) (xy 99.534795 -71.534038) (xy 99.541614 -71.585832) (xy 135.219422 -71.585832)
			(xy 135.219422 -71.525896) (xy 135.227245 -71.466474) (xy 135.242758 -71.408581) (xy 135.265694 -71.353208)
			(xy 135.295661 -71.301302) (xy 135.332148 -71.253752) (xy 135.374528 -71.211372) (xy 135.422078 -71.174885)
			(xy 135.473984 -71.144918) (xy 135.529357 -71.121982) (xy 135.58725 -71.106469) (xy 135.646672 -71.098646)
			(xy 135.706608 -71.098646) (xy 135.76603 -71.106469) (xy 135.823923 -71.121982) (xy 135.879296 -71.144918)
			(xy 135.931202 -71.174885) (xy 135.978752 -71.211372) (xy 136.021132 -71.253752) (xy 136.057619 -71.301302)
			(xy 136.087586 -71.353208) (xy 136.110522 -71.408581) (xy 136.126035 -71.466474) (xy 136.133858 -71.525896)
			(xy 136.134348 -71.555864) (xy 136.133858 -71.585832) (xy 136.126035 -71.645254) (xy 136.123853 -71.653396)
			(xy 136.728436 -71.653396) (xy 136.728436 -71.59346) (xy 136.736259 -71.534038) (xy 136.751772 -71.476145)
			(xy 136.774708 -71.420772) (xy 136.804675 -71.368866) (xy 136.841162 -71.321316) (xy 136.883542 -71.278936)
			(xy 136.931092 -71.242449) (xy 136.982998 -71.212482) (xy 137.038371 -71.189546) (xy 137.096264 -71.174033)
			(xy 137.155686 -71.16621) (xy 137.215622 -71.16621) (xy 137.275044 -71.174033) (xy 137.332937 -71.189546)
			(xy 137.38831 -71.212482) (xy 137.440216 -71.242449) (xy 137.487766 -71.278936) (xy 137.530146 -71.321316)
			(xy 137.566633 -71.368866) (xy 137.5966 -71.420772) (xy 137.619536 -71.476145) (xy 137.635049 -71.534038)
			(xy 137.641868 -71.585832) (xy 161.21937 -71.585832) (xy 161.21937 -71.525896) (xy 161.227193 -71.466474)
			(xy 161.242706 -71.408581) (xy 161.265642 -71.353208) (xy 161.295609 -71.301302) (xy 161.332096 -71.253752)
			(xy 161.374476 -71.211372) (xy 161.422026 -71.174885) (xy 161.473932 -71.144918) (xy 161.529305 -71.121982)
			(xy 161.587198 -71.106469) (xy 161.64662 -71.098646) (xy 161.706556 -71.098646) (xy 161.765978 -71.106469)
			(xy 161.823871 -71.121982) (xy 161.879244 -71.144918) (xy 161.93115 -71.174885) (xy 161.9787 -71.211372)
			(xy 162.02108 -71.253752) (xy 162.057567 -71.301302) (xy 162.087534 -71.353208) (xy 162.11047 -71.408581)
			(xy 162.125983 -71.466474) (xy 162.133806 -71.525896) (xy 162.134296 -71.555864) (xy 162.133806 -71.585832)
			(xy 162.125983 -71.645254) (xy 162.123801 -71.653396) (xy 162.728384 -71.653396) (xy 162.728384 -71.59346)
			(xy 162.736207 -71.534038) (xy 162.75172 -71.476145) (xy 162.774656 -71.420772) (xy 162.804623 -71.368866)
			(xy 162.84111 -71.321316) (xy 162.88349 -71.278936) (xy 162.93104 -71.242449) (xy 162.982946 -71.212482)
			(xy 163.038319 -71.189546) (xy 163.096212 -71.174033) (xy 163.155634 -71.16621) (xy 163.21557 -71.16621)
			(xy 163.274992 -71.174033) (xy 163.332885 -71.189546) (xy 163.388258 -71.212482) (xy 163.440164 -71.242449)
			(xy 163.487714 -71.278936) (xy 163.530094 -71.321316) (xy 163.566581 -71.368866) (xy 163.596548 -71.420772)
			(xy 163.619484 -71.476145) (xy 163.634997 -71.534038) (xy 163.641816 -71.585832) (xy 187.219318 -71.585832)
			(xy 187.219318 -71.525896) (xy 187.227141 -71.466474) (xy 187.242654 -71.408581) (xy 187.26559 -71.353208)
			(xy 187.295557 -71.301302) (xy 187.332044 -71.253752) (xy 187.374424 -71.211372) (xy 187.421974 -71.174885)
			(xy 187.47388 -71.144918) (xy 187.529253 -71.121982) (xy 187.587146 -71.106469) (xy 187.646568 -71.098646)
			(xy 187.706504 -71.098646) (xy 187.765926 -71.106469) (xy 187.823819 -71.121982) (xy 187.879192 -71.144918)
			(xy 187.931098 -71.174885) (xy 187.978648 -71.211372) (xy 188.021028 -71.253752) (xy 188.057515 -71.301302)
			(xy 188.087482 -71.353208) (xy 188.110418 -71.408581) (xy 188.125931 -71.466474) (xy 188.133754 -71.525896)
			(xy 188.134244 -71.555864) (xy 188.133754 -71.585832) (xy 188.125931 -71.645254) (xy 188.123749 -71.653396)
			(xy 188.728332 -71.653396) (xy 188.728332 -71.59346) (xy 188.736155 -71.534038) (xy 188.751668 -71.476145)
			(xy 188.774604 -71.420772) (xy 188.804571 -71.368866) (xy 188.841058 -71.321316) (xy 188.883438 -71.278936)
			(xy 188.930988 -71.242449) (xy 188.982894 -71.212482) (xy 189.038267 -71.189546) (xy 189.09616 -71.174033)
			(xy 189.155582 -71.16621) (xy 189.215518 -71.16621) (xy 189.27494 -71.174033) (xy 189.332833 -71.189546)
			(xy 189.388206 -71.212482) (xy 189.440112 -71.242449) (xy 189.487662 -71.278936) (xy 189.530042 -71.321316)
			(xy 189.566529 -71.368866) (xy 189.596496 -71.420772) (xy 189.619432 -71.476145) (xy 189.634945 -71.534038)
			(xy 189.641764 -71.585832) (xy 213.219266 -71.585832) (xy 213.219266 -71.525896) (xy 213.227089 -71.466474)
			(xy 213.242602 -71.408581) (xy 213.265538 -71.353208) (xy 213.295505 -71.301302) (xy 213.331992 -71.253752)
			(xy 213.374372 -71.211372) (xy 213.421922 -71.174885) (xy 213.473828 -71.144918) (xy 213.529201 -71.121982)
			(xy 213.587094 -71.106469) (xy 213.646516 -71.098646) (xy 213.706452 -71.098646) (xy 213.765874 -71.106469)
			(xy 213.823767 -71.121982) (xy 213.87914 -71.144918) (xy 213.931046 -71.174885) (xy 213.978596 -71.211372)
			(xy 214.020976 -71.253752) (xy 214.057463 -71.301302) (xy 214.08743 -71.353208) (xy 214.110366 -71.408581)
			(xy 214.125879 -71.466474) (xy 214.133702 -71.525896) (xy 214.134192 -71.555864) (xy 214.133702 -71.585832)
			(xy 214.125879 -71.645254) (xy 214.123697 -71.653396) (xy 214.72828 -71.653396) (xy 214.72828 -71.59346)
			(xy 214.736103 -71.534038) (xy 214.751616 -71.476145) (xy 214.774552 -71.420772) (xy 214.804519 -71.368866)
			(xy 214.841006 -71.321316) (xy 214.883386 -71.278936) (xy 214.930936 -71.242449) (xy 214.982842 -71.212482)
			(xy 215.038215 -71.189546) (xy 215.096108 -71.174033) (xy 215.15553 -71.16621) (xy 215.215466 -71.16621)
			(xy 215.274888 -71.174033) (xy 215.332781 -71.189546) (xy 215.388154 -71.212482) (xy 215.44006 -71.242449)
			(xy 215.48761 -71.278936) (xy 215.52999 -71.321316) (xy 215.566477 -71.368866) (xy 215.596444 -71.420772)
			(xy 215.61938 -71.476145) (xy 215.634893 -71.534038) (xy 215.642716 -71.59346) (xy 215.643206 -71.623428)
			(xy 215.642716 -71.653396) (xy 215.634893 -71.712818) (xy 215.61938 -71.770711) (xy 215.596444 -71.826084)
			(xy 215.566477 -71.87799) (xy 215.52999 -71.92554) (xy 215.48761 -71.96792) (xy 215.44006 -72.004407)
			(xy 215.388154 -72.034374) (xy 215.332781 -72.05731) (xy 215.274888 -72.072823) (xy 215.215466 -72.080646)
			(xy 215.15553 -72.080646) (xy 215.096108 -72.072823) (xy 215.038215 -72.05731) (xy 214.982842 -72.034374)
			(xy 214.930936 -72.004407) (xy 214.883386 -71.96792) (xy 214.841006 -71.92554) (xy 214.804519 -71.87799)
			(xy 214.774552 -71.826084) (xy 214.751616 -71.770711) (xy 214.736103 -71.712818) (xy 214.72828 -71.653396)
			(xy 214.123697 -71.653396) (xy 214.110366 -71.703147) (xy 214.08743 -71.75852) (xy 214.057463 -71.810426)
			(xy 214.020976 -71.857976) (xy 213.978596 -71.900356) (xy 213.931046 -71.936843) (xy 213.87914 -71.96681)
			(xy 213.823767 -71.989746) (xy 213.765874 -72.005259) (xy 213.706452 -72.013082) (xy 213.646516 -72.013082)
			(xy 213.587094 -72.005259) (xy 213.529201 -71.989746) (xy 213.473828 -71.96681) (xy 213.421922 -71.936843)
			(xy 213.374372 -71.900356) (xy 213.331992 -71.857976) (xy 213.295505 -71.810426) (xy 213.265538 -71.75852)
			(xy 213.242602 -71.703147) (xy 213.227089 -71.645254) (xy 213.219266 -71.585832) (xy 189.641764 -71.585832)
			(xy 189.642768 -71.59346) (xy 189.643258 -71.623428) (xy 189.642768 -71.653396) (xy 189.634945 -71.712818)
			(xy 189.619432 -71.770711) (xy 189.596496 -71.826084) (xy 189.566529 -71.87799) (xy 189.530042 -71.92554)
			(xy 189.487662 -71.96792) (xy 189.440112 -72.004407) (xy 189.388206 -72.034374) (xy 189.332833 -72.05731)
			(xy 189.27494 -72.072823) (xy 189.215518 -72.080646) (xy 189.155582 -72.080646) (xy 189.09616 -72.072823)
			(xy 189.038267 -72.05731) (xy 188.982894 -72.034374) (xy 188.930988 -72.004407) (xy 188.883438 -71.96792)
			(xy 188.841058 -71.92554) (xy 188.804571 -71.87799) (xy 188.774604 -71.826084) (xy 188.751668 -71.770711)
			(xy 188.736155 -71.712818) (xy 188.728332 -71.653396) (xy 188.123749 -71.653396) (xy 188.110418 -71.703147)
			(xy 188.087482 -71.75852) (xy 188.057515 -71.810426) (xy 188.021028 -71.857976) (xy 187.978648 -71.900356)
			(xy 187.931098 -71.936843) (xy 187.879192 -71.96681) (xy 187.823819 -71.989746) (xy 187.765926 -72.005259)
			(xy 187.706504 -72.013082) (xy 187.646568 -72.013082) (xy 187.587146 -72.005259) (xy 187.529253 -71.989746)
			(xy 187.47388 -71.96681) (xy 187.421974 -71.936843) (xy 187.374424 -71.900356) (xy 187.332044 -71.857976)
			(xy 187.295557 -71.810426) (xy 187.26559 -71.75852) (xy 187.242654 -71.703147) (xy 187.227141 -71.645254)
			(xy 187.219318 -71.585832) (xy 163.641816 -71.585832) (xy 163.64282 -71.59346) (xy 163.64331 -71.623428)
			(xy 163.64282 -71.653396) (xy 163.634997 -71.712818) (xy 163.619484 -71.770711) (xy 163.596548 -71.826084)
			(xy 163.566581 -71.87799) (xy 163.530094 -71.92554) (xy 163.487714 -71.96792) (xy 163.440164 -72.004407)
			(xy 163.388258 -72.034374) (xy 163.332885 -72.05731) (xy 163.274992 -72.072823) (xy 163.21557 -72.080646)
			(xy 163.155634 -72.080646) (xy 163.096212 -72.072823) (xy 163.038319 -72.05731) (xy 162.982946 -72.034374)
			(xy 162.93104 -72.004407) (xy 162.88349 -71.96792) (xy 162.84111 -71.92554) (xy 162.804623 -71.87799)
			(xy 162.774656 -71.826084) (xy 162.75172 -71.770711) (xy 162.736207 -71.712818) (xy 162.728384 -71.653396)
			(xy 162.123801 -71.653396) (xy 162.11047 -71.703147) (xy 162.087534 -71.75852) (xy 162.057567 -71.810426)
			(xy 162.02108 -71.857976) (xy 161.9787 -71.900356) (xy 161.93115 -71.936843) (xy 161.879244 -71.96681)
			(xy 161.823871 -71.989746) (xy 161.765978 -72.005259) (xy 161.706556 -72.013082) (xy 161.64662 -72.013082)
			(xy 161.587198 -72.005259) (xy 161.529305 -71.989746) (xy 161.473932 -71.96681) (xy 161.422026 -71.936843)
			(xy 161.374476 -71.900356) (xy 161.332096 -71.857976) (xy 161.295609 -71.810426) (xy 161.265642 -71.75852)
			(xy 161.242706 -71.703147) (xy 161.227193 -71.645254) (xy 161.21937 -71.585832) (xy 137.641868 -71.585832)
			(xy 137.642872 -71.59346) (xy 137.643362 -71.623428) (xy 137.642872 -71.653396) (xy 137.635049 -71.712818)
			(xy 137.619536 -71.770711) (xy 137.5966 -71.826084) (xy 137.566633 -71.87799) (xy 137.530146 -71.92554)
			(xy 137.487766 -71.96792) (xy 137.440216 -72.004407) (xy 137.38831 -72.034374) (xy 137.332937 -72.05731)
			(xy 137.275044 -72.072823) (xy 137.215622 -72.080646) (xy 137.155686 -72.080646) (xy 137.096264 -72.072823)
			(xy 137.038371 -72.05731) (xy 136.982998 -72.034374) (xy 136.931092 -72.004407) (xy 136.883542 -71.96792)
			(xy 136.841162 -71.92554) (xy 136.804675 -71.87799) (xy 136.774708 -71.826084) (xy 136.751772 -71.770711)
			(xy 136.736259 -71.712818) (xy 136.728436 -71.653396) (xy 136.123853 -71.653396) (xy 136.110522 -71.703147)
			(xy 136.087586 -71.75852) (xy 136.057619 -71.810426) (xy 136.021132 -71.857976) (xy 135.978752 -71.900356)
			(xy 135.931202 -71.936843) (xy 135.879296 -71.96681) (xy 135.823923 -71.989746) (xy 135.76603 -72.005259)
			(xy 135.706608 -72.013082) (xy 135.646672 -72.013082) (xy 135.58725 -72.005259) (xy 135.529357 -71.989746)
			(xy 135.473984 -71.96681) (xy 135.422078 -71.936843) (xy 135.374528 -71.900356) (xy 135.332148 -71.857976)
			(xy 135.295661 -71.810426) (xy 135.265694 -71.75852) (xy 135.242758 -71.703147) (xy 135.227245 -71.645254)
			(xy 135.219422 -71.585832) (xy 99.541614 -71.585832) (xy 99.542618 -71.59346) (xy 99.543108 -71.623428)
			(xy 99.542618 -71.653396) (xy 99.534795 -71.712818) (xy 99.519282 -71.770711) (xy 99.496346 -71.826084)
			(xy 99.466379 -71.87799) (xy 99.429892 -71.92554) (xy 99.387512 -71.96792) (xy 99.339962 -72.004407)
			(xy 99.288056 -72.034374) (xy 99.232683 -72.05731) (xy 99.17479 -72.072823) (xy 99.115368 -72.080646)
			(xy 99.055432 -72.080646) (xy 98.99601 -72.072823) (xy 98.938117 -72.05731) (xy 98.882744 -72.034374)
			(xy 98.830838 -72.004407) (xy 98.783288 -71.96792) (xy 98.740908 -71.92554) (xy 98.704421 -71.87799)
			(xy 98.674454 -71.826084) (xy 98.651518 -71.770711) (xy 98.636005 -71.712818) (xy 98.628182 -71.653396)
			(xy 98.023599 -71.653396) (xy 98.010268 -71.703147) (xy 97.987332 -71.75852) (xy 97.957365 -71.810426)
			(xy 97.920878 -71.857976) (xy 97.878498 -71.900356) (xy 97.830948 -71.936843) (xy 97.779042 -71.96681)
			(xy 97.723669 -71.989746) (xy 97.665776 -72.005259) (xy 97.606354 -72.013082) (xy 97.546418 -72.013082)
			(xy 97.486996 -72.005259) (xy 97.429103 -71.989746) (xy 97.37373 -71.96681) (xy 97.321824 -71.936843)
			(xy 97.274274 -71.900356) (xy 97.231894 -71.857976) (xy 97.195407 -71.810426) (xy 97.16544 -71.75852)
			(xy 97.142504 -71.703147) (xy 97.126991 -71.645254) (xy 97.119168 -71.585832) (xy 73.541666 -71.585832)
			(xy 73.54267 -71.59346) (xy 73.54316 -71.623428) (xy 73.54267 -71.653396) (xy 73.534847 -71.712818)
			(xy 73.519334 -71.770711) (xy 73.496398 -71.826084) (xy 73.466431 -71.87799) (xy 73.429944 -71.92554)
			(xy 73.387564 -71.96792) (xy 73.340014 -72.004407) (xy 73.288108 -72.034374) (xy 73.232735 -72.05731)
			(xy 73.174842 -72.072823) (xy 73.11542 -72.080646) (xy 73.055484 -72.080646) (xy 72.996062 -72.072823)
			(xy 72.938169 -72.05731) (xy 72.882796 -72.034374) (xy 72.83089 -72.004407) (xy 72.78334 -71.96792)
			(xy 72.74096 -71.92554) (xy 72.704473 -71.87799) (xy 72.674506 -71.826084) (xy 72.65157 -71.770711)
			(xy 72.636057 -71.712818) (xy 72.628234 -71.653396) (xy 72.023651 -71.653396) (xy 72.01032 -71.703147)
			(xy 71.987384 -71.75852) (xy 71.957417 -71.810426) (xy 71.92093 -71.857976) (xy 71.87855 -71.900356)
			(xy 71.831 -71.936843) (xy 71.779094 -71.96681) (xy 71.723721 -71.989746) (xy 71.665828 -72.005259)
			(xy 71.606406 -72.013082) (xy 71.54647 -72.013082) (xy 71.487048 -72.005259) (xy 71.429155 -71.989746)
			(xy 71.373782 -71.96681) (xy 71.321876 -71.936843) (xy 71.274326 -71.900356) (xy 71.231946 -71.857976)
			(xy 71.195459 -71.810426) (xy 71.165492 -71.75852) (xy 71.142556 -71.703147) (xy 71.127043 -71.645254)
			(xy 71.11922 -71.585832) (xy 47.541718 -71.585832) (xy 47.542722 -71.59346) (xy 47.543212 -71.623428)
			(xy 47.542722 -71.653396) (xy 47.534899 -71.712818) (xy 47.519386 -71.770711) (xy 47.49645 -71.826084)
			(xy 47.466483 -71.87799) (xy 47.429996 -71.92554) (xy 47.387616 -71.96792) (xy 47.340066 -72.004407)
			(xy 47.28816 -72.034374) (xy 47.232787 -72.05731) (xy 47.174894 -72.072823) (xy 47.115472 -72.080646)
			(xy 47.055536 -72.080646) (xy 46.996114 -72.072823) (xy 46.938221 -72.05731) (xy 46.882848 -72.034374)
			(xy 46.830942 -72.004407) (xy 46.783392 -71.96792) (xy 46.741012 -71.92554) (xy 46.704525 -71.87799)
			(xy 46.674558 -71.826084) (xy 46.651622 -71.770711) (xy 46.636109 -71.712818) (xy 46.628286 -71.653396)
			(xy 46.023703 -71.653396) (xy 46.010372 -71.703147) (xy 45.987436 -71.75852) (xy 45.957469 -71.810426)
			(xy 45.920982 -71.857976) (xy 45.878602 -71.900356) (xy 45.831052 -71.936843) (xy 45.779146 -71.96681)
			(xy 45.723773 -71.989746) (xy 45.66588 -72.005259) (xy 45.606458 -72.013082) (xy 45.546522 -72.013082)
			(xy 45.4871 -72.005259) (xy 45.429207 -71.989746) (xy 45.373834 -71.96681) (xy 45.321928 -71.936843)
			(xy 45.274378 -71.900356) (xy 45.231998 -71.857976) (xy 45.195511 -71.810426) (xy 45.165544 -71.75852)
			(xy 45.142608 -71.703147) (xy 45.127095 -71.645254) (xy 45.119272 -71.585832) (xy 21.54177 -71.585832)
			(xy 21.542774 -71.59346) (xy 21.543264 -71.623428) (xy 21.542774 -71.653396) (xy 21.534951 -71.712818)
			(xy 21.519438 -71.770711) (xy 21.496502 -71.826084) (xy 21.466535 -71.87799) (xy 21.430048 -71.92554)
			(xy 21.387668 -71.96792) (xy 21.340118 -72.004407) (xy 21.288212 -72.034374) (xy 21.232839 -72.05731)
			(xy 21.174946 -72.072823) (xy 21.115524 -72.080646) (xy 21.055588 -72.080646) (xy 20.996166 -72.072823)
			(xy 20.938273 -72.05731) (xy 20.8829 -72.034374) (xy 20.830994 -72.004407) (xy 20.783444 -71.96792)
			(xy 20.741064 -71.92554) (xy 20.704577 -71.87799) (xy 20.67461 -71.826084) (xy 20.651674 -71.770711)
			(xy 20.636161 -71.712818) (xy 20.628338 -71.653396) (xy 20.023755 -71.653396) (xy 20.010424 -71.703147)
			(xy 19.987488 -71.75852) (xy 19.957521 -71.810426) (xy 19.921034 -71.857976) (xy 19.878654 -71.900356)
			(xy 19.831104 -71.936843) (xy 19.779198 -71.96681) (xy 19.723825 -71.989746) (xy 19.665932 -72.005259)
			(xy 19.60651 -72.013082) (xy 19.546574 -72.013082) (xy 19.487152 -72.005259) (xy 19.429259 -71.989746)
			(xy 19.373886 -71.96681) (xy 19.32198 -71.936843) (xy 19.27443 -71.900356) (xy 19.23205 -71.857976)
			(xy 19.195563 -71.810426) (xy 19.165596 -71.75852) (xy 19.14266 -71.703147) (xy 19.127147 -71.645254)
			(xy 19.119324 -71.585832) (xy 7.816181 -71.585832) (xy 7.80641 -71.609422) (xy 7.776443 -71.661328)
			(xy 7.739956 -71.708878) (xy 7.697576 -71.751258) (xy 7.650026 -71.787745) (xy 7.59812 -71.817712)
			(xy 7.542747 -71.840648) (xy 7.484854 -71.856161) (xy 7.425432 -71.863984) (xy 7.365496 -71.863984)
			(xy 7.306074 -71.856161) (xy 7.248181 -71.840648) (xy 7.192808 -71.817712) (xy 7.140902 -71.787745)
			(xy 7.093352 -71.751258) (xy 7.050972 -71.708878) (xy 7.014485 -71.661328) (xy 6.984518 -71.609422)
			(xy 6.961582 -71.554049) (xy 6.946069 -71.496156) (xy 6.938246 -71.436734) (xy 4.151958 -71.436734)
			(xy 4.171924 -71.471318) (xy 4.19486 -71.526691) (xy 4.210373 -71.584584) (xy 4.218196 -71.644006)
			(xy 4.218686 -71.673974) (xy 4.218196 -71.703942) (xy 4.210373 -71.763364) (xy 4.19486 -71.821257)
			(xy 4.171924 -71.87663) (xy 4.141957 -71.928536) (xy 4.10547 -71.976086) (xy 4.06309 -72.018466)
			(xy 4.01554 -72.054953) (xy 3.963634 -72.08492) (xy 3.908261 -72.107856) (xy 3.850368 -72.123369)
			(xy 3.790946 -72.131192) (xy 3.73101 -72.131192) (xy 3.671588 -72.123369) (xy 3.613695 -72.107856)
			(xy 3.558322 -72.08492) (xy 3.506416 -72.054953) (xy 3.458866 -72.018466) (xy 3.416486 -71.976086)
			(xy 3.379999 -71.928536) (xy 3.350032 -71.87663) (xy 3.327096 -71.821257) (xy 3.311583 -71.763364)
			(xy 3.30376 -71.703942) (xy 2.308655 -71.703942) (xy 2.264373 -71.722284) (xy 2.20648 -71.737797)
			(xy 2.147058 -71.74562) (xy 2.087122 -71.74562) (xy 2.0277 -71.737797) (xy 1.969807 -71.722284) (xy 1.914434 -71.699348)
			(xy 1.862528 -71.669381) (xy 1.814978 -71.632894) (xy 1.772598 -71.590514) (xy 1.736111 -71.542964)
			(xy 1.706144 -71.491058) (xy 1.683208 -71.435685) (xy 1.667695 -71.377792) (xy 1.659872 -71.31837)
			(xy 1.384808 -71.31837) (xy 1.384808 -73.319636) (xy 3.479528 -73.319636) (xy 3.479528 -73.2597)
			(xy 3.487351 -73.200278) (xy 3.502864 -73.142385) (xy 3.5258 -73.087012) (xy 3.555767 -73.035106)
			(xy 3.592254 -72.987556) (xy 3.634634 -72.945176) (xy 3.682184 -72.908689) (xy 3.73409 -72.878722)
			(xy 3.789463 -72.855786) (xy 3.847356 -72.840273) (xy 3.906778 -72.83245) (xy 3.966714 -72.83245)
			(xy 4.026136 -72.840273) (xy 4.084029 -72.855786) (xy 4.139402 -72.878722) (xy 4.191308 -72.908689)
			(xy 4.238858 -72.945176) (xy 4.281238 -72.987556) (xy 4.317568 -73.034902) (xy 200.273902 -73.034902)
			(xy 200.273902 -72.974966) (xy 200.281725 -72.915544) (xy 200.297238 -72.857651) (xy 200.320174 -72.802278)
			(xy 200.350141 -72.750372) (xy 200.386628 -72.702822) (xy 200.429008 -72.660442) (xy 200.476558 -72.623955)
			(xy 200.528464 -72.593988) (xy 200.583837 -72.571052) (xy 200.64173 -72.555539) (xy 200.701152 -72.547716)
			(xy 200.761088 -72.547716) (xy 200.82051 -72.555539) (xy 200.878403 -72.571052) (xy 200.933776 -72.593988)
			(xy 200.985682 -72.623955) (xy 201.033232 -72.660442) (xy 201.075612 -72.702822) (xy 201.112099 -72.750372)
			(xy 201.142066 -72.802278) (xy 201.165002 -72.857651) (xy 201.180515 -72.915544) (xy 201.188338 -72.974966)
			(xy 201.188828 -73.004934) (xy 201.188338 -73.034902) (xy 201.180515 -73.094324) (xy 201.165002 -73.152217)
			(xy 201.142066 -73.20759) (xy 201.112099 -73.259496) (xy 201.075612 -73.307046) (xy 201.033232 -73.349426)
			(xy 200.985682 -73.385913) (xy 200.933776 -73.41588) (xy 200.878403 -73.438816) (xy 200.82051 -73.454329)
			(xy 200.761088 -73.462152) (xy 200.701152 -73.462152) (xy 200.64173 -73.454329) (xy 200.583837 -73.438816)
			(xy 200.528464 -73.41588) (xy 200.476558 -73.385913) (xy 200.429008 -73.349426) (xy 200.386628 -73.307046)
			(xy 200.350141 -73.259496) (xy 200.320174 -73.20759) (xy 200.297238 -73.152217) (xy 200.281725 -73.094324)
			(xy 200.273902 -73.034902) (xy 4.317568 -73.034902) (xy 4.317725 -73.035106) (xy 4.347692 -73.087012)
			(xy 4.370628 -73.142385) (xy 4.386141 -73.200278) (xy 4.393964 -73.2597) (xy 4.394454 -73.289668)
			(xy 4.393964 -73.319636) (xy 4.386141 -73.379058) (xy 4.370628 -73.436951) (xy 4.347692 -73.492324)
			(xy 4.317725 -73.54423) (xy 4.281238 -73.59178) (xy 4.238858 -73.63416) (xy 4.191308 -73.670647)
			(xy 4.139402 -73.700614) (xy 4.084029 -73.72355) (xy 4.026136 -73.739063) (xy 3.966714 -73.746886)
			(xy 3.906778 -73.746886) (xy 3.847356 -73.739063) (xy 3.789463 -73.72355) (xy 3.73409 -73.700614)
			(xy 3.682184 -73.670647) (xy 3.634634 -73.63416) (xy 3.592254 -73.59178) (xy 3.555767 -73.54423)
			(xy 3.5258 -73.492324) (xy 3.502864 -73.436951) (xy 3.487351 -73.379058) (xy 3.479528 -73.319636)
			(xy 1.384808 -73.319636) (xy 1.384808 -74.106024) (xy 8.468612 -74.106024) (xy 8.472683 -74.050402)
			(xy 8.484809 -73.995965) (xy 8.504732 -73.943874) (xy 8.532028 -73.895239) (xy 8.566114 -73.851096)
			(xy 8.606263 -73.812387) (xy 8.651621 -73.779936) (xy 8.701221 -73.754435) (xy 8.754005 -73.736428)
			(xy 8.808848 -73.726298) (xy 8.864582 -73.724261) (xy 8.920019 -73.730361) (xy 8.973976 -73.744467)
			(xy 9.025305 -73.766279) (xy 9.072911 -73.795333) (xy 9.090977 -73.810368) (xy 90.899486 -73.810368)
			(xy 90.903557 -73.754746) (xy 90.915683 -73.700309) (xy 90.935606 -73.648218) (xy 90.962902 -73.599583)
			(xy 90.996988 -73.55544) (xy 91.037137 -73.516731) (xy 91.082495 -73.48428) (xy 91.132095 -73.458779)
			(xy 91.184879 -73.440772) (xy 91.239722 -73.430642) (xy 91.295456 -73.428605) (xy 91.350893 -73.434705)
			(xy 91.40485 -73.448811) (xy 91.456179 -73.470623) (xy 91.503785 -73.499677) (xy 91.546653 -73.535352)
			(xy 91.58387 -73.576889) (xy 91.614643 -73.623402) (xy 91.638315 -73.673899) (xy 91.654383 -73.727306)
			(xy 91.662503 -73.782482) (xy 91.663012 -73.810368) (xy 91.662503 -73.838254) (xy 91.654383 -73.89343)
			(xy 91.638315 -73.946837) (xy 91.614643 -73.997334) (xy 91.58387 -74.043847) (xy 91.546653 -74.085384)
			(xy 91.503785 -74.121059) (xy 91.456179 -74.150113) (xy 91.40485 -74.171925) (xy 91.350893 -74.186031)
			(xy 91.295456 -74.192131) (xy 91.239722 -74.190094) (xy 91.184879 -74.179964) (xy 91.132095 -74.161957)
			(xy 91.082495 -74.136456) (xy 91.037137 -74.104005) (xy 90.996988 -74.065296) (xy 90.962902 -74.021153)
			(xy 90.935606 -73.972518) (xy 90.915683 -73.920427) (xy 90.903557 -73.86599) (xy 90.899486 -73.810368)
			(xy 9.090977 -73.810368) (xy 9.115779 -73.831008) (xy 9.152996 -73.872545) (xy 9.183769 -73.919058)
			(xy 9.207441 -73.969555) (xy 9.223509 -74.022962) (xy 9.231629 -74.078138) (xy 9.232138 -74.106024)
			(xy 9.231629 -74.13391) (xy 9.223509 -74.189086) (xy 9.207441 -74.242493) (xy 9.183769 -74.29299)
			(xy 9.152996 -74.339503) (xy 9.115779 -74.38104) (xy 9.072911 -74.416715) (xy 9.025305 -74.445769)
			(xy 8.993981 -74.45908) (xy 199.303876 -74.45908) (xy 199.303876 -74.399144) (xy 199.311699 -74.339722)
			(xy 199.327212 -74.281829) (xy 199.350148 -74.226456) (xy 199.380115 -74.17455) (xy 199.416602 -74.127)
			(xy 199.458982 -74.08462) (xy 199.506532 -74.048133) (xy 199.558438 -74.018166) (xy 199.613811 -73.99523)
			(xy 199.671704 -73.979717) (xy 199.731126 -73.971894) (xy 199.791062 -73.971894) (xy 199.850484 -73.979717)
			(xy 199.908377 -73.99523) (xy 199.96375 -74.018166) (xy 200.015656 -74.048133) (xy 200.063206 -74.08462)
			(xy 200.105586 -74.127) (xy 200.142073 -74.17455) (xy 200.17204 -74.226456) (xy 200.194976 -74.281829)
			(xy 200.210489 -74.339722) (xy 200.218312 -74.399144) (xy 200.218802 -74.429112) (xy 200.218312 -74.45908)
			(xy 200.210489 -74.518502) (xy 200.194976 -74.576395) (xy 200.183072 -74.605134) (xy 222.27997 -74.605134)
			(xy 222.284041 -74.549512) (xy 222.296167 -74.495075) (xy 222.31609 -74.442984) (xy 222.343386 -74.394349)
			(xy 222.377472 -74.350206) (xy 222.417621 -74.311497) (xy 222.462979 -74.279046) (xy 222.512579 -74.253545)
			(xy 222.565363 -74.235538) (xy 222.620206 -74.225408) (xy 222.67594 -74.223371) (xy 222.731377 -74.229471)
			(xy 222.785334 -74.243577) (xy 222.836663 -74.265389) (xy 222.884269 -74.294443) (xy 222.927137 -74.330118)
			(xy 222.964354 -74.371655) (xy 222.995127 -74.418168) (xy 223.018799 -74.468665) (xy 223.034867 -74.522072)
			(xy 223.042987 -74.577248) (xy 223.043496 -74.605134) (xy 223.042987 -74.63302) (xy 223.034867 -74.688196)
			(xy 223.018799 -74.741603) (xy 222.995127 -74.7921) (xy 222.964354 -74.838613) (xy 222.927137 -74.88015)
			(xy 222.884269 -74.915825) (xy 222.836663 -74.944879) (xy 222.785334 -74.966691) (xy 222.731377 -74.980797)
			(xy 222.67594 -74.986897) (xy 222.620206 -74.98486) (xy 222.565363 -74.97473) (xy 222.512579 -74.956723)
			(xy 222.462979 -74.931222) (xy 222.417621 -74.898771) (xy 222.377472 -74.860062) (xy 222.343386 -74.815919)
			(xy 222.31609 -74.767284) (xy 222.296167 -74.715193) (xy 222.284041 -74.660756) (xy 222.27997 -74.605134)
			(xy 200.183072 -74.605134) (xy 200.17204 -74.631768) (xy 200.142073 -74.683674) (xy 200.105586 -74.731224)
			(xy 200.063206 -74.773604) (xy 200.015656 -74.810091) (xy 199.96375 -74.840058) (xy 199.908377 -74.862994)
			(xy 199.850484 -74.878507) (xy 199.791062 -74.88633) (xy 199.731126 -74.88633) (xy 199.671704 -74.878507)
			(xy 199.613811 -74.862994) (xy 199.558438 -74.840058) (xy 199.506532 -74.810091) (xy 199.458982 -74.773604)
			(xy 199.416602 -74.731224) (xy 199.380115 -74.683674) (xy 199.350148 -74.631768) (xy 199.327212 -74.576395)
			(xy 199.311699 -74.518502) (xy 199.303876 -74.45908) (xy 8.993981 -74.45908) (xy 8.973976 -74.467581)
			(xy 8.920019 -74.481687) (xy 8.864582 -74.487787) (xy 8.808848 -74.48575) (xy 8.754005 -74.47562)
			(xy 8.701221 -74.457613) (xy 8.651621 -74.432112) (xy 8.606263 -74.399661) (xy 8.566114 -74.360952)
			(xy 8.532028 -74.316809) (xy 8.504732 -74.268174) (xy 8.484809 -74.216083) (xy 8.472683 -74.161646)
			(xy 8.468612 -74.106024) (xy 1.384808 -74.106024) (xy 1.384808 -75.087226) (xy 6.381748 -75.087226)
			(xy 6.385819 -75.031604) (xy 6.397945 -74.977167) (xy 6.417868 -74.925076) (xy 6.445164 -74.876441)
			(xy 6.47925 -74.832298) (xy 6.519399 -74.793589) (xy 6.564757 -74.761138) (xy 6.614357 -74.735637)
			(xy 6.667141 -74.71763) (xy 6.721984 -74.7075) (xy 6.777718 -74.705463) (xy 6.833155 -74.711563)
			(xy 6.887112 -74.725669) (xy 6.938441 -74.747481) (xy 6.986047 -74.776535) (xy 7.028915 -74.81221)
			(xy 7.066132 -74.853747) (xy 7.096905 -74.90026) (xy 7.120577 -74.950757) (xy 7.136645 -75.004164)
			(xy 7.144765 -75.05934) (xy 7.145274 -75.087226) (xy 7.144765 -75.115112) (xy 7.136645 -75.170288)
			(xy 7.120577 -75.223695) (xy 7.096905 -75.274192) (xy 7.066132 -75.320705) (xy 7.028915 -75.362242)
			(xy 6.986047 -75.397917) (xy 6.938441 -75.426971) (xy 6.887112 -75.448783) (xy 6.833155 -75.462889)
			(xy 6.777718 -75.468989) (xy 6.721984 -75.466952) (xy 6.667141 -75.456822) (xy 6.614357 -75.438815)
			(xy 6.564757 -75.413314) (xy 6.519399 -75.380863) (xy 6.47925 -75.342154) (xy 6.445164 -75.298011)
			(xy 6.417868 -75.249376) (xy 6.397945 -75.197285) (xy 6.385819 -75.142848) (xy 6.381748 -75.087226)
			(xy 1.384808 -75.087226) (xy 1.384808 -77.518514) (xy 1.385234 -77.528583) (xy 1.392953 -77.547183)
			(xy 1.399794 -77.554582) (xy 2.55143 -78.706218) (xy 2.558826 -78.713069) (xy 2.577425 -78.720805)
			(xy 2.587498 -78.721204)
		)
		(stroke
			(width 0)
			(type solid)
		)
		(fill yes)
		(layer "B.Cu")
		(net "GND")
	)
	(gr_poly
		(pts
			(xy 414.848548 -130.789172) (xy 414.858547 -130.788675) (xy 414.877018 -130.781006) (xy 414.891149 -130.766854)
			(xy 414.89879 -130.748372) (xy 414.899348 -130.738372) (xy 414.899348 -129.913634) (xy 414.899856 -129.893568)
			(xy 414.89984 -129.882027) (xy 414.89072 -129.860852) (xy 414.88233 -129.852928) (xy 414.857946 -129.831846)
			(xy 414.848928 -129.824957) (xy 414.827049 -129.819044) (xy 414.815782 -129.820416) (xy 414.798909 -129.823271)
			(xy 414.764822 -129.826328) (xy 414.74771 -129.826512) (xy 414.720456 -129.826049) (xy 414.666504 -129.818293)
			(xy 414.614204 -129.802938) (xy 414.564622 -129.780296) (xy 414.518767 -129.750828) (xy 414.477573 -129.715134)
			(xy 414.441878 -129.673941) (xy 414.412409 -129.628086) (xy 414.389765 -129.578505) (xy 414.374409 -129.526206)
			(xy 414.366651 -129.472254) (xy 414.366651 -129.417746) (xy 414.374409 -129.363794) (xy 414.389765 -129.311495)
			(xy 414.412409 -129.261914) (xy 414.441878 -129.216059) (xy 414.477573 -129.174866) (xy 414.518767 -129.139172)
			(xy 414.564622 -129.109704) (xy 414.614204 -129.087062) (xy 414.666504 -129.071707) (xy 414.720456 -129.063951)
			(xy 414.74771 -129.063496) (xy 414.774716 -129.063965) (xy 414.828189 -129.071582) (xy 414.880054 -129.086664)
			(xy 414.929274 -129.108908) (xy 414.974865 -129.13787) (xy 415.015917 -129.172972) (xy 415.051609 -129.213512)
			(xy 415.081228 -129.258679) (xy 415.104183 -129.307571) (xy 415.120013 -129.359212) (xy 415.124646 -129.385822)
			(xy 415.12617 -129.39649) (xy 415.1376 -129.41427) (xy 415.217864 -129.46761) (xy 415.238438 -129.47142)
			(xy 415.249106 -129.46888) (xy 415.275738 -129.462751) (xy 415.329986 -129.456135) (xy 415.35731 -129.455672)
			(xy 415.384634 -129.456128) (xy 415.438883 -129.462746) (xy 415.465514 -129.46888) (xy 415.476182 -129.47142)
			(xy 415.496756 -129.46761) (xy 415.57702 -129.41427) (xy 415.58845 -129.39649) (xy 415.589974 -129.385822)
			(xy 415.594627 -129.359217) (xy 415.610449 -129.307576) (xy 415.633397 -129.258683) (xy 415.663012 -129.213517)
			(xy 415.698703 -129.172979) (xy 415.739754 -129.137881) (xy 415.785346 -129.108925) (xy 415.834567 -129.08669)
			(xy 415.886432 -129.07162) (xy 415.939905 -129.064017) (xy 415.96691 -129.063496) (xy 415.99416 -129.063982)
			(xy 416.048107 -129.07174) (xy 416.1004 -129.087096) (xy 416.149975 -129.109737) (xy 416.195824 -129.139204)
			(xy 416.237012 -129.174895) (xy 416.272702 -129.216084) (xy 416.302167 -129.261934) (xy 416.324808 -129.31151)
			(xy 416.340162 -129.363803) (xy 416.347918 -129.417749) (xy 416.347918 -129.445004) (xy 417.566092 -129.445004)
			(xy 417.570163 -129.389382) (xy 417.582289 -129.334945) (xy 417.602212 -129.282854) (xy 417.629508 -129.234219)
			(xy 417.663594 -129.190076) (xy 417.703743 -129.151367) (xy 417.749101 -129.118916) (xy 417.798701 -129.093415)
			(xy 417.851485 -129.075408) (xy 417.906328 -129.065278) (xy 417.962062 -129.063241) (xy 418.017499 -129.069341)
			(xy 418.071456 -129.083447) (xy 418.122785 -129.105259) (xy 418.170391 -129.134313) (xy 418.213259 -129.169988)
			(xy 418.250476 -129.211525) (xy 418.281249 -129.258038) (xy 418.304921 -129.308535) (xy 418.320989 -129.361942)
			(xy 418.329109 -129.417118) (xy 418.329618 -129.445004) (xy 420.185086 -129.445004) (xy 420.189157 -129.389382)
			(xy 420.201283 -129.334945) (xy 420.221206 -129.282854) (xy 420.248502 -129.234219) (xy 420.282588 -129.190076)
			(xy 420.322737 -129.151367) (xy 420.368095 -129.118916) (xy 420.417695 -129.093415) (xy 420.470479 -129.075408)
			(xy 420.525322 -129.065278) (xy 420.581056 -129.063241) (xy 420.636493 -129.069341) (xy 420.69045 -129.083447)
			(xy 420.741779 -129.105259) (xy 420.789385 -129.134313) (xy 420.832253 -129.169988) (xy 420.86947 -129.211525)
			(xy 420.900243 -129.258038) (xy 420.923915 -129.308535) (xy 420.939983 -129.361942) (xy 420.948103 -129.417118)
			(xy 420.948612 -129.445004) (xy 422.166286 -129.445004) (xy 422.170357 -129.389382) (xy 422.182483 -129.334945)
			(xy 422.202406 -129.282854) (xy 422.229702 -129.234219) (xy 422.263788 -129.190076) (xy 422.303937 -129.151367)
			(xy 422.349295 -129.118916) (xy 422.398895 -129.093415) (xy 422.451679 -129.075408) (xy 422.506522 -129.065278)
			(xy 422.562256 -129.063241) (xy 422.617693 -129.069341) (xy 422.67165 -129.083447) (xy 422.722979 -129.105259)
			(xy 422.770585 -129.134313) (xy 422.813453 -129.169988) (xy 422.85067 -129.211525) (xy 422.881443 -129.258038)
			(xy 422.905115 -129.308535) (xy 422.921183 -129.361942) (xy 422.929303 -129.417118) (xy 422.929812 -129.445004)
			(xy 422.929303 -129.47289) (xy 422.921183 -129.528066) (xy 422.905115 -129.581473) (xy 422.881443 -129.63197)
			(xy 422.85067 -129.678483) (xy 422.813453 -129.72002) (xy 422.770585 -129.755695) (xy 422.722979 -129.784749)
			(xy 422.67165 -129.806561) (xy 422.617693 -129.820667) (xy 422.562256 -129.826767) (xy 422.506522 -129.82473)
			(xy 422.451679 -129.8146) (xy 422.398895 -129.796593) (xy 422.349295 -129.771092) (xy 422.303937 -129.738641)
			(xy 422.263788 -129.699932) (xy 422.229702 -129.655789) (xy 422.202406 -129.607154) (xy 422.182483 -129.555063)
			(xy 422.170357 -129.500626) (xy 422.166286 -129.445004) (xy 420.948612 -129.445004) (xy 420.948103 -129.47289)
			(xy 420.939983 -129.528066) (xy 420.923915 -129.581473) (xy 420.900243 -129.63197) (xy 420.86947 -129.678483)
			(xy 420.832253 -129.72002) (xy 420.789385 -129.755695) (xy 420.741779 -129.784749) (xy 420.69045 -129.806561)
			(xy 420.636493 -129.820667) (xy 420.581056 -129.826767) (xy 420.525322 -129.82473) (xy 420.470479 -129.8146)
			(xy 420.417695 -129.796593) (xy 420.368095 -129.771092) (xy 420.322737 -129.738641) (xy 420.282588 -129.699932)
			(xy 420.248502 -129.655789) (xy 420.221206 -129.607154) (xy 420.201283 -129.555063) (xy 420.189157 -129.500626)
			(xy 420.185086 -129.445004) (xy 418.329618 -129.445004) (xy 418.329109 -129.47289) (xy 418.320989 -129.528066)
			(xy 418.304921 -129.581473) (xy 418.281249 -129.63197) (xy 418.250476 -129.678483) (xy 418.213259 -129.72002)
			(xy 418.170391 -129.755695) (xy 418.122785 -129.784749) (xy 418.071456 -129.806561) (xy 418.017499 -129.820667)
			(xy 417.962062 -129.826767) (xy 417.906328 -129.82473) (xy 417.851485 -129.8146) (xy 417.798701 -129.796593)
			(xy 417.749101 -129.771092) (xy 417.703743 -129.738641) (xy 417.663594 -129.699932) (xy 417.629508 -129.655789)
			(xy 417.602212 -129.607154) (xy 417.582289 -129.555063) (xy 417.570163 -129.500626) (xy 417.566092 -129.445004)
			(xy 416.347918 -129.445004) (xy 416.347918 -129.472251) (xy 416.340162 -129.526197) (xy 416.324808 -129.57849)
			(xy 416.302167 -129.628066) (xy 416.272702 -129.673916) (xy 416.237012 -129.715105) (xy 416.195824 -129.750796)
			(xy 416.149975 -129.780263) (xy 416.1004 -129.802904) (xy 416.048107 -129.81826) (xy 415.99416 -129.826018)
			(xy 415.96691 -129.826512) (xy 415.949798 -129.826336) (xy 415.91571 -129.823279) (xy 415.898838 -129.820416)
			(xy 415.887571 -129.818977) (xy 415.86568 -129.824922) (xy 415.856674 -129.831846) (xy 415.83229 -129.852928)
			(xy 415.824042 -129.860954) (xy 415.814948 -129.88206) (xy 415.814764 -129.893568) (xy 415.815272 -129.913634)
			(xy 415.815272 -130.738372) (xy 415.815755 -130.748385) (xy 415.823408 -130.766892) (xy 415.837561 -130.78106)
			(xy 415.856059 -130.788734) (xy 415.866072 -130.789172) (xy 417.641532 -130.789172) (xy 417.651231 -130.788746)
			(xy 417.669254 -130.781568) (xy 417.676584 -130.775202) (xy 417.734496 -130.71983) (xy 417.742624 -130.702304)
			(xy 417.743132 -130.692398) (xy 417.744935 -130.664768) (xy 417.755522 -130.610421) (xy 417.773855 -130.558176)
			(xy 417.79955 -130.509131) (xy 417.832066 -130.464316) (xy 417.87072 -130.424673) (xy 417.9147 -130.391036)
			(xy 417.963081 -130.364111) (xy 418.014847 -130.344464) (xy 418.068909 -130.332509) (xy 418.124132 -130.328495)
			(xy 418.179355 -130.332509) (xy 418.233417 -130.344464) (xy 418.285183 -130.364111) (xy 418.333564 -130.391036)
			(xy 418.377544 -130.424673) (xy 418.416198 -130.464316) (xy 418.448714 -130.509131) (xy 418.474409 -130.558176)
			(xy 418.492742 -130.610421) (xy 418.503329 -130.664768) (xy 418.505132 -130.692398) (xy 418.50564 -130.702304)
			(xy 418.513768 -130.71983) (xy 418.57168 -130.775202) (xy 418.579001 -130.781586) (xy 418.597027 -130.788778)
			(xy 418.606732 -130.789172) (xy 428.831248 -130.789172) (xy 428.839859 -130.788834) (xy 428.856115 -130.783148)
			(xy 428.869592 -130.772426) (xy 428.874428 -130.765296) (xy 428.889438 -130.742068) (xy 428.925102 -130.699801)
			(xy 428.966498 -130.66313) (xy 429.012758 -130.632824) (xy 429.062911 -130.609519) (xy 429.115904 -130.593705)
			(xy 429.170627 -130.585712) (xy 429.198278 -130.58521) (xy 429.213071 -130.585355) (xy 429.242567 -130.587647)
			(xy 429.257206 -130.589782) (xy 429.268128 -130.59156) (xy 429.289464 -130.585464) (xy 429.356774 -130.52806)
			(xy 429.364728 -130.520456) (xy 429.373824 -130.500444) (xy 429.3743 -130.489452) (xy 429.3743 -130.18516)
			(xy 429.373819 -130.174167) (xy 429.364731 -130.154153) (xy 429.356774 -130.146552) (xy 429.289464 -130.089148)
			(xy 429.268128 -130.083052) (xy 429.257206 -130.08483) (xy 429.242569 -130.086977) (xy 429.213071 -130.089266)
			(xy 429.198278 -130.089402) (xy 429.171028 -130.088915) (xy 429.117084 -130.081156) (xy 429.064792 -130.065799)
			(xy 429.015219 -130.043157) (xy 428.969372 -130.013691) (xy 428.928185 -129.978) (xy 428.892496 -129.936811)
			(xy 428.863032 -129.890962) (xy 428.840393 -129.841387) (xy 428.82504 -129.789095) (xy 428.817284 -129.73515)
			(xy 428.817284 -129.68065) (xy 428.82504 -129.626705) (xy 428.840393 -129.574413) (xy 428.863032 -129.524838)
			(xy 428.892496 -129.478989) (xy 428.928185 -129.4378) (xy 428.969372 -129.402109) (xy 429.015219 -129.372643)
			(xy 429.064792 -129.350001) (xy 429.117084 -129.334644) (xy 429.171028 -129.326885) (xy 429.198278 -129.326386)
			(xy 429.224208 -129.3268) (xy 429.275594 -129.333785) (xy 429.32556 -129.34767) (xy 429.373182 -129.368198)
			(xy 429.417584 -129.394991) (xy 429.457944 -129.427555) (xy 429.493519 -129.465288) (xy 429.50892 -129.486152)
			(xy 429.51465 -129.493495) (xy 429.530156 -129.503784) (xy 429.539146 -129.506218) (xy 429.569372 -129.513076)
			(xy 429.578652 -129.514727) (xy 429.597286 -129.512001) (xy 429.605694 -129.507742) (xy 429.631679 -129.493471)
			(xy 429.686541 -129.470998) (xy 429.743839 -129.455777) (xy 429.80262 -129.448061) (xy 429.832262 -129.447544)
			(xy 429.861907 -129.448026) (xy 429.920696 -129.455717) (xy 429.977996 -129.470949) (xy 430.032844 -129.493466)
			(xy 430.05883 -129.507742) (xy 430.067212 -129.512087) (xy 430.085876 -129.514831) (xy 430.095152 -129.513076)
			(xy 430.125378 -129.506218) (xy 430.134362 -129.50377) (xy 430.149866 -129.493484) (xy 430.155604 -129.486152)
			(xy 430.171033 -129.465314) (xy 430.206618 -129.427603) (xy 430.246981 -129.395057) (xy 430.291378 -129.368274)
			(xy 430.338992 -129.347749) (xy 430.388946 -129.333859) (xy 430.440321 -129.326859) (xy 430.466246 -129.326386)
			(xy 430.493496 -129.326875) (xy 430.547439 -129.334637) (xy 430.599729 -129.349996) (xy 430.649301 -129.37264)
			(xy 430.695147 -129.402108) (xy 430.736332 -129.4378) (xy 430.772019 -129.47899) (xy 430.801482 -129.524839)
			(xy 430.82412 -129.574414) (xy 430.839473 -129.626706) (xy 430.847228 -129.68065) (xy 430.847228 -129.73515)
			(xy 430.839473 -129.789094) (xy 430.82412 -129.841386) (xy 430.801482 -129.890961) (xy 430.772019 -129.93681)
			(xy 430.736332 -129.978) (xy 430.695147 -130.013692) (xy 430.649301 -130.04316) (xy 430.599729 -130.065804)
			(xy 430.547439 -130.081163) (xy 430.493496 -130.088925) (xy 430.466246 -130.089402) (xy 430.451453 -130.089258)
			(xy 430.421956 -130.086968) (xy 430.407318 -130.08483) (xy 430.396396 -130.083052) (xy 430.37506 -130.089148)
			(xy 430.30775 -130.146552) (xy 430.299795 -130.154155) (xy 430.2907 -130.174167) (xy 430.290224 -130.18516)
			(xy 430.290224 -130.489452) (xy 430.290709 -130.500443) (xy 430.299803 -130.52045) (xy 430.30775 -130.52806)
			(xy 430.37506 -130.585464) (xy 430.396396 -130.59156) (xy 430.407318 -130.589782) (xy 430.421955 -130.587635)
			(xy 430.451453 -130.585349) (xy 430.466246 -130.58521) (xy 430.493899 -130.585699) (xy 430.548627 -130.593684)
			(xy 430.601626 -130.609494) (xy 430.651783 -130.632797) (xy 430.698047 -130.663104) (xy 430.739445 -130.699779)
			(xy 430.775108 -130.742052) (xy 430.790096 -130.765296) (xy 430.794937 -130.772427) (xy 430.808392 -130.783181)
			(xy 430.824662 -130.788834) (xy 430.833276 -130.789172) (xy 447.756026 -130.789172) (xy 447.766094 -130.788744)
			(xy 447.784689 -130.781019) (xy 447.792094 -130.774186) (xy 450.434964 -128.131316) (xy 450.441801 -128.123915)
			(xy 450.449511 -128.105316) (xy 450.44995 -128.095248) (xy 450.44995 -124.380752) (xy 450.449461 -124.370753)
			(xy 450.441833 -124.352266) (xy 450.427742 -124.338074) (xy 450.418708 -124.333762) (xy 450.40423 -124.327666)
			(xy 450.374258 -124.333762) (xy 449.99275 -124.71527) (xy 449.985892 -124.727208) (xy 449.984114 -124.734066)
			(xy 449.976753 -124.761143) (xy 449.955176 -124.812938) (xy 449.926246 -124.861015) (xy 449.890586 -124.904337)
			(xy 449.848967 -124.94197) (xy 449.802285 -124.973101) (xy 449.751548 -124.99706) (xy 449.697848 -125.01333)
			(xy 449.642345 -125.021561) (xy 449.61429 -125.022102) (xy 449.587039 -125.021616) (xy 449.533093 -125.013858)
			(xy 449.4808 -124.998502) (xy 449.431224 -124.97586) (xy 449.385376 -124.946393) (xy 449.344187 -124.910702)
			(xy 449.308497 -124.869512) (xy 449.279032 -124.823662) (xy 449.256393 -124.774085) (xy 449.241039 -124.721791)
			(xy 449.233283 -124.667845) (xy 449.232782 -124.640594) (xy 449.233272 -124.612532) (xy 449.241483 -124.557012)
			(xy 449.257741 -124.503294) (xy 449.281696 -124.452539) (xy 449.31283 -124.405842) (xy 449.350471 -124.364212)
			(xy 449.393806 -124.328547) (xy 449.441899 -124.299618) (xy 449.493713 -124.278049) (xy 449.520818 -124.27077)
			(xy 449.527676 -124.268992) (xy 449.539614 -124.262134) (xy 450.38772 -123.414028) (xy 450.394407 -123.406619)
			(xy 450.401996 -123.388183) (xy 450.402452 -123.378214) (xy 450.402452 -120.734074) (xy 450.401972 -120.72411)
			(xy 450.394389 -120.705679) (xy 450.38772 -120.69826) (xy 450.21754 -120.52808) (xy 450.210132 -120.521392)
			(xy 450.191696 -120.513798) (xy 450.181726 -120.513348) (xy 448.770756 -120.513348) (xy 448.742054 -120.53824)
			(xy 448.73926 -120.557036) (xy 448.734623 -120.586446) (xy 448.718722 -120.643821) (xy 448.695515 -120.69865)
			(xy 448.665397 -120.750008) (xy 448.628873 -120.797028) (xy 448.586562 -120.838915) (xy 448.539177 -120.874964)
			(xy 448.487519 -120.904564) (xy 448.432459 -120.927217) (xy 448.374926 -120.942541) (xy 448.315893 -120.950276)
			(xy 448.286124 -120.950736) (xy 448.256155 -120.950247) (xy 448.196728 -120.942427) (xy 448.138831 -120.926917)
			(xy 448.083454 -120.903982) (xy 448.031544 -120.874016) (xy 447.983989 -120.83753) (xy 447.941604 -120.79515)
			(xy 447.905113 -120.747599) (xy 447.875141 -120.695693) (xy 447.8522 -120.640318) (xy 447.836683 -120.582423)
			(xy 447.828856 -120.522997) (xy 447.828416 -120.493028) (xy 447.828884 -120.463685) (xy 447.836382 -120.40548)
			(xy 447.851259 -120.348711) (xy 447.873271 -120.294309) (xy 447.902056 -120.243167) (xy 447.937143 -120.196125)
			(xy 447.977955 -120.153953) (xy 448.023823 -120.117345) (xy 448.073994 -120.0869) (xy 448.127646 -120.063118)
			(xy 448.183897 -120.04639) (xy 448.241826 -120.036989) (xy 448.271138 -120.035574) (xy 448.281044 -120.03532)
			(xy 448.298316 -120.0277) (xy 448.359784 -119.966232) (xy 448.377912 -119.948741) (xy 448.418645 -119.919106)
			(xy 448.463515 -119.896214) (xy 448.511416 -119.880629) (xy 448.561166 -119.872736) (xy 448.586352 -119.872252)
			(xy 450.335396 -119.872252) (xy 450.345302 -119.872506) (xy 450.355462 -119.87276) (xy 450.374766 -119.865394)
			(xy 450.434456 -119.807482) (xy 450.441511 -119.800031) (xy 450.449513 -119.781157) (xy 450.44995 -119.770906)
			(xy 450.44995 -114.790982) (xy 450.449522 -114.780914) (xy 450.441798 -114.762319) (xy 450.434964 -114.754914)
			(xy 450.17182 -114.49177) (xy 450.16442 -114.484929) (xy 450.145821 -114.477212) (xy 450.135752 -114.476784)
			(xy 449.150486 -114.476784) (xy 449.141591 -114.477111) (xy 449.124871 -114.483187) (xy 449.11125 -114.49463)
			(xy 449.106544 -114.502184) (xy 449.091669 -114.526751) (xy 449.055706 -114.571525) (xy 449.034916 -114.591338)
			(xy 449.027478 -114.598834) (xy 449.018961 -114.618129) (xy 449.018406 -114.628676) (xy 449.018406 -114.703352)
			(xy 449.018988 -114.713889) (xy 449.02751 -114.733172) (xy 449.034916 -114.74069) (xy 449.053979 -114.758839)
			(xy 449.087438 -114.79947) (xy 449.114999 -114.844311) (xy 449.136141 -114.892513) (xy 449.150461 -114.943161)
			(xy 449.157688 -114.995297) (xy 449.158106 -115.021614) (xy 449.157683 -115.047933) (xy 449.15048 -115.100074)
			(xy 449.136172 -115.150729) (xy 449.115031 -115.198933) (xy 449.087459 -115.24377) (xy 449.05398 -115.284388)
			(xy 449.034916 -115.302538) (xy 449.027478 -115.310034) (xy 449.018961 -115.329329) (xy 449.018406 -115.339876)
			(xy 449.018406 -115.414552) (xy 449.018988 -115.425089) (xy 449.02751 -115.444372) (xy 449.034916 -115.45189)
			(xy 449.053979 -115.470039) (xy 449.087438 -115.51067) (xy 449.114999 -115.555511) (xy 449.136141 -115.603713)
			(xy 449.150461 -115.654361) (xy 449.157688 -115.706497) (xy 449.158106 -115.732814) (xy 449.15762 -115.760065)
			(xy 449.149864 -115.814013) (xy 449.134509 -115.866308) (xy 449.111867 -115.915885) (xy 449.082401 -115.961735)
			(xy 449.04671 -116.002926) (xy 449.005519 -116.038617) (xy 448.959669 -116.068083) (xy 448.910092 -116.090725)
			(xy 448.857797 -116.10608) (xy 448.803849 -116.113836) (xy 448.749347 -116.113836) (xy 448.695399 -116.10608)
			(xy 448.643104 -116.090725) (xy 448.593527 -116.068083) (xy 448.547677 -116.038617) (xy 448.506486 -116.002926)
			(xy 448.470795 -115.961735) (xy 448.441329 -115.915885) (xy 448.418687 -115.866308) (xy 448.403332 -115.814013)
			(xy 448.395576 -115.760065) (xy 448.39509 -115.732814) (xy 448.395512 -115.706495) (xy 448.402712 -115.654354)
			(xy 448.41702 -115.603699) (xy 448.438163 -115.555495) (xy 448.465738 -115.51066) (xy 448.499221 -115.470045)
			(xy 448.51828 -115.45189) (xy 448.525723 -115.444396) (xy 448.534252 -115.425101) (xy 448.53479 -115.414552)
			(xy 448.53479 -115.339876) (xy 448.534213 -115.329336) (xy 448.525697 -115.310046) (xy 448.51828 -115.302538)
			(xy 448.499221 -115.284387) (xy 448.46577 -115.243755) (xy 448.438217 -115.198913) (xy 448.417085 -115.150711)
			(xy 448.402775 -115.100063) (xy 448.395557 -115.047929) (xy 448.39509 -115.021614) (xy 448.395512 -114.995295)
			(xy 448.402712 -114.943154) (xy 448.41702 -114.892499) (xy 448.438163 -114.844295) (xy 448.465738 -114.79946)
			(xy 448.499221 -114.758845) (xy 448.51828 -114.74069) (xy 448.525723 -114.733196) (xy 448.534252 -114.713901)
			(xy 448.53479 -114.703352) (xy 448.53479 -114.628676) (xy 448.534213 -114.618136) (xy 448.525697 -114.598846)
			(xy 448.51828 -114.591338) (xy 448.497494 -114.571521) (xy 448.461527 -114.526751) (xy 448.446652 -114.502184)
			(xy 448.441872 -114.494693) (xy 448.428267 -114.483282) (xy 448.411587 -114.477193) (xy 448.40271 -114.476784)
			(xy 446.612264 -114.476784) (xy 446.603371 -114.477115) (xy 446.586656 -114.483195) (xy 446.573042 -114.49464)
			(xy 446.568322 -114.502184) (xy 446.553446 -114.52675) (xy 446.517482 -114.571523) (xy 446.496694 -114.591338)
			(xy 446.489259 -114.598835) (xy 446.480746 -114.61813) (xy 446.480184 -114.628676) (xy 446.480184 -114.703352)
			(xy 446.480765 -114.71389) (xy 446.489285 -114.733175) (xy 446.496694 -114.74069) (xy 446.515758 -114.758839)
			(xy 446.549219 -114.799468) (xy 446.576782 -114.844309) (xy 446.597924 -114.892511) (xy 446.612245 -114.94316)
			(xy 446.619473 -114.995297) (xy 446.619884 -115.021614) (xy 446.619461 -115.047932) (xy 446.612258 -115.100074)
			(xy 446.597949 -115.150728) (xy 446.576807 -115.198931) (xy 446.549234 -115.243767) (xy 446.515754 -115.284384)
			(xy 446.496694 -115.302538) (xy 446.489259 -115.310035) (xy 446.480746 -115.32933) (xy 446.480184 -115.339876)
			(xy 446.480184 -115.414552) (xy 446.480765 -115.42509) (xy 446.489285 -115.444375) (xy 446.496694 -115.45189)
			(xy 446.515758 -115.470039) (xy 446.549219 -115.510668) (xy 446.576782 -115.555509) (xy 446.597924 -115.603711)
			(xy 446.612245 -115.65436) (xy 446.619473 -115.706497) (xy 446.619884 -115.732814) (xy 446.619398 -115.760065)
			(xy 446.611642 -115.814013) (xy 446.596287 -115.866308) (xy 446.573645 -115.915885) (xy 446.544179 -115.961735)
			(xy 446.508488 -116.002926) (xy 446.467297 -116.038617) (xy 446.421447 -116.068083) (xy 446.37187 -116.090725)
			(xy 446.319575 -116.10608) (xy 446.265627 -116.113836) (xy 446.211125 -116.113836) (xy 446.157177 -116.10608)
			(xy 446.104882 -116.090725) (xy 446.055305 -116.068083) (xy 446.009455 -116.038617) (xy 445.968264 -116.002926)
			(xy 445.932573 -115.961735) (xy 445.903107 -115.915885) (xy 445.880465 -115.866308) (xy 445.86511 -115.814013)
			(xy 445.857354 -115.760065) (xy 445.856868 -115.732814) (xy 445.857289 -115.706495) (xy 445.86449 -115.654353)
			(xy 445.878797 -115.603698) (xy 445.899939 -115.555493) (xy 445.927513 -115.510657) (xy 445.960995 -115.470041)
			(xy 445.980058 -115.45189) (xy 445.987504 -115.444398) (xy 445.996036 -115.425102) (xy 445.996568 -115.414552)
			(xy 445.996568 -115.339876) (xy 445.995991 -115.329337) (xy 445.987472 -115.310049) (xy 445.980058 -115.302538)
			(xy 445.961 -115.284387) (xy 445.927551 -115.243754) (xy 445.9 -115.198911) (xy 445.878869 -115.150709)
			(xy 445.864559 -115.100062) (xy 445.857342 -115.047929) (xy 445.856868 -115.021614) (xy 445.857289 -114.995295)
			(xy 445.86449 -114.943153) (xy 445.878797 -114.892498) (xy 445.899939 -114.844293) (xy 445.927513 -114.799457)
			(xy 445.960995 -114.758841) (xy 445.980058 -114.74069) (xy 445.987504 -114.733198) (xy 445.996036 -114.713902)
			(xy 445.996568 -114.703352) (xy 445.996568 -114.628676) (xy 445.995991 -114.618137) (xy 445.987472 -114.598849)
			(xy 445.980058 -114.591338) (xy 445.959273 -114.57152) (xy 445.923308 -114.526749) (xy 445.90843 -114.502184)
			(xy 445.903649 -114.494695) (xy 445.890043 -114.48329) (xy 445.873364 -114.477208) (xy 445.864488 -114.476784)
			(xy 441.379356 -114.476784) (xy 441.370173 -114.477127) (xy 441.352956 -114.483512) (xy 441.339095 -114.495556)
			(xy 441.334398 -114.503454) (xy 441.321019 -114.527409) (xy 441.288437 -114.571556) (xy 441.249864 -114.610575)
			(xy 441.206095 -114.643663) (xy 441.158035 -114.670134) (xy 441.106677 -114.689443) (xy 441.053082 -114.70119)
			(xy 440.998356 -114.705133) (xy 440.94363 -114.70119) (xy 440.890035 -114.689443) (xy 440.838677 -114.670134)
			(xy 440.790617 -114.643663) (xy 440.746848 -114.610575) (xy 440.708275 -114.571556) (xy 440.675693 -114.527409)
			(xy 440.662314 -114.503454) (xy 440.65761 -114.495561) (xy 440.643752 -114.483516) (xy 440.626538 -114.477128)
			(xy 440.617356 -114.476784) (xy 440.566556 -114.476784) (xy 440.557373 -114.477127) (xy 440.540156 -114.483512)
			(xy 440.526295 -114.495556) (xy 440.521598 -114.503454) (xy 440.508219 -114.527409) (xy 440.475637 -114.571556)
			(xy 440.437064 -114.610575) (xy 440.393295 -114.643663) (xy 440.345235 -114.670134) (xy 440.293877 -114.689443)
			(xy 440.240282 -114.70119) (xy 440.185556 -114.705133) (xy 440.13083 -114.70119) (xy 440.077235 -114.689443)
			(xy 440.025877 -114.670134) (xy 439.977817 -114.643663) (xy 439.934048 -114.610575) (xy 439.895475 -114.571556)
			(xy 439.862893 -114.527409) (xy 439.849514 -114.503454) (xy 439.842656 -114.491008) (xy 439.81878 -114.476784)
			(xy 439.790332 -114.476784) (xy 439.766456 -114.491008) (xy 439.759598 -114.503454) (xy 439.746219 -114.527409)
			(xy 439.713637 -114.571556) (xy 439.675064 -114.610575) (xy 439.631295 -114.643663) (xy 439.583235 -114.670134)
			(xy 439.531877 -114.689443) (xy 439.478282 -114.70119) (xy 439.423556 -114.705133) (xy 439.36883 -114.70119)
			(xy 439.315235 -114.689443) (xy 439.263877 -114.670134) (xy 439.215817 -114.643663) (xy 439.172048 -114.610575)
			(xy 439.133475 -114.571556) (xy 439.100893 -114.527409) (xy 439.087514 -114.503454) (xy 439.08281 -114.495561)
			(xy 439.068952 -114.483516) (xy 439.051738 -114.477128) (xy 439.042556 -114.476784) (xy 438.314084 -114.476784)
			(xy 438.30494 -114.480594) (xy 438.27716 -114.491522) (xy 438.21948 -114.506903) (xy 438.16029 -114.51466)
			(xy 438.100594 -114.51466) (xy 438.041404 -114.506903) (xy 437.983724 -114.491522) (xy 437.955944 -114.480594)
			(xy 437.9468 -114.476784) (xy 423.770298 -114.476784) (xy 423.760228 -114.47636) (xy 423.741626 -114.468643)
			(xy 423.73423 -114.461798) (xy 423.518838 -114.246406) (xy 423.511437 -114.239569) (xy 423.492838 -114.231856)
			(xy 423.48277 -114.23142) (xy 421.846248 -114.23142) (xy 421.836182 -114.231853) (xy 421.817594 -114.239583)
			(xy 421.81018 -114.246406) (xy 421.703754 -114.352832) (xy 421.696907 -114.36023) (xy 421.689176 -114.378828)
			(xy 421.688768 -114.3889) (xy 421.688768 -115.400836) (xy 435.560722 -115.400836) (xy 435.564793 -115.345214)
			(xy 435.576919 -115.290777) (xy 435.596842 -115.238686) (xy 435.624138 -115.190051) (xy 435.658224 -115.145908)
			(xy 435.698373 -115.107199) (xy 435.743731 -115.074748) (xy 435.793331 -115.049247) (xy 435.846115 -115.03124)
			(xy 435.900958 -115.02111) (xy 435.956692 -115.019073) (xy 436.012129 -115.025173) (xy 436.066086 -115.039279)
			(xy 436.117415 -115.061091) (xy 436.165021 -115.090145) (xy 436.207889 -115.12582) (xy 436.245106 -115.167357)
			(xy 436.275879 -115.21387) (xy 436.299551 -115.264367) (xy 436.315619 -115.317774) (xy 436.323739 -115.37295)
			(xy 436.324239 -115.400324) (xy 437.586102 -115.400324) (xy 437.586102 -115.340388) (xy 437.593925 -115.280966)
			(xy 437.609438 -115.223073) (xy 437.632374 -115.1677) (xy 437.662341 -115.115794) (xy 437.698828 -115.068244)
			(xy 437.741208 -115.025864) (xy 437.788758 -114.989377) (xy 437.840664 -114.95941) (xy 437.896037 -114.936474)
			(xy 437.95393 -114.920961) (xy 438.013352 -114.913138) (xy 438.073288 -114.913138) (xy 438.13271 -114.920961)
			(xy 438.190603 -114.936474) (xy 438.245976 -114.95941) (xy 438.297882 -114.989377) (xy 438.345432 -115.025864)
			(xy 438.387812 -115.068244) (xy 438.424299 -115.115794) (xy 438.454266 -115.1677) (xy 438.477202 -115.223073)
			(xy 438.492715 -115.280966) (xy 438.500538 -115.340388) (xy 438.501028 -115.370356) (xy 438.500538 -115.400324)
			(xy 438.492715 -115.459746) (xy 438.477202 -115.517639) (xy 438.454266 -115.573012) (xy 438.424299 -115.624918)
			(xy 438.387812 -115.672468) (xy 438.345432 -115.714848) (xy 438.297882 -115.751335) (xy 438.245976 -115.781302)
			(xy 438.190603 -115.804238) (xy 438.13271 -115.819751) (xy 438.073288 -115.827574) (xy 438.013352 -115.827574)
			(xy 437.95393 -115.819751) (xy 437.896037 -115.804238) (xy 437.840664 -115.781302) (xy 437.788758 -115.751335)
			(xy 437.741208 -115.714848) (xy 437.698828 -115.672468) (xy 437.662341 -115.624918) (xy 437.632374 -115.573012)
			(xy 437.609438 -115.517639) (xy 437.593925 -115.459746) (xy 437.586102 -115.400324) (xy 436.324239 -115.400324)
			(xy 436.324248 -115.400836) (xy 436.323739 -115.428722) (xy 436.315619 -115.483898) (xy 436.299551 -115.537305)
			(xy 436.275879 -115.587802) (xy 436.245106 -115.634315) (xy 436.207889 -115.675852) (xy 436.165021 -115.711527)
			(xy 436.117415 -115.740581) (xy 436.066086 -115.762393) (xy 436.012129 -115.776499) (xy 435.956692 -115.782599)
			(xy 435.900958 -115.780562) (xy 435.846115 -115.770432) (xy 435.793331 -115.752425) (xy 435.743731 -115.726924)
			(xy 435.698373 -115.694473) (xy 435.658224 -115.655764) (xy 435.624138 -115.611621) (xy 435.596842 -115.562986)
			(xy 435.576919 -115.510895) (xy 435.564793 -115.456458) (xy 435.560722 -115.400836) (xy 421.688768 -115.400836)
			(xy 421.688768 -115.832636) (xy 441.203588 -115.832636) (xy 441.204103 -115.800435) (xy 441.213139 -115.736669)
			(xy 441.231024 -115.674799) (xy 441.257404 -115.616047) (xy 441.291759 -115.561573) (xy 441.333411 -115.512451)
			(xy 441.381537 -115.469653) (xy 441.408058 -115.451382) (xy 441.418218 -115.444524) (xy 441.429902 -115.424204)
			(xy 441.435744 -115.318286) (xy 441.426346 -115.296696) (xy 441.416694 -115.288822) (xy 441.39566 -115.27059)
			(xy 441.358587 -115.22907) (xy 441.327939 -115.182604) (xy 441.304367 -115.132179) (xy 441.28837 -115.078864)
			(xy 441.280289 -115.023791) (xy 441.279788 -114.99596) (xy 441.280274 -114.968709) (xy 441.28803 -114.914761)
			(xy 441.303385 -114.862466) (xy 441.326027 -114.812889) (xy 441.355493 -114.767039) (xy 441.391184 -114.725848)
			(xy 441.432375 -114.690157) (xy 441.478225 -114.660691) (xy 441.527802 -114.638049) (xy 441.580097 -114.622694)
			(xy 441.634045 -114.614938) (xy 441.688547 -114.614938) (xy 441.742495 -114.622694) (xy 441.79479 -114.638049)
			(xy 441.844367 -114.660691) (xy 441.890217 -114.690157) (xy 441.931408 -114.725848) (xy 441.967099 -114.767039)
			(xy 441.996565 -114.812889) (xy 442.019207 -114.862466) (xy 442.034562 -114.914761) (xy 442.042318 -114.968709)
			(xy 442.042804 -114.99596) (xy 442.042266 -115.023789) (xy 442.034177 -115.078855) (xy 442.018181 -115.132165)
			(xy 441.994615 -115.182587) (xy 441.963979 -115.229054) (xy 441.926921 -115.270582) (xy 441.905898 -115.288822)
			(xy 441.896246 -115.296696) (xy 441.886848 -115.318286) (xy 441.891051 -115.394486) (xy 443.447168 -115.394486)
			(xy 443.451239 -115.338864) (xy 443.463365 -115.284427) (xy 443.483288 -115.232336) (xy 443.510584 -115.183701)
			(xy 443.54467 -115.139558) (xy 443.584819 -115.100849) (xy 443.630177 -115.068398) (xy 443.679777 -115.042897)
			(xy 443.732561 -115.02489) (xy 443.787404 -115.01476) (xy 443.843138 -115.012723) (xy 443.898575 -115.018823)
			(xy 443.952532 -115.032929) (xy 444.003861 -115.054741) (xy 444.051467 -115.083795) (xy 444.094335 -115.11947)
			(xy 444.131552 -115.161007) (xy 444.162325 -115.20752) (xy 444.185997 -115.258017) (xy 444.202065 -115.311424)
			(xy 444.210185 -115.3666) (xy 444.210694 -115.394486) (xy 444.210185 -115.422372) (xy 444.202065 -115.477548)
			(xy 444.185997 -115.530955) (xy 444.162325 -115.581452) (xy 444.131552 -115.627965) (xy 444.094335 -115.669502)
			(xy 444.051467 -115.705177) (xy 444.003861 -115.734231) (xy 443.952532 -115.756043) (xy 443.898575 -115.770149)
			(xy 443.843138 -115.776249) (xy 443.787404 -115.774212) (xy 443.732561 -115.764082) (xy 443.679777 -115.746075)
			(xy 443.630177 -115.720574) (xy 443.584819 -115.688123) (xy 443.54467 -115.649414) (xy 443.510584 -115.605271)
			(xy 443.483288 -115.556636) (xy 443.463365 -115.504545) (xy 443.451239 -115.450108) (xy 443.447168 -115.394486)
			(xy 441.891051 -115.394486) (xy 441.89269 -115.424204) (xy 441.904374 -115.444524) (xy 441.914534 -115.451382)
			(xy 441.941055 -115.469654) (xy 441.989181 -115.512449) (xy 442.030831 -115.56157) (xy 442.065183 -115.616045)
			(xy 442.091557 -115.674798) (xy 442.109433 -115.736669) (xy 442.118458 -115.800435) (xy 442.119004 -115.832636)
			(xy 442.118514 -115.862604) (xy 442.110691 -115.922026) (xy 442.095178 -115.979919) (xy 442.072242 -116.035292)
			(xy 442.042275 -116.087198) (xy 442.005788 -116.134748) (xy 441.963408 -116.177128) (xy 441.915858 -116.213615)
			(xy 441.863952 -116.243582) (xy 441.808579 -116.266518) (xy 441.750686 -116.282031) (xy 441.691264 -116.289854)
			(xy 441.631328 -116.289854) (xy 441.571906 -116.282031) (xy 441.514013 -116.266518) (xy 441.45864 -116.243582)
			(xy 441.406734 -116.213615) (xy 441.359184 -116.177128) (xy 441.316804 -116.134748) (xy 441.280317 -116.087198)
			(xy 441.25035 -116.035292) (xy 441.227414 -115.979919) (xy 441.211901 -115.922026) (xy 441.204078 -115.862604)
			(xy 441.203588 -115.832636) (xy 421.688768 -115.832636) (xy 421.688768 -117.924072) (xy 421.688331 -117.934136)
			(xy 421.680595 -117.952718) (xy 421.673782 -117.96014) (xy 421.371667 -118.262255) (xy 422.167223 -118.262255)
			(xy 422.167223 -118.207745) (xy 422.174981 -118.153789) (xy 422.190338 -118.101486) (xy 422.212983 -118.051902)
			(xy 422.242454 -118.006044) (xy 422.278151 -117.964848) (xy 422.319348 -117.929151) (xy 422.365205 -117.899681)
			(xy 422.41479 -117.877037) (xy 422.467093 -117.86168) (xy 422.521049 -117.853923) (xy 422.548304 -117.85346)
			(xy 422.573297 -117.853857) (xy 422.622859 -117.860354) (xy 422.64711 -117.866414) (xy 422.658794 -117.869716)
			(xy 422.681908 -117.86489) (xy 422.764966 -117.80012) (xy 422.77538 -117.778784) (xy 422.775126 -117.766592)
			(xy 422.774872 -117.759226) (xy 422.774872 -116.895626) (xy 422.776142 -116.862098) (xy 422.776478 -116.853532)
			(xy 422.772091 -116.83697) (xy 422.762494 -116.822777) (xy 422.755822 -116.817394) (xy 422.730676 -116.798852)
			(xy 422.723718 -116.79404) (xy 422.70758 -116.788992) (xy 422.690679 -116.789522) (xy 422.68267 -116.792248)
			(xy 422.650256 -116.803648) (xy 422.582657 -116.815923) (xy 422.548304 -116.816632) (xy 422.521053 -116.816121)
			(xy 422.467105 -116.808365) (xy 422.41481 -116.79301) (xy 422.365232 -116.770369) (xy 422.319381 -116.740903)
			(xy 422.278191 -116.705212) (xy 422.242499 -116.664022) (xy 422.213033 -116.618171) (xy 422.190391 -116.568594)
			(xy 422.175036 -116.516299) (xy 422.167279 -116.462351) (xy 422.167279 -116.407849) (xy 422.175036 -116.353901)
			(xy 422.190391 -116.301606) (xy 422.213033 -116.252029) (xy 422.242499 -116.206178) (xy 422.278191 -116.164988)
			(xy 422.319381 -116.129297) (xy 422.365232 -116.099831) (xy 422.41481 -116.07719) (xy 422.467105 -116.061835)
			(xy 422.521053 -116.054079) (xy 422.548304 -116.053616) (xy 422.575906 -116.054093) (xy 422.63053 -116.062077)
			(xy 422.683433 -116.077848) (xy 422.733512 -116.101077) (xy 422.779721 -116.13128) (xy 422.821096 -116.167826)
			(xy 422.856773 -116.209953) (xy 422.886008 -116.25678) (xy 422.90819 -116.307331) (xy 422.922857 -116.360551)
			(xy 422.926764 -116.38788) (xy 422.928288 -116.399564) (xy 422.939504 -116.416836) (xy 435.560722 -116.416836)
			(xy 435.564793 -116.361214) (xy 435.576919 -116.306777) (xy 435.596842 -116.254686) (xy 435.624138 -116.206051)
			(xy 435.658224 -116.161908) (xy 435.698373 -116.123199) (xy 435.743731 -116.090748) (xy 435.793331 -116.065247)
			(xy 435.846115 -116.04724) (xy 435.900958 -116.03711) (xy 435.956692 -116.035073) (xy 436.012129 -116.041173)
			(xy 436.066086 -116.055279) (xy 436.117415 -116.077091) (xy 436.165021 -116.106145) (xy 436.207889 -116.14182)
			(xy 436.245106 -116.183357) (xy 436.275879 -116.22987) (xy 436.299551 -116.280367) (xy 436.315619 -116.333774)
			(xy 436.323739 -116.38895) (xy 436.324248 -116.416836) (xy 436.323739 -116.444722) (xy 436.315619 -116.499898)
			(xy 436.299551 -116.553305) (xy 436.275879 -116.603802) (xy 436.245106 -116.650315) (xy 436.207889 -116.691852)
			(xy 436.198353 -116.699788) (xy 437.59804 -116.699788) (xy 437.59804 -116.639852) (xy 437.605863 -116.58043)
			(xy 437.621376 -116.522537) (xy 437.644312 -116.467164) (xy 437.674279 -116.415258) (xy 437.710766 -116.367708)
			(xy 437.753146 -116.325328) (xy 437.800696 -116.288841) (xy 437.852602 -116.258874) (xy 437.907975 -116.235938)
			(xy 437.965868 -116.220425) (xy 438.02529 -116.212602) (xy 438.085226 -116.212602) (xy 438.144648 -116.220425)
			(xy 438.202541 -116.235938) (xy 438.257914 -116.258874) (xy 438.30982 -116.288841) (xy 438.35737 -116.325328)
			(xy 438.39975 -116.367708) (xy 438.432575 -116.410486) (xy 443.447168 -116.410486) (xy 443.451239 -116.354864)
			(xy 443.463365 -116.300427) (xy 443.483288 -116.248336) (xy 443.510584 -116.199701) (xy 443.54467 -116.155558)
			(xy 443.584819 -116.116849) (xy 443.630177 -116.084398) (xy 443.679777 -116.058897) (xy 443.732561 -116.04089)
			(xy 443.787404 -116.03076) (xy 443.843138 -116.028723) (xy 443.898575 -116.034823) (xy 443.952532 -116.048929)
			(xy 444.003861 -116.070741) (xy 444.051467 -116.099795) (xy 444.094335 -116.13547) (xy 444.131552 -116.177007)
			(xy 444.162325 -116.22352) (xy 444.185997 -116.274017) (xy 444.202065 -116.327424) (xy 444.210185 -116.3826)
			(xy 444.210694 -116.410486) (xy 444.210185 -116.438372) (xy 444.202065 -116.493548) (xy 444.185997 -116.546955)
			(xy 444.162325 -116.597452) (xy 444.131552 -116.643965) (xy 444.094335 -116.685502) (xy 444.051467 -116.721177)
			(xy 444.003861 -116.750231) (xy 443.952532 -116.772043) (xy 443.898575 -116.786149) (xy 443.843138 -116.792249)
			(xy 443.787404 -116.790212) (xy 443.732561 -116.780082) (xy 443.679777 -116.762075) (xy 443.630177 -116.736574)
			(xy 443.584819 -116.704123) (xy 443.54467 -116.665414) (xy 443.510584 -116.621271) (xy 443.483288 -116.572636)
			(xy 443.463365 -116.520545) (xy 443.451239 -116.466108) (xy 443.447168 -116.410486) (xy 438.432575 -116.410486)
			(xy 438.436237 -116.415258) (xy 438.466204 -116.467164) (xy 438.48914 -116.522537) (xy 438.504653 -116.58043)
			(xy 438.512476 -116.639852) (xy 438.512966 -116.66982) (xy 438.512476 -116.699788) (xy 438.504653 -116.75921)
			(xy 438.48914 -116.817103) (xy 438.466204 -116.872476) (xy 438.436237 -116.924382) (xy 438.39975 -116.971932)
			(xy 438.35737 -117.014312) (xy 438.30982 -117.050799) (xy 438.257914 -117.080766) (xy 438.202541 -117.103702)
			(xy 438.144648 -117.119215) (xy 438.085226 -117.127038) (xy 438.02529 -117.127038) (xy 437.965868 -117.119215)
			(xy 437.907975 -117.103702) (xy 437.852602 -117.080766) (xy 437.800696 -117.050799) (xy 437.753146 -117.014312)
			(xy 437.710766 -116.971932) (xy 437.674279 -116.924382) (xy 437.644312 -116.872476) (xy 437.621376 -116.817103)
			(xy 437.605863 -116.75921) (xy 437.59804 -116.699788) (xy 436.198353 -116.699788) (xy 436.165021 -116.727527)
			(xy 436.117415 -116.756581) (xy 436.066086 -116.778393) (xy 436.012129 -116.792499) (xy 435.956692 -116.798599)
			(xy 435.900958 -116.796562) (xy 435.846115 -116.786432) (xy 435.793331 -116.768425) (xy 435.743731 -116.742924)
			(xy 435.698373 -116.710473) (xy 435.658224 -116.671764) (xy 435.624138 -116.627621) (xy 435.596842 -116.578986)
			(xy 435.576919 -116.526895) (xy 435.564793 -116.472458) (xy 435.560722 -116.416836) (xy 422.939504 -116.416836)
			(xy 422.940988 -116.419122) (xy 423.03065 -116.472208) (xy 423.053764 -116.473986) (xy 423.06494 -116.469668)
			(xy 423.091757 -116.459535) (xy 423.147292 -116.445303) (xy 423.204169 -116.43812) (xy 423.232834 -116.437664)
			(xy 423.26282 -116.438096) (xy 423.322279 -116.445929) (xy 423.380207 -116.461455) (xy 423.435612 -116.484409)
			(xy 423.487548 -116.514399) (xy 423.535125 -116.550911) (xy 423.577529 -116.593321) (xy 423.614035 -116.640902)
			(xy 423.644017 -116.692842) (xy 423.666965 -116.74825) (xy 423.682483 -116.80618) (xy 423.690308 -116.86564)
			(xy 423.690796 -116.895626) (xy 423.690796 -117.132604) (xy 441.204078 -117.132604) (xy 441.204078 -117.072668)
			(xy 441.211901 -117.013246) (xy 441.227414 -116.955353) (xy 441.25035 -116.89998) (xy 441.280317 -116.848074)
			(xy 441.316804 -116.800524) (xy 441.359184 -116.758144) (xy 441.406734 -116.721657) (xy 441.45864 -116.69169)
			(xy 441.514013 -116.668754) (xy 441.571906 -116.653241) (xy 441.631328 -116.645418) (xy 441.691264 -116.645418)
			(xy 441.750686 -116.653241) (xy 441.808579 -116.668754) (xy 441.863952 -116.69169) (xy 441.915858 -116.721657)
			(xy 441.963408 -116.758144) (xy 442.005788 -116.800524) (xy 442.042275 -116.848074) (xy 442.072242 -116.89998)
			(xy 442.095178 -116.955353) (xy 442.110691 -117.013246) (xy 442.118514 -117.072668) (xy 442.119004 -117.102636)
			(xy 442.118514 -117.132604) (xy 442.110691 -117.192026) (xy 442.095178 -117.249919) (xy 442.072242 -117.305292)
			(xy 442.042275 -117.357198) (xy 442.005788 -117.404748) (xy 441.98405 -117.426486) (xy 443.447168 -117.426486)
			(xy 443.451239 -117.370864) (xy 443.463365 -117.316427) (xy 443.483288 -117.264336) (xy 443.510584 -117.215701)
			(xy 443.54467 -117.171558) (xy 443.584819 -117.132849) (xy 443.630177 -117.100398) (xy 443.679777 -117.074897)
			(xy 443.732561 -117.05689) (xy 443.787404 -117.04676) (xy 443.843138 -117.044723) (xy 443.898575 -117.050823)
			(xy 443.952532 -117.064929) (xy 444.003861 -117.086741) (xy 444.051467 -117.115795) (xy 444.094335 -117.15147)
			(xy 444.131552 -117.193007) (xy 444.162325 -117.23952) (xy 444.185997 -117.290017) (xy 444.202065 -117.343424)
			(xy 444.210185 -117.3986) (xy 444.210694 -117.426486) (xy 444.210185 -117.454372) (xy 444.202065 -117.509548)
			(xy 444.185997 -117.562955) (xy 444.162325 -117.613452) (xy 444.131552 -117.659965) (xy 444.094335 -117.701502)
			(xy 444.051467 -117.737177) (xy 444.003861 -117.766231) (xy 443.952532 -117.788043) (xy 443.898575 -117.802149)
			(xy 443.843138 -117.808249) (xy 443.787404 -117.806212) (xy 443.732561 -117.796082) (xy 443.679777 -117.778075)
			(xy 443.630177 -117.752574) (xy 443.584819 -117.720123) (xy 443.54467 -117.681414) (xy 443.510584 -117.637271)
			(xy 443.483288 -117.588636) (xy 443.463365 -117.536545) (xy 443.451239 -117.482108) (xy 443.447168 -117.426486)
			(xy 441.98405 -117.426486) (xy 441.963408 -117.447128) (xy 441.915858 -117.483615) (xy 441.863952 -117.513582)
			(xy 441.808579 -117.536518) (xy 441.750686 -117.552031) (xy 441.691264 -117.559854) (xy 441.631328 -117.559854)
			(xy 441.571906 -117.552031) (xy 441.514013 -117.536518) (xy 441.45864 -117.513582) (xy 441.406734 -117.483615)
			(xy 441.359184 -117.447128) (xy 441.316804 -117.404748) (xy 441.280317 -117.357198) (xy 441.25035 -117.305292)
			(xy 441.227414 -117.249919) (xy 441.211901 -117.192026) (xy 441.204078 -117.132604) (xy 423.690796 -117.132604)
			(xy 423.690796 -117.759226) (xy 423.690296 -117.789209) (xy 423.682466 -117.848663) (xy 423.666944 -117.906586)
			(xy 423.643994 -117.961988) (xy 423.61401 -118.01392) (xy 423.577504 -118.061495) (xy 423.535101 -118.103899)
			(xy 423.487527 -118.140405) (xy 423.435595 -118.17039) (xy 423.380194 -118.193341) (xy 423.322271 -118.208865)
			(xy 423.262817 -118.216696) (xy 423.232834 -118.217188) (xy 423.204398 -118.216753) (xy 423.147967 -118.209669)
			(xy 423.092847 -118.195656) (xy 423.06621 -118.185692) (xy 423.055034 -118.181374) (xy 423.031412 -118.183406)
			(xy 422.94175 -118.238524) (xy 422.929304 -118.258844) (xy 422.928034 -118.270782) (xy 422.92496 -118.298802)
			(xy 422.911482 -118.353537) (xy 422.890093 -118.405691) (xy 422.861261 -118.454129) (xy 422.825613 -118.497795)
			(xy 422.79534 -118.525349) (xy 428.81729 -118.525349) (xy 428.81729 -118.470851) (xy 428.825046 -118.416907)
			(xy 428.840399 -118.364615) (xy 428.863038 -118.315041) (xy 428.892501 -118.269193) (xy 428.928189 -118.228005)
			(xy 428.969376 -118.192315) (xy 429.015222 -118.162849) (xy 429.064795 -118.140207) (xy 429.117085 -118.124851)
			(xy 429.171029 -118.117092) (xy 429.198278 -118.116604) (xy 429.224204 -118.117052) (xy 429.27558 -118.124055)
			(xy 429.325536 -118.137949) (xy 429.37315 -118.158478) (xy 429.417547 -118.185265) (xy 429.457908 -118.217815)
			(xy 429.493492 -118.25553) (xy 429.50892 -118.27637) (xy 429.514646 -118.283713) (xy 429.530159 -118.293992)
			(xy 429.539146 -118.296436) (xy 429.569372 -118.303294) (xy 429.578647 -118.305059) (xy 429.597313 -118.302308)
			(xy 429.605694 -118.29796) (xy 429.63169 -118.283724) (xy 429.686557 -118.261306) (xy 429.743854 -118.246144)
			(xy 429.802627 -118.23849) (xy 429.832262 -118.238016) (xy 429.8619 -118.238467) (xy 429.920683 -118.24609)
			(xy 429.977986 -118.26125) (xy 430.032848 -118.283694) (xy 430.05883 -118.29796) (xy 430.067254 -118.302181)
			(xy 430.085875 -118.304931) (xy 430.095152 -118.303294) (xy 430.125378 -118.296436) (xy 430.13437 -118.294006)
			(xy 430.149874 -118.283713) (xy 430.155604 -118.27637) (xy 430.170996 -118.255499) (xy 430.206572 -118.217765)
			(xy 430.246933 -118.185202) (xy 430.291336 -118.158409) (xy 430.338961 -118.137882) (xy 430.388928 -118.123999)
			(xy 430.440316 -118.117017) (xy 430.466246 -118.116604) (xy 430.493496 -118.117069) (xy 430.54744 -118.124831)
			(xy 430.599731 -118.140191) (xy 430.649304 -118.162835) (xy 430.69515 -118.192304) (xy 430.736336 -118.227996)
			(xy 430.772024 -118.269187) (xy 430.801487 -118.315036) (xy 430.824125 -118.364612) (xy 430.839479 -118.416905)
			(xy 430.847234 -118.47085) (xy 430.847234 -118.52535) (xy 430.839479 -118.579295) (xy 430.824125 -118.631588)
			(xy 430.801487 -118.681164) (xy 430.772024 -118.727013) (xy 430.736336 -118.768204) (xy 430.69515 -118.803896)
			(xy 430.649304 -118.833365) (xy 430.599731 -118.856009) (xy 430.54744 -118.871369) (xy 430.493496 -118.879131)
			(xy 430.466246 -118.87962) (xy 430.451453 -118.879481) (xy 430.421955 -118.877194) (xy 430.407318 -118.875048)
			(xy 430.396396 -118.87327) (xy 430.37506 -118.879366) (xy 430.357488 -118.894352) (xy 441.71616 -118.894352)
			(xy 441.716614 -118.868036) (xy 441.723836 -118.815903) (xy 441.738149 -118.765255) (xy 441.759284 -118.717053)
			(xy 441.786838 -118.672211) (xy 441.820291 -118.631579) (xy 441.83935 -118.613428) (xy 441.846734 -118.605891)
			(xy 441.85527 -118.586623) (xy 441.85586 -118.57609) (xy 441.85586 -118.501414) (xy 441.855349 -118.490862)
			(xy 441.846802 -118.471566) (xy 441.83935 -118.464076) (xy 441.820268 -118.445943) (xy 441.786789 -118.405323)
			(xy 441.759217 -118.360483) (xy 441.738079 -118.312275) (xy 441.723775 -118.261617) (xy 441.716579 -118.209472)
			(xy 441.71616 -118.183152) (xy 441.716646 -118.155901) (xy 441.724402 -118.101953) (xy 441.739757 -118.049658)
			(xy 441.762399 -118.000081) (xy 441.791865 -117.954231) (xy 441.827556 -117.91304) (xy 441.868747 -117.877349)
			(xy 441.914597 -117.847883) (xy 441.964174 -117.825241) (xy 442.016469 -117.809886) (xy 442.070417 -117.80213)
			(xy 442.124919 -117.80213) (xy 442.178867 -117.809886) (xy 442.231162 -117.825241) (xy 442.280739 -117.847883)
			(xy 442.326589 -117.877349) (xy 442.36778 -117.91304) (xy 442.403471 -117.954231) (xy 442.432937 -118.000081)
			(xy 442.455579 -118.049658) (xy 442.470934 -118.101953) (xy 442.47869 -118.155901) (xy 442.479176 -118.183152)
			(xy 442.478745 -118.209469) (xy 442.471521 -118.261604) (xy 442.457205 -118.312253) (xy 442.436066 -118.360455)
			(xy 442.408506 -118.405296) (xy 442.375048 -118.445927) (xy 442.355986 -118.464076) (xy 442.348591 -118.471603)
			(xy 442.340063 -118.490879) (xy 442.339674 -118.497854) (xy 445.707244 -118.497854) (xy 445.707244 -118.437918)
			(xy 445.715067 -118.378496) (xy 445.73058 -118.320603) (xy 445.753516 -118.26523) (xy 445.783483 -118.213324)
			(xy 445.81997 -118.165774) (xy 445.86235 -118.123394) (xy 445.9099 -118.086907) (xy 445.961806 -118.05694)
			(xy 446.017179 -118.034004) (xy 446.075072 -118.018491) (xy 446.134494 -118.010668) (xy 446.19443 -118.010668)
			(xy 446.253852 -118.018491) (xy 446.311745 -118.034004) (xy 446.367118 -118.05694) (xy 446.419024 -118.086907)
			(xy 446.466574 -118.123394) (xy 446.508954 -118.165774) (xy 446.545441 -118.213324) (xy 446.575408 -118.26523)
			(xy 446.598344 -118.320603) (xy 446.613857 -118.378496) (xy 446.62168 -118.437918) (xy 446.62217 -118.467886)
			(xy 447.95262 -118.467886) (xy 447.956691 -118.412264) (xy 447.968817 -118.357827) (xy 447.98874 -118.305736)
			(xy 448.016036 -118.257101) (xy 448.050122 -118.212958) (xy 448.090271 -118.174249) (xy 448.135629 -118.141798)
			(xy 448.185229 -118.116297) (xy 448.238013 -118.09829) (xy 448.292856 -118.08816) (xy 448.34859 -118.086123)
			(xy 448.404027 -118.092223) (xy 448.457984 -118.106329) (xy 448.509313 -118.128141) (xy 448.556919 -118.157195)
			(xy 448.599787 -118.19287) (xy 448.637004 -118.234407) (xy 448.667777 -118.28092) (xy 448.691449 -118.331417)
			(xy 448.707517 -118.384824) (xy 448.715637 -118.44) (xy 448.716146 -118.467886) (xy 448.715637 -118.495772)
			(xy 448.707517 -118.550948) (xy 448.691449 -118.604355) (xy 448.667777 -118.654852) (xy 448.637004 -118.701365)
			(xy 448.599787 -118.742902) (xy 448.578953 -118.76024) (xy 448.838826 -118.76024) (xy 448.842897 -118.704618)
			(xy 448.855023 -118.650181) (xy 448.874946 -118.59809) (xy 448.902242 -118.549455) (xy 448.936328 -118.505312)
			(xy 448.976477 -118.466603) (xy 449.021835 -118.434152) (xy 449.071435 -118.408651) (xy 449.124219 -118.390644)
			(xy 449.179062 -118.380514) (xy 449.234796 -118.378477) (xy 449.290233 -118.384577) (xy 449.34419 -118.398683)
			(xy 449.395519 -118.420495) (xy 449.443125 -118.449549) (xy 449.485993 -118.485224) (xy 449.52321 -118.526761)
			(xy 449.553983 -118.573274) (xy 449.577655 -118.623771) (xy 449.593723 -118.677178) (xy 449.601843 -118.732354)
			(xy 449.602352 -118.76024) (xy 449.601843 -118.788126) (xy 449.593723 -118.843302) (xy 449.577655 -118.896709)
			(xy 449.553983 -118.947206) (xy 449.52321 -118.993719) (xy 449.485993 -119.035256) (xy 449.443125 -119.070931)
			(xy 449.395519 -119.099985) (xy 449.34419 -119.121797) (xy 449.290233 -119.135903) (xy 449.234796 -119.142003)
			(xy 449.179062 -119.139966) (xy 449.124219 -119.129836) (xy 449.071435 -119.111829) (xy 449.021835 -119.086328)
			(xy 448.976477 -119.053877) (xy 448.936328 -119.015168) (xy 448.902242 -118.971025) (xy 448.874946 -118.92239)
			(xy 448.855023 -118.870299) (xy 448.842897 -118.815862) (xy 448.838826 -118.76024) (xy 448.578953 -118.76024)
			(xy 448.556919 -118.778577) (xy 448.509313 -118.807631) (xy 448.457984 -118.829443) (xy 448.404027 -118.843549)
			(xy 448.34859 -118.849649) (xy 448.292856 -118.847612) (xy 448.238013 -118.837482) (xy 448.185229 -118.819475)
			(xy 448.135629 -118.793974) (xy 448.090271 -118.761523) (xy 448.050122 -118.722814) (xy 448.016036 -118.678671)
			(xy 447.98874 -118.630036) (xy 447.968817 -118.577945) (xy 447.956691 -118.523508) (xy 447.95262 -118.467886)
			(xy 446.62217 -118.467886) (xy 446.62168 -118.497854) (xy 446.613857 -118.557276) (xy 446.598344 -118.615169)
			(xy 446.575408 -118.670542) (xy 446.545441 -118.722448) (xy 446.508954 -118.769998) (xy 446.466574 -118.812378)
			(xy 446.419024 -118.848865) (xy 446.367118 -118.878832) (xy 446.311745 -118.901768) (xy 446.253852 -118.917281)
			(xy 446.19443 -118.925104) (xy 446.134494 -118.925104) (xy 446.075072 -118.917281) (xy 446.017179 -118.901768)
			(xy 445.961806 -118.878832) (xy 445.9099 -118.848865) (xy 445.86235 -118.812378) (xy 445.81997 -118.769998)
			(xy 445.783483 -118.722448) (xy 445.753516 -118.670542) (xy 445.73058 -118.615169) (xy 445.715067 -118.557276)
			(xy 445.707244 -118.497854) (xy 442.339674 -118.497854) (xy 442.339476 -118.501414) (xy 442.339476 -118.57609)
			(xy 442.340004 -118.58664) (xy 442.348541 -118.605935) (xy 442.355986 -118.613428) (xy 442.375076 -118.631552)
			(xy 442.408554 -118.672174) (xy 442.436123 -118.717017) (xy 442.45726 -118.765227) (xy 442.471562 -118.815886)
			(xy 442.478757 -118.868032) (xy 442.479176 -118.894352) (xy 442.47869 -118.921603) (xy 442.470934 -118.975551)
			(xy 442.455579 -119.027846) (xy 442.432937 -119.077423) (xy 442.403471 -119.123273) (xy 442.36778 -119.164464)
			(xy 442.326589 -119.200155) (xy 442.280739 -119.229621) (xy 442.231162 -119.252263) (xy 442.178867 -119.267618)
			(xy 442.124919 -119.275374) (xy 442.070417 -119.275374) (xy 442.016469 -119.267618) (xy 441.964174 -119.252263)
			(xy 441.914597 -119.229621) (xy 441.868747 -119.200155) (xy 441.827556 -119.164464) (xy 441.791865 -119.123273)
			(xy 441.762399 -119.077423) (xy 441.739757 -119.027846) (xy 441.724402 -118.975551) (xy 441.716646 -118.921603)
			(xy 441.71616 -118.894352) (xy 430.357488 -118.894352) (xy 430.30775 -118.93677) (xy 430.299789 -118.944367)
			(xy 430.290703 -118.964384) (xy 430.290224 -118.975378) (xy 430.290224 -119.27967) (xy 430.290684 -119.290665)
			(xy 430.29979 -119.310677) (xy 430.30775 -119.318278) (xy 430.37506 -119.375682) (xy 430.396396 -119.381778)
			(xy 430.407318 -119.38) (xy 430.421956 -119.377862) (xy 430.451453 -119.375572) (xy 430.466246 -119.375428)
			(xy 430.493498 -119.375845) (xy 430.547446 -119.383608) (xy 430.59974 -119.398968) (xy 430.618543 -119.407557)
			(xy 442.799609 -119.407557) (xy 442.799609 -119.353043) (xy 442.807368 -119.299083) (xy 442.822727 -119.246777)
			(xy 442.845374 -119.197189) (xy 442.874848 -119.151329) (xy 442.910548 -119.110131) (xy 442.951749 -119.074433)
			(xy 442.99761 -119.044962) (xy 443.0472 -119.022318) (xy 443.099507 -119.006962) (xy 443.153467 -118.999207)
			(xy 443.180724 -118.998746) (xy 443.208095 -118.999187) (xy 443.262276 -119.007009) (xy 443.31478 -119.022503)
			(xy 443.364526 -119.045351) (xy 443.410492 -119.075082) (xy 443.431422 -119.092726) (xy 443.438534 -119.098822)
			(xy 443.455552 -119.105172) (xy 443.540896 -119.105172) (xy 443.557914 -119.098822) (xy 443.565026 -119.092726)
			(xy 443.585979 -119.075112) (xy 443.631945 -119.045396) (xy 443.681688 -119.022554) (xy 443.734184 -119.007058)
			(xy 443.788356 -118.999223) (xy 443.815724 -118.998746) (xy 443.842971 -118.999326) (xy 443.896909 -119.007084)
			(xy 443.949195 -119.022439) (xy 443.998763 -119.045079) (xy 444.044605 -119.074543) (xy 444.085787 -119.11023)
			(xy 444.121472 -119.151414) (xy 444.150932 -119.197258) (xy 444.173569 -119.246828) (xy 444.188921 -119.299114)
			(xy 444.196676 -119.353053) (xy 444.196676 -119.407547) (xy 444.188921 -119.461486) (xy 444.173569 -119.513772)
			(xy 444.150932 -119.563342) (xy 444.121472 -119.609186) (xy 444.085787 -119.65037) (xy 444.044605 -119.686057)
			(xy 443.998763 -119.715521) (xy 443.949195 -119.738161) (xy 443.896909 -119.753516) (xy 443.842971 -119.761274)
			(xy 443.815724 -119.761762) (xy 443.788354 -119.761291) (xy 443.734175 -119.753476) (xy 443.681671 -119.737988)
			(xy 443.631924 -119.715148) (xy 443.585957 -119.685423) (xy 443.565026 -119.667782) (xy 443.557914 -119.661686)
			(xy 443.540896 -119.655336) (xy 443.455552 -119.655336) (xy 443.438534 -119.661686) (xy 443.431422 -119.667782)
			(xy 443.41049 -119.685421) (xy 443.364518 -119.715134) (xy 443.31477 -119.73797) (xy 443.262269 -119.753461)
			(xy 443.208093 -119.761288) (xy 443.180724 -119.761762) (xy 443.153467 -119.761393) (xy 443.099507 -119.753638)
			(xy 443.0472 -119.738282) (xy 442.99761 -119.715638) (xy 442.951749 -119.686167) (xy 442.910548 -119.650469)
			(xy 442.874848 -119.609271) (xy 442.845374 -119.563411) (xy 442.822727 -119.513823) (xy 442.807368 -119.461517)
			(xy 442.799609 -119.407557) (xy 430.618543 -119.407557) (xy 430.649316 -119.421614) (xy 430.695165 -119.451084)
			(xy 430.736353 -119.486779) (xy 430.772043 -119.527972) (xy 430.801508 -119.573825) (xy 430.824148 -119.623403)
			(xy 430.839502 -119.6757) (xy 430.847258 -119.729648) (xy 430.847258 -119.784152) (xy 430.839502 -119.838101)
			(xy 430.824148 -119.890397) (xy 430.801508 -119.939975) (xy 430.772043 -119.985828) (xy 430.736353 -120.027021)
			(xy 430.695165 -120.062716) (xy 430.649316 -120.092186) (xy 430.59974 -120.114832) (xy 430.547446 -120.130192)
			(xy 430.493498 -120.137955) (xy 430.466246 -120.138444) (xy 430.44032 -120.138) (xy 430.388942 -120.130999)
			(xy 430.338986 -120.117106) (xy 430.291371 -120.096576) (xy 430.246974 -120.069789) (xy 430.206613 -120.037237)
			(xy 430.171031 -119.999519) (xy 430.155604 -119.978678) (xy 430.149859 -119.971351) (xy 430.13436 -119.961062)
			(xy 430.125378 -119.958612) (xy 430.095152 -119.951754) (xy 430.085875 -119.950008) (xy 430.067213 -119.952748)
			(xy 430.05883 -119.957088) (xy 430.032831 -119.971319) (xy 429.977966 -119.993737) (xy 429.920669 -120.0089)
			(xy 429.861896 -120.016556) (xy 429.832262 -120.017032) (xy 429.802625 -120.016564) (xy 429.743843 -120.008946)
			(xy 429.686539 -119.99379) (xy 429.631677 -119.971351) (xy 429.605694 -119.957088) (xy 429.597286 -119.952831)
			(xy 429.578652 -119.950103) (xy 429.569372 -119.951754) (xy 429.539146 -119.958612) (xy 429.530152 -119.961037)
			(xy 429.514648 -119.971332) (xy 429.50892 -119.978678) (xy 429.493498 -119.999526) (xy 429.457929 -120.037263)
			(xy 429.417573 -120.06983) (xy 429.373176 -120.096626) (xy 429.325556 -120.117157) (xy 429.275592 -120.131044)
			(xy 429.224207 -120.13803) (xy 429.198278 -120.138444) (xy 429.17103 -120.137884) (xy 429.11709 -120.130126)
			(xy 429.064803 -120.11477) (xy 429.015233 -120.09213) (xy 428.96939 -120.062666) (xy 428.928206 -120.026978)
			(xy 428.892521 -119.985792) (xy 428.863059 -119.939947) (xy 428.840422 -119.890376) (xy 428.825069 -119.838088)
			(xy 428.817314 -119.784148) (xy 428.817314 -119.729652) (xy 428.825069 -119.675712) (xy 428.840422 -119.623424)
			(xy 428.863059 -119.573853) (xy 428.892521 -119.528008) (xy 428.928206 -119.486822) (xy 428.96939 -119.451134)
			(xy 429.015233 -119.42167) (xy 429.064803 -119.39903) (xy 429.11709 -119.383674) (xy 429.17103 -119.375916)
			(xy 429.198278 -119.375428) (xy 429.213071 -119.375564) (xy 429.242569 -119.377852) (xy 429.257206 -119.38)
			(xy 429.268128 -119.381778) (xy 429.289464 -119.375682) (xy 429.356774 -119.318278) (xy 429.364762 -119.310705)
			(xy 429.373832 -119.29067) (xy 429.3743 -119.27967) (xy 429.3743 -118.975378) (xy 429.373807 -118.964388)
			(xy 429.364723 -118.944375) (xy 429.356774 -118.93677) (xy 429.289464 -118.879366) (xy 429.268128 -118.87327)
			(xy 429.257206 -118.875048) (xy 429.242567 -118.877183) (xy 429.213071 -118.879475) (xy 429.198278 -118.87962)
			(xy 429.171029 -118.879108) (xy 429.117085 -118.871349) (xy 429.064795 -118.855993) (xy 429.015222 -118.833351)
			(xy 428.969376 -118.803885) (xy 428.928189 -118.768195) (xy 428.892501 -118.727007) (xy 428.863038 -118.681159)
			(xy 428.840399 -118.631585) (xy 428.825046 -118.579293) (xy 428.81729 -118.525349) (xy 422.79534 -118.525349)
			(xy 422.783926 -118.535738) (xy 422.737107 -118.567132) (xy 422.686178 -118.591292) (xy 422.632247 -118.607693)
			(xy 422.576489 -118.615976) (xy 422.548304 -118.616476) (xy 422.521049 -118.616077) (xy 422.467093 -118.60832)
			(xy 422.41479 -118.592963) (xy 422.365205 -118.570319) (xy 422.319348 -118.540849) (xy 422.278151 -118.505152)
			(xy 422.242454 -118.463956) (xy 422.212983 -118.418098) (xy 422.190338 -118.368514) (xy 422.174981 -118.316211)
			(xy 422.167223 -118.262255) (xy 421.371667 -118.262255) (xy 421.028876 -118.605046) (xy 421.021479 -118.611894)
			(xy 421.00288 -118.619629) (xy 420.992808 -118.620032) (xy 420.522908 -118.620032) (xy 420.512888 -118.620451)
			(xy 420.494374 -118.62812) (xy 420.480207 -118.642294) (xy 420.472546 -118.660812) (xy 420.472108 -118.670832)
			(xy 420.472108 -118.672864) (xy 420.472362 -118.674642) (xy 420.473632 -118.711218) (xy 420.473632 -119.414544)
			(xy 420.473218 -119.443203) (xy 420.466466 -119.50012) (xy 420.46017 -119.528082) (xy 420.457376 -119.539766)
			(xy 420.462456 -119.562372) (xy 420.527734 -119.643906) (xy 420.548816 -119.653812) (xy 420.560754 -119.653558)
			(xy 420.567104 -119.653558) (xy 420.59436 -119.654021) (xy 420.648316 -119.66178) (xy 420.70062 -119.677138)
			(xy 420.750205 -119.699784) (xy 420.796062 -119.729256) (xy 420.837258 -119.764954) (xy 420.872955 -119.806152)
			(xy 420.902425 -119.852011) (xy 420.925068 -119.901597) (xy 420.940424 -119.953901) (xy 420.94818 -120.007858)
			(xy 420.948179 -120.035066) (xy 422.166286 -120.035066) (xy 422.170357 -119.979444) (xy 422.182483 -119.925007)
			(xy 422.202406 -119.872916) (xy 422.229702 -119.824281) (xy 422.263788 -119.780138) (xy 422.303937 -119.741429)
			(xy 422.349295 -119.708978) (xy 422.398895 -119.683477) (xy 422.451679 -119.66547) (xy 422.506522 -119.65534)
			(xy 422.562256 -119.653303) (xy 422.617693 -119.659403) (xy 422.67165 -119.673509) (xy 422.722979 -119.695321)
			(xy 422.770585 -119.724375) (xy 422.813453 -119.76005) (xy 422.85067 -119.801587) (xy 422.881443 -119.8481)
			(xy 422.905115 -119.898597) (xy 422.921183 -119.952004) (xy 422.929303 -120.00718) (xy 422.929812 -120.035066)
			(xy 422.929303 -120.062952) (xy 422.921183 -120.118128) (xy 422.905115 -120.171535) (xy 422.881443 -120.222032)
			(xy 422.85067 -120.268545) (xy 422.813453 -120.310082) (xy 422.787292 -120.331853) (xy 431.459338 -120.331853)
			(xy 431.459338 -120.277347) (xy 431.467095 -120.223394) (xy 431.482451 -120.171095) (xy 431.505093 -120.121514)
			(xy 431.534561 -120.075659) (xy 431.570255 -120.034465) (xy 431.611448 -119.99877) (xy 431.657301 -119.9693)
			(xy 431.706882 -119.946656) (xy 431.759181 -119.931298) (xy 431.813133 -119.923539) (xy 431.840386 -119.923052)
			(xy 431.866313 -119.923474) (xy 431.917691 -119.930479) (xy 431.967648 -119.944376) (xy 432.015263 -119.964909)
			(xy 432.05966 -119.9917) (xy 432.10002 -120.024255) (xy 432.135601 -120.061976) (xy 432.151028 -120.082818)
			(xy 432.156797 -120.090123) (xy 432.172279 -120.100424) (xy 432.181254 -120.102884) (xy 432.21148 -120.109742)
			(xy 432.220755 -120.111505) (xy 432.23942 -120.108754) (xy 432.247802 -120.104408) (xy 432.273794 -120.090165)
			(xy 432.328662 -120.06775) (xy 432.385961 -120.05259) (xy 432.444735 -120.044938) (xy 432.47437 -120.044464)
			(xy 432.504008 -120.044918) (xy 432.56279 -120.052541) (xy 432.620093 -120.067701) (xy 432.674955 -120.090143)
			(xy 432.700938 -120.104408) (xy 432.709361 -120.108631) (xy 432.727983 -120.111381) (xy 432.73726 -120.109742)
			(xy 432.767486 -120.102884) (xy 432.776485 -120.100474) (xy 432.791987 -120.090168) (xy 432.797712 -120.082818)
			(xy 432.813113 -120.061954) (xy 432.848686 -120.024218) (xy 432.889045 -119.991652) (xy 432.933446 -119.964858)
			(xy 432.98107 -119.944329) (xy 433.031037 -119.930446) (xy 433.082424 -119.923464) (xy 433.108354 -119.923052)
			(xy 433.135606 -119.923592) (xy 433.189556 -119.931343) (xy 433.205443 -119.936006) (xy 440.994544 -119.936006)
			(xy 440.998615 -119.880384) (xy 441.010741 -119.825947) (xy 441.030664 -119.773856) (xy 441.05796 -119.725221)
			(xy 441.092046 -119.681078) (xy 441.132195 -119.642369) (xy 441.177553 -119.609918) (xy 441.227153 -119.584417)
			(xy 441.279937 -119.56641) (xy 441.33478 -119.55628) (xy 441.390514 -119.554243) (xy 441.445951 -119.560343)
			(xy 441.499908 -119.574449) (xy 441.551237 -119.596261) (xy 441.598843 -119.625315) (xy 441.641711 -119.66099)
			(xy 441.678928 -119.702527) (xy 441.709701 -119.74904) (xy 441.733373 -119.799537) (xy 441.749441 -119.852944)
			(xy 441.757561 -119.90812) (xy 441.757833 -119.923048) (xy 445.793858 -119.923048) (xy 445.793858 -119.863112)
			(xy 445.801681 -119.80369) (xy 445.817194 -119.745797) (xy 445.84013 -119.690424) (xy 445.870097 -119.638518)
			(xy 445.906584 -119.590968) (xy 445.948964 -119.548588) (xy 445.996514 -119.512101) (xy 446.04842 -119.482134)
			(xy 446.103793 -119.459198) (xy 446.161686 -119.443685) (xy 446.221108 -119.435862) (xy 446.281044 -119.435862)
			(xy 446.340466 -119.443685) (xy 446.398359 -119.459198) (xy 446.453732 -119.482134) (xy 446.505638 -119.512101)
			(xy 446.553188 -119.548588) (xy 446.595568 -119.590968) (xy 446.632055 -119.638518) (xy 446.662022 -119.690424)
			(xy 446.684958 -119.745797) (xy 446.700471 -119.80369) (xy 446.708294 -119.863112) (xy 446.708784 -119.89308)
			(xy 446.708294 -119.923048) (xy 446.700471 -119.98247) (xy 446.684958 -120.040363) (xy 446.662022 -120.095736)
			(xy 446.632055 -120.147642) (xy 446.595568 -120.195192) (xy 446.553188 -120.237572) (xy 446.505638 -120.274059)
			(xy 446.453732 -120.304026) (xy 446.398359 -120.326962) (xy 446.340466 -120.342475) (xy 446.281044 -120.350298)
			(xy 446.221108 -120.350298) (xy 446.161686 -120.342475) (xy 446.103793 -120.326962) (xy 446.04842 -120.304026)
			(xy 445.996514 -120.274059) (xy 445.948964 -120.237572) (xy 445.906584 -120.195192) (xy 445.870097 -120.147642)
			(xy 445.84013 -120.095736) (xy 445.817194 -120.040363) (xy 445.801681 -119.98247) (xy 445.793858 -119.923048)
			(xy 441.757833 -119.923048) (xy 441.75807 -119.936006) (xy 441.757561 -119.963892) (xy 441.749441 -120.019068)
			(xy 441.733373 -120.072475) (xy 441.709701 -120.122972) (xy 441.678928 -120.169485) (xy 441.641711 -120.211022)
			(xy 441.598843 -120.246697) (xy 441.551237 -120.275751) (xy 441.499908 -120.297563) (xy 441.445951 -120.311669)
			(xy 441.390514 -120.317769) (xy 441.33478 -120.315732) (xy 441.279937 -120.305602) (xy 441.227153 -120.287595)
			(xy 441.177553 -120.262094) (xy 441.132195 -120.229643) (xy 441.092046 -120.190934) (xy 441.05796 -120.146791)
			(xy 441.030664 -120.098156) (xy 441.010741 -120.046065) (xy 440.998615 -119.991628) (xy 440.994544 -119.936006)
			(xy 433.205443 -119.936006) (xy 433.241854 -119.946693) (xy 433.291435 -119.969331) (xy 433.337289 -119.998795)
			(xy 433.378483 -120.034484) (xy 433.414178 -120.075674) (xy 433.443647 -120.121525) (xy 433.466291 -120.171103)
			(xy 433.481647 -120.223399) (xy 433.489405 -120.277348) (xy 433.489405 -120.331852) (xy 433.481647 -120.385801)
			(xy 433.466291 -120.438097) (xy 433.443647 -120.487675) (xy 433.414178 -120.533526) (xy 433.378483 -120.574716)
			(xy 433.337289 -120.610405) (xy 433.291435 -120.639869) (xy 433.241854 -120.662507) (xy 433.189556 -120.677857)
			(xy 433.135606 -120.685608) (xy 433.108354 -120.686068) (xy 433.093561 -120.685928) (xy 433.064063 -120.683642)
			(xy 433.049426 -120.681496) (xy 433.038504 -120.679718) (xy 433.017168 -120.685814) (xy 432.949858 -120.743218)
			(xy 432.941877 -120.750797) (xy 432.932801 -120.770828) (xy 432.932332 -120.781826) (xy 432.932332 -121.086118)
			(xy 432.932818 -121.09711) (xy 432.941906 -121.117122) (xy 432.949858 -121.124726) (xy 433.017168 -121.18213)
			(xy 433.038504 -121.188226) (xy 433.049426 -121.186448) (xy 433.064064 -121.184309) (xy 433.093561 -121.18202)
			(xy 433.108354 -121.181876) (xy 433.135608 -121.182368) (xy 433.189561 -121.190119) (xy 433.241863 -121.205471)
			(xy 433.291447 -121.22811) (xy 433.337303 -121.257575) (xy 433.35019 -121.26874) (xy 445.809098 -121.26874)
			(xy 445.809098 -121.208804) (xy 445.816921 -121.149382) (xy 445.832434 -121.091489) (xy 445.85537 -121.036116)
			(xy 445.885337 -120.98421) (xy 445.921824 -120.93666) (xy 445.964204 -120.89428) (xy 446.011754 -120.857793)
			(xy 446.06366 -120.827826) (xy 446.119033 -120.80489) (xy 446.176926 -120.789377) (xy 446.236348 -120.781554)
			(xy 446.296284 -120.781554) (xy 446.355706 -120.789377) (xy 446.413599 -120.80489) (xy 446.468972 -120.827826)
			(xy 446.520878 -120.857793) (xy 446.568428 -120.89428) (xy 446.610808 -120.93666) (xy 446.647295 -120.98421)
			(xy 446.677262 -121.036116) (xy 446.700198 -121.091489) (xy 446.715711 -121.149382) (xy 446.723534 -121.208804)
			(xy 446.724024 -121.238772) (xy 446.723534 -121.26874) (xy 446.715711 -121.328162) (xy 446.700198 -121.386055)
			(xy 446.677262 -121.441428) (xy 446.647295 -121.493334) (xy 446.635252 -121.509028) (xy 447.929506 -121.509028)
			(xy 447.933577 -121.453406) (xy 447.945703 -121.398969) (xy 447.965626 -121.346878) (xy 447.992922 -121.298243)
			(xy 448.027008 -121.2541) (xy 448.067157 -121.215391) (xy 448.112515 -121.18294) (xy 448.162115 -121.157439)
			(xy 448.214899 -121.139432) (xy 448.269742 -121.129302) (xy 448.325476 -121.127265) (xy 448.380913 -121.133365)
			(xy 448.43487 -121.147471) (xy 448.486199 -121.169283) (xy 448.533805 -121.198337) (xy 448.576673 -121.234012)
			(xy 448.61389 -121.275549) (xy 448.644663 -121.322062) (xy 448.668335 -121.372559) (xy 448.684403 -121.425966)
			(xy 448.692523 -121.481142) (xy 448.693032 -121.509028) (xy 448.692523 -121.536914) (xy 448.684403 -121.59209)
			(xy 448.668335 -121.645497) (xy 448.644663 -121.695994) (xy 448.61389 -121.742507) (xy 448.576673 -121.784044)
			(xy 448.547598 -121.80824) (xy 448.836032 -121.80824) (xy 448.840103 -121.752618) (xy 448.852229 -121.698181)
			(xy 448.872152 -121.64609) (xy 448.899448 -121.597455) (xy 448.933534 -121.553312) (xy 448.973683 -121.514603)
			(xy 449.019041 -121.482152) (xy 449.068641 -121.456651) (xy 449.121425 -121.438644) (xy 449.176268 -121.428514)
			(xy 449.232002 -121.426477) (xy 449.287439 -121.432577) (xy 449.341396 -121.446683) (xy 449.392725 -121.468495)
			(xy 449.440331 -121.497549) (xy 449.483199 -121.533224) (xy 449.520416 -121.574761) (xy 449.551189 -121.621274)
			(xy 449.574861 -121.671771) (xy 449.590929 -121.725178) (xy 449.599049 -121.780354) (xy 449.599558 -121.80824)
			(xy 449.599049 -121.836126) (xy 449.590929 -121.891302) (xy 449.574861 -121.944709) (xy 449.551189 -121.995206)
			(xy 449.520416 -122.041719) (xy 449.483199 -122.083256) (xy 449.440331 -122.118931) (xy 449.392725 -122.147985)
			(xy 449.341396 -122.169797) (xy 449.287439 -122.183903) (xy 449.232002 -122.190003) (xy 449.176268 -122.187966)
			(xy 449.121425 -122.177836) (xy 449.068641 -122.159829) (xy 449.019041 -122.134328) (xy 448.973683 -122.101877)
			(xy 448.933534 -122.063168) (xy 448.899448 -122.019025) (xy 448.872152 -121.97039) (xy 448.852229 -121.918299)
			(xy 448.840103 -121.863862) (xy 448.836032 -121.80824) (xy 448.547598 -121.80824) (xy 448.533805 -121.819719)
			(xy 448.486199 -121.848773) (xy 448.43487 -121.870585) (xy 448.380913 -121.884691) (xy 448.325476 -121.890791)
			(xy 448.269742 -121.888754) (xy 448.214899 -121.878624) (xy 448.162115 -121.860617) (xy 448.112515 -121.835116)
			(xy 448.067157 -121.802665) (xy 448.027008 -121.763956) (xy 447.992922 -121.719813) (xy 447.965626 -121.671178)
			(xy 447.945703 -121.619087) (xy 447.933577 -121.56465) (xy 447.929506 -121.509028) (xy 446.635252 -121.509028)
			(xy 446.610808 -121.540884) (xy 446.568428 -121.583264) (xy 446.520878 -121.619751) (xy 446.468972 -121.649718)
			(xy 446.413599 -121.672654) (xy 446.355706 -121.688167) (xy 446.296284 -121.69599) (xy 446.236348 -121.69599)
			(xy 446.176926 -121.688167) (xy 446.119033 -121.672654) (xy 446.06366 -121.649718) (xy 446.011754 -121.619751)
			(xy 445.964204 -121.583264) (xy 445.921824 -121.540884) (xy 445.885337 -121.493334) (xy 445.85537 -121.441428)
			(xy 445.832434 -121.386055) (xy 445.816921 -121.328162) (xy 445.809098 -121.26874) (xy 433.35019 -121.26874)
			(xy 433.3785 -121.293268) (xy 433.414197 -121.33446) (xy 433.443668 -121.380313) (xy 433.466313 -121.429894)
			(xy 433.481671 -121.482193) (xy 433.489429 -121.536146) (xy 433.489429 -121.590654) (xy 433.481671 -121.644607)
			(xy 433.466313 -121.696906) (xy 433.443668 -121.746487) (xy 433.414197 -121.79234) (xy 433.3785 -121.833532)
			(xy 433.337303 -121.869225) (xy 433.291447 -121.89869) (xy 433.241863 -121.921329) (xy 433.189561 -121.936681)
			(xy 433.135608 -121.944432) (xy 433.108354 -121.944892) (xy 433.082426 -121.944497) (xy 433.031048 -121.937484)
			(xy 432.981091 -121.923581) (xy 432.933476 -121.903043) (xy 432.88908 -121.876249) (xy 432.84872 -121.843691)
			(xy 432.813139 -121.805969) (xy 432.797712 -121.785126) (xy 432.791975 -121.777793) (xy 432.77647 -121.767509)
			(xy 432.767486 -121.76506) (xy 432.73726 -121.758202) (xy 432.727983 -121.756455) (xy 432.70932 -121.759194)
			(xy 432.700938 -121.763536) (xy 432.674956 -121.777798) (xy 432.620084 -121.800209) (xy 432.562782 -121.815364)
			(xy 432.504006 -121.82301) (xy 432.47437 -121.82348) (xy 432.444733 -121.823016) (xy 432.38595 -121.815397)
			(xy 432.328647 -121.800241) (xy 432.273785 -121.7778) (xy 432.247802 -121.763536) (xy 432.239393 -121.759281)
			(xy 432.22076 -121.756553) (xy 432.21148 -121.758202) (xy 432.181254 -121.76506) (xy 432.172267 -121.767505)
			(xy 432.15676 -121.777787) (xy 432.151028 -121.785126) (xy 432.135615 -121.805981) (xy 432.100043 -121.843716)
			(xy 432.059685 -121.876281) (xy 432.015286 -121.903075) (xy 431.967665 -121.923605) (xy 431.917701 -121.937491)
			(xy 431.866315 -121.944477) (xy 431.840386 -121.944892) (xy 431.813134 -121.944437) (xy 431.759186 -121.936679)
			(xy 431.706891 -121.921322) (xy 431.657313 -121.898679) (xy 431.611462 -121.869211) (xy 431.570272 -121.833518)
			(xy 431.534581 -121.792326) (xy 431.505114 -121.746475) (xy 431.482473 -121.696896) (xy 431.467118 -121.644601)
			(xy 431.459362 -121.590652) (xy 431.459362 -121.536148) (xy 431.467118 -121.482199) (xy 431.482473 -121.429904)
			(xy 431.505114 -121.380325) (xy 431.534581 -121.334474) (xy 431.570272 -121.293282) (xy 431.611462 -121.257589)
			(xy 431.657313 -121.228121) (xy 431.706891 -121.205478) (xy 431.759186 -121.190121) (xy 431.813134 -121.182363)
			(xy 431.840386 -121.181876) (xy 431.855179 -121.182012) (xy 431.884677 -121.1843) (xy 431.899314 -121.186448)
			(xy 431.910236 -121.188226) (xy 431.931572 -121.18213) (xy 431.998882 -121.124726) (xy 432.00685 -121.117135)
			(xy 432.015931 -121.097113) (xy 432.016408 -121.086118) (xy 432.016408 -120.781826) (xy 432.015941 -120.770833)
			(xy 432.006838 -120.750821) (xy 431.998882 -120.743218) (xy 431.931572 -120.685814) (xy 431.910236 -120.679718)
			(xy 431.899314 -120.681496) (xy 431.884677 -120.683641) (xy 431.855179 -120.685926) (xy 431.840386 -120.686068)
			(xy 431.813133 -120.685661) (xy 431.759181 -120.677902) (xy 431.706882 -120.662544) (xy 431.657301 -120.6399)
			(xy 431.611448 -120.61043) (xy 431.570255 -120.574735) (xy 431.534561 -120.533541) (xy 431.505093 -120.487686)
			(xy 431.482451 -120.438105) (xy 431.467095 -120.385806) (xy 431.459338 -120.331853) (xy 422.787292 -120.331853)
			(xy 422.770585 -120.345757) (xy 422.722979 -120.374811) (xy 422.67165 -120.396623) (xy 422.617693 -120.410729)
			(xy 422.562256 -120.416829) (xy 422.506522 -120.414792) (xy 422.451679 -120.404662) (xy 422.398895 -120.386655)
			(xy 422.349295 -120.361154) (xy 422.303937 -120.328703) (xy 422.263788 -120.289994) (xy 422.229702 -120.245851)
			(xy 422.202406 -120.197216) (xy 422.182483 -120.145125) (xy 422.170357 -120.090688) (xy 422.166286 -120.035066)
			(xy 420.948179 -120.035066) (xy 420.948178 -120.06237) (xy 420.940418 -120.116326) (xy 420.925058 -120.168629)
			(xy 420.902411 -120.218213) (xy 420.872938 -120.26407) (xy 420.837238 -120.305265) (xy 420.79604 -120.340961)
			(xy 420.75018 -120.370429) (xy 420.700593 -120.393072) (xy 420.648289 -120.408426) (xy 420.594332 -120.416181)
			(xy 420.53982 -120.416177) (xy 420.485864 -120.408416) (xy 420.433562 -120.393055) (xy 420.383978 -120.370406)
			(xy 420.338122 -120.340932) (xy 420.296928 -120.305231) (xy 420.261233 -120.264032) (xy 420.231766 -120.218171)
			(xy 420.209125 -120.168584) (xy 420.193772 -120.116279) (xy 420.186019 -120.062322) (xy 420.185596 -120.035066)
			(xy 420.18712 -120.000522) (xy 420.188136 -119.988584) (xy 420.180008 -119.96674) (xy 420.103554 -119.895874)
			(xy 420.081202 -119.889016) (xy 420.069518 -119.891048) (xy 420.049975 -119.894101) (xy 420.010556 -119.897406)
			(xy 419.990778 -119.897652) (xy 419.959153 -119.897155) (xy 419.896444 -119.888894) (xy 419.835352 -119.872516)
			(xy 419.77692 -119.848302) (xy 419.72215 -119.816665) (xy 419.67198 -119.778148) (xy 419.627268 -119.733411)
			(xy 419.58878 -119.683218) (xy 419.557175 -119.62843) (xy 419.532994 -119.569985) (xy 419.516652 -119.508883)
			(xy 419.508426 -119.446169) (xy 419.507924 -119.414544) (xy 419.507924 -119.079264) (xy 419.507368 -119.069283)
			(xy 419.499646 -119.050866) (xy 419.485524 -119.036747) (xy 419.467105 -119.029029) (xy 419.457124 -119.028464)
			(xy 419.378892 -119.028464) (xy 419.368895 -119.028984) (xy 419.350433 -119.036672) (xy 419.336288 -119.05081)
			(xy 419.32859 -119.069267) (xy 419.328092 -119.079264) (xy 419.328092 -119.088408) (xy 419.06063 -119.088408)
			(xy 419.036042 -119.087819) (xy 418.988014 -119.077268) (xy 418.943399 -119.056593) (xy 418.92347 -119.04218)
			(xy 418.916721 -119.037333) (xy 418.901036 -119.031889) (xy 418.892736 -119.031512) (xy 418.712904 -119.031512)
			(xy 418.706082 -119.031804) (xy 418.692953 -119.035541) (xy 418.686996 -119.038878) (xy 418.664726 -119.051663)
			(xy 418.617489 -119.071803) (xy 418.56798 -119.085435) (xy 418.517092 -119.092314) (xy 418.491416 -119.092726)
			(xy 418.464162 -119.092264) (xy 418.41021 -119.084507) (xy 418.357911 -119.069149) (xy 418.308331 -119.046503)
			(xy 418.26248 -119.01703) (xy 418.221291 -118.98133) (xy 418.185603 -118.94013) (xy 418.156143 -118.89427)
			(xy 418.133512 -118.844683) (xy 418.125402 -118.81866) (xy 418.122608 -118.80977) (xy 418.111432 -118.795038)
			(xy 418.038534 -118.749318) (xy 418.020246 -118.745508) (xy 418.011102 -118.747032) (xy 417.995471 -118.749502)
			(xy 417.963934 -118.75217) (xy 417.94811 -118.752366) (xy 417.92253 -118.751955) (xy 417.87183 -118.745121)
			(xy 417.822497 -118.731573) (xy 417.775416 -118.711554) (xy 417.731433 -118.685425) (xy 417.691336 -118.653652)
			(xy 417.673282 -118.635526) (xy 417.665835 -118.628462) (xy 417.64696 -118.620446) (xy 417.636706 -118.620032)
			(xy 415.864802 -118.620032) (xy 415.854783 -118.620452) (xy 415.836271 -118.628123) (xy 415.822106 -118.642296)
			(xy 415.814446 -118.660813) (xy 415.814002 -118.670832) (xy 415.814002 -118.672356) (xy 415.814256 -118.674134)
			(xy 415.815272 -118.703598) (xy 415.815272 -119.567198) (xy 415.814764 -119.586502) (xy 415.814774 -119.598046)
			(xy 415.823889 -119.619228) (xy 415.83229 -119.627142) (xy 415.856674 -119.648224) (xy 415.865687 -119.655132)
			(xy 415.887574 -119.661082) (xy 415.898838 -119.659654) (xy 415.915711 -119.6568) (xy 415.949798 -119.653745)
			(xy 415.96691 -119.653558) (xy 415.994163 -119.654045) (xy 416.048115 -119.661803) (xy 416.100413 -119.67716)
			(xy 416.149993 -119.699804) (xy 416.195846 -119.729273) (xy 416.237039 -119.764968) (xy 416.272733 -119.806162)
			(xy 416.302201 -119.852016) (xy 416.324843 -119.901597) (xy 416.340199 -119.953895) (xy 416.347956 -120.007847)
			(xy 416.347956 -120.062353) (xy 416.340199 -120.116305) (xy 416.324843 -120.168603) (xy 416.302201 -120.218184)
			(xy 416.272733 -120.264038) (xy 416.237039 -120.305232) (xy 416.195846 -120.340927) (xy 416.149993 -120.370396)
			(xy 416.100413 -120.39304) (xy 416.048115 -120.408397) (xy 415.994163 -120.416155) (xy 415.96691 -120.416574)
			(xy 415.939937 -120.416101) (xy 415.88653 -120.408488) (xy 415.834729 -120.393428) (xy 415.785566 -120.371219)
			(xy 415.740022 -120.342306) (xy 415.699006 -120.307264) (xy 415.663336 -120.266794) (xy 415.633723 -120.221702)
			(xy 415.610758 -120.172888) (xy 415.594899 -120.121326) (xy 415.590228 -120.094756) (xy 415.58845 -120.084088)
			(xy 415.57702 -120.066562) (xy 415.496756 -120.012968) (xy 415.476182 -120.009412) (xy 415.465768 -120.011952)
			(xy 415.439074 -120.018096) (xy 415.384698 -120.024721) (xy 415.35731 -120.02516) (xy 415.329922 -120.024714)
			(xy 415.275547 -120.018091) (xy 415.248852 -120.011952) (xy 415.238438 -120.009412) (xy 415.217864 -120.012968)
			(xy 415.1376 -120.066562) (xy 415.12617 -120.084088) (xy 415.124392 -120.094756) (xy 415.119729 -120.12133)
			(xy 415.103895 -120.172907) (xy 415.080946 -120.221736) (xy 415.051341 -120.26684) (xy 415.01567 -120.307319)
			(xy 414.974648 -120.342363) (xy 414.929094 -120.371271) (xy 414.879918 -120.393467) (xy 414.828104 -120.408506)
			(xy 414.774687 -120.416088) (xy 414.74771 -120.416574) (xy 414.720342 -120.416096) (xy 414.666171 -120.40826)
			(xy 414.613675 -120.392762) (xy 414.563934 -120.369921) (xy 414.517967 -120.340204) (xy 414.497012 -120.322594)
			(xy 414.4899 -120.316498) (xy 414.472882 -120.310148) (xy 414.387538 -120.310148) (xy 414.37052 -120.316498)
			(xy 414.363408 -120.322594) (xy 414.342477 -120.340237) (xy 414.296511 -120.369964) (xy 414.246764 -120.392809)
			(xy 414.194261 -120.4083) (xy 414.140081 -120.41612) (xy 414.11271 -120.416574) (xy 414.095598 -120.416398)
			(xy 414.06151 -120.413342) (xy 414.044638 -120.410478) (xy 414.03337 -120.40904) (xy 414.011477 -120.41498)
			(xy 414.002474 -120.421908) (xy 413.97809 -120.44299) (xy 413.969835 -120.451014) (xy 413.960726 -120.47212)
			(xy 413.960564 -120.48363) (xy 413.961072 -120.503696) (xy 413.961072 -120.716548) (xy 417.60216 -120.716548)
			(xy 417.606231 -120.660926) (xy 417.618357 -120.606489) (xy 417.63828 -120.554398) (xy 417.665576 -120.505763)
			(xy 417.699662 -120.46162) (xy 417.739811 -120.422911) (xy 417.785169 -120.39046) (xy 417.834769 -120.364959)
			(xy 417.887553 -120.346952) (xy 417.942396 -120.336822) (xy 417.99813 -120.334785) (xy 418.053567 -120.340885)
			(xy 418.107524 -120.354991) (xy 418.158853 -120.376803) (xy 418.206459 -120.405857) (xy 418.249327 -120.441532)
			(xy 418.286544 -120.483069) (xy 418.317317 -120.529582) (xy 418.340989 -120.580079) (xy 418.357057 -120.633486)
			(xy 418.365177 -120.688662) (xy 418.365686 -120.716548) (xy 418.365177 -120.744434) (xy 418.357057 -120.79961)
			(xy 418.340989 -120.853017) (xy 418.317317 -120.903514) (xy 418.286544 -120.950027) (xy 418.249327 -120.991564)
			(xy 418.206459 -121.027239) (xy 418.158853 -121.056293) (xy 418.107524 -121.078105) (xy 418.053567 -121.092211)
			(xy 417.99813 -121.098311) (xy 417.942396 -121.096274) (xy 417.887553 -121.086144) (xy 417.834769 -121.068137)
			(xy 417.785169 -121.042636) (xy 417.739811 -121.010185) (xy 417.699662 -120.971476) (xy 417.665576 -120.927333)
			(xy 417.63828 -120.878698) (xy 417.618357 -120.826607) (xy 417.606231 -120.77217) (xy 417.60216 -120.716548)
			(xy 413.961072 -120.716548) (xy 413.961072 -121.367296) (xy 413.960564 -121.3866) (xy 413.960574 -121.398144)
			(xy 413.969688 -121.419327) (xy 413.97809 -121.42724) (xy 414.002474 -121.448322) (xy 414.011487 -121.45523)
			(xy 414.033374 -121.461181) (xy 414.044638 -121.459752) (xy 414.061511 -121.456898) (xy 414.095598 -121.453844)
			(xy 414.11271 -121.453656) (xy 414.140079 -121.454129) (xy 414.194256 -121.461955) (xy 414.246758 -121.477445)
			(xy 414.296506 -121.50028) (xy 414.342479 -121.529993) (xy 414.363408 -121.547636) (xy 414.37052 -121.553732)
			(xy 414.387538 -121.560082) (xy 414.472882 -121.560082) (xy 414.4899 -121.553732) (xy 414.497012 -121.547636)
			(xy 414.517943 -121.529993) (xy 414.563909 -121.500266) (xy 414.613656 -121.477422) (xy 414.666159 -121.461932)
			(xy 414.720339 -121.454114) (xy 414.74771 -121.453656) (xy 414.7747 -121.454131) (xy 414.828141 -121.461753)
			(xy 414.879974 -121.476829) (xy 414.929165 -121.499058) (xy 414.974733 -121.527997) (xy 415.015769 -121.563069)
			(xy 415.051454 -121.603573) (xy 415.081075 -121.648701) (xy 415.104041 -121.697553) (xy 415.119895 -121.749153)
			(xy 415.124646 -121.775728) (xy 415.12617 -121.78665) (xy 415.1376 -121.804176) (xy 415.217864 -121.857516)
			(xy 415.238438 -121.861326) (xy 415.248852 -121.858786) (xy 415.275552 -121.852703) (xy 415.329928 -121.846212)
			(xy 415.35731 -121.845832) (xy 415.384627 -121.846232) (xy 415.438874 -121.852729) (xy 415.465514 -121.858786)
			(xy 415.476182 -121.861326) (xy 415.496756 -121.857516) (xy 415.57702 -121.804176) (xy 415.58845 -121.786396)
			(xy 415.589974 -121.775728) (xy 415.594626 -121.749122) (xy 415.610448 -121.697481) (xy 415.633395 -121.648588)
			(xy 415.663011 -121.60342) (xy 415.698701 -121.562882) (xy 415.739753 -121.527784) (xy 415.785345 -121.498827)
			(xy 415.834566 -121.476591) (xy 415.886432 -121.461521) (xy 415.939905 -121.453918) (xy 415.96691 -121.453402)
			(xy 415.99416 -121.453889) (xy 416.048105 -121.461646) (xy 416.100397 -121.477002) (xy 416.149972 -121.499643)
			(xy 416.19582 -121.529109) (xy 416.237008 -121.564799) (xy 416.272697 -121.605988) (xy 416.302162 -121.651837)
			(xy 416.324802 -121.701412) (xy 416.340156 -121.753705) (xy 416.347912 -121.80765) (xy 416.347912 -121.83491)
			(xy 420.185086 -121.83491) (xy 420.189157 -121.779288) (xy 420.201283 -121.724851) (xy 420.221206 -121.67276)
			(xy 420.248502 -121.624125) (xy 420.282588 -121.579982) (xy 420.322737 -121.541273) (xy 420.368095 -121.508822)
			(xy 420.417695 -121.483321) (xy 420.470479 -121.465314) (xy 420.525322 -121.455184) (xy 420.581056 -121.453147)
			(xy 420.636493 -121.459247) (xy 420.69045 -121.473353) (xy 420.741779 -121.495165) (xy 420.789385 -121.524219)
			(xy 420.832253 -121.559894) (xy 420.86947 -121.601431) (xy 420.900243 -121.647944) (xy 420.923915 -121.698441)
			(xy 420.939983 -121.751848) (xy 420.948103 -121.807024) (xy 420.948612 -121.83491) (xy 422.166286 -121.83491)
			(xy 422.170357 -121.779288) (xy 422.182483 -121.724851) (xy 422.202406 -121.67276) (xy 422.229702 -121.624125)
			(xy 422.263788 -121.579982) (xy 422.303937 -121.541273) (xy 422.349295 -121.508822) (xy 422.398895 -121.483321)
			(xy 422.451679 -121.465314) (xy 422.506522 -121.455184) (xy 422.562256 -121.453147) (xy 422.617693 -121.459247)
			(xy 422.67165 -121.473353) (xy 422.722979 -121.495165) (xy 422.770585 -121.524219) (xy 422.813453 -121.559894)
			(xy 422.85067 -121.601431) (xy 422.881443 -121.647944) (xy 422.905115 -121.698441) (xy 422.921183 -121.751848)
			(xy 422.929303 -121.807024) (xy 422.929812 -121.83491) (xy 422.929303 -121.862796) (xy 422.921183 -121.917972)
			(xy 422.905115 -121.971379) (xy 422.881443 -122.021876) (xy 422.85067 -122.068389) (xy 422.813453 -122.109926)
			(xy 422.794914 -122.125354) (xy 428.817232 -122.125354) (xy 428.817232 -122.070846) (xy 428.824989 -122.016894)
			(xy 428.840345 -121.964595) (xy 428.862987 -121.915013) (xy 428.892455 -121.869158) (xy 428.928148 -121.827964)
			(xy 428.969341 -121.792268) (xy 429.015194 -121.762797) (xy 429.064774 -121.740152) (xy 429.117073 -121.724793)
			(xy 429.171024 -121.717033) (xy 429.198278 -121.716546) (xy 429.224205 -121.716976) (xy 429.275583 -121.72398)
			(xy 429.325539 -121.737876) (xy 429.373154 -121.758408) (xy 429.417551 -121.785198) (xy 429.457911 -121.817751)
			(xy 429.493493 -121.85547) (xy 429.50892 -121.876312) (xy 429.514658 -121.883645) (xy 429.530162 -121.893931)
			(xy 429.539146 -121.896378) (xy 429.569372 -121.903236) (xy 429.578647 -121.904996) (xy 429.597312 -121.902247)
			(xy 429.605694 -121.897902) (xy 429.631673 -121.883613) (xy 429.686524 -121.8611) (xy 429.743826 -121.845872)
			(xy 429.802617 -121.838185) (xy 429.832262 -121.837704) (xy 429.861904 -121.838216) (xy 429.920685 -121.845935)
			(xy 429.977983 -121.861157) (xy 430.032845 -121.883631) (xy 430.05883 -121.897902) (xy 430.067255 -121.902121)
			(xy 430.085875 -121.904874) (xy 430.095152 -121.903236) (xy 430.125378 -121.896378) (xy 430.134376 -121.893966)
			(xy 430.149879 -121.883662) (xy 430.155604 -121.876312) (xy 430.171008 -121.85545) (xy 430.206581 -121.817714)
			(xy 430.246939 -121.785149) (xy 430.29134 -121.758354) (xy 430.338963 -121.737825) (xy 430.388929 -121.723942)
			(xy 430.440316 -121.716959) (xy 430.466246 -121.716546) (xy 430.493492 -121.717127) (xy 430.547428 -121.724888)
			(xy 430.599711 -121.740245) (xy 430.649276 -121.762886) (xy 430.695115 -121.79235) (xy 430.736295 -121.828038)
			(xy 430.771977 -121.869222) (xy 430.801436 -121.915064) (xy 430.824071 -121.964632) (xy 430.839422 -122.016917)
			(xy 430.847176 -122.070854) (xy 430.847176 -122.125346) (xy 430.839422 -122.179283) (xy 430.824071 -122.231568)
			(xy 430.801436 -122.281136) (xy 430.771977 -122.326978) (xy 430.736295 -122.368162) (xy 430.695115 -122.40385)
			(xy 430.649276 -122.433314) (xy 430.599711 -122.455955) (xy 430.547428 -122.471312) (xy 430.493492 -122.479073)
			(xy 430.466246 -122.479562) (xy 430.451453 -122.479423) (xy 430.421955 -122.477137) (xy 430.407318 -122.47499)
			(xy 430.396396 -122.473212) (xy 430.37506 -122.479308) (xy 430.32145 -122.525028) (xy 447.90563 -122.525028)
			(xy 447.909701 -122.469406) (xy 447.921827 -122.414969) (xy 447.94175 -122.362878) (xy 447.969046 -122.314243)
			(xy 448.003132 -122.2701) (xy 448.043281 -122.231391) (xy 448.088639 -122.19894) (xy 448.138239 -122.173439)
			(xy 448.191023 -122.155432) (xy 448.245866 -122.145302) (xy 448.3016 -122.143265) (xy 448.357037 -122.149365)
			(xy 448.410994 -122.163471) (xy 448.462323 -122.185283) (xy 448.509929 -122.214337) (xy 448.552797 -122.250012)
			(xy 448.590014 -122.291549) (xy 448.620787 -122.338062) (xy 448.644459 -122.388559) (xy 448.660527 -122.441966)
			(xy 448.668647 -122.497142) (xy 448.669156 -122.525028) (xy 448.668647 -122.552914) (xy 448.660527 -122.60809)
			(xy 448.644459 -122.661497) (xy 448.620787 -122.711994) (xy 448.590014 -122.758507) (xy 448.552797 -122.800044)
			(xy 448.509929 -122.835719) (xy 448.462323 -122.864773) (xy 448.410994 -122.886585) (xy 448.357037 -122.900691)
			(xy 448.3016 -122.906791) (xy 448.245866 -122.904754) (xy 448.191023 -122.894624) (xy 448.138239 -122.876617)
			(xy 448.088639 -122.851116) (xy 448.043281 -122.818665) (xy 448.003132 -122.779956) (xy 447.969046 -122.735813)
			(xy 447.94175 -122.687178) (xy 447.921827 -122.635087) (xy 447.909701 -122.58065) (xy 447.90563 -122.525028)
			(xy 430.32145 -122.525028) (xy 430.30775 -122.536712) (xy 430.29977 -122.544293) (xy 430.290694 -122.564322)
			(xy 430.290224 -122.57532) (xy 430.290224 -122.879612) (xy 430.290716 -122.890603) (xy 430.2998 -122.910615)
			(xy 430.30775 -122.91822) (xy 430.37506 -122.975624) (xy 430.396396 -122.98172) (xy 430.407318 -122.979942)
			(xy 430.421956 -122.977804) (xy 430.451453 -122.975514) (xy 430.466246 -122.97537) (xy 430.493493 -122.975903)
			(xy 430.547433 -122.983665) (xy 430.599719 -122.999023) (xy 430.649288 -123.021665) (xy 430.69513 -123.051131)
			(xy 430.736312 -123.086821) (xy 430.771996 -123.128007) (xy 430.801457 -123.173853) (xy 430.824093 -123.223424)
			(xy 430.839445 -123.275712) (xy 430.8472 -123.329652) (xy 430.8472 -123.364548) (xy 442.364398 -123.364548)
			(xy 442.364398 -123.310052) (xy 442.372153 -123.25611) (xy 442.387506 -123.20382) (xy 442.410144 -123.154248)
			(xy 442.439605 -123.108401) (xy 442.475292 -123.067214) (xy 442.516476 -123.031525) (xy 442.56232 -123.002059)
			(xy 442.61189 -122.979417) (xy 442.664178 -122.96406) (xy 442.71812 -122.9563) (xy 442.745368 -122.955812)
			(xy 442.772738 -122.956294) (xy 442.826916 -122.964107) (xy 442.879419 -122.979593) (xy 442.929166 -123.002431)
			(xy 442.975134 -123.032152) (xy 442.996066 -123.049792) (xy 443.003178 -123.055888) (xy 443.020196 -123.062238)
			(xy 443.10554 -123.062238) (xy 443.122558 -123.055888) (xy 443.12967 -123.049792) (xy 443.150603 -123.032151)
			(xy 443.196571 -123.002427) (xy 443.246317 -122.979581) (xy 443.298819 -122.964085) (xy 443.352997 -122.956256)
			(xy 443.407739 -122.956256) (xy 443.461917 -122.964085) (xy 443.514419 -122.979581) (xy 443.564165 -123.002427)
			(xy 443.610133 -123.032151) (xy 443.631066 -123.049792) (xy 443.638178 -123.055888) (xy 443.655196 -123.062238)
			(xy 443.74054 -123.062238) (xy 443.757558 -123.055888) (xy 443.76467 -123.049792) (xy 443.785602 -123.032152)
			(xy 443.831575 -123.002441) (xy 443.881322 -122.979605) (xy 443.933823 -122.964114) (xy 443.987999 -122.956286)
			(xy 444.015368 -122.955812) (xy 444.042624 -122.956233) (xy 444.096581 -122.963986) (xy 444.148886 -122.97934)
			(xy 444.198472 -123.001982) (xy 444.244332 -123.031451) (xy 444.285531 -123.067147) (xy 444.32123 -123.108342)
			(xy 444.350702 -123.154199) (xy 444.373348 -123.203784) (xy 444.388707 -123.256088) (xy 444.396465 -123.310044)
			(xy 444.396465 -123.364556) (xy 444.388707 -123.418512) (xy 444.373348 -123.470816) (xy 444.350702 -123.520401)
			(xy 444.32123 -123.566258) (xy 444.285531 -123.607453) (xy 444.244332 -123.643149) (xy 444.198472 -123.672618)
			(xy 444.148886 -123.69526) (xy 444.096581 -123.710614) (xy 444.042624 -123.718367) (xy 444.015368 -123.718828)
			(xy 443.987996 -123.718398) (xy 443.933815 -123.710574) (xy 443.881311 -123.695078) (xy 443.831564 -123.672227)
			(xy 443.7856 -123.642494) (xy 443.76467 -123.624848) (xy 443.757558 -123.618752) (xy 443.74054 -123.612402)
			(xy 443.655196 -123.612402) (xy 443.638178 -123.618752) (xy 443.631066 -123.624848) (xy 443.610133 -123.642489)
			(xy 443.564165 -123.672213) (xy 443.514419 -123.695059) (xy 443.461917 -123.710555) (xy 443.407739 -123.718384)
			(xy 443.352997 -123.718384) (xy 443.298819 -123.710555) (xy 443.246317 -123.695059) (xy 443.196571 -123.672213)
			(xy 443.150603 -123.642489) (xy 443.12967 -123.624848) (xy 443.122558 -123.618752) (xy 443.10554 -123.612402)
			(xy 443.020196 -123.612402) (xy 443.003178 -123.618752) (xy 442.996066 -123.624848) (xy 442.975113 -123.642462)
			(xy 442.929147 -123.672179) (xy 442.879405 -123.695021) (xy 442.826908 -123.710518) (xy 442.772736 -123.718351)
			(xy 442.745368 -123.718828) (xy 442.71812 -123.7183) (xy 442.664178 -123.71054) (xy 442.61189 -123.695183)
			(xy 442.56232 -123.672541) (xy 442.516476 -123.643075) (xy 442.475292 -123.607386) (xy 442.439605 -123.566199)
			(xy 442.410144 -123.520352) (xy 442.387506 -123.47078) (xy 442.372153 -123.41849) (xy 442.364398 -123.364548)
			(xy 430.8472 -123.364548) (xy 430.8472 -123.384148) (xy 430.839445 -123.438088) (xy 430.824093 -123.490376)
			(xy 430.801457 -123.539947) (xy 430.771996 -123.585793) (xy 430.736312 -123.626979) (xy 430.69513 -123.662669)
			(xy 430.649288 -123.692135) (xy 430.599719 -123.714777) (xy 430.547433 -123.730135) (xy 430.493493 -123.737897)
			(xy 430.466246 -123.738386) (xy 430.44032 -123.737925) (xy 430.388944 -123.730924) (xy 430.338989 -123.717033)
			(xy 430.291375 -123.696506) (xy 430.246978 -123.669721) (xy 430.206616 -123.637173) (xy 430.171032 -123.599459)
			(xy 430.155604 -123.57862) (xy 430.149871 -123.571283) (xy 430.134363 -123.561001) (xy 430.125378 -123.558554)
			(xy 430.095152 -123.551696) (xy 430.085876 -123.549945) (xy 430.067212 -123.552687) (xy 430.05883 -123.55703)
			(xy 430.032848 -123.571313) (xy 429.977998 -123.593826) (xy 429.920697 -123.609056) (xy 429.861907 -123.616746)
			(xy 429.832262 -123.617228) (xy 429.80262 -123.616714) (xy 429.743838 -123.608998) (xy 429.68654 -123.593776)
			(xy 429.631679 -123.571302) (xy 429.605694 -123.55703) (xy 429.597287 -123.552771) (xy 429.578652 -123.550045)
			(xy 429.569372 -123.551696) (xy 429.539146 -123.558554) (xy 429.530159 -123.560997) (xy 429.514652 -123.571281)
			(xy 429.50892 -123.57862) (xy 429.49351 -123.599478) (xy 429.457938 -123.637212) (xy 429.41758 -123.669777)
			(xy 429.37318 -123.696572) (xy 429.325558 -123.717101) (xy 429.275593 -123.730986) (xy 429.224208 -123.737972)
			(xy 429.198278 -123.738386) (xy 429.171026 -123.737943) (xy 429.117078 -123.730183) (xy 429.064783 -123.714825)
			(xy 429.015205 -123.692182) (xy 428.969355 -123.662713) (xy 428.928165 -123.627019) (xy 428.892474 -123.585827)
			(xy 428.863008 -123.539975) (xy 428.840367 -123.490397) (xy 428.825012 -123.438101) (xy 428.817256 -123.384152)
			(xy 428.817256 -123.329648) (xy 428.825012 -123.275699) (xy 428.840367 -123.223403) (xy 428.863008 -123.173825)
			(xy 428.892474 -123.127973) (xy 428.928165 -123.086781) (xy 428.969355 -123.051087) (xy 429.015205 -123.021618)
			(xy 429.064783 -122.998975) (xy 429.117078 -122.983617) (xy 429.171026 -122.975857) (xy 429.198278 -122.97537)
			(xy 429.213071 -122.975505) (xy 429.242569 -122.977794) (xy 429.257206 -122.979942) (xy 429.268128 -122.98172)
			(xy 429.289464 -122.975624) (xy 429.356774 -122.91822) (xy 429.364743 -122.91063) (xy 429.373824 -122.890608)
			(xy 429.3743 -122.879612) (xy 429.3743 -122.57532) (xy 429.373783 -122.564332) (xy 429.364716 -122.54432)
			(xy 429.356774 -122.536712) (xy 429.289464 -122.479308) (xy 429.268128 -122.473212) (xy 429.257206 -122.47499)
			(xy 429.242567 -122.477125) (xy 429.213071 -122.479417) (xy 429.198278 -122.479562) (xy 429.171024 -122.479167)
			(xy 429.117073 -122.471407) (xy 429.064774 -122.456048) (xy 429.015194 -122.433403) (xy 428.969341 -122.403932)
			(xy 428.928148 -122.368236) (xy 428.892455 -122.327042) (xy 428.862987 -122.281187) (xy 428.840345 -122.231605)
			(xy 428.824989 -122.179306) (xy 428.817232 -122.125354) (xy 422.794914 -122.125354) (xy 422.770585 -122.145601)
			(xy 422.722979 -122.174655) (xy 422.67165 -122.196467) (xy 422.617693 -122.210573) (xy 422.562256 -122.216673)
			(xy 422.506522 -122.214636) (xy 422.451679 -122.204506) (xy 422.398895 -122.186499) (xy 422.349295 -122.160998)
			(xy 422.303937 -122.128547) (xy 422.263788 -122.089838) (xy 422.229702 -122.045695) (xy 422.202406 -121.99706)
			(xy 422.182483 -121.944969) (xy 422.170357 -121.890532) (xy 422.166286 -121.83491) (xy 420.948612 -121.83491)
			(xy 420.948103 -121.862796) (xy 420.939983 -121.917972) (xy 420.923915 -121.971379) (xy 420.900243 -122.021876)
			(xy 420.86947 -122.068389) (xy 420.832253 -122.109926) (xy 420.789385 -122.145601) (xy 420.741779 -122.174655)
			(xy 420.69045 -122.196467) (xy 420.636493 -122.210573) (xy 420.581056 -122.216673) (xy 420.525322 -122.214636)
			(xy 420.470479 -122.204506) (xy 420.417695 -122.186499) (xy 420.368095 -122.160998) (xy 420.322737 -122.128547)
			(xy 420.282588 -122.089838) (xy 420.248502 -122.045695) (xy 420.221206 -121.99706) (xy 420.201283 -121.944969)
			(xy 420.189157 -121.890532) (xy 420.185086 -121.83491) (xy 416.347912 -121.83491) (xy 416.347912 -121.86215)
			(xy 416.340156 -121.916095) (xy 416.324802 -121.968388) (xy 416.302162 -122.017963) (xy 416.272697 -122.063812)
			(xy 416.237008 -122.105001) (xy 416.19582 -122.140691) (xy 416.149972 -122.170157) (xy 416.100397 -122.192798)
			(xy 416.048105 -122.208154) (xy 415.99416 -122.215911) (xy 415.96691 -122.216418) (xy 415.949798 -122.216242)
			(xy 415.91571 -122.213185) (xy 415.898838 -122.210322) (xy 415.887571 -122.208883) (xy 415.86568 -122.214828)
			(xy 415.856674 -122.221752) (xy 415.83229 -122.242834) (xy 415.824043 -122.25086) (xy 415.814952 -122.271966)
			(xy 415.814764 -122.283474) (xy 415.815272 -122.30354) (xy 415.815272 -122.597164) (xy 417.60216 -122.597164)
			(xy 417.606231 -122.541542) (xy 417.618357 -122.487105) (xy 417.63828 -122.435014) (xy 417.665576 -122.386379)
			(xy 417.699662 -122.342236) (xy 417.739811 -122.303527) (xy 417.785169 -122.271076) (xy 417.834769 -122.245575)
			(xy 417.887553 -122.227568) (xy 417.942396 -122.217438) (xy 417.99813 -122.215401) (xy 418.053567 -122.221501)
			(xy 418.107524 -122.235607) (xy 418.158853 -122.257419) (xy 418.206459 -122.286473) (xy 418.249327 -122.322148)
			(xy 418.286544 -122.363685) (xy 418.317317 -122.410198) (xy 418.340989 -122.460695) (xy 418.357057 -122.514102)
			(xy 418.365177 -122.569278) (xy 418.365686 -122.597164) (xy 418.365177 -122.62505) (xy 418.357057 -122.680226)
			(xy 418.340989 -122.733633) (xy 418.317317 -122.78413) (xy 418.286544 -122.830643) (xy 418.249327 -122.87218)
			(xy 418.206459 -122.907855) (xy 418.158853 -122.936909) (xy 418.107524 -122.958721) (xy 418.053567 -122.972827)
			(xy 417.99813 -122.978927) (xy 417.942396 -122.97689) (xy 417.887553 -122.96676) (xy 417.834769 -122.948753)
			(xy 417.785169 -122.923252) (xy 417.739811 -122.890801) (xy 417.699662 -122.852092) (xy 417.665576 -122.807949)
			(xy 417.63828 -122.759314) (xy 417.618357 -122.707223) (xy 417.606231 -122.652786) (xy 417.60216 -122.597164)
			(xy 415.815272 -122.597164) (xy 415.815272 -123.16714) (xy 415.814764 -123.186444) (xy 415.814783 -123.197983)
			(xy 415.823909 -123.219152) (xy 415.83229 -123.227084) (xy 415.856674 -123.248166) (xy 415.865685 -123.25508)
			(xy 415.887574 -123.261038) (xy 415.898838 -123.259596) (xy 415.915711 -123.256743) (xy 415.949798 -123.253688)
			(xy 415.96691 -123.2535) (xy 415.99416 -123.253986) (xy 416.048106 -123.261744) (xy 416.100398 -123.2771)
			(xy 416.149973 -123.299741) (xy 416.195821 -123.329207) (xy 416.237009 -123.364898) (xy 416.272699 -123.406087)
			(xy 416.302164 -123.451936) (xy 416.324804 -123.501511) (xy 416.340158 -123.553804) (xy 416.347914 -123.60775)
			(xy 416.347914 -123.635008) (xy 420.185086 -123.635008) (xy 420.189157 -123.579386) (xy 420.201283 -123.524949)
			(xy 420.221206 -123.472858) (xy 420.248502 -123.424223) (xy 420.282588 -123.38008) (xy 420.322737 -123.341371)
			(xy 420.368095 -123.30892) (xy 420.417695 -123.283419) (xy 420.470479 -123.265412) (xy 420.525322 -123.255282)
			(xy 420.581056 -123.253245) (xy 420.636493 -123.259345) (xy 420.69045 -123.273451) (xy 420.741779 -123.295263)
			(xy 420.789385 -123.324317) (xy 420.832253 -123.359992) (xy 420.86947 -123.401529) (xy 420.900243 -123.448042)
			(xy 420.923915 -123.498539) (xy 420.939983 -123.551946) (xy 420.948103 -123.607122) (xy 420.948612 -123.635008)
			(xy 422.166286 -123.635008) (xy 422.170357 -123.579386) (xy 422.182483 -123.524949) (xy 422.202406 -123.472858)
			(xy 422.229702 -123.424223) (xy 422.263788 -123.38008) (xy 422.303937 -123.341371) (xy 422.349295 -123.30892)
			(xy 422.398895 -123.283419) (xy 422.451679 -123.265412) (xy 422.506522 -123.255282) (xy 422.562256 -123.253245)
			(xy 422.617693 -123.259345) (xy 422.67165 -123.273451) (xy 422.722979 -123.295263) (xy 422.770585 -123.324317)
			(xy 422.813453 -123.359992) (xy 422.85067 -123.401529) (xy 422.881443 -123.448042) (xy 422.905115 -123.498539)
			(xy 422.921183 -123.551946) (xy 422.929303 -123.607122) (xy 422.929812 -123.635008) (xy 422.929303 -123.662894)
			(xy 422.921183 -123.71807) (xy 422.905115 -123.771477) (xy 422.881443 -123.821974) (xy 422.85067 -123.868487)
			(xy 422.813453 -123.910024) (xy 422.787346 -123.93175) (xy 431.45938 -123.93175) (xy 431.45938 -123.87725)
			(xy 431.467136 -123.823303) (xy 431.48249 -123.77101) (xy 431.50513 -123.721434) (xy 431.534595 -123.675584)
			(xy 431.570285 -123.634395) (xy 431.611473 -123.598703) (xy 431.657322 -123.569237) (xy 431.706897 -123.546595)
			(xy 431.75919 -123.531239) (xy 431.813136 -123.523481) (xy 431.840386 -123.522994) (xy 431.866312 -123.52344)
			(xy 431.917688 -123.530444) (xy 431.967643 -123.544339) (xy 432.015258 -123.564869) (xy 432.059654 -123.591655)
			(xy 432.100016 -123.624206) (xy 432.135599 -123.66192) (xy 432.151028 -123.68276) (xy 432.156789 -123.690072)
			(xy 432.172277 -123.700368) (xy 432.181254 -123.702826) (xy 432.21148 -123.709684) (xy 432.220754 -123.711455)
			(xy 432.239421 -123.7087) (xy 432.247802 -123.70435) (xy 432.273777 -123.690053) (xy 432.32863 -123.667543)
			(xy 432.385933 -123.652318) (xy 432.444724 -123.644632) (xy 432.47437 -123.644152) (xy 432.504013 -123.644655)
			(xy 432.562794 -123.652375) (xy 432.620092 -123.6676) (xy 432.674953 -123.690077) (xy 432.700938 -123.70435)
			(xy 432.70936 -123.708575) (xy 432.727982 -123.711323) (xy 432.73726 -123.709684) (xy 432.767486 -123.702826)
			(xy 432.77648 -123.700402) (xy 432.791983 -123.690105) (xy 432.797712 -123.68276) (xy 432.813096 -123.661883)
			(xy 432.848674 -123.62415) (xy 432.889037 -123.591587) (xy 432.933441 -123.564795) (xy 432.981067 -123.544269)
			(xy 433.031035 -123.530387) (xy 433.082423 -123.523406) (xy 433.108354 -123.522994) (xy 433.135609 -123.52345)
			(xy 433.189565 -123.531202) (xy 433.241869 -123.546554) (xy 433.291455 -123.569194) (xy 433.337314 -123.598661)
			(xy 433.378513 -123.634355) (xy 433.414211 -123.675549) (xy 433.443684 -123.721404) (xy 433.46633 -123.770988)
			(xy 433.481688 -123.82329) (xy 433.489447 -123.877245) (xy 433.489447 -123.931755) (xy 433.481688 -123.98571)
			(xy 433.46633 -124.038012) (xy 433.443684 -124.087596) (xy 433.414211 -124.133451) (xy 433.378513 -124.174645)
			(xy 433.337314 -124.210339) (xy 433.291455 -124.239806) (xy 433.241869 -124.262446) (xy 433.189565 -124.277798)
			(xy 433.135609 -124.28555) (xy 433.108354 -124.28601) (xy 433.093561 -124.28587) (xy 433.064063 -124.283584)
			(xy 433.049426 -124.281438) (xy 433.038504 -124.27966) (xy 433.017168 -124.285756) (xy 432.949858 -124.34316)
			(xy 432.941903 -124.350763) (xy 432.932813 -124.370775) (xy 432.932332 -124.381768) (xy 432.932332 -124.68606)
			(xy 432.932794 -124.697054) (xy 432.941899 -124.717067) (xy 432.949858 -124.724668) (xy 433.017168 -124.782072)
			(xy 433.038504 -124.788168) (xy 433.049426 -124.78639) (xy 433.064064 -124.784251) (xy 433.093561 -124.781962)
			(xy 433.108354 -124.781818) (xy 433.135611 -124.782226) (xy 433.189571 -124.789978) (xy 433.241878 -124.805331)
			(xy 433.291467 -124.827973) (xy 433.337329 -124.857441) (xy 433.37853 -124.893137) (xy 433.414231 -124.934334)
			(xy 433.443705 -124.980193) (xy 433.466353 -125.029779) (xy 433.481712 -125.082084) (xy 433.489471 -125.136043)
			(xy 433.489471 -125.190557) (xy 433.481712 -125.244516) (xy 433.466353 -125.296821) (xy 433.443705 -125.346407)
			(xy 433.414231 -125.392266) (xy 433.37853 -125.433463) (xy 433.337329 -125.469159) (xy 433.291467 -125.498627)
			(xy 433.241878 -125.521269) (xy 433.189571 -125.536622) (xy 433.135611 -125.544374) (xy 433.108354 -125.544834)
			(xy 433.082425 -125.544463) (xy 433.031044 -125.537449) (xy 432.981086 -125.523544) (xy 432.933471 -125.503003)
			(xy 432.889075 -125.476204) (xy 432.848716 -125.443641) (xy 432.813137 -125.405914) (xy 432.797712 -125.385068)
			(xy 432.791967 -125.377742) (xy 432.776468 -125.367453) (xy 432.767486 -125.365002) (xy 432.73726 -125.358144)
			(xy 432.727983 -125.356404) (xy 432.709321 -125.35914) (xy 432.700938 -125.363478) (xy 432.674972 -125.377792)
			(xy 432.620116 -125.400299) (xy 432.56281 -125.41552) (xy 432.504017 -125.4232) (xy 432.47437 -125.423676)
			(xy 432.444728 -125.423153) (xy 432.385947 -125.415438) (xy 432.328649 -125.400219) (xy 432.273788 -125.377748)
			(xy 432.247802 -125.363478) (xy 432.239392 -125.359224) (xy 432.22076 -125.356494) (xy 432.21148 -125.358144)
			(xy 432.181254 -125.365002) (xy 432.172262 -125.367433) (xy 432.156757 -125.377724) (xy 432.151028 -125.385068)
			(xy 432.135627 -125.405932) (xy 432.100052 -125.443665) (xy 432.059691 -125.476228) (xy 432.01529 -125.50302)
			(xy 431.967667 -125.523549) (xy 431.917702 -125.537434) (xy 431.866316 -125.544419) (xy 431.840386 -125.544834)
			(xy 431.813137 -125.544295) (xy 431.759195 -125.536537) (xy 431.706905 -125.521182) (xy 431.657333 -125.498542)
			(xy 431.611488 -125.469077) (xy 431.570302 -125.433388) (xy 431.534615 -125.392201) (xy 431.505152 -125.346354)
			(xy 431.482513 -125.296781) (xy 431.46716 -125.244491) (xy 431.459404 -125.190549) (xy 431.459404 -125.136051)
			(xy 431.46716 -125.082109) (xy 431.482513 -125.029819) (xy 431.505152 -124.980246) (xy 431.534615 -124.934399)
			(xy 431.570302 -124.893212) (xy 431.611488 -124.857523) (xy 431.657333 -124.828058) (xy 431.706905 -124.805418)
			(xy 431.759195 -124.790063) (xy 431.813137 -124.782305) (xy 431.840386 -124.781818) (xy 431.855179 -124.781953)
			(xy 431.884677 -124.784242) (xy 431.899314 -124.78639) (xy 431.910236 -124.788168) (xy 431.931572 -124.782072)
			(xy 431.998882 -124.724668) (xy 432.006831 -124.71706) (xy 432.015923 -124.697051) (xy 432.016408 -124.68606)
			(xy 432.016408 -124.381768) (xy 432.015918 -124.370777) (xy 432.006832 -124.350765) (xy 431.998882 -124.34316)
			(xy 431.931572 -124.285756) (xy 431.910236 -124.27966) (xy 431.899314 -124.281438) (xy 431.884677 -124.283584)
			(xy 431.855179 -124.285868) (xy 431.840386 -124.28601) (xy 431.813136 -124.285519) (xy 431.75919 -124.277761)
			(xy 431.706897 -124.262405) (xy 431.657322 -124.239763) (xy 431.611473 -124.210297) (xy 431.570285 -124.174605)
			(xy 431.534595 -124.133416) (xy 431.50513 -124.087566) (xy 431.48249 -124.03799) (xy 431.467136 -123.985697)
			(xy 431.45938 -123.93175) (xy 422.787346 -123.93175) (xy 422.770585 -123.945699) (xy 422.722979 -123.974753)
			(xy 422.67165 -123.996565) (xy 422.617693 -124.010671) (xy 422.562256 -124.016771) (xy 422.506522 -124.014734)
			(xy 422.451679 -124.004604) (xy 422.398895 -123.986597) (xy 422.349295 -123.961096) (xy 422.303937 -123.928645)
			(xy 422.263788 -123.889936) (xy 422.229702 -123.845793) (xy 422.202406 -123.797158) (xy 422.182483 -123.745067)
			(xy 422.170357 -123.69063) (xy 422.166286 -123.635008) (xy 420.948612 -123.635008) (xy 420.948103 -123.662894)
			(xy 420.939983 -123.71807) (xy 420.923915 -123.771477) (xy 420.900243 -123.821974) (xy 420.86947 -123.868487)
			(xy 420.832253 -123.910024) (xy 420.789385 -123.945699) (xy 420.741779 -123.974753) (xy 420.69045 -123.996565)
			(xy 420.636493 -124.010671) (xy 420.581056 -124.016771) (xy 420.525322 -124.014734) (xy 420.470479 -124.004604)
			(xy 420.417695 -123.986597) (xy 420.368095 -123.961096) (xy 420.322737 -123.928645) (xy 420.282588 -123.889936)
			(xy 420.248502 -123.845793) (xy 420.221206 -123.797158) (xy 420.201283 -123.745067) (xy 420.189157 -123.69063)
			(xy 420.185086 -123.635008) (xy 416.347914 -123.635008) (xy 416.347914 -123.66225) (xy 416.340158 -123.716196)
			(xy 416.324804 -123.768489) (xy 416.302164 -123.818064) (xy 416.272699 -123.863913) (xy 416.237009 -123.905102)
			(xy 416.195821 -123.940793) (xy 416.149973 -123.970259) (xy 416.100398 -123.9929) (xy 416.048106 -124.008256)
			(xy 415.99416 -124.016014) (xy 415.96691 -124.016516) (xy 415.939938 -124.016043) (xy 415.886534 -124.00843)
			(xy 415.834736 -123.993368) (xy 415.785576 -123.971158) (xy 415.740036 -123.942244) (xy 415.699024 -123.907201)
			(xy 415.663359 -123.866729) (xy 415.633752 -123.821637) (xy 415.610794 -123.772822) (xy 415.594943 -123.721259)
			(xy 415.590228 -123.694698) (xy 415.58845 -123.68403) (xy 415.57702 -123.666504) (xy 415.496756 -123.61291)
			(xy 415.476182 -123.609354) (xy 415.465768 -123.611894) (xy 415.439068 -123.617978) (xy 415.384692 -123.624472)
			(xy 415.35731 -123.624848) (xy 415.329929 -123.624464) (xy 415.275552 -123.617975) (xy 415.248852 -123.611894)
			(xy 415.238438 -123.609354) (xy 415.217864 -123.61291) (xy 415.1376 -123.666504) (xy 415.12617 -123.68403)
			(xy 415.124392 -123.694698) (xy 415.119732 -123.721275) (xy 415.103904 -123.772859) (xy 415.080959 -123.821694)
			(xy 415.051356 -123.866805) (xy 415.015686 -123.90729) (xy 414.974663 -123.94234) (xy 414.929107 -123.971254)
			(xy 414.879928 -123.993454) (xy 414.82811 -124.008495) (xy 414.774689 -124.016079) (xy 414.74771 -124.016516)
			(xy 414.720342 -124.016038) (xy 414.66617 -124.008203) (xy 414.613673 -123.992706) (xy 414.56393 -123.969867)
			(xy 414.517962 -123.940153) (xy 414.497012 -123.922536) (xy 414.4899 -123.91644) (xy 414.472882 -123.91009)
			(xy 414.387538 -123.91009) (xy 414.37052 -123.91644) (xy 414.363408 -123.922536) (xy 414.342478 -123.940181)
			(xy 414.296513 -123.969913) (xy 414.246767 -123.992761) (xy 414.194262 -124.008255) (xy 414.140081 -124.016076)
			(xy 414.11271 -124.016516) (xy 414.095598 -124.01634) (xy 414.06151 -124.013283) (xy 414.044638 -124.01042)
			(xy 414.033371 -124.008981) (xy 414.01148 -124.014926) (xy 414.002474 -124.02185) (xy 413.97809 -124.042932)
			(xy 413.969842 -124.050958) (xy 413.960751 -124.072064) (xy 413.960564 -124.083572) (xy 413.961072 -124.103638)
			(xy 413.961072 -124.31649) (xy 417.60216 -124.31649) (xy 417.606231 -124.260868) (xy 417.618357 -124.206431)
			(xy 417.63828 -124.15434) (xy 417.665576 -124.105705) (xy 417.699662 -124.061562) (xy 417.739811 -124.022853)
			(xy 417.785169 -123.990402) (xy 417.834769 -123.964901) (xy 417.887553 -123.946894) (xy 417.942396 -123.936764)
			(xy 417.99813 -123.934727) (xy 418.053567 -123.940827) (xy 418.107524 -123.954933) (xy 418.158853 -123.976745)
			(xy 418.206459 -124.005799) (xy 418.249327 -124.041474) (xy 418.286544 -124.083011) (xy 418.317317 -124.129524)
			(xy 418.340989 -124.180021) (xy 418.357057 -124.233428) (xy 418.365177 -124.288604) (xy 418.365686 -124.31649)
			(xy 418.365177 -124.344376) (xy 418.357057 -124.399552) (xy 418.340989 -124.452959) (xy 418.317317 -124.503456)
			(xy 418.286544 -124.549969) (xy 418.249327 -124.591506) (xy 418.206459 -124.627181) (xy 418.158853 -124.656235)
			(xy 418.107524 -124.678047) (xy 418.053567 -124.692153) (xy 417.99813 -124.698253) (xy 417.942396 -124.696216)
			(xy 417.887553 -124.686086) (xy 417.834769 -124.668079) (xy 417.785169 -124.642578) (xy 417.739811 -124.610127)
			(xy 417.699662 -124.571418) (xy 417.665576 -124.527275) (xy 417.63828 -124.47864) (xy 417.618357 -124.426549)
			(xy 417.606231 -124.372112) (xy 417.60216 -124.31649) (xy 413.961072 -124.31649) (xy 413.961072 -124.967238)
			(xy 413.960564 -124.986542) (xy 413.960583 -124.998082) (xy 413.969708 -125.019251) (xy 413.97809 -125.027182)
			(xy 414.002474 -125.048264) (xy 414.011485 -125.055179) (xy 414.033374 -125.061136) (xy 414.044638 -125.059694)
			(xy 414.061511 -125.056841) (xy 414.095598 -125.053786) (xy 414.11271 -125.053598) (xy 414.13996 -125.054084)
			(xy 414.193906 -125.061842) (xy 414.246199 -125.077198) (xy 414.295774 -125.099839) (xy 414.341623 -125.129305)
			(xy 414.382811 -125.164996) (xy 414.418501 -125.206186) (xy 414.447966 -125.252035) (xy 414.470606 -125.30161)
			(xy 414.48596 -125.353904) (xy 414.493716 -125.40785) (xy 414.493716 -125.435106) (xy 415.584892 -125.435106)
			(xy 415.588963 -125.379484) (xy 415.601089 -125.325047) (xy 415.621012 -125.272956) (xy 415.648308 -125.224321)
			(xy 415.682394 -125.180178) (xy 415.722543 -125.141469) (xy 415.767901 -125.109018) (xy 415.817501 -125.083517)
			(xy 415.870285 -125.06551) (xy 415.925128 -125.05538) (xy 415.980862 -125.053343) (xy 416.036299 -125.059443)
			(xy 416.090256 -125.073549) (xy 416.141585 -125.095361) (xy 416.189191 -125.124415) (xy 416.232059 -125.16009)
			(xy 416.269276 -125.201627) (xy 416.300049 -125.24814) (xy 416.323721 -125.298637) (xy 416.339789 -125.352044)
			(xy 416.347909 -125.40722) (xy 416.348418 -125.435106) (xy 416.347909 -125.462992) (xy 416.339789 -125.518168)
			(xy 416.323721 -125.571575) (xy 416.300049 -125.622072) (xy 416.269276 -125.668585) (xy 416.232059 -125.710122)
			(xy 416.189191 -125.745797) (xy 416.17845 -125.752352) (xy 417.555424 -125.752352) (xy 417.559495 -125.69673)
			(xy 417.571621 -125.642293) (xy 417.591544 -125.590202) (xy 417.61884 -125.541567) (xy 417.652926 -125.497424)
			(xy 417.693075 -125.458715) (xy 417.738433 -125.426264) (xy 417.788033 -125.400763) (xy 417.840817 -125.382756)
			(xy 417.89566 -125.372626) (xy 417.951394 -125.370589) (xy 418.006831 -125.376689) (xy 418.060788 -125.390795)
			(xy 418.112117 -125.412607) (xy 418.148982 -125.435106) (xy 420.185086 -125.435106) (xy 420.189157 -125.379484)
			(xy 420.201283 -125.325047) (xy 420.221206 -125.272956) (xy 420.248502 -125.224321) (xy 420.282588 -125.180178)
			(xy 420.322737 -125.141469) (xy 420.368095 -125.109018) (xy 420.417695 -125.083517) (xy 420.470479 -125.06551)
			(xy 420.525322 -125.05538) (xy 420.581056 -125.053343) (xy 420.636493 -125.059443) (xy 420.69045 -125.073549)
			(xy 420.741779 -125.095361) (xy 420.789385 -125.124415) (xy 420.832253 -125.16009) (xy 420.86947 -125.201627)
			(xy 420.900243 -125.24814) (xy 420.923915 -125.298637) (xy 420.939983 -125.352044) (xy 420.948103 -125.40722)
			(xy 420.948612 -125.435106) (xy 422.166286 -125.435106) (xy 422.170357 -125.379484) (xy 422.182483 -125.325047)
			(xy 422.202406 -125.272956) (xy 422.229702 -125.224321) (xy 422.263788 -125.180178) (xy 422.303937 -125.141469)
			(xy 422.349295 -125.109018) (xy 422.398895 -125.083517) (xy 422.451679 -125.06551) (xy 422.506522 -125.05538)
			(xy 422.562256 -125.053343) (xy 422.617693 -125.059443) (xy 422.67165 -125.073549) (xy 422.722979 -125.095361)
			(xy 422.770585 -125.124415) (xy 422.813453 -125.16009) (xy 422.85067 -125.201627) (xy 422.881443 -125.24814)
			(xy 422.905115 -125.298637) (xy 422.921183 -125.352044) (xy 422.929303 -125.40722) (xy 422.929812 -125.435106)
			(xy 422.929303 -125.462992) (xy 422.921183 -125.518168) (xy 422.905115 -125.571575) (xy 422.881443 -125.622072)
			(xy 422.85067 -125.668585) (xy 422.813453 -125.710122) (xy 422.770585 -125.745797) (xy 422.722979 -125.774851)
			(xy 422.67165 -125.796663) (xy 422.617693 -125.810769) (xy 422.562256 -125.816869) (xy 422.506522 -125.814832)
			(xy 422.451679 -125.804702) (xy 422.398895 -125.786695) (xy 422.349295 -125.761194) (xy 422.303937 -125.728743)
			(xy 422.263788 -125.690034) (xy 422.229702 -125.645891) (xy 422.202406 -125.597256) (xy 422.182483 -125.545165)
			(xy 422.170357 -125.490728) (xy 422.166286 -125.435106) (xy 420.948612 -125.435106) (xy 420.948103 -125.462992)
			(xy 420.939983 -125.518168) (xy 420.923915 -125.571575) (xy 420.900243 -125.622072) (xy 420.86947 -125.668585)
			(xy 420.832253 -125.710122) (xy 420.789385 -125.745797) (xy 420.741779 -125.774851) (xy 420.69045 -125.796663)
			(xy 420.636493 -125.810769) (xy 420.581056 -125.816869) (xy 420.525322 -125.814832) (xy 420.470479 -125.804702)
			(xy 420.417695 -125.786695) (xy 420.368095 -125.761194) (xy 420.322737 -125.728743) (xy 420.282588 -125.690034)
			(xy 420.248502 -125.645891) (xy 420.221206 -125.597256) (xy 420.201283 -125.545165) (xy 420.189157 -125.490728)
			(xy 420.185086 -125.435106) (xy 418.148982 -125.435106) (xy 418.159723 -125.441661) (xy 418.202591 -125.477336)
			(xy 418.239808 -125.518873) (xy 418.270581 -125.565386) (xy 418.294253 -125.615883) (xy 418.310321 -125.66929)
			(xy 418.318441 -125.724466) (xy 418.31895 -125.752352) (xy 418.318441 -125.780238) (xy 418.310321 -125.835414)
			(xy 418.294253 -125.888821) (xy 418.270581 -125.939318) (xy 418.239808 -125.985831) (xy 418.214594 -126.013972)
			(xy 437.750712 -126.013972) (xy 437.751159 -125.986601) (xy 437.758981 -125.932421) (xy 437.774474 -125.879918)
			(xy 437.79732 -125.830171) (xy 437.827049 -125.784205) (xy 437.844692 -125.763274) (xy 437.850788 -125.756162)
			(xy 437.857138 -125.739144) (xy 437.857138 -125.6538) (xy 437.850788 -125.636782) (xy 437.844692 -125.62967)
			(xy 437.827025 -125.608759) (xy 437.797304 -125.562786) (xy 437.774463 -125.513036) (xy 437.75897 -125.460531)
			(xy 437.751145 -125.40635) (xy 437.751148 -125.351607) (xy 437.758979 -125.297427) (xy 437.774478 -125.244924)
			(xy 437.797325 -125.195177) (xy 437.827051 -125.149207) (xy 437.844692 -125.128274) (xy 437.850788 -125.121162)
			(xy 437.857138 -125.104144) (xy 437.857138 -125.0188) (xy 437.850788 -125.001782) (xy 437.844692 -124.99467)
			(xy 437.827025 -124.973759) (xy 437.797304 -124.927786) (xy 437.774463 -124.878036) (xy 437.75897 -124.825531)
			(xy 437.751145 -124.77135) (xy 437.751148 -124.716607) (xy 437.758979 -124.662427) (xy 437.774478 -124.609924)
			(xy 437.797325 -124.560177) (xy 437.827051 -124.514207) (xy 437.844692 -124.493274) (xy 437.850788 -124.486162)
			(xy 437.857138 -124.469144) (xy 437.857138 -124.3838) (xy 437.850788 -124.366782) (xy 437.844692 -124.35967)
			(xy 437.827071 -124.338723) (xy 437.797357 -124.292754) (xy 437.774517 -124.243011) (xy 437.759022 -124.190513)
			(xy 437.751189 -124.13634) (xy 437.750712 -124.108972) (xy 437.751198 -124.081721) (xy 437.758954 -124.027773)
			(xy 437.774309 -123.975478) (xy 437.796951 -123.925901) (xy 437.826417 -123.880051) (xy 437.862108 -123.83886)
			(xy 437.903299 -123.803169) (xy 437.949149 -123.773703) (xy 437.998726 -123.751061) (xy 438.051021 -123.735706)
			(xy 438.104969 -123.72795) (xy 438.159471 -123.72795) (xy 438.213419 -123.735706) (xy 438.265714 -123.751061)
			(xy 438.315291 -123.773703) (xy 438.361141 -123.803169) (xy 438.402332 -123.83886) (xy 438.438023 -123.880051)
			(xy 438.467489 -123.925901) (xy 438.490131 -123.975478) (xy 438.505486 -124.027773) (xy 438.513242 -124.081721)
			(xy 438.513728 -124.108972) (xy 438.513263 -124.136342) (xy 438.505448 -124.190522) (xy 438.489959 -124.243026)
			(xy 438.467117 -124.292773) (xy 438.43739 -124.338739) (xy 438.419748 -124.35967) (xy 438.413652 -124.366782)
			(xy 438.407302 -124.3838) (xy 438.407302 -124.469144) (xy 438.410524 -124.47778) (xy 440.71286 -124.47778)
			(xy 440.7133 -124.450409) (xy 440.721122 -124.396228) (xy 440.736616 -124.343724) (xy 440.759464 -124.293977)
			(xy 440.789195 -124.248012) (xy 440.80684 -124.227082) (xy 440.812936 -124.21997) (xy 440.819286 -124.202952)
			(xy 440.819286 -124.117608) (xy 440.812936 -124.10059) (xy 440.80684 -124.093478) (xy 440.78923 -124.072522)
			(xy 440.759513 -124.026557) (xy 440.73667 -123.976815) (xy 440.721173 -123.924319) (xy 440.713337 -123.870148)
			(xy 440.71286 -123.84278) (xy 440.713346 -123.815529) (xy 440.721102 -123.761581) (xy 440.736457 -123.709286)
			(xy 440.759099 -123.659709) (xy 440.788565 -123.613859) (xy 440.824256 -123.572668) (xy 440.865447 -123.536977)
			(xy 440.911297 -123.507511) (xy 440.960874 -123.484869) (xy 441.013169 -123.469514) (xy 441.067117 -123.461758)
			(xy 441.121619 -123.461758) (xy 441.175567 -123.469514) (xy 441.227862 -123.484869) (xy 441.277439 -123.507511)
			(xy 441.323289 -123.536977) (xy 441.36448 -123.572668) (xy 441.400171 -123.613859) (xy 441.429637 -123.659709)
			(xy 441.452279 -123.709286) (xy 441.467634 -123.761581) (xy 441.47539 -123.815529) (xy 441.475558 -123.824947)
			(xy 445.666109 -123.824947) (xy 445.666111 -123.765016) (xy 445.673936 -123.705598) (xy 445.68945 -123.647709)
			(xy 445.712387 -123.592341) (xy 445.742354 -123.54044) (xy 445.77884 -123.492894) (xy 445.821219 -123.450518)
			(xy 445.868767 -123.414036) (xy 445.92067 -123.384072) (xy 445.97604 -123.361139) (xy 446.03393 -123.34563)
			(xy 446.093348 -123.337809) (xy 446.123314 -123.33732) (xy 446.150746 -123.338082) (xy 446.16243 -123.338844)
			(xy 446.183766 -123.330208) (xy 446.2526 -123.254008) (xy 446.25895 -123.232164) (xy 446.257172 -123.22048)
			(xy 446.254905 -123.20547) (xy 446.252491 -123.175207) (xy 446.252346 -123.160028) (xy 446.252832 -123.132777)
			(xy 446.260588 -123.078829) (xy 446.275943 -123.026534) (xy 446.298585 -122.976957) (xy 446.328051 -122.931107)
			(xy 446.363742 -122.889916) (xy 446.404933 -122.854225) (xy 446.450783 -122.824759) (xy 446.50036 -122.802117)
			(xy 446.552655 -122.786762) (xy 446.606603 -122.779006) (xy 446.661105 -122.779006) (xy 446.715053 -122.786762)
			(xy 446.767348 -122.802117) (xy 446.816925 -122.824759) (xy 446.862775 -122.854225) (xy 446.903966 -122.889916)
			(xy 446.939657 -122.931107) (xy 446.969123 -122.976957) (xy 446.991765 -123.026534) (xy 447.00712 -123.078829)
			(xy 447.014876 -123.132777) (xy 447.015362 -123.160028) (xy 447.014926 -123.188925) (xy 447.006233 -123.246061)
			(xy 446.989021 -123.301231) (xy 446.963682 -123.353174) (xy 446.930798 -123.4007) (xy 446.891121 -123.442721)
			(xy 446.845559 -123.478276) (xy 446.795154 -123.506551) (xy 446.741061 -123.526898) (xy 446.684518 -123.538852)
			(xy 446.655698 -123.541028) (xy 446.644014 -123.541536) (xy 446.623948 -123.552712) (xy 446.564258 -123.636278)
			(xy 446.560448 -123.658884) (xy 446.56375 -123.67006) (xy 446.571862 -123.700661) (xy 446.580525 -123.763373)
			(xy 446.581022 -123.795028) (xy 447.949064 -123.795028) (xy 447.953135 -123.739406) (xy 447.965261 -123.684969)
			(xy 447.985184 -123.632878) (xy 448.01248 -123.584243) (xy 448.046566 -123.5401) (xy 448.086715 -123.501391)
			(xy 448.132073 -123.46894) (xy 448.181673 -123.443439) (xy 448.234457 -123.425432) (xy 448.2893 -123.415302)
			(xy 448.345034 -123.413265) (xy 448.400471 -123.419365) (xy 448.454428 -123.433471) (xy 448.505757 -123.455283)
			(xy 448.553363 -123.484337) (xy 448.596231 -123.520012) (xy 448.633448 -123.561549) (xy 448.664221 -123.608062)
			(xy 448.687893 -123.658559) (xy 448.703961 -123.711966) (xy 448.712081 -123.767142) (xy 448.71259 -123.795028)
			(xy 448.712081 -123.822914) (xy 448.703961 -123.87809) (xy 448.687893 -123.931497) (xy 448.664221 -123.981994)
			(xy 448.633448 -124.028507) (xy 448.596231 -124.070044) (xy 448.553363 -124.105719) (xy 448.505757 -124.134773)
			(xy 448.454428 -124.156585) (xy 448.400471 -124.170691) (xy 448.345034 -124.176791) (xy 448.2893 -124.174754)
			(xy 448.234457 -124.164624) (xy 448.181673 -124.146617) (xy 448.132073 -124.121116) (xy 448.086715 -124.088665)
			(xy 448.046566 -124.049956) (xy 448.01248 -124.005813) (xy 447.985184 -123.957178) (xy 447.965261 -123.905087)
			(xy 447.953135 -123.85065) (xy 447.949064 -123.795028) (xy 446.581022 -123.795028) (xy 446.580488 -123.824994)
			(xy 446.572662 -123.884412) (xy 446.557147 -123.9423) (xy 446.534209 -123.997668) (xy 446.504241 -124.049568)
			(xy 446.467754 -124.097113) (xy 446.425374 -124.139488) (xy 446.377825 -124.175969) (xy 446.325922 -124.205932)
			(xy 446.270551 -124.228864) (xy 446.212661 -124.244372) (xy 446.153242 -124.252192) (xy 446.093311 -124.252189)
			(xy 446.033893 -124.244363) (xy 445.976005 -124.228849) (xy 445.920636 -124.205911) (xy 445.868736 -124.175943)
			(xy 445.821191 -124.139457) (xy 445.778815 -124.097077) (xy 445.742333 -124.049529) (xy 445.71237 -123.997626)
			(xy 445.689438 -123.942256) (xy 445.673929 -123.884366) (xy 445.666109 -123.824947) (xy 441.475558 -123.824947)
			(xy 441.475876 -123.84278) (xy 441.475404 -123.87015) (xy 441.467589 -123.924329) (xy 441.452101 -123.976832)
			(xy 441.429261 -124.026579) (xy 441.399537 -124.072546) (xy 441.381896 -124.093478) (xy 441.3758 -124.10059)
			(xy 441.36945 -124.117608) (xy 441.36945 -124.202952) (xy 441.373999 -124.215144) (xy 442.906656 -124.215144)
			(xy 442.910727 -124.159522) (xy 442.922853 -124.105085) (xy 442.942776 -124.052994) (xy 442.970072 -124.004359)
			(xy 443.004158 -123.960216) (xy 443.044307 -123.921507) (xy 443.089665 -123.889056) (xy 443.139265 -123.863555)
			(xy 443.192049 -123.845548) (xy 443.246892 -123.835418) (xy 443.302626 -123.833381) (xy 443.358063 -123.839481)
			(xy 443.41202 -123.853587) (xy 443.463349 -123.875399) (xy 443.510955 -123.904453) (xy 443.553823 -123.940128)
			(xy 443.59104 -123.981665) (xy 443.621813 -124.028178) (xy 443.645485 -124.078675) (xy 443.661553 -124.132082)
			(xy 443.669673 -124.187258) (xy 443.670182 -124.215144) (xy 443.669673 -124.24303) (xy 443.661553 -124.298206)
			(xy 443.645485 -124.351613) (xy 443.621813 -124.40211) (xy 443.59104 -124.448623) (xy 443.553823 -124.49016)
			(xy 443.510955 -124.525835) (xy 443.463349 -124.554889) (xy 443.41202 -124.576701) (xy 443.358063 -124.590807)
			(xy 443.302626 -124.596907) (xy 443.246892 -124.59487) (xy 443.192049 -124.58474) (xy 443.139265 -124.566733)
			(xy 443.089665 -124.541232) (xy 443.044307 -124.508781) (xy 443.004158 -124.470072) (xy 442.970072 -124.425929)
			(xy 442.942776 -124.377294) (xy 442.922853 -124.325203) (xy 442.910727 -124.270766) (xy 442.906656 -124.215144)
			(xy 441.373999 -124.215144) (xy 441.3758 -124.21997) (xy 441.381896 -124.227082) (xy 441.399539 -124.248011)
			(xy 441.429251 -124.293984) (xy 441.452086 -124.343733) (xy 441.467576 -124.396234) (xy 441.475403 -124.450411)
			(xy 441.475876 -124.47778) (xy 441.47539 -124.505031) (xy 441.467634 -124.558979) (xy 441.452279 -124.611274)
			(xy 441.429637 -124.660851) (xy 441.400171 -124.706701) (xy 441.36448 -124.747892) (xy 441.323289 -124.783583)
			(xy 441.277439 -124.813049) (xy 441.227862 -124.835691) (xy 441.175567 -124.851046) (xy 441.121619 -124.858802)
			(xy 441.067117 -124.858802) (xy 441.013169 -124.851046) (xy 440.960874 -124.835691) (xy 440.911297 -124.813049)
			(xy 440.865447 -124.783583) (xy 440.824256 -124.747892) (xy 440.788565 -124.706701) (xy 440.759099 -124.660851)
			(xy 440.736457 -124.611274) (xy 440.721102 -124.558979) (xy 440.713346 -124.505031) (xy 440.71286 -124.47778)
			(xy 438.410524 -124.47778) (xy 438.413652 -124.486162) (xy 438.419748 -124.493274) (xy 438.43545 -124.511829)
			(xy 438.462519 -124.552204) (xy 438.484259 -124.595681) (xy 438.492646 -124.618496) (xy 438.49671 -124.630688)
			(xy 438.516014 -124.648214) (xy 438.624218 -124.674376) (xy 438.64911 -124.667772) (xy 438.658508 -124.658628)
			(xy 438.679934 -124.639009) (xy 438.727608 -124.605814) (xy 438.779759 -124.580222) (xy 438.835185 -124.562823)
			(xy 438.892606 -124.554018) (xy 438.921652 -124.553472) (xy 438.949022 -124.553949) (xy 439.003201 -124.561761)
			(xy 439.055705 -124.577247) (xy 439.105452 -124.600087) (xy 439.151419 -124.629811) (xy 439.17235 -124.647452)
			(xy 439.179462 -124.653548) (xy 439.19648 -124.659898) (xy 439.281824 -124.659898) (xy 439.298842 -124.653548)
			(xy 439.305954 -124.647452) (xy 439.326899 -124.629829) (xy 439.372868 -124.600113) (xy 439.422612 -124.577273)
			(xy 439.47511 -124.561778) (xy 439.529284 -124.553947) (xy 439.556652 -124.553472) (xy 439.583903 -124.554)
			(xy 439.63785 -124.56175) (xy 439.690146 -124.577099) (xy 439.739724 -124.599734) (xy 439.785577 -124.629195)
			(xy 439.82677 -124.664882) (xy 439.862464 -124.706069) (xy 439.891933 -124.751916) (xy 439.914577 -124.80149)
			(xy 439.929936 -124.853783) (xy 439.937695 -124.907729) (xy 439.93816 -124.93498) (xy 439.937398 -124.959872)
			(xy 439.936382 -124.97308) (xy 439.947558 -124.996448) (xy 440.038744 -125.062488) (xy 440.064398 -125.06579)
			(xy 440.07659 -125.06071) (xy 440.099362 -125.051961) (xy 440.146562 -125.039633) (xy 440.194947 -125.033414)
			(xy 440.219338 -125.033024) (xy 440.246592 -125.033443) (xy 440.300543 -125.041205) (xy 440.352841 -125.056567)
			(xy 440.402421 -125.079215) (xy 440.448273 -125.108688) (xy 440.489463 -125.144386) (xy 440.525154 -125.185583)
			(xy 440.554619 -125.231441) (xy 440.577258 -125.281024) (xy 440.59261 -125.333325) (xy 440.600362 -125.387278)
			(xy 440.600846 -125.414532) (xy 440.600412 -125.441904) (xy 440.592588 -125.496085) (xy 440.577093 -125.548588)
			(xy 440.554243 -125.598335) (xy 440.524511 -125.6443) (xy 440.506866 -125.66523) (xy 440.50077 -125.672342)
			(xy 440.49442 -125.68936) (xy 440.49442 -125.774704) (xy 440.50077 -125.791722) (xy 440.506866 -125.798834)
			(xy 440.524482 -125.819785) (xy 440.554199 -125.865752) (xy 440.566042 -125.891544) (xy 443.47511 -125.891544)
			(xy 443.475543 -125.865227) (xy 443.482767 -125.813092) (xy 443.497083 -125.762444) (xy 443.518222 -125.714242)
			(xy 443.545781 -125.6694) (xy 443.579238 -125.628769) (xy 443.5983 -125.61062) (xy 443.605695 -125.603093)
			(xy 443.614223 -125.583817) (xy 443.61481 -125.573282) (xy 443.61481 -125.498606) (xy 443.614288 -125.488056)
			(xy 443.605748 -125.46876) (xy 443.5983 -125.461268) (xy 443.579205 -125.443149) (xy 443.545728 -125.402525)
			(xy 443.51816 -125.357681) (xy 443.497024 -125.309471) (xy 443.482723 -125.258811) (xy 443.475529 -125.206664)
			(xy 443.47511 -125.180344) (xy 443.475596 -125.153093) (xy 443.483352 -125.099145) (xy 443.498707 -125.04685)
			(xy 443.521349 -124.997273) (xy 443.550815 -124.951423) (xy 443.586506 -124.910232) (xy 443.627697 -124.874541)
			(xy 443.673547 -124.845075) (xy 443.723124 -124.822433) (xy 443.775419 -124.807078) (xy 443.829367 -124.799322)
			(xy 443.883869 -124.799322) (xy 443.937817 -124.807078) (xy 443.990112 -124.822433) (xy 444.039689 -124.845075)
			(xy 444.085539 -124.874541) (xy 444.12673 -124.910232) (xy 444.162421 -124.951423) (xy 444.191887 -124.997273)
			(xy 444.214529 -125.04685) (xy 444.229884 -125.099145) (xy 444.23764 -125.153093) (xy 444.238126 -125.180344)
			(xy 444.237674 -125.20666) (xy 444.230452 -125.258794) (xy 444.216139 -125.309442) (xy 444.195004 -125.357643)
			(xy 444.167449 -125.402485) (xy 444.133996 -125.443118) (xy 444.114936 -125.461268) (xy 444.107552 -125.468804)
			(xy 444.099016 -125.488073) (xy 444.098426 -125.498606) (xy 444.098426 -125.573282) (xy 444.098944 -125.583833)
			(xy 444.107486 -125.603129) (xy 444.114936 -125.61062) (xy 444.134013 -125.628758) (xy 444.167494 -125.669376)
			(xy 444.195066 -125.714215) (xy 444.216205 -125.762423) (xy 444.23051 -125.81308) (xy 444.237707 -125.865224)
			(xy 444.238126 -125.891544) (xy 444.23764 -125.918795) (xy 444.229884 -125.972743) (xy 444.214529 -126.025038)
			(xy 444.191887 -126.074615) (xy 444.162421 -126.120465) (xy 444.12673 -126.161656) (xy 444.085539 -126.197347)
			(xy 444.039689 -126.226813) (xy 443.990112 -126.249455) (xy 443.937817 -126.26481) (xy 443.883869 -126.272566)
			(xy 443.829367 -126.272566) (xy 443.775419 -126.26481) (xy 443.723124 -126.249455) (xy 443.673547 -126.226813)
			(xy 443.627697 -126.197347) (xy 443.586506 -126.161656) (xy 443.550815 -126.120465) (xy 443.521349 -126.074615)
			(xy 443.498707 -126.025038) (xy 443.483352 -125.972743) (xy 443.475596 -125.918795) (xy 443.47511 -125.891544)
			(xy 440.566042 -125.891544) (xy 440.57704 -125.915494) (xy 440.592536 -125.967991) (xy 440.600369 -126.022164)
			(xy 440.600846 -126.049532) (xy 440.60036 -126.076783) (xy 440.592604 -126.130731) (xy 440.577249 -126.183026)
			(xy 440.554607 -126.232603) (xy 440.525141 -126.278453) (xy 440.48945 -126.319644) (xy 440.448259 -126.355335)
			(xy 440.402409 -126.384801) (xy 440.352832 -126.407443) (xy 440.300537 -126.422798) (xy 440.246589 -126.430554)
			(xy 440.192087 -126.430554) (xy 440.138139 -126.422798) (xy 440.085844 -126.407443) (xy 440.036267 -126.384801)
			(xy 439.990417 -126.355335) (xy 439.949226 -126.319644) (xy 439.913535 -126.278453) (xy 439.884069 -126.232603)
			(xy 439.861427 -126.183026) (xy 439.846072 -126.130731) (xy 439.838316 -126.076783) (xy 439.83783 -126.049532)
			(xy 439.838308 -126.022162) (xy 439.846121 -125.967983) (xy 439.861607 -125.91548) (xy 439.884447 -125.865733)
			(xy 439.91417 -125.819766) (xy 439.93181 -125.798834) (xy 439.937906 -125.791722) (xy 439.944256 -125.774704)
			(xy 439.944256 -125.68936) (xy 439.937906 -125.672342) (xy 439.93181 -125.66523) (xy 439.914173 -125.644296)
			(xy 439.884461 -125.598324) (xy 439.861624 -125.548577) (xy 439.846133 -125.496077) (xy 439.838304 -125.441901)
			(xy 439.83783 -125.414532) (xy 439.838592 -125.38964) (xy 439.839608 -125.376432) (xy 439.828432 -125.353064)
			(xy 439.737246 -125.287024) (xy 439.711592 -125.283722) (xy 439.6994 -125.288802) (xy 439.676629 -125.297554)
			(xy 439.629429 -125.309881) (xy 439.581044 -125.316099) (xy 439.556652 -125.316488) (xy 439.529283 -125.315994)
			(xy 439.475105 -125.308184) (xy 439.422602 -125.292701) (xy 439.372854 -125.269866) (xy 439.326886 -125.240147)
			(xy 439.305954 -125.222508) (xy 439.298842 -125.216412) (xy 439.281824 -125.210062) (xy 439.19648 -125.210062)
			(xy 439.179462 -125.216412) (xy 439.17235 -125.222508) (xy 439.151411 -125.240138) (xy 439.10544 -125.269851)
			(xy 439.055694 -125.292689) (xy 439.003195 -125.308182) (xy 438.949021 -125.316013) (xy 438.921652 -125.316488)
			(xy 438.893829 -125.315917) (xy 438.838771 -125.307862) (xy 438.78547 -125.291885) (xy 438.735058 -125.268326)
			(xy 438.688609 -125.237687) (xy 438.647109 -125.200619) (xy 438.611441 -125.157909) (xy 438.582363 -125.110467)
			(xy 438.560493 -125.0593) (xy 438.546297 -125.005497) (xy 438.542684 -124.977906) (xy 438.541032 -124.967608)
			(xy 438.53075 -124.94949) (xy 438.514124 -124.936938) (xy 438.493882 -124.932013) (xy 438.473347 -124.935524)
			(xy 438.455891 -124.946894) (xy 438.44972 -124.9553) (xy 438.442797 -124.965564) (xy 438.427797 -124.985263)
			(xy 438.419748 -124.99467) (xy 438.413652 -125.001782) (xy 438.407302 -125.0188) (xy 438.407302 -125.104144)
			(xy 438.413652 -125.121162) (xy 438.419748 -125.128274) (xy 438.437362 -125.149228) (xy 438.46709 -125.195192)
			(xy 438.489939 -125.244934) (xy 438.505438 -125.297433) (xy 438.51327 -125.351609) (xy 438.513273 -125.406349)
			(xy 438.505447 -125.460525) (xy 438.489954 -125.513026) (xy 438.46711 -125.562771) (xy 438.437388 -125.608738)
			(xy 438.419748 -125.62967) (xy 438.413652 -125.636782) (xy 438.407302 -125.6538) (xy 438.407302 -125.739144)
			(xy 438.413652 -125.756162) (xy 438.419748 -125.763274) (xy 438.43738 -125.784212) (xy 438.467095 -125.830182)
			(xy 438.489933 -125.879928) (xy 438.505425 -125.932428) (xy 438.513254 -125.986603) (xy 438.513728 -126.013972)
			(xy 438.513242 -126.041223) (xy 438.505486 -126.095171) (xy 438.490131 -126.147466) (xy 438.467489 -126.197043)
			(xy 438.438023 -126.242893) (xy 438.402332 -126.284084) (xy 438.361141 -126.319775) (xy 438.315291 -126.349241)
			(xy 438.265714 -126.371883) (xy 438.213419 -126.387238) (xy 438.159471 -126.394994) (xy 438.104969 -126.394994)
			(xy 438.051021 -126.387238) (xy 437.998726 -126.371883) (xy 437.949149 -126.349241) (xy 437.903299 -126.319775)
			(xy 437.862108 -126.284084) (xy 437.826417 -126.242893) (xy 437.796951 -126.197043) (xy 437.774309 -126.147466)
			(xy 437.758954 -126.095171) (xy 437.751198 -126.041223) (xy 437.750712 -126.013972) (xy 418.214594 -126.013972)
			(xy 418.202591 -126.027368) (xy 418.159723 -126.063043) (xy 418.112117 -126.092097) (xy 418.060788 -126.113909)
			(xy 418.006831 -126.128015) (xy 417.951394 -126.134115) (xy 417.89566 -126.132078) (xy 417.840817 -126.121948)
			(xy 417.788033 -126.103941) (xy 417.738433 -126.07844) (xy 417.693075 -126.045989) (xy 417.652926 -126.00728)
			(xy 417.61884 -125.963137) (xy 417.591544 -125.914502) (xy 417.571621 -125.862411) (xy 417.559495 -125.807974)
			(xy 417.555424 -125.752352) (xy 416.17845 -125.752352) (xy 416.141585 -125.774851) (xy 416.090256 -125.796663)
			(xy 416.036299 -125.810769) (xy 415.980862 -125.816869) (xy 415.925128 -125.814832) (xy 415.870285 -125.804702)
			(xy 415.817501 -125.786695) (xy 415.767901 -125.761194) (xy 415.722543 -125.728743) (xy 415.682394 -125.690034)
			(xy 415.648308 -125.645891) (xy 415.621012 -125.597256) (xy 415.601089 -125.545165) (xy 415.588963 -125.490728)
			(xy 415.584892 -125.435106) (xy 414.493716 -125.435106) (xy 414.493716 -125.46235) (xy 414.48596 -125.516296)
			(xy 414.470606 -125.56859) (xy 414.447966 -125.618165) (xy 414.418501 -125.664014) (xy 414.382811 -125.705204)
			(xy 414.341623 -125.740895) (xy 414.295774 -125.770361) (xy 414.246199 -125.793002) (xy 414.193906 -125.808358)
			(xy 414.13996 -125.816116) (xy 414.11271 -125.816614) (xy 414.085738 -125.816141) (xy 414.032334 -125.808528)
			(xy 413.980536 -125.793466) (xy 413.931376 -125.771256) (xy 413.885836 -125.742342) (xy 413.844825 -125.707299)
			(xy 413.80916 -125.666827) (xy 413.779553 -125.621734) (xy 413.756595 -125.57292) (xy 413.740744 -125.521357)
			(xy 413.736028 -125.494796) (xy 413.73425 -125.484128) (xy 413.72282 -125.466602) (xy 413.642556 -125.413008)
			(xy 413.621982 -125.409452) (xy 413.611568 -125.411992) (xy 413.584874 -125.418136) (xy 413.530498 -125.42476)
			(xy 413.50311 -125.4252) (xy 413.475722 -125.424754) (xy 413.421347 -125.418132) (xy 413.394652 -125.411992)
			(xy 413.384238 -125.409452) (xy 413.363664 -125.413008) (xy 413.2834 -125.466602) (xy 413.27197 -125.484128)
			(xy 413.270192 -125.494796) (xy 413.265533 -125.521373) (xy 413.249705 -125.572957) (xy 413.22676 -125.621793)
			(xy 413.197157 -125.666904) (xy 413.161487 -125.707389) (xy 413.120464 -125.742439) (xy 413.074908 -125.771353)
			(xy 413.025729 -125.793553) (xy 412.973911 -125.808595) (xy 412.920489 -125.816178) (xy 412.89351 -125.816614)
			(xy 412.866256 -125.816151) (xy 412.812303 -125.808395) (xy 412.760004 -125.79304) (xy 412.710421 -125.770398)
			(xy 412.664566 -125.74093) (xy 412.623372 -125.705235) (xy 412.587676 -125.664042) (xy 412.558207 -125.618187)
			(xy 412.535564 -125.568606) (xy 412.520207 -125.516306) (xy 412.512449 -125.462354) (xy 412.512449 -125.407846)
			(xy 412.520207 -125.353894) (xy 412.535564 -125.301594) (xy 412.558207 -125.252013) (xy 412.587676 -125.206158)
			(xy 412.623372 -125.164965) (xy 412.664566 -125.12927) (xy 412.710421 -125.099802) (xy 412.760004 -125.07716)
			(xy 412.812303 -125.061805) (xy 412.866256 -125.054049) (xy 412.89351 -125.053598) (xy 412.910623 -125.05377)
			(xy 412.944712 -125.05682) (xy 412.961582 -125.059694) (xy 412.972848 -125.061128) (xy 412.994734 -125.055178)
			(xy 413.003746 -125.048264) (xy 413.02813 -125.027182) (xy 413.036377 -125.019156) (xy 413.045471 -124.99805)
			(xy 413.045656 -124.986542) (xy 413.045148 -124.967238) (xy 413.045148 -124.103638) (xy 413.045656 -124.083572)
			(xy 413.045641 -124.07203) (xy 413.036522 -124.050854) (xy 413.02813 -124.042932) (xy 413.003746 -124.02185)
			(xy 412.994729 -124.01496) (xy 412.972849 -124.009047) (xy 412.961582 -124.01042) (xy 412.944709 -124.013275)
			(xy 412.910622 -124.016332) (xy 412.89351 -124.016516) (xy 412.866256 -124.016053) (xy 412.812303 -124.008297)
			(xy 412.760003 -123.992942) (xy 412.71042 -123.970299) (xy 412.664565 -123.940831) (xy 412.62337 -123.905137)
			(xy 412.587675 -123.863943) (xy 412.558205 -123.818088) (xy 412.535562 -123.768507) (xy 412.520205 -123.716207)
			(xy 412.512447 -123.662254) (xy 412.512447 -123.607746) (xy 412.520205 -123.553793) (xy 412.535562 -123.501493)
			(xy 412.558205 -123.451912) (xy 412.587675 -123.406057) (xy 412.62337 -123.364863) (xy 412.664565 -123.329169)
			(xy 412.71042 -123.299701) (xy 412.760003 -123.277058) (xy 412.812303 -123.261703) (xy 412.866256 -123.253947)
			(xy 412.89351 -123.2535) (xy 412.920516 -123.253969) (xy 412.973989 -123.261586) (xy 413.025853 -123.276668)
			(xy 413.075073 -123.298912) (xy 413.120664 -123.327875) (xy 413.161716 -123.362976) (xy 413.197407 -123.403516)
			(xy 413.227026 -123.448683) (xy 413.24998 -123.497576) (xy 413.26581 -123.549217) (xy 413.270446 -123.575826)
			(xy 413.27197 -123.586494) (xy 413.2834 -123.604274) (xy 413.363664 -123.657614) (xy 413.384238 -123.661424)
			(xy 413.394906 -123.658884) (xy 413.421538 -123.652755) (xy 413.475786 -123.646139) (xy 413.50311 -123.645676)
			(xy 413.530434 -123.646132) (xy 413.584683 -123.65275) (xy 413.611314 -123.658884) (xy 413.621982 -123.661424)
			(xy 413.642556 -123.657614) (xy 413.72282 -123.604274) (xy 413.73425 -123.586494) (xy 413.735774 -123.575826)
			(xy 413.740427 -123.54922) (xy 413.756248 -123.497579) (xy 413.779196 -123.448686) (xy 413.808811 -123.403519)
			(xy 413.844501 -123.362981) (xy 413.885553 -123.327883) (xy 413.931146 -123.298926) (xy 413.980367 -123.276691)
			(xy 414.032232 -123.261621) (xy 414.085705 -123.254017) (xy 414.11271 -123.2535) (xy 414.14008 -123.253972)
			(xy 414.194257 -123.261798) (xy 414.24676 -123.277286) (xy 414.29651 -123.300119) (xy 414.342486 -123.329828)
			(xy 414.363408 -123.34748) (xy 414.37052 -123.353576) (xy 414.387538 -123.359926) (xy 414.472882 -123.359926)
			(xy 414.4899 -123.353576) (xy 414.497012 -123.34748) (xy 414.517944 -123.32984) (xy 414.563911 -123.300116)
			(xy 414.613658 -123.277276) (xy 414.666161 -123.261788) (xy 414.72034 -123.253972) (xy 414.74771 -123.2535)
			(xy 414.764823 -123.253672) (xy 414.798912 -123.256722) (xy 414.815782 -123.259596) (xy 414.827048 -123.26103)
			(xy 414.848934 -123.25508) (xy 414.857946 -123.248166) (xy 414.88233 -123.227084) (xy 414.890577 -123.219058)
			(xy 414.899672 -123.197952) (xy 414.899856 -123.186444) (xy 414.899348 -123.16714) (xy 414.899348 -122.30354)
			(xy 414.899856 -122.283728) (xy 414.899832 -122.272191) (xy 414.890701 -122.251029) (xy 414.88233 -122.243088)
			(xy 414.857946 -122.222006) (xy 414.848931 -122.21511) (xy 414.827049 -122.20919) (xy 414.815782 -122.210576)
			(xy 414.798909 -122.21343) (xy 414.764822 -122.216487) (xy 414.74771 -122.216672) (xy 414.720342 -122.216194)
			(xy 414.666171 -122.208358) (xy 414.613675 -122.19286) (xy 414.563934 -122.170019) (xy 414.517967 -122.140302)
			(xy 414.497012 -122.122692) (xy 414.4899 -122.116596) (xy 414.472882 -122.110246) (xy 414.387538 -122.110246)
			(xy 414.37052 -122.116596) (xy 414.363408 -122.122692) (xy 414.342477 -122.140335) (xy 414.296511 -122.170062)
			(xy 414.246764 -122.192907) (xy 414.194261 -122.208399) (xy 414.140081 -122.216219) (xy 414.11271 -122.216672)
			(xy 414.085737 -122.216199) (xy 414.032331 -122.208586) (xy 413.980529 -122.193525) (xy 413.931366 -122.171317)
			(xy 413.885823 -122.142404) (xy 413.844807 -122.107362) (xy 413.809137 -122.066892) (xy 413.779524 -122.0218)
			(xy 413.756559 -121.972986) (xy 413.7407 -121.921423) (xy 413.736028 -121.894854) (xy 413.73425 -121.884186)
			(xy 413.72282 -121.86666) (xy 413.642556 -121.813066) (xy 413.621982 -121.80951) (xy 413.611568 -121.81205)
			(xy 413.584868 -121.818133) (xy 413.530492 -121.824627) (xy 413.50311 -121.825004) (xy 413.475729 -121.82462)
			(xy 413.421352 -121.81813) (xy 413.394652 -121.81205) (xy 413.384238 -121.80951) (xy 413.363664 -121.813066)
			(xy 413.2834 -121.86666) (xy 413.27197 -121.884186) (xy 413.270192 -121.894854) (xy 413.265529 -121.921428)
			(xy 413.249695 -121.973006) (xy 413.226747 -122.021835) (xy 413.197141 -122.066939) (xy 413.161471 -122.107418)
			(xy 413.120449 -122.142462) (xy 413.074894 -122.171371) (xy 413.025719 -122.193567) (xy 412.973904 -122.208606)
			(xy 412.920487 -122.216188) (xy 412.89351 -122.216672) (xy 412.866259 -122.216209) (xy 412.812312 -122.208454)
			(xy 412.760018 -122.193101) (xy 412.710442 -122.170461) (xy 412.664591 -122.140996) (xy 412.623401 -122.105306)
			(xy 412.58771 -122.064117) (xy 412.558244 -122.018267) (xy 412.535603 -121.968691) (xy 412.520248 -121.916397)
			(xy 412.512491 -121.862451) (xy 412.512491 -121.807949) (xy 412.520248 -121.754003) (xy 412.535603 -121.701709)
			(xy 412.558244 -121.652133) (xy 412.58771 -121.606283) (xy 412.623401 -121.565094) (xy 412.664591 -121.529404)
			(xy 412.710442 -121.499939) (xy 412.760018 -121.477299) (xy 412.812312 -121.461946) (xy 412.866259 -121.454191)
			(xy 412.89351 -121.453656) (xy 412.910623 -121.453828) (xy 412.944712 -121.456878) (xy 412.961582 -121.459752)
			(xy 412.972849 -121.461186) (xy 412.994738 -121.455242) (xy 413.003746 -121.448322) (xy 413.02813 -121.42724)
			(xy 413.03637 -121.419211) (xy 413.045446 -121.398106) (xy 413.045656 -121.3866) (xy 413.045148 -121.367296)
			(xy 413.045148 -120.503696) (xy 413.045656 -120.48363) (xy 413.045632 -120.472092) (xy 413.036502 -120.45093)
			(xy 413.02813 -120.44299) (xy 413.003746 -120.421908) (xy 412.994731 -120.415012) (xy 412.972849 -120.409092)
			(xy 412.961582 -120.410478) (xy 412.944709 -120.413332) (xy 412.910622 -120.416389) (xy 412.89351 -120.416574)
			(xy 412.866259 -120.416111) (xy 412.812312 -120.408356) (xy 412.760018 -120.393003) (xy 412.710441 -120.370363)
			(xy 412.66459 -120.340897) (xy 412.6234 -120.305207) (xy 412.587709 -120.264018) (xy 412.558242 -120.218168)
			(xy 412.535601 -120.168592) (xy 412.520246 -120.116298) (xy 412.512489 -120.062351) (xy 412.512489 -120.007849)
			(xy 412.520246 -119.953902) (xy 412.535601 -119.901608) (xy 412.558242 -119.852032) (xy 412.587709 -119.806182)
			(xy 412.6234 -119.764993) (xy 412.66459 -119.729303) (xy 412.710441 -119.699837) (xy 412.760018 -119.677197)
			(xy 412.812312 -119.661844) (xy 412.866259 -119.654089) (xy 412.89351 -119.653558) (xy 412.920517 -119.654027)
			(xy 412.973992 -119.661644) (xy 413.025858 -119.676725) (xy 413.07508 -119.698968) (xy 413.120674 -119.72793)
			(xy 413.161729 -119.76303) (xy 413.197424 -119.803569) (xy 413.227048 -119.848736) (xy 413.250007 -119.897628)
			(xy 413.265842 -119.949269) (xy 413.270446 -119.975884) (xy 413.27197 -119.986552) (xy 413.2834 -120.004332)
			(xy 413.363664 -120.057672) (xy 413.384238 -120.061482) (xy 413.394906 -120.058942) (xy 413.421543 -120.052867)
			(xy 413.475792 -120.04637) (xy 413.50311 -120.045988) (xy 413.530427 -120.046388) (xy 413.584674 -120.052885)
			(xy 413.611314 -120.058942) (xy 413.621982 -120.061482) (xy 413.642556 -120.057672) (xy 413.72282 -120.004332)
			(xy 413.73425 -119.986552) (xy 413.735774 -119.975884) (xy 413.740423 -119.949276) (xy 413.756239 -119.897628)
			(xy 413.779183 -119.848728) (xy 413.808796 -119.803554) (xy 413.844485 -119.76301) (xy 413.885538 -119.727905)
			(xy 413.931132 -119.698944) (xy 413.980356 -119.676704) (xy 414.032225 -119.661631) (xy 414.085702 -119.654026)
			(xy 414.11271 -119.653558) (xy 414.140079 -119.654031) (xy 414.194256 -119.661857) (xy 414.246758 -119.677347)
			(xy 414.296506 -119.700183) (xy 414.342479 -119.729895) (xy 414.363408 -119.747538) (xy 414.37052 -119.753634)
			(xy 414.387538 -119.759984) (xy 414.472882 -119.759984) (xy 414.4899 -119.753634) (xy 414.497012 -119.747538)
			(xy 414.517943 -119.729895) (xy 414.563909 -119.700168) (xy 414.613656 -119.677324) (xy 414.666159 -119.661833)
			(xy 414.720339 -119.654016) (xy 414.74771 -119.653558) (xy 414.764823 -119.65373) (xy 414.798912 -119.65678)
			(xy 414.815782 -119.659654) (xy 414.827048 -119.661088) (xy 414.848931 -119.655135) (xy 414.857946 -119.648224)
			(xy 414.88233 -119.627142) (xy 414.89057 -119.619113) (xy 414.899648 -119.598008) (xy 414.899856 -119.586502)
			(xy 414.899348 -119.567198) (xy 414.899348 -118.703598) (xy 414.900364 -118.674134) (xy 414.900618 -118.672356)
			(xy 414.900618 -118.670832) (xy 414.900204 -118.660805) (xy 414.892541 -118.642274) (xy 414.878368 -118.628088)
			(xy 414.859844 -118.620406) (xy 414.849818 -118.620032) (xy 414.22701 -118.620032) (xy 414.216938 -118.619612)
			(xy 414.198328 -118.611903) (xy 414.190942 -118.605046) (xy 413.497776 -117.91188) (xy 413.490925 -117.904484)
			(xy 413.483185 -117.885885) (xy 413.48279 -117.875812) (xy 413.48279 -115.648994) (xy 413.482251 -115.639007)
			(xy 413.474535 -115.620578) (xy 413.467804 -115.61318) (xy 413.268922 -115.414044) (xy 413.24644 -115.390938)
			(xy 413.206227 -115.340546) (xy 413.171908 -115.285968) (xy 413.143916 -115.227891) (xy 413.122602 -115.167046)
			(xy 413.108234 -115.104196) (xy 413.100994 -115.040133) (xy 413.10052 -115.007898) (xy 413.10052 -114.750596)
			(xy 413.100033 -114.740505) (xy 413.092176 -114.721911) (xy 413.08528 -114.714528) (xy 413.025844 -114.656362)
			(xy 413.007302 -114.648996) (xy 412.996888 -114.64925) (xy 412.988252 -114.64925) (xy 412.961 -114.648761)
			(xy 412.907052 -114.640998) (xy 412.854757 -114.625637) (xy 412.80518 -114.602991) (xy 412.759331 -114.57352)
			(xy 412.718142 -114.537824) (xy 412.682451 -114.496631) (xy 412.652986 -114.450778) (xy 412.630346 -114.401198)
			(xy 412.614992 -114.348902) (xy 412.607236 -114.294952) (xy 412.607236 -114.240448) (xy 412.614992 -114.186498)
			(xy 412.630346 -114.134202) (xy 412.652986 -114.084622) (xy 412.682451 -114.038769) (xy 412.718142 -113.997576)
			(xy 412.759331 -113.96188) (xy 412.80518 -113.932409) (xy 412.854757 -113.909763) (xy 412.907052 -113.894402)
			(xy 412.961 -113.886639) (xy 412.988252 -113.886234) (xy 412.996888 -113.886234) (xy 413.007302 -113.886488)
			(xy 413.025844 -113.879122) (xy 413.08528 -113.820956) (xy 413.092202 -113.813587) (xy 413.100081 -113.794987)
			(xy 413.10052 -113.784888) (xy 413.10052 -113.28527) (xy 413.100069 -113.275243) (xy 413.092477 -113.256686)
			(xy 413.085788 -113.249202) (xy 412.93669 -113.100104) (xy 412.929265 -113.093327) (xy 412.910668 -113.085737)
			(xy 412.900622 -113.085372) (xy 412.48457 -113.085372) (xy 412.449984 -113.084837) (xy 412.381315 -113.076497)
			(xy 412.314143 -113.059977) (xy 412.24944 -113.035515) (xy 412.188139 -113.003466) (xy 412.131127 -112.964292)
			(xy 412.079228 -112.918559) (xy 412.055818 -112.893094) (xy 412.048254 -112.88547) (xy 412.028695 -112.876662)
			(xy 412.017972 -112.876076) (xy 410.142436 -112.876076) (xy 410.132371 -112.875641) (xy 410.113786 -112.867907)
			(xy 410.106368 -112.86109) (xy 408.598116 -111.352838) (xy 408.591278 -111.345437) (xy 408.583563 -111.326838)
			(xy 408.58313 -111.31677) (xy 408.58313 -107.317794) (xy 408.583555 -107.307725) (xy 408.591274 -107.289125)
			(xy 408.598116 -107.281726) (xy 409.376372 -106.50347) (xy 409.383771 -106.496627) (xy 409.40237 -106.488908)
			(xy 409.41244 -106.488484) (xy 415.318702 -106.488484) (xy 415.329814 -106.487929) (xy 415.34998 -106.478588)
			(xy 415.357564 -106.47045) (xy 415.387278 -106.43588) (xy 415.452366 -106.372049) (xy 415.523328 -106.314818)
			(xy 415.599496 -106.264725) (xy 415.680155 -106.22224) (xy 415.764548 -106.187762) (xy 415.851882 -106.161615)
			(xy 415.941336 -106.144044) (xy 416.032072 -106.135215) (xy 416.077654 -106.134662) (xy 416.121106 -106.135146)
			(xy 416.207641 -106.143161) (xy 416.293067 -106.159125) (xy 416.376655 -106.182904) (xy 416.457693 -106.214294)
			(xy 416.535489 -106.253028) (xy 416.609379 -106.298774) (xy 416.678733 -106.351143) (xy 416.742958 -106.409688)
			(xy 416.801508 -106.473909) (xy 416.853883 -106.543258) (xy 416.899635 -106.617145) (xy 416.938375 -106.694937)
			(xy 416.969772 -106.775973) (xy 416.993557 -106.859559) (xy 417.009529 -106.944984) (xy 417.01755 -107.031518)
			(xy 417.017962 -107.07497) (xy 417.01775 -107.102211) (xy 417.014571 -107.156601) (xy 417.011612 -107.183682)
			(xy 417.010342 -107.194604) (xy 417.016692 -107.214924) (xy 417.074604 -107.279948) (xy 417.082172 -107.287564)
			(xy 417.101731 -107.296356) (xy 417.11245 -107.296966) (xy 417.295584 -107.296966) (xy 417.306335 -107.296493)
			(xy 417.325946 -107.28768) (xy 417.33343 -107.279948) (xy 417.391342 -107.214924) (xy 417.397692 -107.194604)
			(xy 417.396422 -107.183682) (xy 417.393447 -107.156602) (xy 417.390268 -107.102212) (xy 417.390072 -107.07497)
			(xy 417.39056 -107.031525) (xy 417.398582 -106.945006) (xy 417.414553 -106.859597) (xy 417.438338 -106.776026)
			(xy 417.469734 -106.695006) (xy 417.508473 -106.61723) (xy 417.554224 -106.54336) (xy 417.606596 -106.474028)
			(xy 417.665144 -106.409825) (xy 417.729366 -106.351298) (xy 417.798716 -106.298948) (xy 417.872601 -106.253222)
			(xy 417.95039 -106.214509) (xy 418.03142 -106.18314) (xy 418.114999 -106.159382) (xy 418.200413 -106.143439)
			(xy 418.286935 -106.135446) (xy 418.33038 -106.134916) (xy 420.18458 -106.134916) (xy 420.228023 -106.135417)
			(xy 420.314537 -106.14343) (xy 420.399944 -106.159391) (xy 420.483514 -106.183164) (xy 420.564534 -106.214544)
			(xy 420.642314 -106.253265) (xy 420.71619 -106.298997) (xy 420.785531 -106.351349) (xy 420.849748 -106.409875)
			(xy 420.908291 -106.474076) (xy 420.960661 -106.543404) (xy 421.006413 -106.617268) (xy 421.045155 -106.695037)
			(xy 421.076557 -106.776049) (xy 421.100351 -106.859613) (xy 421.116335 -106.945015) (xy 421.124372 -107.031528)
			(xy 421.124888 -107.07497) (xy 421.124676 -107.102211) (xy 421.121497 -107.156601) (xy 421.118538 -107.183682)
			(xy 421.117268 -107.194604) (xy 421.123618 -107.214924) (xy 421.18153 -107.279948) (xy 421.189099 -107.28756)
			(xy 421.208658 -107.296342) (xy 421.219376 -107.296966) (xy 422.412668 -107.296966) (xy 422.423421 -107.296496)
			(xy 422.443036 -107.287687) (xy 422.450514 -107.279948) (xy 422.508426 -107.214924) (xy 422.514776 -107.194604)
			(xy 422.513506 -107.183682) (xy 422.510531 -107.156602) (xy 422.507352 -107.102212) (xy 422.507156 -107.07497)
			(xy 422.507658 -107.03152) (xy 422.515676 -106.944991) (xy 422.531644 -106.859571) (xy 422.555425 -106.775989)
			(xy 422.586817 -106.694957) (xy 422.625551 -106.617168) (xy 422.671298 -106.543284) (xy 422.723667 -106.473937)
			(xy 422.782211 -106.409717) (xy 422.846431 -106.351173) (xy 422.915778 -106.298804) (xy 422.989662 -106.253057)
			(xy 423.067451 -106.214323) (xy 423.148483 -106.182931) (xy 423.232065 -106.15915) (xy 423.317485 -106.143182)
			(xy 423.404014 -106.135164) (xy 423.490914 -106.135164) (xy 423.577443 -106.143182) (xy 423.662863 -106.15915)
			(xy 423.746445 -106.182931) (xy 423.827477 -106.214323) (xy 423.905266 -106.253057) (xy 423.97915 -106.298804)
			(xy 424.048497 -106.351173) (xy 424.085441 -106.384852) (xy 425.812964 -106.384852) (xy 425.817035 -106.32923)
			(xy 425.829161 -106.274793) (xy 425.849084 -106.222702) (xy 425.87638 -106.174067) (xy 425.910466 -106.129924)
			(xy 425.950615 -106.091215) (xy 425.995973 -106.058764) (xy 426.045573 -106.033263) (xy 426.098357 -106.015256)
			(xy 426.1532 -106.005126) (xy 426.208934 -106.003089) (xy 426.264371 -106.009189) (xy 426.318328 -106.023295)
			(xy 426.369657 -106.045107) (xy 426.417263 -106.074161) (xy 426.460131 -106.109836) (xy 426.497348 -106.151373)
			(xy 426.528121 -106.197886) (xy 426.551793 -106.248383) (xy 426.567861 -106.30179) (xy 426.575981 -106.356966)
			(xy 426.57649 -106.384852) (xy 426.575981 -106.412738) (xy 426.567861 -106.467914) (xy 426.551793 -106.521321)
			(xy 426.528121 -106.571818) (xy 426.497348 -106.618331) (xy 426.460131 -106.659868) (xy 426.417263 -106.695543)
			(xy 426.369657 -106.724597) (xy 426.318328 -106.746409) (xy 426.264371 -106.760515) (xy 426.208934 -106.766615)
			(xy 426.1532 -106.764578) (xy 426.098357 -106.754448) (xy 426.045573 -106.736441) (xy 425.995973 -106.71094)
			(xy 425.950615 -106.678489) (xy 425.910466 -106.63978) (xy 425.87638 -106.595637) (xy 425.849084 -106.547002)
			(xy 425.829161 -106.494911) (xy 425.817035 -106.440474) (xy 425.812964 -106.384852) (xy 424.085441 -106.384852)
			(xy 424.112717 -106.409717) (xy 424.171261 -106.473937) (xy 424.22363 -106.543284) (xy 424.269377 -106.617168)
			(xy 424.308111 -106.694957) (xy 424.339503 -106.775989) (xy 424.363284 -106.859571) (xy 424.379252 -106.944991)
			(xy 424.38727 -107.03152) (xy 424.387772 -107.07497) (xy 424.38756 -107.102211) (xy 424.384381 -107.156601)
			(xy 424.381422 -107.183682) (xy 424.380152 -107.194604) (xy 424.386502 -107.214924) (xy 424.444414 -107.279948)
			(xy 424.451982 -107.287562) (xy 424.471541 -107.29635) (xy 424.48226 -107.296966) (xy 429.495966 -107.296966)
			(xy 429.50603 -107.29653) (xy 429.524614 -107.288795) (xy 429.532034 -107.28198) (xy 433.459128 -103.354886)
			(xy 433.46598 -103.34749) (xy 433.473721 -103.328891) (xy 433.474114 -103.318818) (xy 433.474114 -81.022952)
			(xy 433.473683 -81.012885) (xy 433.465958 -80.994292) (xy 433.459128 -80.986884) (xy 431.361596 -78.889352)
			(xy 431.3542 -78.8825) (xy 431.335601 -78.874759) (xy 431.325528 -78.874366) (xy 405.24303 -78.874366)
			(xy 405.232967 -78.874804) (xy 405.214387 -78.882543) (xy 405.206962 -78.889352) (xy 404.076408 -80.019906)
			(xy 420.800782 -80.019906) (xy 420.804853 -79.964284) (xy 420.816979 -79.909847) (xy 420.836902 -79.857756)
			(xy 420.864198 -79.809121) (xy 420.898284 -79.764978) (xy 420.938433 -79.726269) (xy 420.983791 -79.693818)
			(xy 421.033391 -79.668317) (xy 421.086175 -79.65031) (xy 421.141018 -79.64018) (xy 421.196752 -79.638143)
			(xy 421.252189 -79.644243) (xy 421.306146 -79.658349) (xy 421.357475 -79.680161) (xy 421.405081 -79.709215)
			(xy 421.447949 -79.74489) (xy 421.485166 -79.786427) (xy 421.515939 -79.83294) (xy 421.539611 -79.883437)
			(xy 421.555679 -79.936844) (xy 421.563799 -79.99202) (xy 421.564164 -80.012028) (xy 427.872888 -80.012028)
			(xy 427.872888 -79.952092) (xy 427.880711 -79.89267) (xy 427.896224 -79.834777) (xy 427.91916 -79.779404)
			(xy 427.949127 -79.727498) (xy 427.985614 -79.679948) (xy 428.027994 -79.637568) (xy 428.075544 -79.601081)
			(xy 428.12745 -79.571114) (xy 428.182823 -79.548178) (xy 428.240716 -79.532665) (xy 428.300138 -79.524842)
			(xy 428.360074 -79.524842) (xy 428.419496 -79.532665) (xy 428.477389 -79.548178) (xy 428.532762 -79.571114)
			(xy 428.584668 -79.601081) (xy 428.632218 -79.637568) (xy 428.674598 -79.679948) (xy 428.711085 -79.727498)
			(xy 428.741052 -79.779404) (xy 428.763988 -79.834777) (xy 428.779501 -79.89267) (xy 428.787324 -79.952092)
			(xy 428.787814 -79.98206) (xy 428.787324 -80.012028) (xy 428.779501 -80.07145) (xy 428.763988 -80.129343)
			(xy 428.741052 -80.184716) (xy 428.711085 -80.236622) (xy 428.674598 -80.284172) (xy 428.632218 -80.326552)
			(xy 428.584668 -80.363039) (xy 428.532762 -80.393006) (xy 428.477389 -80.415942) (xy 428.419496 -80.431455)
			(xy 428.360074 -80.439278) (xy 428.300138 -80.439278) (xy 428.240716 -80.431455) (xy 428.182823 -80.415942)
			(xy 428.12745 -80.393006) (xy 428.075544 -80.363039) (xy 428.027994 -80.326552) (xy 427.985614 -80.284172)
			(xy 427.949127 -80.236622) (xy 427.91916 -80.184716) (xy 427.896224 -80.129343) (xy 427.880711 -80.07145)
			(xy 427.872888 -80.012028) (xy 421.564164 -80.012028) (xy 421.564308 -80.019906) (xy 421.563799 -80.047792)
			(xy 421.555679 -80.102968) (xy 421.539611 -80.156375) (xy 421.515939 -80.206872) (xy 421.485166 -80.253385)
			(xy 421.447949 -80.294922) (xy 421.405081 -80.330597) (xy 421.357475 -80.359651) (xy 421.306146 -80.381463)
			(xy 421.252189 -80.395569) (xy 421.196752 -80.401669) (xy 421.141018 -80.399632) (xy 421.086175 -80.389502)
			(xy 421.033391 -80.371495) (xy 420.983791 -80.345994) (xy 420.938433 -80.313543) (xy 420.898284 -80.274834)
			(xy 420.864198 -80.230691) (xy 420.836902 -80.182056) (xy 420.816979 -80.129965) (xy 420.804853 -80.075528)
			(xy 420.800782 -80.019906) (xy 404.076408 -80.019906) (xy 403.64664 -80.449674) (xy 426.661324 -80.449674)
			(xy 426.665395 -80.394052) (xy 426.677521 -80.339615) (xy 426.697444 -80.287524) (xy 426.72474 -80.238889)
			(xy 426.758826 -80.194746) (xy 426.798975 -80.156037) (xy 426.844333 -80.123586) (xy 426.893933 -80.098085)
			(xy 426.946717 -80.080078) (xy 427.00156 -80.069948) (xy 427.057294 -80.067911) (xy 427.112731 -80.074011)
			(xy 427.166688 -80.088117) (xy 427.218017 -80.109929) (xy 427.265623 -80.138983) (xy 427.308491 -80.174658)
			(xy 427.345708 -80.216195) (xy 427.376481 -80.262708) (xy 427.400153 -80.313205) (xy 427.416221 -80.366612)
			(xy 427.424341 -80.421788) (xy 427.42485 -80.449674) (xy 427.424341 -80.47756) (xy 427.416221 -80.532736)
			(xy 427.400153 -80.586143) (xy 427.376481 -80.63664) (xy 427.345708 -80.683153) (xy 427.308491 -80.72469)
			(xy 427.265623 -80.760365) (xy 427.218017 -80.789419) (xy 427.166688 -80.811231) (xy 427.112731 -80.825337)
			(xy 427.057294 -80.831437) (xy 427.00156 -80.8294) (xy 426.946717 -80.81927) (xy 426.893933 -80.801263)
			(xy 426.844333 -80.775762) (xy 426.798975 -80.743311) (xy 426.758826 -80.704602) (xy 426.72474 -80.660459)
			(xy 426.697444 -80.611824) (xy 426.677521 -80.559733) (xy 426.665395 -80.505296) (xy 426.661324 -80.449674)
			(xy 403.64664 -80.449674) (xy 403.10943 -80.986884) (xy 403.102593 -80.994286) (xy 403.094885 -81.012884)
			(xy 403.094444 -81.022952) (xy 403.094444 -81.698846) (xy 429.1617 -81.698846) (xy 429.165771 -81.643224)
			(xy 429.177897 -81.588787) (xy 429.19782 -81.536696) (xy 429.225116 -81.488061) (xy 429.259202 -81.443918)
			(xy 429.299351 -81.405209) (xy 429.344709 -81.372758) (xy 429.394309 -81.347257) (xy 429.447093 -81.32925)
			(xy 429.501936 -81.31912) (xy 429.55767 -81.317083) (xy 429.613107 -81.323183) (xy 429.667064 -81.337289)
			(xy 429.718393 -81.359101) (xy 429.765999 -81.388155) (xy 429.808867 -81.42383) (xy 429.846084 -81.465367)
			(xy 429.876857 -81.51188) (xy 429.900529 -81.562377) (xy 429.916597 -81.615784) (xy 429.924717 -81.67096)
			(xy 429.925226 -81.698846) (xy 429.924717 -81.726732) (xy 429.916597 -81.781908) (xy 429.900529 -81.835315)
			(xy 429.876857 -81.885812) (xy 429.846084 -81.932325) (xy 429.808867 -81.973862) (xy 429.765999 -82.009537)
			(xy 429.718393 -82.038591) (xy 429.667064 -82.060403) (xy 429.613107 -82.074509) (xy 429.55767 -82.080609)
			(xy 429.501936 -82.078572) (xy 429.447093 -82.068442) (xy 429.394309 -82.050435) (xy 429.344709 -82.024934)
			(xy 429.299351 -81.992483) (xy 429.259202 -81.953774) (xy 429.225116 -81.909631) (xy 429.19782 -81.860996)
			(xy 429.177897 -81.808905) (xy 429.165771 -81.754468) (xy 429.1617 -81.698846) (xy 403.094444 -81.698846)
			(xy 403.094444 -82.331306) (xy 424.871386 -82.331306) (xy 424.875457 -82.275684) (xy 424.887583 -82.221247)
			(xy 424.907506 -82.169156) (xy 424.934802 -82.120521) (xy 424.968888 -82.076378) (xy 425.009037 -82.037669)
			(xy 425.054395 -82.005218) (xy 425.103995 -81.979717) (xy 425.156779 -81.96171) (xy 425.211622 -81.95158)
			(xy 425.267356 -81.949543) (xy 425.322793 -81.955643) (xy 425.37675 -81.969749) (xy 425.428079 -81.991561)
			(xy 425.475685 -82.020615) (xy 425.518553 -82.05629) (xy 425.55577 -82.097827) (xy 425.586543 -82.14434)
			(xy 425.610215 -82.194837) (xy 425.626283 -82.248244) (xy 425.634403 -82.30342) (xy 425.634912 -82.331306)
			(xy 425.634403 -82.359192) (xy 425.626284 -82.414364) (xy 425.781722 -82.414364) (xy 425.785793 -82.358742)
			(xy 425.797919 -82.304305) (xy 425.817842 -82.252214) (xy 425.845138 -82.203579) (xy 425.879224 -82.159436)
			(xy 425.919373 -82.120727) (xy 425.964731 -82.088276) (xy 426.014331 -82.062775) (xy 426.067115 -82.044768)
			(xy 426.121958 -82.034638) (xy 426.177692 -82.032601) (xy 426.233129 -82.038701) (xy 426.287086 -82.052807)
			(xy 426.338415 -82.074619) (xy 426.386021 -82.103673) (xy 426.428889 -82.139348) (xy 426.466106 -82.180885)
			(xy 426.496879 -82.227398) (xy 426.520551 -82.277895) (xy 426.536619 -82.331302) (xy 426.544739 -82.386478)
			(xy 426.545248 -82.414364) (xy 426.544739 -82.44225) (xy 426.542489 -82.45754) (xy 427.157624 -82.45754)
			(xy 427.157624 -82.397604) (xy 427.165447 -82.338182) (xy 427.18096 -82.280289) (xy 427.203896 -82.224916)
			(xy 427.233863 -82.17301) (xy 427.27035 -82.12546) (xy 427.31273 -82.08308) (xy 427.36028 -82.046593)
			(xy 427.412186 -82.016626) (xy 427.467559 -81.99369) (xy 427.525452 -81.978177) (xy 427.584874 -81.970354)
			(xy 427.64481 -81.970354) (xy 427.704232 -81.978177) (xy 427.762125 -81.99369) (xy 427.817498 -82.016626)
			(xy 427.869404 -82.046593) (xy 427.916954 -82.08308) (xy 427.959334 -82.12546) (xy 427.995821 -82.17301)
			(xy 428.025788 -82.224916) (xy 428.048724 -82.280289) (xy 428.064237 -82.338182) (xy 428.07206 -82.397604)
			(xy 428.07255 -82.427572) (xy 428.07206 -82.45754) (xy 428.064237 -82.516962) (xy 428.048724 -82.574855)
			(xy 428.025788 -82.630228) (xy 427.995821 -82.682134) (xy 427.959334 -82.729684) (xy 427.916954 -82.772064)
			(xy 427.869404 -82.808551) (xy 427.817498 -82.838518) (xy 427.762125 -82.861454) (xy 427.704232 -82.876967)
			(xy 427.64481 -82.88479) (xy 427.584874 -82.88479) (xy 427.525452 -82.876967) (xy 427.467559 -82.861454)
			(xy 427.412186 -82.838518) (xy 427.36028 -82.808551) (xy 427.31273 -82.772064) (xy 427.27035 -82.729684)
			(xy 427.233863 -82.682134) (xy 427.203896 -82.630228) (xy 427.18096 -82.574855) (xy 427.165447 -82.516962)
			(xy 427.157624 -82.45754) (xy 426.542489 -82.45754) (xy 426.536619 -82.497426) (xy 426.520551 -82.550833)
			(xy 426.496879 -82.60133) (xy 426.466106 -82.647843) (xy 426.428889 -82.68938) (xy 426.386021 -82.725055)
			(xy 426.338415 -82.754109) (xy 426.287086 -82.775921) (xy 426.233129 -82.790027) (xy 426.177692 -82.796127)
			(xy 426.121958 -82.79409) (xy 426.067115 -82.78396) (xy 426.014331 -82.765953) (xy 425.964731 -82.740452)
			(xy 425.919373 -82.708001) (xy 425.879224 -82.669292) (xy 425.845138 -82.625149) (xy 425.817842 -82.576514)
			(xy 425.797919 -82.524423) (xy 425.785793 -82.469986) (xy 425.781722 -82.414364) (xy 425.626284 -82.414364)
			(xy 425.626283 -82.414368) (xy 425.610215 -82.467775) (xy 425.586543 -82.518272) (xy 425.55577 -82.564785)
			(xy 425.518553 -82.606322) (xy 425.475685 -82.641997) (xy 425.428079 -82.671051) (xy 425.37675 -82.692863)
			(xy 425.322793 -82.706969) (xy 425.267356 -82.713069) (xy 425.211622 -82.711032) (xy 425.156779 -82.700902)
			(xy 425.103995 -82.682895) (xy 425.054395 -82.657394) (xy 425.009037 -82.624943) (xy 424.968888 -82.586234)
			(xy 424.934802 -82.542091) (xy 424.907506 -82.493456) (xy 424.887583 -82.441365) (xy 424.875457 -82.386928)
			(xy 424.871386 -82.331306) (xy 403.094444 -82.331306) (xy 403.094444 -84.410804) (xy 408.03703 -84.410804)
			(xy 408.037528 -84.383158) (xy 408.045502 -84.328444) (xy 408.061298 -84.275456) (xy 408.084585 -84.225307)
			(xy 408.114873 -84.179049) (xy 408.151527 -84.137652) (xy 408.193778 -84.101986) (xy 408.240738 -84.072799)
			(xy 408.265884 -84.0613) (xy 408.278222 -84.055474) (xy 408.299421 -84.038308) (xy 408.315322 -84.016145)
			(xy 408.324793 -83.990564) (xy 408.327157 -83.963389) (xy 408.322247 -83.936557) (xy 408.310412 -83.911981)
			(xy 408.292496 -83.891411) (xy 408.281378 -83.8835) (xy 408.259316 -83.868279) (xy 408.21932 -83.832594)
			(xy 408.184711 -83.791663) (xy 408.15617 -83.746293) (xy 408.134258 -83.697376) (xy 408.119405 -83.645874)
			(xy 408.111905 -83.5928) (xy 408.111452 -83.566) (xy 408.111938 -83.538749) (xy 408.119694 -83.484801)
			(xy 408.135049 -83.432506) (xy 408.157691 -83.382929) (xy 408.187157 -83.337079) (xy 408.222848 -83.295888)
			(xy 408.264039 -83.260197) (xy 408.309889 -83.230731) (xy 408.359466 -83.208089) (xy 408.411761 -83.192734)
			(xy 408.465709 -83.184978) (xy 408.520211 -83.184978) (xy 408.574159 -83.192734) (xy 408.626454 -83.208089)
			(xy 408.676031 -83.230731) (xy 408.721881 -83.260197) (xy 408.763072 -83.295888) (xy 408.798763 -83.337079)
			(xy 408.828229 -83.382929) (xy 408.850871 -83.432506) (xy 408.866226 -83.484801) (xy 408.873982 -83.538749)
			(xy 408.874468 -83.566) (xy 408.873974 -83.593646) (xy 408.866 -83.64836) (xy 408.850203 -83.701348)
			(xy 408.826916 -83.751497) (xy 408.796627 -83.797756) (xy 408.759973 -83.839152) (xy 408.717721 -83.874818)
			(xy 408.67076 -83.904005) (xy 408.645614 -83.915504) (xy 408.633273 -83.921324) (xy 408.612074 -83.938491)
			(xy 408.596173 -83.960655) (xy 408.586703 -83.986237) (xy 408.584339 -84.013413) (xy 408.58925 -84.040246)
			(xy 408.601085 -84.064823) (xy 408.619001 -84.085392) (xy 408.63012 -84.093304) (xy 408.652184 -84.108523)
			(xy 408.692179 -84.144209) (xy 408.726788 -84.185139) (xy 408.755329 -84.23051) (xy 408.777241 -84.279427)
			(xy 408.792093 -84.33093) (xy 408.799593 -84.384003) (xy 408.800046 -84.410804) (xy 408.79956 -84.438055)
			(xy 408.791804 -84.492003) (xy 408.776449 -84.544298) (xy 408.753807 -84.593875) (xy 408.724341 -84.639725)
			(xy 408.68865 -84.680916) (xy 408.647459 -84.716607) (xy 408.601609 -84.746073) (xy 408.552032 -84.768715)
			(xy 408.499737 -84.78407) (xy 408.445789 -84.791826) (xy 408.391287 -84.791826) (xy 408.337339 -84.78407)
			(xy 408.285044 -84.768715) (xy 408.235467 -84.746073) (xy 408.189617 -84.716607) (xy 408.148426 -84.680916)
			(xy 408.112735 -84.639725) (xy 408.083269 -84.593875) (xy 408.060627 -84.544298) (xy 408.045272 -84.492003)
			(xy 408.037516 -84.438055) (xy 408.03703 -84.410804) (xy 403.094444 -84.410804) (xy 403.094444 -84.560918)
			(xy 403.094872 -84.570986) (xy 403.102596 -84.589581) (xy 403.10943 -84.596986) (xy 403.450552 -84.938108)
			(xy 413.4612 -84.938108) (xy 413.461671 -84.910698) (xy 413.469516 -84.856442) (xy 413.485047 -84.803868)
			(xy 413.507942 -84.754058) (xy 413.537732 -84.708038) (xy 413.573801 -84.666755) (xy 413.594296 -84.648548)
			(xy 413.60217 -84.64169) (xy 413.61106 -84.624164) (xy 413.618426 -84.532216) (xy 413.61233 -84.51342)
			(xy 413.605726 -84.505546) (xy 413.588681 -84.484776) (xy 413.559995 -84.439344) (xy 413.537969 -84.390336)
			(xy 413.52304 -84.338722) (xy 413.515504 -84.285523) (xy 413.515048 -84.258658) (xy 413.515656 -84.228536)
			(xy 413.525128 -84.169042) (xy 413.54383 -84.111774) (xy 413.571298 -84.058156) (xy 413.606849 -84.00952)
			(xy 413.627824 -83.987894) (xy 413.634936 -83.980782) (xy 413.642556 -83.962494) (xy 413.64408 -83.871562)
			(xy 413.636714 -83.85302) (xy 413.629856 -83.845908) (xy 413.610269 -83.8245) (xy 413.577154 -83.776856)
			(xy 413.551627 -83.724751) (xy 413.534274 -83.669384) (xy 413.525495 -83.612029) (xy 413.524954 -83.583018)
			(xy 413.525495 -83.555769) (xy 413.533248 -83.501825) (xy 413.548599 -83.449534) (xy 413.571235 -83.399959)
			(xy 413.600696 -83.354111) (xy 413.636382 -83.312921) (xy 413.677566 -83.27723) (xy 413.72341 -83.247762)
			(xy 413.772981 -83.225118) (xy 413.82527 -83.20976) (xy 413.879213 -83.201999) (xy 413.906462 -83.20151)
			(xy 413.935443 -83.202008) (xy 413.992739 -83.210756) (xy 414.048053 -83.228073) (xy 414.100109 -83.25356)
			(xy 414.147711 -83.286629) (xy 414.18976 -83.326519) (xy 414.225291 -83.372313) (xy 414.253484 -83.422955)
			(xy 414.27369 -83.477279) (xy 414.280096 -83.505548) (xy 414.282382 -83.517232) (xy 414.296606 -83.53552)
			(xy 414.389062 -83.581748) (xy 414.41243 -83.581748) (xy 414.423098 -83.576922) (xy 414.448744 -83.565313)
			(xy 414.502597 -83.548921) (xy 414.558274 -83.540615) (xy 414.58642 -83.540092) (xy 414.61367 -83.540579)
			(xy 414.667616 -83.548338) (xy 414.719908 -83.563695) (xy 414.769483 -83.586337) (xy 414.815331 -83.615804)
			(xy 414.856519 -83.651495) (xy 414.892208 -83.692685) (xy 414.921672 -83.738535) (xy 414.944312 -83.788111)
			(xy 414.959666 -83.840404) (xy 414.967422 -83.89435) (xy 414.967422 -83.94885) (xy 414.959666 -84.002796)
			(xy 414.944312 -84.055089) (xy 414.921672 -84.104665) (xy 414.892208 -84.150515) (xy 414.856519 -84.191705)
			(xy 414.815331 -84.227396) (xy 414.769483 -84.256863) (xy 414.719908 -84.279505) (xy 414.667616 -84.294862)
			(xy 414.61367 -84.302621) (xy 414.58642 -84.303108) (xy 414.556905 -84.302575) (xy 414.498581 -84.293465)
			(xy 414.442363 -84.275459) (xy 414.415732 -84.262722) (xy 414.405064 -84.257388) (xy 414.381442 -84.257388)
			(xy 414.287462 -84.303108) (xy 414.272984 -84.321904) (xy 414.270946 -84.332318) (xy 424.612054 -84.332318)
			(xy 424.612493 -84.305713) (xy 424.619873 -84.253019) (xy 424.634508 -84.201862) (xy 424.656111 -84.153236)
			(xy 424.684265 -84.108086) (xy 424.718422 -84.067287) (xy 424.757918 -84.031634) (xy 424.779694 -84.016342)
			(xy 424.791206 -84.008047) (xy 424.809411 -83.986295) (xy 424.820927 -83.960373) (xy 424.824864 -83.932282)
			(xy 424.820917 -83.904192) (xy 424.809392 -83.878274) (xy 424.791179 -83.856528) (xy 424.779694 -83.848194)
			(xy 424.757924 -83.832898) (xy 424.718443 -83.797234) (xy 424.684297 -83.756431) (xy 424.656151 -83.711281)
			(xy 424.634548 -83.66266) (xy 424.619909 -83.611509) (xy 424.612516 -83.55882) (xy 424.612054 -83.532218)
			(xy 424.61254 -83.504967) (xy 424.620296 -83.451019) (xy 424.635651 -83.398724) (xy 424.658293 -83.349147)
			(xy 424.687759 -83.303297) (xy 424.72345 -83.262106) (xy 424.764641 -83.226415) (xy 424.810491 -83.196949)
			(xy 424.860068 -83.174307) (xy 424.912363 -83.158952) (xy 424.966311 -83.151196) (xy 425.020813 -83.151196)
			(xy 425.074761 -83.158952) (xy 425.127056 -83.174307) (xy 425.176633 -83.196949) (xy 425.222483 -83.226415)
			(xy 425.263674 -83.262106) (xy 425.299365 -83.303297) (xy 425.328831 -83.349147) (xy 425.351473 -83.398724)
			(xy 425.366828 -83.451019) (xy 425.374584 -83.504967) (xy 425.37507 -83.532218) (xy 425.374648 -83.558823)
			(xy 425.367263 -83.611518) (xy 425.352625 -83.662675) (xy 425.331018 -83.7113) (xy 425.302863 -83.75645)
			(xy 425.268704 -83.797248) (xy 425.229206 -83.832902) (xy 425.20743 -83.848194) (xy 425.195979 -83.856567)
			(xy 425.177771 -83.8783) (xy 425.166249 -83.904205) (xy 425.162303 -83.932282) (xy 425.166239 -83.96036)
			(xy 425.177752 -83.98627) (xy 425.195952 -84.008009) (xy 425.20743 -84.016342) (xy 425.229175 -84.031671)
			(xy 425.268656 -84.067331) (xy 425.302802 -84.108128) (xy 425.330952 -84.153272) (xy 425.352558 -84.201888)
			(xy 425.367203 -84.253034) (xy 425.374603 -84.305718) (xy 425.37507 -84.332318) (xy 425.374584 -84.359569)
			(xy 425.366828 -84.413517) (xy 425.351473 -84.465812) (xy 425.346667 -84.476336) (xy 427.965614 -84.476336)
			(xy 427.969685 -84.420714) (xy 427.981811 -84.366277) (xy 428.001734 -84.314186) (xy 428.02903 -84.265551)
			(xy 428.063116 -84.221408) (xy 428.103265 -84.182699) (xy 428.148623 -84.150248) (xy 428.198223 -84.124747)
			(xy 428.251007 -84.10674) (xy 428.30585 -84.09661) (xy 428.361584 -84.094573) (xy 428.417021 -84.100673)
			(xy 428.470978 -84.114779) (xy 428.522307 -84.136591) (xy 428.569913 -84.165645) (xy 428.612781 -84.20132)
			(xy 428.649998 -84.242857) (xy 428.680771 -84.28937) (xy 428.704443 -84.339867) (xy 428.720511 -84.393274)
			(xy 428.728631 -84.44845) (xy 428.72914 -84.476336) (xy 428.728631 -84.504222) (xy 428.720511 -84.559398)
			(xy 428.704443 -84.612805) (xy 428.680771 -84.663302) (xy 428.649998 -84.709815) (xy 428.612781 -84.751352)
			(xy 428.569913 -84.787027) (xy 428.522307 -84.816081) (xy 428.470978 -84.837893) (xy 428.417021 -84.851999)
			(xy 428.361584 -84.858099) (xy 428.30585 -84.856062) (xy 428.251007 -84.845932) (xy 428.198223 -84.827925)
			(xy 428.148623 -84.802424) (xy 428.103265 -84.769973) (xy 428.063116 -84.731264) (xy 428.02903 -84.687121)
			(xy 428.001734 -84.638486) (xy 427.981811 -84.586395) (xy 427.969685 -84.531958) (xy 427.965614 -84.476336)
			(xy 425.346667 -84.476336) (xy 425.328831 -84.515389) (xy 425.299365 -84.561239) (xy 425.263674 -84.60243)
			(xy 425.222483 -84.638121) (xy 425.176633 -84.667587) (xy 425.127056 -84.690229) (xy 425.074761 -84.705584)
			(xy 425.020813 -84.71334) (xy 424.966311 -84.71334) (xy 424.912363 -84.705584) (xy 424.860068 -84.690229)
			(xy 424.810491 -84.667587) (xy 424.764641 -84.638121) (xy 424.72345 -84.60243) (xy 424.687759 -84.561239)
			(xy 424.658293 -84.515389) (xy 424.635651 -84.465812) (xy 424.620296 -84.413517) (xy 424.61254 -84.359569)
			(xy 424.612054 -84.332318) (xy 414.270946 -84.332318) (xy 414.270698 -84.333588) (xy 414.265324 -84.358362)
			(xy 414.248847 -84.406303) (xy 414.226174 -84.451644) (xy 414.197703 -84.493588) (xy 414.163935 -84.531398)
			(xy 414.144968 -84.548218) (xy 414.137094 -84.555076) (xy 414.128204 -84.572602) (xy 414.120838 -84.66455)
			(xy 414.126934 -84.683346) (xy 414.133538 -84.69122) (xy 414.150577 -84.711995) (xy 414.179262 -84.757426)
			(xy 414.201288 -84.806433) (xy 414.216218 -84.858046) (xy 414.223758 -84.911243) (xy 414.224216 -84.938108)
			(xy 414.22373 -84.965359) (xy 414.215974 -85.019307) (xy 414.200619 -85.071602) (xy 414.177977 -85.121179)
			(xy 414.148511 -85.167029) (xy 414.11282 -85.20822) (xy 414.071629 -85.243911) (xy 414.067656 -85.246464)
			(xy 415.15868 -85.246464) (xy 415.162751 -85.190842) (xy 415.174877 -85.136405) (xy 415.1948 -85.084314)
			(xy 415.222096 -85.035679) (xy 415.256182 -84.991536) (xy 415.296331 -84.952827) (xy 415.341689 -84.920376)
			(xy 415.391289 -84.894875) (xy 415.444073 -84.876868) (xy 415.498916 -84.866738) (xy 415.55465 -84.864701)
			(xy 415.610087 -84.870801) (xy 415.664044 -84.884907) (xy 415.715373 -84.906719) (xy 415.762979 -84.935773)
			(xy 415.805847 -84.971448) (xy 415.843064 -85.012985) (xy 415.873837 -85.059498) (xy 415.897509 -85.109995)
			(xy 415.913577 -85.163402) (xy 415.921697 -85.218578) (xy 415.9219 -85.2297) (xy 416.185602 -85.2297)
			(xy 416.189673 -85.174078) (xy 416.201799 -85.119641) (xy 416.221722 -85.06755) (xy 416.249018 -85.018915)
			(xy 416.283104 -84.974772) (xy 416.323253 -84.936063) (xy 416.368611 -84.903612) (xy 416.418211 -84.878111)
			(xy 416.470995 -84.860104) (xy 416.525838 -84.849974) (xy 416.581572 -84.847937) (xy 416.637009 -84.854037)
			(xy 416.690966 -84.868143) (xy 416.742295 -84.889955) (xy 416.789901 -84.919009) (xy 416.832769 -84.954684)
			(xy 416.869986 -84.996221) (xy 416.900759 -85.042734) (xy 416.924431 -85.093231) (xy 416.940499 -85.146638)
			(xy 416.948619 -85.201814) (xy 416.949128 -85.2297) (xy 416.948619 -85.257586) (xy 416.940499 -85.312762)
			(xy 416.924431 -85.366169) (xy 416.900759 -85.416666) (xy 416.894388 -85.426296) (xy 428.157638 -85.426296)
			(xy 428.161709 -85.370674) (xy 428.173835 -85.316237) (xy 428.193758 -85.264146) (xy 428.221054 -85.215511)
			(xy 428.25514 -85.171368) (xy 428.295289 -85.132659) (xy 428.340647 -85.100208) (xy 428.390247 -85.074707)
			(xy 428.443031 -85.0567) (xy 428.497874 -85.04657) (xy 428.553608 -85.044533) (xy 428.609045 -85.050633)
			(xy 428.663002 -85.064739) (xy 428.714331 -85.086551) (xy 428.761937 -85.115605) (xy 428.804805 -85.15128)
			(xy 428.842022 -85.192817) (xy 428.872795 -85.23933) (xy 428.896467 -85.289827) (xy 428.912535 -85.343234)
			(xy 428.920655 -85.39841) (xy 428.921164 -85.426296) (xy 428.920655 -85.454182) (xy 428.912535 -85.509358)
			(xy 428.896467 -85.562765) (xy 428.872795 -85.613262) (xy 428.842022 -85.659775) (xy 428.804805 -85.701312)
			(xy 428.761937 -85.736987) (xy 428.714331 -85.766041) (xy 428.663002 -85.787853) (xy 428.609045 -85.801959)
			(xy 428.553608 -85.808059) (xy 428.497874 -85.806022) (xy 428.443031 -85.795892) (xy 428.390247 -85.777885)
			(xy 428.340647 -85.752384) (xy 428.295289 -85.719933) (xy 428.25514 -85.681224) (xy 428.221054 -85.637081)
			(xy 428.193758 -85.588446) (xy 428.173835 -85.536355) (xy 428.161709 -85.481918) (xy 428.157638 -85.426296)
			(xy 416.894388 -85.426296) (xy 416.869986 -85.463179) (xy 416.832769 -85.504716) (xy 416.789901 -85.540391)
			(xy 416.742295 -85.569445) (xy 416.690966 -85.591257) (xy 416.637009 -85.605363) (xy 416.581572 -85.611463)
			(xy 416.525838 -85.609426) (xy 416.470995 -85.599296) (xy 416.418211 -85.581289) (xy 416.368611 -85.555788)
			(xy 416.323253 -85.523337) (xy 416.283104 -85.484628) (xy 416.249018 -85.440485) (xy 416.221722 -85.39185)
			(xy 416.201799 -85.339759) (xy 416.189673 -85.285322) (xy 416.185602 -85.2297) (xy 415.9219 -85.2297)
			(xy 415.922206 -85.246464) (xy 415.921697 -85.27435) (xy 415.913577 -85.329526) (xy 415.897509 -85.382933)
			(xy 415.873837 -85.43343) (xy 415.843064 -85.479943) (xy 415.805847 -85.52148) (xy 415.762979 -85.557155)
			(xy 415.715373 -85.586209) (xy 415.664044 -85.608021) (xy 415.610087 -85.622127) (xy 415.55465 -85.628227)
			(xy 415.498916 -85.62619) (xy 415.444073 -85.61606) (xy 415.391289 -85.598053) (xy 415.341689 -85.572552)
			(xy 415.296331 -85.540101) (xy 415.256182 -85.501392) (xy 415.222096 -85.457249) (xy 415.1948 -85.408614)
			(xy 415.174877 -85.356523) (xy 415.162751 -85.302086) (xy 415.15868 -85.246464) (xy 414.067656 -85.246464)
			(xy 414.025779 -85.273377) (xy 413.976202 -85.296019) (xy 413.923907 -85.311374) (xy 413.869959 -85.31913)
			(xy 413.815457 -85.31913) (xy 413.761509 -85.311374) (xy 413.709214 -85.296019) (xy 413.659637 -85.273377)
			(xy 413.613787 -85.243911) (xy 413.572596 -85.20822) (xy 413.536905 -85.167029) (xy 413.507439 -85.121179)
			(xy 413.484797 -85.071602) (xy 413.469442 -85.019307) (xy 413.461686 -84.965359) (xy 413.4612 -84.938108)
			(xy 403.450552 -84.938108) (xy 403.460458 -84.948014) (xy 403.467856 -84.954861) (xy 403.486455 -84.962587)
			(xy 403.496526 -84.963) (xy 405.489918 -84.963) (xy 405.499987 -84.963427) (xy 405.518586 -84.971146)
			(xy 405.525986 -84.977986) (xy 405.877014 -85.329014) (xy 405.883868 -85.336409) (xy 405.89161 -85.355008)
			(xy 405.892 -85.365082) (xy 405.892 -86.277954) (xy 423.463448 -86.277954) (xy 423.463448 -86.218018)
			(xy 423.471271 -86.158596) (xy 423.486784 -86.100703) (xy 423.50972 -86.04533) (xy 423.539687 -85.993424)
			(xy 423.576174 -85.945874) (xy 423.618554 -85.903494) (xy 423.666104 -85.867007) (xy 423.71801 -85.83704)
			(xy 423.773383 -85.814104) (xy 423.831276 -85.798591) (xy 423.890698 -85.790768) (xy 423.950634 -85.790768)
			(xy 424.010056 -85.798591) (xy 424.067949 -85.814104) (xy 424.123322 -85.83704) (xy 424.175228 -85.867007)
			(xy 424.222778 -85.903494) (xy 424.265158 -85.945874) (xy 424.301645 -85.993424) (xy 424.331612 -86.04533)
			(xy 424.354548 -86.100703) (xy 424.370061 -86.158596) (xy 424.377884 -86.218018) (xy 424.378374 -86.247986)
			(xy 424.377884 -86.277954) (xy 424.370061 -86.337376) (xy 424.354548 -86.395269) (xy 424.331612 -86.450642)
			(xy 424.301645 -86.502548) (xy 424.265158 -86.550098) (xy 424.222778 -86.592478) (xy 424.175228 -86.628965)
			(xy 424.123322 -86.658932) (xy 424.067949 -86.681868) (xy 424.010056 -86.697381) (xy 423.950634 -86.705204)
			(xy 423.890698 -86.705204) (xy 423.831276 -86.697381) (xy 423.773383 -86.681868) (xy 423.71801 -86.658932)
			(xy 423.666104 -86.628965) (xy 423.618554 -86.592478) (xy 423.576174 -86.550098) (xy 423.539687 -86.502548)
			(xy 423.50972 -86.450642) (xy 423.486784 -86.395269) (xy 423.471271 -86.337376) (xy 423.463448 -86.277954)
			(xy 405.892 -86.277954) (xy 405.892 -87.04665) (xy 406.949662 -87.04665) (xy 406.949662 -86.99215)
			(xy 406.957417 -86.938203) (xy 406.972771 -86.88591) (xy 406.99541 -86.836334) (xy 407.024873 -86.790483)
			(xy 407.060562 -86.749293) (xy 407.101748 -86.7136) (xy 407.147595 -86.684131) (xy 407.197169 -86.661486)
			(xy 407.24946 -86.646127) (xy 407.303406 -86.638365) (xy 407.330656 -86.637876) (xy 407.360017 -86.63846)
			(xy 407.418046 -86.647452) (xy 407.474011 -86.66523) (xy 407.526591 -86.691374) (xy 407.574544 -86.725266)
			(xy 407.616737 -86.766107) (xy 407.652173 -86.812931) (xy 407.680016 -86.864632) (xy 407.69032 -86.89213)
			(xy 407.693622 -86.901274) (xy 407.706068 -86.915752) (xy 407.785062 -86.956646) (xy 407.803858 -86.958678)
			(xy 407.813256 -86.956138) (xy 407.838281 -86.94963) (xy 407.889511 -86.942618) (xy 407.915364 -86.942168)
			(xy 407.942617 -86.942677) (xy 407.996568 -86.950429) (xy 408.048867 -86.965781) (xy 408.098449 -86.98842)
			(xy 408.144303 -87.017885) (xy 408.185498 -87.053577) (xy 408.221193 -87.094768) (xy 408.250663 -87.14062)
			(xy 408.273306 -87.190199) (xy 408.288663 -87.242497) (xy 408.296421 -87.296447) (xy 408.296421 -87.350953)
			(xy 408.288663 -87.404903) (xy 408.273306 -87.457201) (xy 408.250663 -87.50678) (xy 408.221193 -87.552632)
			(xy 408.185498 -87.593823) (xy 408.144303 -87.629515) (xy 408.098449 -87.65898) (xy 408.048867 -87.681619)
			(xy 407.996568 -87.696971) (xy 407.942617 -87.704723) (xy 407.915364 -87.705184) (xy 407.886 -87.704696)
			(xy 407.827965 -87.695691) (xy 407.771996 -87.6779) (xy 407.719414 -87.651742) (xy 407.671461 -87.617836)
			(xy 407.62927 -87.576982) (xy 407.593838 -87.530146) (xy 407.566001 -87.478434) (xy 407.5557 -87.45093)
			(xy 407.552398 -87.441786) (xy 407.539952 -87.427308) (xy 407.460958 -87.386414) (xy 407.442162 -87.384382)
			(xy 407.432764 -87.386922) (xy 407.407738 -87.393428) (xy 407.356509 -87.400441) (xy 407.330656 -87.400892)
			(xy 407.303406 -87.400435) (xy 407.24946 -87.392673) (xy 407.197169 -87.377314) (xy 407.147595 -87.354669)
			(xy 407.101748 -87.3252) (xy 407.060561 -87.289507) (xy 407.024873 -87.248317) (xy 406.99541 -87.202466)
			(xy 406.972771 -87.15289) (xy 406.957417 -87.100597) (xy 406.949662 -87.04665) (xy 405.892 -87.04665)
			(xy 405.892 -87.608918) (xy 405.891573 -87.618987) (xy 405.883854 -87.637586) (xy 405.877014 -87.644986)
			(xy 405.74087 -87.78113) (xy 415.281364 -87.78113) (xy 415.281924 -87.752012) (xy 415.290765 -87.694452)
			(xy 415.308246 -87.638903) (xy 415.333962 -87.586653) (xy 415.367316 -87.538916) (xy 415.387028 -87.517478)
			(xy 415.393632 -87.510874) (xy 415.400744 -87.493856) (xy 415.403792 -87.407496) (xy 415.39795 -87.38997)
			(xy 415.392108 -87.382858) (xy 415.375713 -87.362285) (xy 415.348139 -87.317483) (xy 415.326987 -87.269316)
			(xy 415.312659 -87.218699) (xy 415.305427 -87.166591) (xy 415.304986 -87.140288) (xy 415.305472 -87.113037)
			(xy 415.313228 -87.059089) (xy 415.328583 -87.006794) (xy 415.351225 -86.957217) (xy 415.380691 -86.911367)
			(xy 415.416382 -86.870176) (xy 415.457573 -86.834485) (xy 415.503423 -86.805019) (xy 415.553 -86.782377)
			(xy 415.605295 -86.767022) (xy 415.659243 -86.759266) (xy 415.713745 -86.759266) (xy 415.767693 -86.767022)
			(xy 415.819988 -86.782377) (xy 415.869565 -86.805019) (xy 415.915415 -86.834485) (xy 415.956606 -86.870176)
			(xy 415.992297 -86.911367) (xy 416.016499 -86.949026) (xy 425.84827 -86.949026) (xy 425.852341 -86.893404)
			(xy 425.864467 -86.838967) (xy 425.88439 -86.786876) (xy 425.911686 -86.738241) (xy 425.945772 -86.694098)
			(xy 425.985921 -86.655389) (xy 426.031279 -86.622938) (xy 426.080879 -86.597437) (xy 426.133663 -86.57943)
			(xy 426.188506 -86.5693) (xy 426.24424 -86.567263) (xy 426.299677 -86.573363) (xy 426.353634 -86.587469)
			(xy 426.404963 -86.609281) (xy 426.452569 -86.638335) (xy 426.495437 -86.67401) (xy 426.532654 -86.715547)
			(xy 426.563427 -86.76206) (xy 426.587099 -86.812557) (xy 426.603167 -86.865964) (xy 426.611287 -86.92114)
			(xy 426.611796 -86.949026) (xy 426.611287 -86.976912) (xy 426.603167 -87.032088) (xy 426.587099 -87.085495)
			(xy 426.563427 -87.135992) (xy 426.532654 -87.182505) (xy 426.495437 -87.224042) (xy 426.452569 -87.259717)
			(xy 426.404963 -87.288771) (xy 426.353634 -87.310583) (xy 426.299677 -87.324689) (xy 426.24424 -87.330789)
			(xy 426.188506 -87.328752) (xy 426.133663 -87.318622) (xy 426.080879 -87.300615) (xy 426.031279 -87.275114)
			(xy 425.985921 -87.242663) (xy 425.945772 -87.203954) (xy 425.911686 -87.159811) (xy 425.88439 -87.111176)
			(xy 425.864467 -87.059085) (xy 425.852341 -87.004648) (xy 425.84827 -86.949026) (xy 416.016499 -86.949026)
			(xy 416.021763 -86.957217) (xy 416.044405 -87.006794) (xy 416.05976 -87.059089) (xy 416.067516 -87.113037)
			(xy 416.068002 -87.140288) (xy 416.067436 -87.169405) (xy 416.058594 -87.226964) (xy 416.041113 -87.282513)
			(xy 416.015399 -87.334763) (xy 415.982048 -87.382501) (xy 415.962338 -87.40394) (xy 415.955734 -87.410544)
			(xy 415.948622 -87.427562) (xy 415.945574 -87.513922) (xy 415.951416 -87.531448) (xy 415.957258 -87.53856)
			(xy 415.973671 -87.55912) (xy 416.00124 -87.603925) (xy 416.022388 -87.652096) (xy 416.036712 -87.702717)
			(xy 416.04394 -87.754826) (xy 416.04438 -87.78113) (xy 416.043894 -87.808381) (xy 416.036138 -87.862329)
			(xy 416.020783 -87.914624) (xy 415.998141 -87.964201) (xy 415.968675 -88.010051) (xy 415.932984 -88.051242)
			(xy 415.891793 -88.086933) (xy 415.845943 -88.116399) (xy 415.796366 -88.139041) (xy 415.744071 -88.154396)
			(xy 415.690123 -88.162152) (xy 415.635621 -88.162152) (xy 415.581673 -88.154396) (xy 415.529378 -88.139041)
			(xy 415.479801 -88.116399) (xy 415.433951 -88.086933) (xy 415.39276 -88.051242) (xy 415.357069 -88.010051)
			(xy 415.327603 -87.964201) (xy 415.304961 -87.914624) (xy 415.289606 -87.862329) (xy 415.28185 -87.808381)
			(xy 415.281364 -87.78113) (xy 405.74087 -87.78113) (xy 405.652986 -87.869014) (xy 405.645591 -87.875868)
			(xy 405.626992 -87.88361) (xy 405.616918 -87.884) (xy 403.373082 -87.884) (xy 403.363013 -87.884427)
			(xy 403.344414 -87.892146) (xy 403.337014 -87.898986) (xy 403.10943 -88.12657) (xy 403.102591 -88.133971)
			(xy 403.094878 -88.152569) (xy 403.094444 -88.162638) (xy 403.094444 -88.247728) (xy 413.814006 -88.247728)
			(xy 413.814492 -88.220477) (xy 413.822248 -88.166529) (xy 413.837603 -88.114234) (xy 413.860245 -88.064657)
			(xy 413.889711 -88.018807) (xy 413.925402 -87.977616) (xy 413.966593 -87.941925) (xy 414.012443 -87.912459)
			(xy 414.06202 -87.889817) (xy 414.114315 -87.874462) (xy 414.168263 -87.866706) (xy 414.222765 -87.866706)
			(xy 414.276713 -87.874462) (xy 414.329008 -87.889817) (xy 414.378585 -87.912459) (xy 414.424435 -87.941925)
			(xy 414.465626 -87.977616) (xy 414.501317 -88.018807) (xy 414.530783 -88.064657) (xy 414.553425 -88.114234)
			(xy 414.56878 -88.166529) (xy 414.576536 -88.220477) (xy 414.577022 -88.247728) (xy 414.576534 -88.275186)
			(xy 414.568675 -88.329535) (xy 414.553108 -88.382197) (xy 414.542172 -88.405966) (xy 428.148478 -88.405966)
			(xy 428.148478 -88.34603) (xy 428.156301 -88.286608) (xy 428.171814 -88.228715) (xy 428.19475 -88.173342)
			(xy 428.224717 -88.121436) (xy 428.261204 -88.073886) (xy 428.303584 -88.031506) (xy 428.351134 -87.995019)
			(xy 428.40304 -87.965052) (xy 428.458413 -87.942116) (xy 428.516306 -87.926603) (xy 428.575728 -87.91878)
			(xy 428.635664 -87.91878) (xy 428.695086 -87.926603) (xy 428.752979 -87.942116) (xy 428.808352 -87.965052)
			(xy 428.860258 -87.995019) (xy 428.907808 -88.031506) (xy 428.950188 -88.073886) (xy 428.986675 -88.121436)
			(xy 429.016642 -88.173342) (xy 429.039578 -88.228715) (xy 429.055091 -88.286608) (xy 429.062914 -88.34603)
			(xy 429.063404 -88.375998) (xy 429.062914 -88.405966) (xy 429.060306 -88.425778) (xy 429.482486 -88.425778)
			(xy 429.482486 -88.365842) (xy 429.490309 -88.30642) (xy 429.505822 -88.248527) (xy 429.528758 -88.193154)
			(xy 429.558725 -88.141248) (xy 429.595212 -88.093698) (xy 429.637592 -88.051318) (xy 429.685142 -88.014831)
			(xy 429.737048 -87.984864) (xy 429.792421 -87.961928) (xy 429.850314 -87.946415) (xy 429.909736 -87.938592)
			(xy 429.969672 -87.938592) (xy 430.029094 -87.946415) (xy 430.086987 -87.961928) (xy 430.14236 -87.984864)
			(xy 430.194266 -88.014831) (xy 430.241816 -88.051318) (xy 430.284196 -88.093698) (xy 430.320683 -88.141248)
			(xy 430.35065 -88.193154) (xy 430.373586 -88.248527) (xy 430.389099 -88.30642) (xy 430.396922 -88.365842)
			(xy 430.397412 -88.39581) (xy 430.396922 -88.425778) (xy 430.389099 -88.4852) (xy 430.373586 -88.543093)
			(xy 430.35065 -88.598466) (xy 430.320683 -88.650372) (xy 430.284196 -88.697922) (xy 430.241816 -88.740302)
			(xy 430.194266 -88.776789) (xy 430.14236 -88.806756) (xy 430.086987 -88.829692) (xy 430.029094 -88.845205)
			(xy 429.969672 -88.853028) (xy 429.909736 -88.853028) (xy 429.850314 -88.845205) (xy 429.792421 -88.829692)
			(xy 429.737048 -88.806756) (xy 429.685142 -88.776789) (xy 429.637592 -88.740302) (xy 429.595212 -88.697922)
			(xy 429.558725 -88.650372) (xy 429.528758 -88.598466) (xy 429.505822 -88.543093) (xy 429.490309 -88.4852)
			(xy 429.482486 -88.425778) (xy 429.060306 -88.425778) (xy 429.055091 -88.465388) (xy 429.039578 -88.523281)
			(xy 429.016642 -88.578654) (xy 428.986675 -88.63056) (xy 428.950188 -88.67811) (xy 428.907808 -88.72049)
			(xy 428.860258 -88.756977) (xy 428.808352 -88.786944) (xy 428.752979 -88.80988) (xy 428.695086 -88.825393)
			(xy 428.635664 -88.833216) (xy 428.575728 -88.833216) (xy 428.516306 -88.825393) (xy 428.458413 -88.80988)
			(xy 428.40304 -88.786944) (xy 428.351134 -88.756977) (xy 428.303584 -88.72049) (xy 428.261204 -88.67811)
			(xy 428.224717 -88.63056) (xy 428.19475 -88.578654) (xy 428.171814 -88.523281) (xy 428.156301 -88.465388)
			(xy 428.148478 -88.405966) (xy 414.542172 -88.405966) (xy 414.530155 -88.432085) (xy 414.500291 -88.478169)
			(xy 414.46413 -88.519498) (xy 414.42242 -88.555218) (xy 414.399476 -88.570308) (xy 414.387288 -88.57852)
			(xy 414.367935 -88.600626) (xy 414.355681 -88.627329) (xy 414.351542 -88.656416) (xy 414.355861 -88.685477)
			(xy 414.36828 -88.712104) (xy 414.38777 -88.734089) (xy 414.399984 -88.742266) (xy 414.423244 -88.757258)
			(xy 414.465518 -88.792969) (xy 414.502191 -88.83441) (xy 414.532495 -88.880714) (xy 414.555795 -88.930908)
			(xy 414.571601 -88.983941) (xy 414.579583 -89.038701) (xy 414.58007 -89.06637) (xy 414.579584 -89.093621)
			(xy 414.571828 -89.147569) (xy 414.556473 -89.199864) (xy 414.533831 -89.249441) (xy 414.504365 -89.295291)
			(xy 414.468674 -89.336482) (xy 414.427483 -89.372173) (xy 414.381633 -89.401639) (xy 414.332056 -89.424281)
			(xy 414.31138 -89.430352) (xy 419.929816 -89.430352) (xy 419.933887 -89.37473) (xy 419.946013 -89.320293)
			(xy 419.965936 -89.268202) (xy 419.993232 -89.219567) (xy 420.027318 -89.175424) (xy 420.067467 -89.136715)
			(xy 420.112825 -89.104264) (xy 420.162425 -89.078763) (xy 420.215209 -89.060756) (xy 420.270052 -89.050626)
			(xy 420.325786 -89.048589) (xy 420.381223 -89.054689) (xy 420.43518 -89.068795) (xy 420.486509 -89.090607)
			(xy 420.534115 -89.119661) (xy 420.576983 -89.155336) (xy 420.6142 -89.196873) (xy 420.644973 -89.243386)
			(xy 420.668645 -89.293883) (xy 420.684713 -89.34729) (xy 420.692833 -89.402466) (xy 420.693342 -89.430352)
			(xy 420.692833 -89.458238) (xy 420.684713 -89.513414) (xy 420.668645 -89.566821) (xy 420.644973 -89.617318)
			(xy 420.6142 -89.663831) (xy 420.576983 -89.705368) (xy 420.534115 -89.741043) (xy 420.501164 -89.761153)
			(xy 422.18606 -89.761153) (xy 422.18606 -89.706647) (xy 422.193817 -89.652697) (xy 422.209173 -89.6004)
			(xy 422.231815 -89.55082) (xy 422.261282 -89.504968) (xy 422.296976 -89.463776) (xy 422.338168 -89.428082)
			(xy 422.38402 -89.398615) (xy 422.4336 -89.375973) (xy 422.485897 -89.360617) (xy 422.539847 -89.35286)
			(xy 422.5671 -89.352374) (xy 422.594118 -89.352881) (xy 422.64761 -89.360518) (xy 422.699491 -89.375624)
			(xy 422.748722 -89.397899) (xy 422.794318 -89.426895) (xy 422.835368 -89.462034) (xy 422.87105 -89.502612)
			(xy 422.900651 -89.547818) (xy 422.91254 -89.572084) (xy 422.919278 -89.585231) (xy 422.938949 -89.607253)
			(xy 422.964097 -89.622728) (xy 422.992621 -89.630364) (xy 423.022138 -89.629523) (xy 423.050181 -89.620275)
			(xy 423.074407 -89.603392) (xy 423.08399 -89.59215) (xy 423.102187 -89.570117) (xy 423.144068 -89.531242)
			(xy 423.191278 -89.499046) (xy 423.24276 -89.474249) (xy 423.297364 -89.457405) (xy 423.353869 -89.448891)
			(xy 423.38244 -89.448386) (xy 423.409689 -89.448886) (xy 423.463632 -89.456648) (xy 423.515921 -89.472006)
			(xy 423.565492 -89.494649) (xy 423.611337 -89.524116) (xy 423.652522 -89.559807) (xy 423.688208 -89.600995)
			(xy 423.71767 -89.646843) (xy 423.740308 -89.696417) (xy 423.755661 -89.748708) (xy 423.762695 -89.797636)
			(xy 423.880024 -89.797636) (xy 423.884095 -89.742014) (xy 423.896221 -89.687577) (xy 423.916144 -89.635486)
			(xy 423.94344 -89.586851) (xy 423.977526 -89.542708) (xy 424.017675 -89.503999) (xy 424.063033 -89.471548)
			(xy 424.112633 -89.446047) (xy 424.165417 -89.42804) (xy 424.22026 -89.41791) (xy 424.275994 -89.415873)
			(xy 424.331431 -89.421973) (xy 424.385388 -89.436079) (xy 424.436717 -89.457891) (xy 424.484323 -89.486945)
			(xy 424.527191 -89.52262) (xy 424.564408 -89.564157) (xy 424.595181 -89.61067) (xy 424.618853 -89.661167)
			(xy 424.634921 -89.714574) (xy 424.643041 -89.76975) (xy 424.64355 -89.797636) (xy 424.643041 -89.825522)
			(xy 424.634921 -89.880698) (xy 424.633394 -89.885774) (xy 424.743624 -89.885774) (xy 424.747695 -89.830152)
			(xy 424.759821 -89.775715) (xy 424.779744 -89.723624) (xy 424.80704 -89.674989) (xy 424.841126 -89.630846)
			(xy 424.881275 -89.592137) (xy 424.926633 -89.559686) (xy 424.976233 -89.534185) (xy 425.029017 -89.516178)
			(xy 425.08386 -89.506048) (xy 425.139594 -89.504011) (xy 425.195031 -89.510111) (xy 425.248988 -89.524217)
			(xy 425.300317 -89.546029) (xy 425.347923 -89.575083) (xy 425.390791 -89.610758) (xy 425.428008 -89.652295)
			(xy 425.458781 -89.698808) (xy 425.482453 -89.749305) (xy 425.498521 -89.802712) (xy 425.499396 -89.808655)
			(xy 428.521535 -89.808655) (xy 428.521535 -89.754145) (xy 428.529293 -89.700189) (xy 428.544651 -89.647887)
			(xy 428.567296 -89.598302) (xy 428.596768 -89.552446) (xy 428.632466 -89.51125) (xy 428.673663 -89.475555)
			(xy 428.719522 -89.446086) (xy 428.769107 -89.423443) (xy 428.82141 -89.408088) (xy 428.875367 -89.400333)
			(xy 428.902622 -89.399872) (xy 428.929525 -89.400328) (xy 428.982794 -89.407902) (xy 429.034472 -89.422884)
			(xy 429.083534 -89.444975) (xy 429.129006 -89.473738) (xy 429.169988 -89.508603) (xy 429.205666 -89.548878)
			(xy 429.220884 -89.571068) (xy 429.227996 -89.581736) (xy 429.250094 -89.593928) (xy 429.359568 -89.595198)
			(xy 429.38192 -89.583514) (xy 429.389286 -89.5731) (xy 429.404651 -89.551764) (xy 429.440252 -89.513075)
			(xy 429.480831 -89.479645) (xy 429.525618 -89.452107) (xy 429.573764 -89.430984) (xy 429.624356 -89.416676)
			(xy 429.676434 -89.409455) (xy 429.702722 -89.409016) (xy 429.729977 -89.409434) (xy 429.78393 -89.417195)
			(xy 429.836231 -89.432555) (xy 429.885812 -89.455202) (xy 429.931667 -89.484675) (xy 429.97286 -89.520373)
			(xy 430.008553 -89.56157) (xy 430.03802 -89.607428) (xy 430.060661 -89.657013) (xy 430.076015 -89.709315)
			(xy 430.083769 -89.763269) (xy 430.08423 -89.790524) (xy 430.083705 -89.818239) (xy 430.075668 -89.873082)
			(xy 430.059781 -89.926186) (xy 430.036378 -89.976433) (xy 430.005952 -90.022765) (xy 429.969143 -90.064208)
			(xy 429.926725 -90.09989) (xy 429.879592 -90.129059) (xy 429.85436 -90.140536) (xy 429.84166 -90.146124)
			(xy 429.825658 -90.167714) (xy 429.812196 -90.282268) (xy 429.822864 -90.306906) (xy 429.83404 -90.315288)
			(xy 429.858092 -90.333888) (xy 429.901568 -90.376389) (xy 429.939035 -90.424273) (xy 429.969834 -90.476695)
			(xy 429.993421 -90.532733) (xy 430.009382 -90.5914) (xy 430.017436 -90.651664) (xy 430.017936 -90.682064)
			(xy 430.017446 -90.712032) (xy 430.009623 -90.771454) (xy 429.99411 -90.829347) (xy 429.971174 -90.88472)
			(xy 429.941207 -90.936626) (xy 429.90472 -90.984176) (xy 429.86234 -91.026556) (xy 429.81479 -91.063043)
			(xy 429.762884 -91.09301) (xy 429.707511 -91.115946) (xy 429.649618 -91.131459) (xy 429.590196 -91.139282)
			(xy 429.53026 -91.139282) (xy 429.470838 -91.131459) (xy 429.412945 -91.115946) (xy 429.357572 -91.09301)
			(xy 429.305666 -91.063043) (xy 429.258116 -91.026556) (xy 429.215736 -90.984176) (xy 429.179249 -90.936626)
			(xy 429.149282 -90.88472) (xy 429.126346 -90.829347) (xy 429.110833 -90.771454) (xy 429.10301 -90.712032)
			(xy 429.10252 -90.682064) (xy 429.103109 -90.650356) (xy 429.111869 -90.587547) (xy 429.129215 -90.526548)
			(xy 429.154815 -90.468528) (xy 429.18818 -90.414598) (xy 429.22867 -90.365789) (xy 429.27551 -90.323038)
			(xy 429.327803 -90.287162) (xy 429.384549 -90.258848) (xy 429.414432 -90.248232) (xy 429.42764 -90.243914)
			(xy 429.44542 -90.223594) (xy 429.46828 -90.110564) (xy 429.459898 -90.085164) (xy 429.449484 -90.07602)
			(xy 429.431128 -90.059146) (xy 429.398512 -90.021433) (xy 429.38446 -90.000836) (xy 429.377348 -89.990168)
			(xy 429.35525 -89.977976) (xy 429.245776 -89.976706) (xy 429.223424 -89.98839) (xy 429.216058 -89.998804)
			(xy 429.200729 -90.020167) (xy 429.165122 -90.058855) (xy 429.124537 -90.092283) (xy 429.079744 -90.119818)
			(xy 429.031591 -90.140937) (xy 428.980994 -90.155239) (xy 428.928912 -90.162453) (xy 428.902622 -90.162888)
			(xy 428.875367 -90.162467) (xy 428.82141 -90.154712) (xy 428.769107 -90.139357) (xy 428.719522 -90.116714)
			(xy 428.673663 -90.087245) (xy 428.632466 -90.05155) (xy 428.596768 -90.010354) (xy 428.567296 -89.964498)
			(xy 428.544651 -89.914913) (xy 428.529293 -89.862611) (xy 428.521535 -89.808655) (xy 425.499396 -89.808655)
			(xy 425.506641 -89.857888) (xy 425.50715 -89.885774) (xy 425.506641 -89.91366) (xy 425.498521 -89.968836)
			(xy 425.482453 -90.022243) (xy 425.458781 -90.07274) (xy 425.428008 -90.119253) (xy 425.390791 -90.16079)
			(xy 425.347923 -90.196465) (xy 425.300317 -90.225519) (xy 425.248988 -90.247331) (xy 425.195031 -90.261437)
			(xy 425.139594 -90.267537) (xy 425.08386 -90.2655) (xy 425.029017 -90.25537) (xy 424.976233 -90.237363)
			(xy 424.926633 -90.211862) (xy 424.881275 -90.179411) (xy 424.841126 -90.140702) (xy 424.80704 -90.096559)
			(xy 424.779744 -90.047924) (xy 424.759821 -89.995833) (xy 424.747695 -89.941396) (xy 424.743624 -89.885774)
			(xy 424.633394 -89.885774) (xy 424.618853 -89.934105) (xy 424.595181 -89.984602) (xy 424.564408 -90.031115)
			(xy 424.527191 -90.072652) (xy 424.484323 -90.108327) (xy 424.436717 -90.137381) (xy 424.385388 -90.159193)
			(xy 424.331431 -90.173299) (xy 424.275994 -90.179399) (xy 424.22026 -90.177362) (xy 424.165417 -90.167232)
			(xy 424.112633 -90.149225) (xy 424.063033 -90.123724) (xy 424.017675 -90.091273) (xy 423.977526 -90.052564)
			(xy 423.94344 -90.008421) (xy 423.916144 -89.959786) (xy 423.896221 -89.907695) (xy 423.884095 -89.853258)
			(xy 423.880024 -89.797636) (xy 423.762695 -89.797636) (xy 423.763416 -89.802651) (xy 423.763416 -89.857149)
			(xy 423.755661 -89.911092) (xy 423.740308 -89.963383) (xy 423.71767 -90.012957) (xy 423.688208 -90.058805)
			(xy 423.652522 -90.099993) (xy 423.611337 -90.135684) (xy 423.565492 -90.165151) (xy 423.515921 -90.187794)
			(xy 423.463632 -90.203152) (xy 423.409689 -90.210914) (xy 423.38244 -90.211402) (xy 423.35542 -90.210959)
			(xy 423.301924 -90.203313) (xy 423.250041 -90.188198) (xy 423.200809 -90.165914) (xy 423.155213 -90.136909)
			(xy 423.114165 -90.101762) (xy 423.078485 -90.061175) (xy 423.048887 -90.015961) (xy 423.037 -89.991692)
			(xy 423.030208 -89.978577) (xy 423.010545 -89.956563) (xy 422.985408 -89.941092) (xy 422.956896 -89.933454)
			(xy 422.927391 -89.934289) (xy 422.899357 -89.943525) (xy 422.875134 -89.960392) (xy 422.86555 -89.971626)
			(xy 422.847325 -89.993634) (xy 422.80545 -90.032512) (xy 422.758247 -90.064712) (xy 422.70677 -90.089513)
			(xy 422.652171 -90.106362) (xy 422.59567 -90.114882) (xy 422.5671 -90.11539) (xy 422.539847 -90.11494)
			(xy 422.485897 -90.107183) (xy 422.4336 -90.091827) (xy 422.38402 -90.069185) (xy 422.338168 -90.039718)
			(xy 422.296976 -90.004024) (xy 422.261282 -89.962832) (xy 422.231815 -89.91698) (xy 422.209173 -89.8674)
			(xy 422.193817 -89.815103) (xy 422.18606 -89.761153) (xy 420.501164 -89.761153) (xy 420.486509 -89.770097)
			(xy 420.43518 -89.791909) (xy 420.381223 -89.806015) (xy 420.325786 -89.812115) (xy 420.270052 -89.810078)
			(xy 420.215209 -89.799948) (xy 420.162425 -89.781941) (xy 420.112825 -89.75644) (xy 420.067467 -89.723989)
			(xy 420.027318 -89.68528) (xy 419.993232 -89.641137) (xy 419.965936 -89.592502) (xy 419.946013 -89.540411)
			(xy 419.933887 -89.485974) (xy 419.929816 -89.430352) (xy 414.31138 -89.430352) (xy 414.279761 -89.439636)
			(xy 414.225813 -89.447392) (xy 414.171311 -89.447392) (xy 414.117363 -89.439636) (xy 414.065068 -89.424281)
			(xy 414.015491 -89.401639) (xy 413.969641 -89.372173) (xy 413.92845 -89.336482) (xy 413.892759 -89.295291)
			(xy 413.863293 -89.249441) (xy 413.840651 -89.199864) (xy 413.825296 -89.147569) (xy 413.81754 -89.093621)
			(xy 413.817054 -89.06637) (xy 413.817505 -89.038911) (xy 413.825367 -88.984558) (xy 413.840937 -88.931893)
			(xy 413.863895 -88.882004) (xy 413.893766 -88.83592) (xy 413.929934 -88.794593) (xy 413.971652 -88.758877)
			(xy 413.9946 -88.74379) (xy 414.006783 -88.735575) (xy 414.026121 -88.713465) (xy 414.038365 -88.686764)
			(xy 414.0425 -88.657683) (xy 414.038184 -88.628627) (xy 414.025775 -88.602003) (xy 414.006299 -88.580014)
			(xy 413.994092 -88.571832) (xy 413.970848 -88.556815) (xy 413.928571 -88.521112) (xy 413.891894 -88.479676)
			(xy 413.861586 -88.433376) (xy 413.838284 -88.383185) (xy 413.822476 -88.330154) (xy 413.814493 -88.275396)
			(xy 413.814006 -88.247728) (xy 403.094444 -88.247728) (xy 403.094444 -89.179904) (xy 404.537146 -89.179904)
			(xy 404.537146 -89.119968) (xy 404.544969 -89.060546) (xy 404.560482 -89.002653) (xy 404.583418 -88.94728)
			(xy 404.613385 -88.895374) (xy 404.649872 -88.847824) (xy 404.692252 -88.805444) (xy 404.739802 -88.768957)
			(xy 404.791708 -88.73899) (xy 404.847081 -88.716054) (xy 404.904974 -88.700541) (xy 404.964396 -88.692718)
			(xy 405.024332 -88.692718) (xy 405.083754 -88.700541) (xy 405.141647 -88.716054) (xy 405.19702 -88.73899)
			(xy 405.248926 -88.768957) (xy 405.296476 -88.805444) (xy 405.338856 -88.847824) (xy 405.375343 -88.895374)
			(xy 405.40531 -88.94728) (xy 405.428246 -89.002653) (xy 405.443759 -89.060546) (xy 405.451582 -89.119968)
			(xy 405.452072 -89.149936) (xy 405.451993 -89.154762) (xy 405.566624 -89.154762) (xy 405.570695 -89.09914)
			(xy 405.582821 -89.044703) (xy 405.602744 -88.992612) (xy 405.63004 -88.943977) (xy 405.664126 -88.899834)
			(xy 405.704275 -88.861125) (xy 405.749633 -88.828674) (xy 405.799233 -88.803173) (xy 405.852017 -88.785166)
			(xy 405.90686 -88.775036) (xy 405.962594 -88.772999) (xy 406.018031 -88.779099) (xy 406.071988 -88.793205)
			(xy 406.123317 -88.815017) (xy 406.170923 -88.844071) (xy 406.213791 -88.879746) (xy 406.251008 -88.921283)
			(xy 406.281781 -88.967796) (xy 406.305453 -89.018293) (xy 406.321521 -89.0717) (xy 406.329641 -89.126876)
			(xy 406.33015 -89.154762) (xy 406.329946 -89.165938) (xy 406.561034 -89.165938) (xy 406.565105 -89.110316)
			(xy 406.577231 -89.055879) (xy 406.597154 -89.003788) (xy 406.62445 -88.955153) (xy 406.658536 -88.91101)
			(xy 406.698685 -88.872301) (xy 406.744043 -88.83985) (xy 406.793643 -88.814349) (xy 406.846427 -88.796342)
			(xy 406.90127 -88.786212) (xy 406.957004 -88.784175) (xy 407.012441 -88.790275) (xy 407.066398 -88.804381)
			(xy 407.117727 -88.826193) (xy 407.165333 -88.855247) (xy 407.208201 -88.890922) (xy 407.245418 -88.932459)
			(xy 407.276191 -88.978972) (xy 407.299863 -89.029469) (xy 407.315931 -89.082876) (xy 407.324051 -89.138052)
			(xy 407.324495 -89.162382) (xy 412.65932 -89.162382) (xy 412.663391 -89.10676) (xy 412.675517 -89.052323)
			(xy 412.69544 -89.000232) (xy 412.722736 -88.951597) (xy 412.756822 -88.907454) (xy 412.796971 -88.868745)
			(xy 412.842329 -88.836294) (xy 412.891929 -88.810793) (xy 412.944713 -88.792786) (xy 412.999556 -88.782656)
			(xy 413.05529 -88.780619) (xy 413.110727 -88.786719) (xy 413.164684 -88.800825) (xy 413.216013 -88.822637)
			(xy 413.263619 -88.851691) (xy 413.306487 -88.887366) (xy 413.343704 -88.928903) (xy 413.374477 -88.975416)
			(xy 413.398149 -89.025913) (xy 413.414217 -89.07932) (xy 413.422337 -89.134496) (xy 413.422846 -89.162382)
			(xy 413.422337 -89.190268) (xy 413.414217 -89.245444) (xy 413.398149 -89.298851) (xy 413.374477 -89.349348)
			(xy 413.343704 -89.395861) (xy 413.306487 -89.437398) (xy 413.263619 -89.473073) (xy 413.216013 -89.502127)
			(xy 413.164684 -89.523939) (xy 413.110727 -89.538045) (xy 413.05529 -89.544145) (xy 412.999556 -89.542108)
			(xy 412.944713 -89.531978) (xy 412.891929 -89.513971) (xy 412.842329 -89.48847) (xy 412.796971 -89.456019)
			(xy 412.756822 -89.41731) (xy 412.722736 -89.373167) (xy 412.69544 -89.324532) (xy 412.675517 -89.272441)
			(xy 412.663391 -89.218004) (xy 412.65932 -89.162382) (xy 407.324495 -89.162382) (xy 407.32456 -89.165938)
			(xy 407.324051 -89.193824) (xy 407.315931 -89.249) (xy 407.299863 -89.302407) (xy 407.276191 -89.352904)
			(xy 407.245418 -89.399417) (xy 407.208201 -89.440954) (xy 407.165333 -89.476629) (xy 407.117727 -89.505683)
			(xy 407.066398 -89.527495) (xy 407.012441 -89.541601) (xy 406.957004 -89.547701) (xy 406.90127 -89.545664)
			(xy 406.846427 -89.535534) (xy 406.793643 -89.517527) (xy 406.744043 -89.492026) (xy 406.698685 -89.459575)
			(xy 406.658536 -89.420866) (xy 406.62445 -89.376723) (xy 406.597154 -89.328088) (xy 406.577231 -89.275997)
			(xy 406.565105 -89.22156) (xy 406.561034 -89.165938) (xy 406.329946 -89.165938) (xy 406.329641 -89.182648)
			(xy 406.321521 -89.237824) (xy 406.305453 -89.291231) (xy 406.281781 -89.341728) (xy 406.251008 -89.388241)
			(xy 406.213791 -89.429778) (xy 406.170923 -89.465453) (xy 406.123317 -89.494507) (xy 406.071988 -89.516319)
			(xy 406.018031 -89.530425) (xy 405.962594 -89.536525) (xy 405.90686 -89.534488) (xy 405.852017 -89.524358)
			(xy 405.799233 -89.506351) (xy 405.749633 -89.48085) (xy 405.704275 -89.448399) (xy 405.664126 -89.40969)
			(xy 405.63004 -89.365547) (xy 405.602744 -89.316912) (xy 405.582821 -89.264821) (xy 405.570695 -89.210384)
			(xy 405.566624 -89.154762) (xy 405.451993 -89.154762) (xy 405.451582 -89.179904) (xy 405.443759 -89.239326)
			(xy 405.428246 -89.297219) (xy 405.40531 -89.352592) (xy 405.375343 -89.404498) (xy 405.338856 -89.452048)
			(xy 405.296476 -89.494428) (xy 405.248926 -89.530915) (xy 405.19702 -89.560882) (xy 405.141647 -89.583818)
			(xy 405.083754 -89.599331) (xy 405.024332 -89.607154) (xy 404.964396 -89.607154) (xy 404.904974 -89.599331)
			(xy 404.847081 -89.583818) (xy 404.791708 -89.560882) (xy 404.739802 -89.530915) (xy 404.692252 -89.494428)
			(xy 404.649872 -89.452048) (xy 404.613385 -89.404498) (xy 404.583418 -89.352592) (xy 404.560482 -89.297219)
			(xy 404.544969 -89.239326) (xy 404.537146 -89.179904) (xy 403.094444 -89.179904) (xy 403.094444 -93.708447)
			(xy 417.390634 -93.708447) (xy 417.390634 -93.621553) (xy 417.398651 -93.535028) (xy 417.414618 -93.449613)
			(xy 417.438398 -93.366035) (xy 417.469787 -93.285008) (xy 417.508519 -93.207223) (xy 417.554263 -93.133343)
			(xy 417.606628 -93.063999) (xy 417.665168 -92.999782) (xy 417.729383 -92.941241) (xy 417.798726 -92.888874)
			(xy 417.872605 -92.843129) (xy 417.95039 -92.804395) (xy 418.031416 -92.773004) (xy 418.114994 -92.749223)
			(xy 418.200409 -92.733254) (xy 418.286933 -92.725235) (xy 418.33038 -92.724732) (xy 420.18458 -92.724732)
			(xy 420.228031 -92.725198) (xy 420.314564 -92.733214) (xy 420.399987 -92.749182) (xy 420.483573 -92.772963)
			(xy 420.564607 -92.804355) (xy 420.6424 -92.843091) (xy 420.716286 -92.88884) (xy 420.785636 -92.941211)
			(xy 420.849857 -92.999757) (xy 420.908402 -93.06398) (xy 420.960772 -93.133331) (xy 421.006519 -93.207218)
			(xy 421.045253 -93.285011) (xy 421.076644 -93.366046) (xy 421.100423 -93.449632) (xy 421.116388 -93.535056)
			(xy 421.124403 -93.621589) (xy 421.124888 -93.66504) (xy 421.124328 -93.710119) (xy 421.115685 -93.799862)
			(xy 421.098499 -93.888368) (xy 421.07293 -93.974824) (xy 421.056562 -94.01683) (xy 421.05199 -94.028006)
			(xy 421.053768 -94.05112) (xy 421.106854 -94.141544) (xy 421.126158 -94.154244) (xy 421.13835 -94.155768)
			(xy 421.18485 -94.162051) (xy 421.276615 -94.181676) (xy 421.366303 -94.209281) (xy 421.453221 -94.244652)
			(xy 421.536698 -94.287517) (xy 421.616091 -94.337544) (xy 421.690785 -94.394348) (xy 421.760205 -94.457489)
			(xy 421.823814 -94.52648) (xy 421.881121 -94.600789) (xy 421.931684 -94.679841) (xy 421.975113 -94.763027)
			(xy 422.011071 -94.849704) (xy 422.039281 -94.939203) (xy 422.059527 -95.030833) (xy 422.07165 -95.123886)
			(xy 422.075558 -95.217644) (xy 422.071221 -95.311384) (xy 422.06545 -95.35795) (xy 422.063926 -95.369126)
			(xy 422.070022 -95.389954) (xy 422.12768 -95.455994) (xy 422.135236 -95.463872) (xy 422.155127 -95.472814)
			(xy 422.166034 -95.473266) (xy 425.622466 -95.473266) (xy 425.632536 -95.473692) (xy 425.651134 -95.48141)
			(xy 425.658534 -95.488252) (xy 425.842684 -95.672148) (xy 425.844208 -95.672148) (xy 425.844208 -95.673926)
			(xy 425.959524 -95.789242) (xy 425.966378 -95.796631) (xy 425.974089 -95.815239) (xy 425.97451 -95.82531)
			(xy 425.97451 -97.2439) (xy 425.974933 -97.25397) (xy 425.982655 -97.272567) (xy 425.989496 -97.279968)
			(xy 426.233336 -97.523808) (xy 426.240753 -97.530479) (xy 426.259186 -97.538058) (xy 426.26915 -97.53854)
			(xy 426.851572 -97.53854) (xy 426.883205 -97.539013) (xy 426.945932 -97.547269) (xy 427.007043 -97.563641)
			(xy 427.065495 -97.587851) (xy 427.120286 -97.619485) (xy 427.170478 -97.657999) (xy 427.215214 -97.702737)
			(xy 427.253727 -97.752931) (xy 427.285357 -97.807723) (xy 427.309565 -97.866176) (xy 427.325935 -97.927288)
			(xy 427.334188 -97.990014) (xy 427.33468 -98.021648) (xy 427.334185 -98.053449) (xy 427.325807 -98.116498)
			(xy 427.309228 -98.177902) (xy 427.284734 -98.236599) (xy 427.25275 -98.291575) (xy 427.213828 -98.341879)
			(xy 427.168642 -98.38664) (xy 427.117973 -98.425084) (xy 427.090586 -98.441256) (xy 427.082989 -98.446005)
			(xy 427.071441 -98.459687) (xy 427.065284 -98.4765) (xy 427.064932 -98.485452) (xy 427.064932 -98.573844)
			(xy 427.065277 -98.582801) (xy 427.071409 -98.599631) (xy 427.082973 -98.61331) (xy 427.090586 -98.61804)
			(xy 427.117979 -98.634199) (xy 427.168641 -98.672651) (xy 427.21382 -98.717416) (xy 427.252735 -98.767723)
			(xy 427.284714 -98.8227) (xy 427.309204 -98.881397) (xy 427.32578 -98.9428) (xy 427.334157 -99.005848)
			(xy 427.33468 -99.037648) (xy 427.334155 -99.069611) (xy 427.325691 -99.132975) (xy 427.308943 -99.194669)
			(xy 427.284205 -99.253616) (xy 427.251909 -99.308784) (xy 427.212618 -99.359211) (xy 427.16702 -99.404015)
			(xy 427.11591 -99.442414) (xy 427.0883 -99.458526) (xy 427.080578 -99.463219) (xy 427.068869 -99.476971)
			(xy 427.062694 -99.493943) (xy 427.062392 -99.502976) (xy 427.062392 -99.591368) (xy 427.06273 -99.600388)
			(xy 427.068945 -99.617322) (xy 427.080622 -99.631072) (xy 427.0883 -99.635818) (xy 427.115882 -99.651976)
			(xy 427.16699 -99.690369) (xy 427.212588 -99.735167) (xy 427.25188 -99.785587) (xy 427.284179 -99.840749)
			(xy 427.308921 -99.899689) (xy 427.325673 -99.961377) (xy 427.334143 -100.024735) (xy 427.33468 -100.056696)
			(xy 427.334209 -100.088329) (xy 427.325951 -100.151054) (xy 427.309577 -100.212165) (xy 427.285365 -100.270615)
			(xy 427.253731 -100.325405) (xy 427.215216 -100.375597) (xy 427.170479 -100.420332) (xy 427.120285 -100.458845)
			(xy 427.065494 -100.490476) (xy 427.007042 -100.514684) (xy 426.945931 -100.531056) (xy 426.883205 -100.539311)
			(xy 426.851572 -100.539804) (xy 426.241972 -100.539804) (xy 426.210157 -100.539283) (xy 426.147084 -100.530868)
			(xy 426.116242 -100.52304) (xy 426.104812 -100.519992) (xy 426.081444 -100.524564) (xy 426.008038 -100.580698)
			(xy 425.999143 -100.588342) (xy 425.98882 -100.609372) (xy 425.988226 -100.621084) (xy 425.988226 -101.524308)
			(xy 425.988727 -101.536042) (xy 425.999077 -101.557098) (xy 426.008038 -101.564694) (xy 426.081444 -101.620828)
			(xy 426.104812 -101.6254) (xy 426.116242 -101.622352) (xy 426.147088 -101.614546) (xy 426.210158 -101.606132)
			(xy 426.241972 -101.605588) (xy 426.851572 -101.605588) (xy 426.883203 -101.606113) (xy 426.945925 -101.614367)
			(xy 427.007033 -101.630738) (xy 427.065481 -101.654945) (xy 427.120269 -101.686574) (xy 427.17046 -101.725084)
			(xy 427.215195 -101.769816) (xy 427.253709 -101.820004) (xy 427.285341 -101.87479) (xy 427.309552 -101.933237)
			(xy 427.325927 -101.994343) (xy 427.334185 -102.057065) (xy 427.33468 -102.088696) (xy 427.334144 -102.120496)
			(xy 427.325772 -102.183543) (xy 427.309199 -102.244946) (xy 427.284712 -102.303643) (xy 427.252733 -102.358619)
			(xy 427.213817 -102.408923) (xy 427.168636 -102.453686) (xy 427.117971 -102.492132) (xy 427.090586 -102.508304)
			(xy 427.082968 -102.513023) (xy 427.071422 -102.526719) (xy 427.065277 -102.543544) (xy 427.064932 -102.5525)
			(xy 427.064932 -102.640892) (xy 427.065243 -102.649852) (xy 427.07139 -102.666684) (xy 427.082967 -102.680361)
			(xy 427.090586 -102.685088) (xy 427.117957 -102.701284) (xy 427.168618 -102.73973) (xy 427.213798 -102.784491)
			(xy 427.252715 -102.834792) (xy 427.284696 -102.889764) (xy 427.309189 -102.948456) (xy 427.325771 -103.009854)
			(xy 427.334154 -103.072897) (xy 427.33468 -103.104696) (xy 427.334144 -103.136496) (xy 427.325772 -103.199543)
			(xy 427.309199 -103.260946) (xy 427.284712 -103.319643) (xy 427.252733 -103.374619) (xy 427.213817 -103.424923)
			(xy 427.168636 -103.469686) (xy 427.117971 -103.508132) (xy 427.090586 -103.524304) (xy 427.082968 -103.529023)
			(xy 427.071422 -103.542719) (xy 427.065277 -103.559544) (xy 427.064932 -103.5685) (xy 427.064932 -103.656892)
			(xy 427.065243 -103.665852) (xy 427.07139 -103.682684) (xy 427.082967 -103.696361) (xy 427.090586 -103.701088)
			(xy 427.117957 -103.717284) (xy 427.168618 -103.75573) (xy 427.213798 -103.800491) (xy 427.252715 -103.850792)
			(xy 427.284696 -103.905764) (xy 427.309189 -103.964456) (xy 427.325771 -104.025854) (xy 427.334154 -104.088897)
			(xy 427.33468 -104.120696) (xy 427.334209 -104.152329) (xy 427.325951 -104.215054) (xy 427.309577 -104.276165)
			(xy 427.285365 -104.334615) (xy 427.253731 -104.389405) (xy 427.215216 -104.439597) (xy 427.170479 -104.484332)
			(xy 427.120285 -104.522845) (xy 427.065494 -104.554476) (xy 427.007042 -104.578684) (xy 426.945931 -104.595056)
			(xy 426.883205 -104.603311) (xy 426.851572 -104.603804) (xy 426.241972 -104.603804) (xy 426.209366 -104.603279)
			(xy 426.144748 -104.594503) (xy 426.081897 -104.577115) (xy 426.021957 -104.55143) (xy 425.966017 -104.517916)
			(xy 425.915093 -104.477182) (xy 425.892214 -104.453944) (xy 425.884717 -104.446816) (xy 425.865717 -104.438686)
			(xy 425.855384 -104.438196) (xy 425.57954 -104.438196) (xy 425.57954 -104.44734) (xy 425.579046 -104.457345)
			(xy 425.57138 -104.47583) (xy 425.55723 -104.48998) (xy 425.538745 -104.497646) (xy 425.52874 -104.49814)
			(xy 425.311824 -104.49814) (xy 425.287223 -104.497514) (xy 425.239183 -104.486883) (xy 425.194577 -104.466118)
			(xy 425.174664 -104.451658) (xy 425.167894 -104.446879) (xy 425.15221 -104.441565) (xy 425.14393 -104.441244)
			(xy 424.734736 -104.441244) (xy 424.709549 -104.440772) (xy 424.659799 -104.432875) (xy 424.611898 -104.417288)
			(xy 424.567028 -104.394393) (xy 424.526295 -104.364757) (xy 424.508168 -104.347264) (xy 424.382184 -104.22128)
			(xy 424.37475 -104.21463) (xy 424.356331 -104.207036) (xy 424.34637 -104.206548) (xy 424.329606 -104.206548)
			(xy 424.31208 -104.213406) (xy 424.304968 -104.22001) (xy 424.283717 -104.239341) (xy 424.237207 -104.273065)
			(xy 424.186843 -104.300702) (xy 424.133414 -104.321817) (xy 424.077763 -104.336079) (xy 424.020765 -104.343263)
			(xy 423.99204 -104.343708) (xy 423.962072 -104.343202) (xy 423.902648 -104.335383) (xy 423.844753 -104.319875)
			(xy 423.789378 -104.296942) (xy 423.73747 -104.266977) (xy 423.689917 -104.230492) (xy 423.647534 -104.188113)
			(xy 423.611046 -104.140564) (xy 423.581076 -104.088658) (xy 423.558138 -104.033285) (xy 423.542625 -103.975391)
			(xy 423.534801 -103.915968) (xy 423.534332 -103.886) (xy 423.534853 -103.854519) (xy 423.54349 -103.792151)
			(xy 423.560588 -103.731553) (xy 423.585823 -103.673869) (xy 423.618722 -103.620184) (xy 423.658663 -103.571511)
			(xy 423.704894 -103.528767) (xy 423.73042 -103.510334) (xy 423.739818 -103.503984) (xy 423.750994 -103.484426)
			(xy 423.758868 -103.395526) (xy 423.759298 -103.384363) (xy 423.751656 -103.363401) (xy 423.744136 -103.35514)
			(xy 423.29481 -102.905814) (xy 423.286936 -102.902004) (xy 423.259064 -102.888102) (xy 423.20701 -102.853905)
			(xy 423.160075 -102.812962) (xy 423.119128 -102.766032) (xy 423.084924 -102.713982) (xy 423.071036 -102.686104)
			(xy 423.067226 -102.67823) (xy 423.050716 -102.66172) (xy 423.04268 -102.65431) (xy 423.022275 -102.646538)
			(xy 423.011346 -102.646734) (xy 422.92397 -102.652576) (xy 422.90492 -102.66299) (xy 422.898062 -102.671626)
			(xy 422.879871 -102.694475) (xy 422.837765 -102.734941) (xy 422.789981 -102.768513) (xy 422.737636 -102.794406)
			(xy 422.681955 -102.812015) (xy 422.624239 -102.820926) (xy 422.59504 -102.821486) (xy 422.567784 -102.82107)
			(xy 422.513825 -102.813317) (xy 422.46152 -102.797964) (xy 422.411931 -102.775322) (xy 422.366071 -102.745853)
			(xy 422.324871 -102.710158) (xy 422.289171 -102.668961) (xy 422.259697 -102.623104) (xy 422.23705 -102.573518)
			(xy 422.221691 -102.521214) (xy 422.213933 -102.467256) (xy 422.213933 -102.412744) (xy 422.221691 -102.358786)
			(xy 422.23705 -102.306482) (xy 422.259697 -102.256896) (xy 422.289171 -102.211039) (xy 422.324871 -102.169842)
			(xy 422.366071 -102.134147) (xy 422.411931 -102.104678) (xy 422.46152 -102.082036) (xy 422.513825 -102.066683)
			(xy 422.567784 -102.05893) (xy 422.59504 -102.05847) (xy 422.612215 -102.05865) (xy 422.64643 -102.061704)
			(xy 422.663366 -102.064566) (xy 422.674288 -102.066598) (xy 422.696132 -102.06101) (xy 422.764712 -102.003606)
			(xy 422.772879 -101.996017) (xy 422.78237 -101.975874) (xy 422.783 -101.964744) (xy 422.783 -101.68636)
			(xy 422.78264 -101.677242) (xy 422.776337 -101.660134) (xy 422.76441 -101.646346) (xy 422.756584 -101.641656)
			(xy 422.729909 -101.62657) (xy 422.68052 -101.590287) (xy 422.636417 -101.547736) (xy 422.598388 -101.499679)
			(xy 422.567115 -101.446975) (xy 422.543157 -101.390569) (xy 422.526943 -101.331469) (xy 422.518763 -101.270733)
			(xy 422.518764 -101.20945) (xy 422.526946 -101.148714) (xy 422.543162 -101.089615) (xy 422.567122 -101.033209)
			(xy 422.598398 -100.980507) (xy 422.636428 -100.932451) (xy 422.680533 -100.889902) (xy 422.729924 -100.853621)
			(xy 422.756584 -100.838508) (xy 422.764373 -100.833776) (xy 422.776259 -100.819977) (xy 422.782616 -100.802909)
			(xy 422.783 -100.793804) (xy 422.783 -100.585778) (xy 422.782502 -100.574274) (xy 422.772587 -100.553515)
			(xy 422.76395 -100.5459) (xy 422.69283 -100.489258) (xy 422.670478 -100.483924) (xy 422.659048 -100.486464)
			(xy 422.634355 -100.491661) (xy 422.584203 -100.497263) (xy 422.558972 -100.49764) (xy 422.529008 -100.497084)
			(xy 422.469592 -100.489259) (xy 422.411706 -100.473745) (xy 422.35634 -100.450809) (xy 422.304441 -100.420842)
			(xy 422.256898 -100.384358) (xy 422.214523 -100.341981) (xy 422.178042 -100.294435) (xy 422.148079 -100.242535)
			(xy 422.125146 -100.187167) (xy 422.109636 -100.129281) (xy 422.101814 -100.069864) (xy 422.101814 -100.009936)
			(xy 422.109636 -99.950519) (xy 422.125146 -99.892633) (xy 422.148079 -99.837265) (xy 422.178042 -99.785365)
			(xy 422.214523 -99.737819) (xy 422.256898 -99.695442) (xy 422.304441 -99.658958) (xy 422.35634 -99.628991)
			(xy 422.411706 -99.606055) (xy 422.469592 -99.590541) (xy 422.529008 -99.582716) (xy 422.558972 -99.582224)
			(xy 422.584205 -99.582574) (xy 422.634359 -99.588179) (xy 422.659048 -99.5934) (xy 422.670478 -99.59594)
			(xy 422.69283 -99.590606) (xy 422.76395 -99.533964) (xy 422.772619 -99.526376) (xy 422.782526 -99.505599)
			(xy 422.783 -99.494086) (xy 422.783 -98.051874) (xy 422.782533 -98.041865) (xy 422.774865 -98.023372)
			(xy 422.760706 -98.00922) (xy 422.74221 -98.001562) (xy 422.7322 -98.001074) (xy 422.724326 -98.001074)
			(xy 422.716706 -98.00336) (xy 422.693592 -98.009964) (xy 422.686734 -98.011742) (xy 422.674796 -98.0186)
			(xy 422.295828 -98.397568) (xy 422.276834 -98.415787) (xy 422.23404 -98.446416) (xy 422.186817 -98.469643)
			(xy 422.136434 -98.484844) (xy 422.110408 -98.488754) (xy 422.102026 -98.48977) (xy 422.086786 -98.49739)
			(xy 422.044368 -98.539808) (xy 422.036748 -98.55708) (xy 422.036494 -98.566986) (xy 422.035033 -98.596295)
			(xy 422.025631 -98.654218) (xy 422.008903 -98.710465) (xy 421.985123 -98.764113) (xy 421.954682 -98.814281)
			(xy 421.918077 -98.860147) (xy 421.875911 -98.900958) (xy 421.828875 -98.936045) (xy 421.777739 -98.964833)
			(xy 421.723344 -98.986848) (xy 421.666581 -99.001731) (xy 421.608381 -99.009236) (xy 421.57904 -99.009708)
			(xy 421.550317 -99.009259) (xy 421.493322 -99.002064) (xy 421.437676 -98.987795) (xy 421.384252 -98.966677)
			(xy 421.33389 -98.93904) (xy 421.287381 -98.90532) (xy 421.266112 -98.88601) (xy 421.258837 -98.879855)
			(xy 421.24109 -98.872942) (xy 421.231568 -98.872548) (xy 420.753032 -98.872548) (xy 420.744756 -98.872885)
			(xy 420.72908 -98.878207) (xy 420.722298 -98.882962) (xy 420.702375 -98.897401) (xy 420.657763 -98.918136)
			(xy 420.609735 -98.92879) (xy 420.585138 -98.929444) (xy 420.317676 -98.929444) (xy 420.317676 -98.9203)
			(xy 420.31728 -98.910276) (xy 420.309605 -98.891754) (xy 420.295426 -98.877581) (xy 420.2769 -98.869915)
			(xy 420.266876 -98.8695) (xy 419.792404 -98.8695) (xy 419.792404 -98.878644) (xy 419.791948 -98.888654)
			(xy 419.784275 -98.907146) (xy 419.770112 -98.921297) (xy 419.751614 -98.928956) (xy 419.741604 -98.929444)
			(xy 419.524942 -98.929444) (xy 419.500341 -98.928808) (xy 419.452302 -98.918181) (xy 419.407695 -98.89742)
			(xy 419.387782 -98.882962) (xy 419.381008 -98.878191) (xy 419.365327 -98.872872) (xy 419.357048 -98.872548)
			(xy 419.175184 -98.872548) (xy 419.165156 -98.872908) (xy 419.146629 -98.880592) (xy 419.132456 -98.894783)
			(xy 419.124795 -98.913319) (xy 419.124384 -98.923348) (xy 419.124384 -98.97237) (xy 419.128194 -98.985578)
			(xy 419.13175 -98.99142) (xy 419.144538 -99.01369) (xy 419.164702 -99.060919) (xy 419.178338 -99.110429)
			(xy 419.185198 -99.161323) (xy 419.185598 -99.187) (xy 419.185145 -99.214253) (xy 419.177387 -99.268205)
			(xy 419.162031 -99.320504) (xy 419.139388 -99.370085) (xy 419.109919 -99.415938) (xy 419.074224 -99.457131)
			(xy 419.03303 -99.492825) (xy 418.987176 -99.522292) (xy 418.937594 -99.544934) (xy 418.885295 -99.56029)
			(xy 418.831343 -99.568045) (xy 418.80409 -99.568508) (xy 418.775137 -99.567989) (xy 418.717896 -99.55923)
			(xy 418.662639 -99.541915) (xy 418.610635 -99.516442) (xy 418.563083 -99.483397) (xy 418.541708 -99.46386)
			(xy 418.53358 -99.45624) (xy 418.513514 -99.449128) (xy 418.415724 -99.45751) (xy 418.397182 -99.467924)
			(xy 418.390578 -99.47656) (xy 418.370962 -99.501887) (xy 418.326136 -99.547652) (xy 418.275652 -99.587088)
			(xy 418.220397 -99.619502) (xy 418.16134 -99.644323) (xy 418.099519 -99.661116) (xy 418.036021 -99.669587)
			(xy 418.00399 -99.670108) (xy 417.972362 -99.669668) (xy 417.909647 -99.661407) (xy 417.848548 -99.645028)
			(xy 417.790111 -99.620811) (xy 417.735336 -99.58917) (xy 417.685162 -99.550648) (xy 417.640447 -99.505905)
			(xy 417.601957 -99.455706) (xy 417.570352 -99.400911) (xy 417.546173 -99.342458) (xy 417.529832 -99.281349)
			(xy 417.521612 -99.218629) (xy 417.521136 -99.187) (xy 417.521136 -98.552) (xy 417.521679 -98.518704)
			(xy 417.530815 -98.45274) (xy 417.548926 -98.388658) (xy 417.575669 -98.327671) (xy 417.610538 -98.270937)
			(xy 417.65287 -98.219531) (xy 417.701863 -98.174429) (xy 417.728908 -98.154998) (xy 417.738814 -98.14814)
			(xy 417.750498 -98.127058) (xy 417.7538 -98.02114) (xy 417.74364 -97.999296) (xy 417.733988 -97.991676)
			(xy 417.718109 -97.978565) (xy 417.690923 -97.947643) (xy 417.669781 -97.912312) (xy 417.655381 -97.873738)
			(xy 417.648199 -97.833195) (xy 417.647882 -97.812606) (xy 417.648136 -97.812606) (xy 417.648136 -97.513394)
			(xy 417.647882 -97.513394) (xy 417.648154 -97.493782) (xy 417.654682 -97.455108) (xy 417.667802 -97.418147)
			(xy 417.677092 -97.400872) (xy 417.680394 -97.39503) (xy 417.683696 -97.382838) (xy 417.683696 -97.122488)
			(xy 417.68342 -97.115662) (xy 417.67969 -97.102527) (xy 417.67633 -97.09658) (xy 417.663549 -97.074306)
			(xy 417.643382 -97.027079) (xy 417.629743 -96.97757) (xy 417.622882 -96.926677) (xy 417.622482 -96.901)
			(xy 417.622978 -96.873749) (xy 417.630734 -96.819802) (xy 417.646089 -96.767508) (xy 417.668729 -96.717932)
			(xy 417.698194 -96.672082) (xy 417.733885 -96.630892) (xy 417.775074 -96.5952) (xy 417.820923 -96.565734)
			(xy 417.870499 -96.543092) (xy 417.922793 -96.527736) (xy 417.976739 -96.519978) (xy 418.00399 -96.519492)
			(xy 418.03037 -96.51994) (xy 418.082628 -96.527209) (xy 418.133386 -96.541609) (xy 418.181675 -96.562867)
			(xy 418.226574 -96.590576) (xy 418.267226 -96.624207) (xy 418.302856 -96.66312) (xy 418.318188 -96.684592)
			(xy 418.324792 -96.69399) (xy 418.344096 -96.70542) (xy 418.444426 -96.714564) (xy 418.465762 -96.706944)
			(xy 418.470588 -96.702118) (xy 418.478 -96.695293) (xy 418.49659 -96.687564) (xy 418.506656 -96.687132)
			(xy 419.333426 -96.687132) (xy 419.358318 -96.67113) (xy 419.364414 -96.657668) (xy 419.376847 -96.63256)
			(xy 419.409029 -96.586703) (xy 419.428422 -96.566482) (xy 419.828472 -96.166432) (xy 419.84903 -96.146742)
			(xy 419.895744 -96.114222) (xy 419.947469 -96.090467) (xy 420.002578 -96.076225) (xy 420.03091 -96.073468)
			(xy 420.040054 -96.072706) (xy 420.05631 -96.06534) (xy 420.185088 -95.936562) (xy 420.18712 -95.898208)
			(xy 420.174928 -95.882714) (xy 420.146355 -95.846379) (xy 420.094977 -95.769527) (xy 420.050437 -95.68852)
			(xy 420.013071 -95.603965) (xy 419.983157 -95.516495) (xy 419.960921 -95.426765) (xy 419.946528 -95.335448)
			(xy 419.940087 -95.243229) (xy 419.941645 -95.150798) (xy 419.951192 -95.058849) (xy 419.968655 -94.968069)
			(xy 419.993904 -94.87914) (xy 420.026749 -94.792728) (xy 420.046404 -94.75089) (xy 420.052246 -94.738952)
			(xy 420.050722 -94.713298) (xy 419.99789 -94.62897) (xy 419.993072 -94.621901) (xy 419.979667 -94.611284)
			(xy 419.963515 -94.605668) (xy 419.954964 -94.605348) (xy 418.33038 -94.605348) (xy 418.286933 -94.604765)
			(xy 418.200409 -94.596746) (xy 418.114994 -94.580777) (xy 418.031416 -94.556996) (xy 417.95039 -94.525605)
			(xy 417.872605 -94.486871) (xy 417.798726 -94.441126) (xy 417.729383 -94.388759) (xy 417.665168 -94.330218)
			(xy 417.606628 -94.266001) (xy 417.554263 -94.196657) (xy 417.508519 -94.122777) (xy 417.469787 -94.044992)
			(xy 417.438398 -93.963965) (xy 417.414618 -93.880387) (xy 417.398651 -93.794972) (xy 417.390634 -93.708447)
			(xy 403.094444 -93.708447) (xy 403.094444 -95.438051) (xy 405.06726 -95.438051) (xy 405.06726 -95.383549)
			(xy 405.075016 -95.329602) (xy 405.09037 -95.277308) (xy 405.113009 -95.227731) (xy 405.142473 -95.18188)
			(xy 405.178162 -95.140689) (xy 405.21935 -95.104996) (xy 405.265198 -95.075527) (xy 405.314772 -95.052883)
			(xy 405.367065 -95.037524) (xy 405.421011 -95.029762) (xy 405.448262 -95.029274) (xy 405.474997 -95.029709)
			(xy 405.527944 -95.037171) (xy 405.57933 -95.051955) (xy 405.628148 -95.07377) (xy 405.67344 -95.102189)
			(xy 405.71432 -95.136655) (xy 405.732488 -95.156274) (xy 405.740108 -95.164656) (xy 405.75992 -95.173292)
			(xy 405.859234 -95.171768) (xy 405.878792 -95.16237) (xy 405.885904 -95.153734) (xy 405.904163 -95.132818)
			(xy 405.945645 -95.095919) (xy 405.99204 -95.065425) (xy 406.042367 -95.041982) (xy 406.095561 -95.026086)
			(xy 406.150498 -95.018072) (xy 406.178258 -95.01759) (xy 406.205513 -95.018054) (xy 406.259468 -95.025807)
			(xy 406.31177 -95.041159) (xy 406.361356 -95.063799) (xy 406.407214 -95.093266) (xy 406.448411 -95.128959)
			(xy 406.484109 -95.170153) (xy 406.484821 -95.17126) (xy 416.22802 -95.17126) (xy 416.232091 -95.115638)
			(xy 416.244217 -95.061201) (xy 416.26414 -95.00911) (xy 416.291436 -94.960475) (xy 416.325522 -94.916332)
			(xy 416.365671 -94.877623) (xy 416.411029 -94.845172) (xy 416.460629 -94.819671) (xy 416.513413 -94.801664)
			(xy 416.568256 -94.791534) (xy 416.62399 -94.789497) (xy 416.679427 -94.795597) (xy 416.733384 -94.809703)
			(xy 416.784713 -94.831515) (xy 416.832319 -94.860569) (xy 416.875187 -94.896244) (xy 416.912404 -94.937781)
			(xy 416.943177 -94.984294) (xy 416.966849 -95.034791) (xy 416.982917 -95.088198) (xy 416.991037 -95.143374)
			(xy 416.991546 -95.17126) (xy 416.991037 -95.199146) (xy 416.982917 -95.254322) (xy 416.966849 -95.307729)
			(xy 416.943177 -95.358226) (xy 416.912404 -95.404739) (xy 416.875187 -95.446276) (xy 416.832319 -95.481951)
			(xy 416.784713 -95.511005) (xy 416.733384 -95.532817) (xy 416.679427 -95.546923) (xy 416.62399 -95.553023)
			(xy 416.568256 -95.550986) (xy 416.513413 -95.540856) (xy 416.460629 -95.522849) (xy 416.411029 -95.497348)
			(xy 416.365671 -95.464897) (xy 416.325522 -95.426188) (xy 416.291436 -95.382045) (xy 416.26414 -95.33341)
			(xy 416.244217 -95.281319) (xy 416.232091 -95.226882) (xy 416.22802 -95.17126) (xy 406.484821 -95.17126)
			(xy 406.513581 -95.216007) (xy 406.536226 -95.26559) (xy 406.551585 -95.317891) (xy 406.559343 -95.371845)
			(xy 406.559343 -95.426355) (xy 406.551585 -95.480309) (xy 406.536226 -95.53261) (xy 406.513581 -95.582193)
			(xy 406.484109 -95.628047) (xy 406.448411 -95.669241) (xy 406.407214 -95.704934) (xy 406.361356 -95.734401)
			(xy 406.31177 -95.757041) (xy 406.259468 -95.772393) (xy 406.205513 -95.780146) (xy 406.178258 -95.780606)
			(xy 406.151523 -95.780164) (xy 406.098576 -95.772705) (xy 406.04719 -95.757923) (xy 405.998372 -95.736109)
			(xy 405.953079 -95.70769) (xy 405.9122 -95.673225) (xy 405.894032 -95.653606) (xy 405.886412 -95.645224)
			(xy 405.8666 -95.636588) (xy 405.767286 -95.638112) (xy 405.747728 -95.64751) (xy 405.740616 -95.656146)
			(xy 405.722418 -95.677117) (xy 405.680921 -95.714009) (xy 405.634512 -95.744493) (xy 405.584174 -95.767926)
			(xy 405.53097 -95.783811) (xy 405.476025 -95.791814) (xy 405.448262 -95.79229) (xy 405.421011 -95.791838)
			(xy 405.367065 -95.784076) (xy 405.314772 -95.768717) (xy 405.265198 -95.746073) (xy 405.21935 -95.716604)
			(xy 405.178162 -95.680911) (xy 405.142473 -95.63972) (xy 405.113009 -95.593869) (xy 405.09037 -95.544292)
			(xy 405.075016 -95.491998) (xy 405.06726 -95.438051) (xy 403.094444 -95.438051) (xy 403.094444 -96.45904)
			(xy 405.138128 -96.45904) (xy 405.138614 -96.431789) (xy 405.14637 -96.377841) (xy 405.161725 -96.325546)
			(xy 405.184367 -96.275969) (xy 405.213833 -96.230119) (xy 405.249524 -96.188928) (xy 405.290715 -96.153237)
			(xy 405.336565 -96.123771) (xy 405.386142 -96.101129) (xy 405.438437 -96.085774) (xy 405.492385 -96.078018)
			(xy 405.546887 -96.078018) (xy 405.600835 -96.085774) (xy 405.65313 -96.101129) (xy 405.702707 -96.123771)
			(xy 405.748557 -96.153237) (xy 405.789748 -96.188928) (xy 405.825439 -96.230119) (xy 405.854905 -96.275969)
			(xy 405.877547 -96.325546) (xy 405.892902 -96.377841) (xy 405.900307 -96.429346) (xy 415.757422 -96.429346)
			(xy 415.757422 -96.374854) (xy 415.765177 -96.320916) (xy 415.780528 -96.26863) (xy 415.803164 -96.219062)
			(xy 415.832623 -96.173218) (xy 415.868306 -96.132034) (xy 415.909486 -96.096347) (xy 415.955326 -96.066883)
			(xy 416.004893 -96.044242) (xy 416.057177 -96.028885) (xy 416.111114 -96.021125) (xy 416.13836 -96.020636)
			(xy 416.167179 -96.021157) (xy 416.224159 -96.029847) (xy 416.279184 -96.047006) (xy 416.331003 -96.072244)
			(xy 416.378439 -96.104986) (xy 416.420412 -96.144489) (xy 416.455968 -96.189853) (xy 416.470592 -96.214692)
			(xy 416.47853 -96.227544) (xy 416.500395 -96.248359) (xy 416.527391 -96.261871) (xy 416.557157 -96.266901)
			(xy 416.587093 -96.263007) (xy 416.614583 -96.250532) (xy 416.637224 -96.230564) (xy 416.645598 -96.217994)
			(xy 416.660612 -96.194657) (xy 416.696287 -96.152155) (xy 416.737744 -96.115272) (xy 416.784109 -96.084786)
			(xy 416.834402 -96.06134) (xy 416.887561 -96.04543) (xy 416.942465 -96.03739) (xy 416.97021 -96.036892)
			(xy 416.997461 -96.037378) (xy 417.051407 -96.045136) (xy 417.103701 -96.060492) (xy 417.153277 -96.083134)
			(xy 417.199126 -96.1126) (xy 417.240315 -96.148292) (xy 417.276006 -96.189482) (xy 417.305471 -96.235332)
			(xy 417.328111 -96.284908) (xy 417.343466 -96.337202) (xy 417.351222 -96.391149) (xy 417.351222 -96.445651)
			(xy 417.343466 -96.499598) (xy 417.328111 -96.551892) (xy 417.305471 -96.601468) (xy 417.276006 -96.647318)
			(xy 417.240315 -96.688508) (xy 417.199126 -96.7242) (xy 417.153277 -96.753666) (xy 417.103701 -96.776308)
			(xy 417.051407 -96.791664) (xy 416.997461 -96.799422) (xy 416.97021 -96.799908) (xy 416.941392 -96.79936)
			(xy 416.884412 -96.790679) (xy 416.829386 -96.773526) (xy 416.777566 -96.748294) (xy 416.730129 -96.715555)
			(xy 416.688156 -96.676054) (xy 416.652601 -96.630691) (xy 416.637978 -96.605852) (xy 416.630083 -96.592969)
			(xy 416.608212 -96.572143) (xy 416.581206 -96.558625) (xy 416.551428 -96.553597) (xy 416.521481 -96.557497)
			(xy 416.493985 -96.569986) (xy 416.471343 -96.589971) (xy 416.462972 -96.60255) (xy 416.447994 -96.625911)
			(xy 416.412311 -96.66841) (xy 416.370847 -96.70529) (xy 416.324476 -96.735773) (xy 416.274178 -96.759214)
			(xy 416.221014 -96.775121) (xy 416.166106 -96.783156) (xy 416.13836 -96.783652) (xy 416.111114 -96.783075)
			(xy 416.057177 -96.775315) (xy 416.004893 -96.759958) (xy 415.955326 -96.737317) (xy 415.909486 -96.707853)
			(xy 415.868306 -96.672166) (xy 415.832623 -96.630982) (xy 415.803164 -96.585138) (xy 415.780528 -96.53557)
			(xy 415.765177 -96.483284) (xy 415.757422 -96.429346) (xy 405.900307 -96.429346) (xy 405.900658 -96.431789)
			(xy 405.901144 -96.45904) (xy 405.900686 -96.48542) (xy 405.893422 -96.537679) (xy 405.879025 -96.588437)
			(xy 405.85777 -96.636727) (xy 405.830062 -96.681626) (xy 405.796431 -96.722278) (xy 405.757517 -96.757907)
			(xy 405.736044 -96.773238) (xy 405.724042 -96.782069) (xy 405.7054 -96.805302) (xy 405.694256 -96.832926)
			(xy 405.69156 -96.86259) (xy 405.697541 -96.89177) (xy 405.711689 -96.917983) (xy 405.732801 -96.938996)
			(xy 405.745696 -96.946466) (xy 405.771353 -96.960855) (xy 405.818304 -96.99629) (xy 405.859261 -97.03851)
			(xy 405.893254 -97.086516) (xy 405.919476 -97.13917) (xy 405.937308 -97.195224) (xy 405.946325 -97.253351)
			(xy 405.946864 -97.282762) (xy 405.946378 -97.310013) (xy 405.938622 -97.363961) (xy 405.923267 -97.416256)
			(xy 405.900625 -97.465833) (xy 405.871159 -97.511683) (xy 405.835468 -97.552874) (xy 405.794277 -97.588565)
			(xy 405.748427 -97.618031) (xy 405.69885 -97.640673) (xy 405.646555 -97.656028) (xy 405.592607 -97.663784)
			(xy 405.538105 -97.663784) (xy 405.484157 -97.656028) (xy 405.431862 -97.640673) (xy 405.382285 -97.618031)
			(xy 405.336435 -97.588565) (xy 405.295244 -97.552874) (xy 405.259553 -97.511683) (xy 405.230087 -97.465833)
			(xy 405.207445 -97.416256) (xy 405.19209 -97.363961) (xy 405.184334 -97.310013) (xy 405.183848 -97.282762)
			(xy 405.184311 -97.256382) (xy 405.191575 -97.204124) (xy 405.205971 -97.153366) (xy 405.227225 -97.105076)
			(xy 405.254932 -97.060177) (xy 405.288563 -97.019524) (xy 405.327475 -96.983895) (xy 405.348948 -96.968564)
			(xy 405.36095 -96.959731) (xy 405.379593 -96.9365) (xy 405.390738 -96.908876) (xy 405.393434 -96.879211)
			(xy 405.387453 -96.85003) (xy 405.373304 -96.823818) (xy 405.352191 -96.802806) (xy 405.339296 -96.795336)
			(xy 405.313638 -96.780948) (xy 405.266688 -96.745513) (xy 405.225731 -96.703292) (xy 405.191739 -96.655286)
			(xy 405.165516 -96.602632) (xy 405.147685 -96.546578) (xy 405.138667 -96.488451) (xy 405.138128 -96.45904)
			(xy 403.094444 -96.45904) (xy 403.094444 -98.45167) (xy 403.113494 -98.47834) (xy 403.128988 -98.48342)
			(xy 403.155287 -98.492861) (xy 403.205016 -98.518341) (xy 403.250499 -98.550798) (xy 403.290764 -98.589539)
			(xy 403.324952 -98.633736) (xy 403.352331 -98.682445) (xy 403.372317 -98.734625) (xy 403.384483 -98.789161)
			(xy 403.388568 -98.844888) (xy 403.384486 -98.900615) (xy 403.372324 -98.955152) (xy 403.352341 -99.007333)
			(xy 403.324965 -99.056043) (xy 403.29078 -99.100242) (xy 403.250518 -99.138986) (xy 403.205037 -99.171446)
			(xy 403.15531 -99.19693) (xy 403.128988 -99.206304) (xy 403.113494 -99.211384) (xy 403.094444 -99.238054)
			(xy 403.094444 -99.750372) (xy 405.89784 -99.750372) (xy 405.901911 -99.69475) (xy 405.914037 -99.640313)
			(xy 405.93396 -99.588222) (xy 405.961256 -99.539587) (xy 405.995342 -99.495444) (xy 406.035491 -99.456735)
			(xy 406.080849 -99.424284) (xy 406.130449 -99.398783) (xy 406.183233 -99.380776) (xy 406.238076 -99.370646)
			(xy 406.29381 -99.368609) (xy 406.349247 -99.374709) (xy 406.403204 -99.388815) (xy 406.454533 -99.410627)
			(xy 406.502139 -99.439681) (xy 406.545007 -99.475356) (xy 406.582224 -99.516893) (xy 406.612997 -99.563406)
			(xy 406.636669 -99.613903) (xy 406.652737 -99.66731) (xy 406.660857 -99.722486) (xy 406.661366 -99.750372)
			(xy 406.660857 -99.778258) (xy 406.652737 -99.833434) (xy 406.636669 -99.886841) (xy 406.612997 -99.937338)
			(xy 406.582224 -99.983851) (xy 406.545007 -100.025388) (xy 406.502139 -100.061063) (xy 406.454533 -100.090117)
			(xy 406.403204 -100.111929) (xy 406.349247 -100.126035) (xy 406.29381 -100.132135) (xy 406.238076 -100.130098)
			(xy 406.183233 -100.119968) (xy 406.130449 -100.101961) (xy 406.080849 -100.07646) (xy 406.035491 -100.044009)
			(xy 405.995342 -100.0053) (xy 405.961256 -99.961157) (xy 405.93396 -99.912522) (xy 405.914037 -99.860431)
			(xy 405.901911 -99.805994) (xy 405.89784 -99.750372) (xy 403.094444 -99.750372) (xy 403.094444 -100.251768)
			(xy 403.113494 -100.278438) (xy 403.128988 -100.283518) (xy 403.155287 -100.292959) (xy 403.205016 -100.318439)
			(xy 403.250499 -100.350896) (xy 403.290765 -100.389638) (xy 403.324953 -100.433835) (xy 403.352332 -100.482544)
			(xy 403.372318 -100.534724) (xy 403.384484 -100.58926) (xy 403.38857 -100.644987) (xy 403.384488 -100.700714)
			(xy 403.372326 -100.755251) (xy 403.352343 -100.807433) (xy 403.324967 -100.856144) (xy 403.290782 -100.900343)
			(xy 403.250519 -100.939087) (xy 403.205038 -100.971548) (xy 403.155311 -100.997031) (xy 403.128988 -101.006402)
			(xy 403.113494 -101.011482) (xy 403.094444 -101.038152) (xy 403.094444 -101.782372) (xy 405.89784 -101.782372)
			(xy 405.901911 -101.72675) (xy 405.914037 -101.672313) (xy 405.93396 -101.620222) (xy 405.961256 -101.571587)
			(xy 405.995342 -101.527444) (xy 406.035491 -101.488735) (xy 406.080849 -101.456284) (xy 406.130449 -101.430783)
			(xy 406.183233 -101.412776) (xy 406.238076 -101.402646) (xy 406.29381 -101.400609) (xy 406.349247 -101.406709)
			(xy 406.403204 -101.420815) (xy 406.454533 -101.442627) (xy 406.502139 -101.471681) (xy 406.545007 -101.507356)
			(xy 406.582224 -101.548893) (xy 406.612997 -101.595406) (xy 406.636669 -101.645903) (xy 406.652737 -101.69931)
			(xy 406.660857 -101.754486) (xy 406.661366 -101.782372) (xy 406.660857 -101.810258) (xy 406.652737 -101.865434)
			(xy 406.636669 -101.918841) (xy 406.612997 -101.969338) (xy 406.582224 -102.015851) (xy 406.545007 -102.057388)
			(xy 406.502139 -102.093063) (xy 406.454533 -102.122117) (xy 406.403204 -102.143929) (xy 406.349247 -102.158035)
			(xy 406.29381 -102.164135) (xy 406.238076 -102.162098) (xy 406.183233 -102.151968) (xy 406.130449 -102.133961)
			(xy 406.080849 -102.10846) (xy 406.035491 -102.076009) (xy 405.995342 -102.0373) (xy 405.961256 -101.993157)
			(xy 405.93396 -101.944522) (xy 405.914037 -101.892431) (xy 405.901911 -101.837994) (xy 405.89784 -101.782372)
			(xy 403.094444 -101.782372) (xy 403.094444 -102.051612) (xy 403.113494 -102.078282) (xy 403.128988 -102.083362)
			(xy 403.155284 -102.092803) (xy 403.205007 -102.118282) (xy 403.250484 -102.150737) (xy 403.290744 -102.189476)
			(xy 403.324926 -102.23367) (xy 403.352301 -102.282374) (xy 403.372283 -102.334549) (xy 403.384445 -102.38908)
			(xy 403.388528 -102.444801) (xy 403.384445 -102.500522) (xy 403.372282 -102.555053) (xy 403.352299 -102.607228)
			(xy 403.324924 -102.655932) (xy 403.290742 -102.700126) (xy 403.250482 -102.738864) (xy 403.205005 -102.771319)
			(xy 403.155282 -102.796798) (xy 403.128988 -102.806246) (xy 403.113494 -102.811326) (xy 403.101341 -102.82834)
			(xy 405.82264 -102.82834) (xy 405.82264 -102.768404) (xy 405.830463 -102.708982) (xy 405.845976 -102.651089)
			(xy 405.868912 -102.595716) (xy 405.898879 -102.54381) (xy 405.935366 -102.49626) (xy 405.977746 -102.45388)
			(xy 406.025296 -102.417393) (xy 406.077202 -102.387426) (xy 406.132575 -102.36449) (xy 406.190468 -102.348977)
			(xy 406.24989 -102.341154) (xy 406.309826 -102.341154) (xy 406.369248 -102.348977) (xy 406.427141 -102.36449)
			(xy 406.482514 -102.387426) (xy 406.53442 -102.417393) (xy 406.58197 -102.45388) (xy 406.598036 -102.469946)
			(xy 415.155616 -102.469946) (xy 415.155616 -102.41001) (xy 415.163439 -102.350588) (xy 415.178952 -102.292695)
			(xy 415.201888 -102.237322) (xy 415.231855 -102.185416) (xy 415.268342 -102.137866) (xy 415.310722 -102.095486)
			(xy 415.358272 -102.058999) (xy 415.410178 -102.029032) (xy 415.465551 -102.006096) (xy 415.523444 -101.990583)
			(xy 415.582866 -101.98276) (xy 415.642802 -101.98276) (xy 415.702224 -101.990583) (xy 415.760117 -102.006096)
			(xy 415.81549 -102.029032) (xy 415.867396 -102.058999) (xy 415.914946 -102.095486) (xy 415.957326 -102.137866)
			(xy 415.993813 -102.185416) (xy 416.02378 -102.237322) (xy 416.046716 -102.292695) (xy 416.062229 -102.350588)
			(xy 416.070052 -102.41001) (xy 416.070542 -102.439978) (xy 416.070052 -102.469946) (xy 416.062229 -102.529368)
			(xy 416.046716 -102.587261) (xy 416.02378 -102.642634) (xy 415.993813 -102.69454) (xy 415.957326 -102.74209)
			(xy 415.914946 -102.78447) (xy 415.867396 -102.820957) (xy 415.81549 -102.850924) (xy 415.760117 -102.87386)
			(xy 415.702224 -102.889373) (xy 415.642802 -102.897196) (xy 415.582866 -102.897196) (xy 415.523444 -102.889373)
			(xy 415.465551 -102.87386) (xy 415.410178 -102.850924) (xy 415.358272 -102.820957) (xy 415.310722 -102.78447)
			(xy 415.268342 -102.74209) (xy 415.231855 -102.69454) (xy 415.201888 -102.642634) (xy 415.178952 -102.587261)
			(xy 415.163439 -102.529368) (xy 415.155616 -102.469946) (xy 406.598036 -102.469946) (xy 406.62435 -102.49626)
			(xy 406.660837 -102.54381) (xy 406.690804 -102.595716) (xy 406.71374 -102.651089) (xy 406.729253 -102.708982)
			(xy 406.737076 -102.768404) (xy 406.737566 -102.798372) (xy 406.737076 -102.82834) (xy 406.729253 -102.887762)
			(xy 406.71374 -102.945655) (xy 406.690804 -103.001028) (xy 406.660837 -103.052934) (xy 406.62435 -103.100484)
			(xy 406.58197 -103.142864) (xy 406.53442 -103.179351) (xy 406.482514 -103.209318) (xy 406.427141 -103.232254)
			(xy 406.369248 -103.247767) (xy 406.309826 -103.25559) (xy 406.24989 -103.25559) (xy 406.190468 -103.247767)
			(xy 406.132575 -103.232254) (xy 406.077202 -103.209318) (xy 406.025296 -103.179351) (xy 405.977746 -103.142864)
			(xy 405.935366 -103.100484) (xy 405.898879 -103.052934) (xy 405.868912 -103.001028) (xy 405.845976 -102.945655)
			(xy 405.830463 -102.887762) (xy 405.82264 -102.82834) (xy 403.101341 -102.82834) (xy 403.094444 -102.837996)
			(xy 403.094444 -103.814372) (xy 405.89784 -103.814372) (xy 405.901911 -103.75875) (xy 405.914037 -103.704313)
			(xy 405.93396 -103.652222) (xy 405.961256 -103.603587) (xy 405.995342 -103.559444) (xy 406.035491 -103.520735)
			(xy 406.080849 -103.488284) (xy 406.130449 -103.462783) (xy 406.183233 -103.444776) (xy 406.238076 -103.434646)
			(xy 406.29381 -103.432609) (xy 406.349247 -103.438709) (xy 406.403204 -103.452815) (xy 406.454533 -103.474627)
			(xy 406.502139 -103.503681) (xy 406.545007 -103.539356) (xy 406.582224 -103.580893) (xy 406.612997 -103.627406)
			(xy 406.636669 -103.677903) (xy 406.652737 -103.73131) (xy 406.660857 -103.786486) (xy 406.661366 -103.814372)
			(xy 406.660857 -103.842258) (xy 406.652737 -103.897434) (xy 406.636669 -103.950841) (xy 406.612997 -104.001338)
			(xy 406.582224 -104.047851) (xy 406.545007 -104.089388) (xy 406.502139 -104.125063) (xy 406.454533 -104.154117)
			(xy 406.403204 -104.175929) (xy 406.349247 -104.190035) (xy 406.29381 -104.196135) (xy 406.238076 -104.194098)
			(xy 406.183233 -104.183968) (xy 406.130449 -104.165961) (xy 406.080849 -104.14046) (xy 406.035491 -104.108009)
			(xy 405.995342 -104.0693) (xy 405.961256 -104.025157) (xy 405.93396 -103.976522) (xy 405.914037 -103.924431)
			(xy 405.901911 -103.869994) (xy 405.89784 -103.814372) (xy 403.094444 -103.814372) (xy 403.094444 -103.85171)
			(xy 403.113494 -103.87838) (xy 403.128988 -103.88346) (xy 403.155284 -103.892901) (xy 403.205007 -103.91838)
			(xy 403.250484 -103.950836) (xy 403.290744 -103.989574) (xy 403.324927 -104.033768) (xy 403.352302 -104.082473)
			(xy 403.372284 -104.134648) (xy 403.384447 -104.189179) (xy 403.388176 -104.240076) (xy 415.230816 -104.240076)
			(xy 415.234887 -104.184454) (xy 415.247013 -104.130017) (xy 415.266936 -104.077926) (xy 415.294232 -104.029291)
			(xy 415.328318 -103.985148) (xy 415.368467 -103.946439) (xy 415.413825 -103.913988) (xy 415.463425 -103.888487)
			(xy 415.516209 -103.87048) (xy 415.571052 -103.86035) (xy 415.626786 -103.858313) (xy 415.682223 -103.864413)
			(xy 415.73618 -103.878519) (xy 415.787509 -103.900331) (xy 415.835115 -103.929385) (xy 415.877983 -103.96506)
			(xy 415.9152 -104.006597) (xy 415.945973 -104.05311) (xy 415.969645 -104.103607) (xy 415.985713 -104.157014)
			(xy 415.993833 -104.21219) (xy 415.994342 -104.240076) (xy 422.213022 -104.240076) (xy 422.217093 -104.184454)
			(xy 422.229219 -104.130017) (xy 422.249142 -104.077926) (xy 422.276438 -104.029291) (xy 422.310524 -103.985148)
			(xy 422.350673 -103.946439) (xy 422.396031 -103.913988) (xy 422.445631 -103.888487) (xy 422.498415 -103.87048)
			(xy 422.553258 -103.86035) (xy 422.608992 -103.858313) (xy 422.664429 -103.864413) (xy 422.718386 -103.878519)
			(xy 422.769715 -103.900331) (xy 422.817321 -103.929385) (xy 422.860189 -103.96506) (xy 422.897406 -104.006597)
			(xy 422.928179 -104.05311) (xy 422.951851 -104.103607) (xy 422.967919 -104.157014) (xy 422.976039 -104.21219)
			(xy 422.976548 -104.240076) (xy 422.976039 -104.267962) (xy 422.967919 -104.323138) (xy 422.951851 -104.376545)
			(xy 422.928179 -104.427042) (xy 422.897406 -104.473555) (xy 422.860189 -104.515092) (xy 422.817321 -104.550767)
			(xy 422.769715 -104.579821) (xy 422.718386 -104.601633) (xy 422.664429 -104.615739) (xy 422.608992 -104.621839)
			(xy 422.553258 -104.619802) (xy 422.498415 -104.609672) (xy 422.445631 -104.591665) (xy 422.396031 -104.566164)
			(xy 422.350673 -104.533713) (xy 422.310524 -104.495004) (xy 422.276438 -104.450861) (xy 422.249142 -104.402226)
			(xy 422.229219 -104.350135) (xy 422.217093 -104.295698) (xy 422.213022 -104.240076) (xy 415.994342 -104.240076)
			(xy 415.993833 -104.267962) (xy 415.985713 -104.323138) (xy 415.969645 -104.376545) (xy 415.945973 -104.427042)
			(xy 415.9152 -104.473555) (xy 415.877983 -104.515092) (xy 415.835115 -104.550767) (xy 415.787509 -104.579821)
			(xy 415.73618 -104.601633) (xy 415.682223 -104.615739) (xy 415.626786 -104.621839) (xy 415.571052 -104.619802)
			(xy 415.516209 -104.609672) (xy 415.463425 -104.591665) (xy 415.413825 -104.566164) (xy 415.368467 -104.533713)
			(xy 415.328318 -104.495004) (xy 415.294232 -104.450861) (xy 415.266936 -104.402226) (xy 415.247013 -104.350135)
			(xy 415.234887 -104.295698) (xy 415.230816 -104.240076) (xy 403.388176 -104.240076) (xy 403.38853 -104.244901)
			(xy 403.384447 -104.300622) (xy 403.372284 -104.355153) (xy 403.352301 -104.407328) (xy 403.324926 -104.456033)
			(xy 403.290744 -104.500227) (xy 403.250483 -104.538965) (xy 403.205006 -104.571421) (xy 403.155283 -104.5969)
			(xy 403.128988 -104.606344) (xy 403.113494 -104.611424) (xy 403.094444 -104.638094) (xy 403.094444 -104.86034)
			(xy 405.82264 -104.86034) (xy 405.82264 -104.800404) (xy 405.830463 -104.740982) (xy 405.845976 -104.683089)
			(xy 405.868912 -104.627716) (xy 405.898879 -104.57581) (xy 405.935366 -104.52826) (xy 405.977746 -104.48588)
			(xy 406.025296 -104.449393) (xy 406.077202 -104.419426) (xy 406.132575 -104.39649) (xy 406.190468 -104.380977)
			(xy 406.24989 -104.373154) (xy 406.309826 -104.373154) (xy 406.369248 -104.380977) (xy 406.427141 -104.39649)
			(xy 406.482514 -104.419426) (xy 406.53442 -104.449393) (xy 406.58197 -104.48588) (xy 406.62435 -104.52826)
			(xy 406.660837 -104.57581) (xy 406.690804 -104.627716) (xy 406.71374 -104.683089) (xy 406.729253 -104.740982)
			(xy 406.737076 -104.800404) (xy 406.737566 -104.830372) (xy 406.737076 -104.86034) (xy 406.729253 -104.919762)
			(xy 406.71374 -104.977655) (xy 406.690804 -105.033028) (xy 406.660837 -105.084934) (xy 406.62435 -105.132484)
			(xy 406.58197 -105.174864) (xy 406.53442 -105.211351) (xy 406.482514 -105.241318) (xy 406.427141 -105.264254)
			(xy 406.369248 -105.279767) (xy 406.309826 -105.28759) (xy 406.24989 -105.28759) (xy 406.190468 -105.279767)
			(xy 406.132575 -105.264254) (xy 406.077202 -105.241318) (xy 406.025296 -105.211351) (xy 405.977746 -105.174864)
			(xy 405.935366 -105.132484) (xy 405.898879 -105.084934) (xy 405.868912 -105.033028) (xy 405.845976 -104.977655)
			(xy 405.830463 -104.919762) (xy 405.82264 -104.86034) (xy 403.094444 -104.86034) (xy 403.094444 -105.651554)
			(xy 403.113494 -105.678224) (xy 403.128988 -105.683304) (xy 403.155281 -105.692745) (xy 403.204998 -105.718223)
			(xy 403.250469 -105.750677) (xy 403.290723 -105.789413) (xy 403.3249 -105.833603) (xy 403.35227 -105.882304)
			(xy 403.372248 -105.934474) (xy 403.384408 -105.988999) (xy 403.388489 -106.044715) (xy 403.384403 -106.10043)
			(xy 403.37224 -106.154954) (xy 403.352258 -106.207123) (xy 403.324884 -106.255822) (xy 403.290703 -106.300009)
			(xy 403.250446 -106.338742) (xy 403.204972 -106.371193) (xy 403.155254 -106.396667) (xy 403.128988 -106.406188)
			(xy 403.113494 -106.411268) (xy 403.094444 -106.437938) (xy 403.094444 -107.451652) (xy 403.113494 -107.478322)
			(xy 403.128988 -107.483402) (xy 403.155281 -107.492843) (xy 403.204998 -107.518321) (xy 403.250469 -107.550775)
			(xy 403.290724 -107.589511) (xy 403.324901 -107.633701) (xy 403.352272 -107.682402) (xy 403.37225 -107.734573)
			(xy 403.38441 -107.789098) (xy 403.38849 -107.844814) (xy 403.384405 -107.90053) (xy 403.372242 -107.955054)
			(xy 403.35226 -108.007224) (xy 403.324886 -108.055922) (xy 403.290705 -108.10011) (xy 403.250448 -108.138843)
			(xy 403.204974 -108.171294) (xy 403.155255 -108.196769) (xy 403.128988 -108.206286) (xy 403.113494 -108.211366)
			(xy 403.094444 -108.238036) (xy 403.094444 -109.25175) (xy 403.113494 -109.27842) (xy 403.128988 -109.2835)
			(xy 403.155281 -109.292941) (xy 403.204999 -109.318419) (xy 403.25047 -109.350873) (xy 403.290725 -109.389609)
			(xy 403.324903 -109.4338) (xy 403.352273 -109.482501) (xy 403.372252 -109.534672) (xy 403.384411 -109.589197)
			(xy 403.388492 -109.644914) (xy 403.384407 -109.700629) (xy 403.372244 -109.755154) (xy 403.352262 -109.807324)
			(xy 403.324888 -109.856023) (xy 403.290707 -109.900211) (xy 403.250449 -109.938944) (xy 403.204975 -109.971395)
			(xy 403.155257 -109.99687) (xy 403.128988 -110.006384) (xy 403.113494 -110.011464) (xy 403.094444 -110.038134)
			(xy 403.094444 -111.051848) (xy 403.113494 -111.078518) (xy 403.128988 -111.083598) (xy 403.155282 -111.093039)
			(xy 403.204999 -111.118517) (xy 403.250471 -111.150971) (xy 403.290726 -111.189707) (xy 403.324904 -111.233898)
			(xy 403.352275 -111.282599) (xy 403.372253 -111.33477) (xy 403.384413 -111.389297) (xy 403.388494 -111.445013)
			(xy 403.384409 -111.500729) (xy 403.372246 -111.555254) (xy 403.352264 -111.607424) (xy 403.32489 -111.656123)
			(xy 403.290709 -111.700312) (xy 403.250451 -111.739045) (xy 403.204977 -111.771496) (xy 403.155258 -111.796972)
			(xy 403.128988 -111.806482) (xy 403.113494 -111.811562) (xy 403.094444 -111.838232) (xy 403.094444 -115.801394)
			(xy 404.147272 -115.801394) (xy 404.151343 -115.745772) (xy 404.163469 -115.691335) (xy 404.183392 -115.639244)
			(xy 404.210688 -115.590609) (xy 404.244774 -115.546466) (xy 404.284923 -115.507757) (xy 404.330281 -115.475306)
			(xy 404.379881 -115.449805) (xy 404.432665 -115.431798) (xy 404.487508 -115.421668) (xy 404.543242 -115.419631)
			(xy 404.598679 -115.425731) (xy 404.652636 -115.439837) (xy 404.703965 -115.461649) (xy 404.751571 -115.490703)
			(xy 404.794439 -115.526378) (xy 404.831656 -115.567915) (xy 404.862429 -115.614428) (xy 404.886101 -115.664925)
			(xy 404.902169 -115.718332) (xy 404.910289 -115.773508) (xy 404.910798 -115.801394) (xy 404.910289 -115.82928)
			(xy 404.902169 -115.884456) (xy 404.89086 -115.922044) (xy 411.503366 -115.922044) (xy 411.507437 -115.866422)
			(xy 411.519563 -115.811985) (xy 411.539486 -115.759894) (xy 411.566782 -115.711259) (xy 411.600868 -115.667116)
			(xy 411.641017 -115.628407) (xy 411.686375 -115.595956) (xy 411.735975 -115.570455) (xy 411.788759 -115.552448)
			(xy 411.843602 -115.542318) (xy 411.899336 -115.540281) (xy 411.954773 -115.546381) (xy 412.00873 -115.560487)
			(xy 412.060059 -115.582299) (xy 412.107665 -115.611353) (xy 412.150533 -115.647028) (xy 412.18775 -115.688565)
			(xy 412.218523 -115.735078) (xy 412.242195 -115.785575) (xy 412.258263 -115.838982) (xy 412.266383 -115.894158)
			(xy 412.266892 -115.922044) (xy 412.266383 -115.94993) (xy 412.258263 -116.005106) (xy 412.242195 -116.058513)
			(xy 412.218523 -116.10901) (xy 412.18775 -116.155523) (xy 412.150533 -116.19706) (xy 412.107665 -116.232735)
			(xy 412.060059 -116.261789) (xy 412.00873 -116.283601) (xy 411.954773 -116.297707) (xy 411.899336 -116.303807)
			(xy 411.843602 -116.30177) (xy 411.788759 -116.29164) (xy 411.735975 -116.273633) (xy 411.686375 -116.248132)
			(xy 411.641017 -116.215681) (xy 411.600868 -116.176972) (xy 411.566782 -116.132829) (xy 411.539486 -116.084194)
			(xy 411.519563 -116.032103) (xy 411.507437 -115.977666) (xy 411.503366 -115.922044) (xy 404.89086 -115.922044)
			(xy 404.886101 -115.937863) (xy 404.862429 -115.98836) (xy 404.831656 -116.034873) (xy 404.794439 -116.07641)
			(xy 404.751571 -116.112085) (xy 404.703965 -116.141139) (xy 404.652636 -116.162951) (xy 404.598679 -116.177057)
			(xy 404.543242 -116.183157) (xy 404.487508 -116.18112) (xy 404.432665 -116.17099) (xy 404.379881 -116.152983)
			(xy 404.330281 -116.127482) (xy 404.284923 -116.095031) (xy 404.244774 -116.056322) (xy 404.210688 -116.012179)
			(xy 404.183392 -115.963544) (xy 404.163469 -115.911453) (xy 404.151343 -115.857016) (xy 404.147272 -115.801394)
			(xy 403.094444 -115.801394) (xy 403.094444 -118.194328) (xy 403.844504 -118.194328) (xy 403.848575 -118.138706)
			(xy 403.860701 -118.084269) (xy 403.880624 -118.032178) (xy 403.90792 -117.983543) (xy 403.942006 -117.9394)
			(xy 403.982155 -117.900691) (xy 404.027513 -117.86824) (xy 404.077113 -117.842739) (xy 404.129897 -117.824732)
			(xy 404.18474 -117.814602) (xy 404.240474 -117.812565) (xy 404.295911 -117.818665) (xy 404.349868 -117.832771)
			(xy 404.401197 -117.854583) (xy 404.448803 -117.883637) (xy 404.491671 -117.919312) (xy 404.528888 -117.960849)
			(xy 404.559661 -118.007362) (xy 404.583333 -118.057859) (xy 404.599401 -118.111266) (xy 404.607521 -118.166442)
			(xy 404.60803 -118.194328) (xy 404.607521 -118.222214) (xy 404.599401 -118.27739) (xy 404.583333 -118.330797)
			(xy 404.568723 -118.361964) (xy 411.120572 -118.361964) (xy 411.120572 -118.302028) (xy 411.128395 -118.242606)
			(xy 411.143908 -118.184713) (xy 411.166844 -118.12934) (xy 411.196811 -118.077434) (xy 411.233298 -118.029884)
			(xy 411.275678 -117.987504) (xy 411.323228 -117.951017) (xy 411.375134 -117.92105) (xy 411.430507 -117.898114)
			(xy 411.4884 -117.882601) (xy 411.547822 -117.874778) (xy 411.607758 -117.874778) (xy 411.66718 -117.882601)
			(xy 411.725073 -117.898114) (xy 411.780446 -117.92105) (xy 411.832352 -117.951017) (xy 411.879902 -117.987504)
			(xy 411.922282 -118.029884) (xy 411.958769 -118.077434) (xy 411.988736 -118.12934) (xy 412.011672 -118.184713)
			(xy 412.027185 -118.242606) (xy 412.035008 -118.302028) (xy 412.035498 -118.331996) (xy 412.035008 -118.361964)
			(xy 412.027185 -118.421386) (xy 412.011672 -118.479279) (xy 411.988736 -118.534652) (xy 411.958769 -118.586558)
			(xy 411.922282 -118.634108) (xy 411.879902 -118.676488) (xy 411.832352 -118.712975) (xy 411.780446 -118.742942)
			(xy 411.725073 -118.765878) (xy 411.66718 -118.781391) (xy 411.607758 -118.789214) (xy 411.547822 -118.789214)
			(xy 411.4884 -118.781391) (xy 411.430507 -118.765878) (xy 411.375134 -118.742942) (xy 411.323228 -118.712975)
			(xy 411.275678 -118.676488) (xy 411.233298 -118.634108) (xy 411.196811 -118.586558) (xy 411.166844 -118.534652)
			(xy 411.143908 -118.479279) (xy 411.128395 -118.421386) (xy 411.120572 -118.361964) (xy 404.568723 -118.361964)
			(xy 404.559661 -118.381294) (xy 404.528888 -118.427807) (xy 404.491671 -118.469344) (xy 404.448803 -118.505019)
			(xy 404.401197 -118.534073) (xy 404.349868 -118.555885) (xy 404.295911 -118.569991) (xy 404.240474 -118.576091)
			(xy 404.18474 -118.574054) (xy 404.129897 -118.563924) (xy 404.077113 -118.545917) (xy 404.027513 -118.520416)
			(xy 403.982155 -118.487965) (xy 403.942006 -118.449256) (xy 403.90792 -118.405113) (xy 403.880624 -118.356478)
			(xy 403.860701 -118.304387) (xy 403.848575 -118.24995) (xy 403.844504 -118.194328) (xy 403.094444 -118.194328)
			(xy 403.094444 -118.361714) (xy 403.113494 -118.388384) (xy 403.128988 -118.393464) (xy 403.155284 -118.402905)
			(xy 403.205006 -118.428384) (xy 403.250483 -118.460839) (xy 403.290743 -118.499578) (xy 403.324925 -118.543771)
			(xy 403.352299 -118.592476) (xy 403.372281 -118.644651) (xy 403.384443 -118.699181) (xy 403.388526 -118.754902)
			(xy 403.384443 -118.810623) (xy 403.37228 -118.865153) (xy 403.352297 -118.917328) (xy 403.324923 -118.966032)
			(xy 403.29074 -119.010225) (xy 403.25048 -119.048963) (xy 403.205003 -119.081418) (xy 403.155281 -119.106897)
			(xy 403.128988 -119.116348) (xy 403.113494 -119.121428) (xy 403.094444 -119.148098) (xy 403.094444 -120.161812)
			(xy 403.113494 -120.188482) (xy 403.128988 -120.193562) (xy 403.155284 -120.203003) (xy 403.205007 -120.228482)
			(xy 403.250484 -120.260937) (xy 403.290744 -120.299676) (xy 403.324926 -120.34387) (xy 403.352301 -120.392574)
			(xy 403.372283 -120.444749) (xy 403.384445 -120.49928) (xy 403.388528 -120.555001) (xy 403.384445 -120.610722)
			(xy 403.372282 -120.665253) (xy 403.352299 -120.717428) (xy 403.324924 -120.766132) (xy 403.290742 -120.810326)
			(xy 403.250482 -120.849064) (xy 403.205005 -120.881519) (xy 403.155282 -120.906998) (xy 403.128988 -120.916446)
			(xy 403.113494 -120.921526) (xy 403.094444 -120.948196) (xy 403.094444 -121.961656) (xy 403.113494 -121.988326)
			(xy 403.128988 -121.993406) (xy 403.155281 -122.002846) (xy 403.204997 -122.028325) (xy 403.250468 -122.060779)
			(xy 403.290722 -122.099514) (xy 403.324899 -122.143705) (xy 403.352269 -122.192405) (xy 403.372247 -122.244575)
			(xy 403.384406 -122.2991) (xy 403.388487 -122.354815) (xy 403.384402 -122.41053) (xy 403.372238 -122.465055)
			(xy 403.352256 -122.517223) (xy 403.324882 -122.565921) (xy 403.290701 -122.610109) (xy 403.250444 -122.648841)
			(xy 403.204971 -122.681291) (xy 403.155253 -122.706766) (xy 403.128988 -122.71629) (xy 403.113494 -122.72137)
			(xy 403.094444 -122.74804) (xy 403.094444 -123.761754) (xy 403.113494 -123.788424) (xy 403.128988 -123.793504)
			(xy 403.153826 -123.802409) (xy 403.200978 -123.826092) (xy 403.24442 -123.856041) (xy 403.283325 -123.891687)
			(xy 403.316952 -123.932349) (xy 403.34466 -123.977253) (xy 403.365922 -124.025545) (xy 403.380333 -124.076304)
			(xy 403.387619 -124.128564) (xy 403.388068 -124.154946) (xy 403.387511 -124.184964) (xy 403.378113 -124.244259)
			(xy 403.359541 -124.30135) (xy 403.332253 -124.354826) (xy 403.296924 -124.403365) (xy 403.276054 -124.424948)
			(xy 403.269216 -124.432316) (xy 403.261476 -124.45085) (xy 403.261473 -124.470935) (xy 403.269207 -124.489471)
			(xy 403.276054 -124.49683) (xy 406.267673 -127.488449) (xy 417.390602 -127.488449) (xy 417.390602 -127.401551)
			(xy 417.39862 -127.315024) (xy 417.414587 -127.229606) (xy 417.438367 -127.146025) (xy 417.469758 -127.064995)
			(xy 417.508491 -126.987207) (xy 417.554236 -126.913325) (xy 417.606603 -126.843978) (xy 417.665145 -126.77976)
			(xy 417.729363 -126.721216) (xy 417.798708 -126.668848) (xy 417.87259 -126.623101) (xy 417.950377 -126.584366)
			(xy 418.031406 -126.552974) (xy 418.114986 -126.529191) (xy 418.200404 -126.513222) (xy 418.286931 -126.505203)
			(xy 418.33038 -126.5047) (xy 420.18458 -126.5047) (xy 420.228032 -126.505169) (xy 420.314564 -126.513186)
			(xy 420.399988 -126.529153) (xy 420.483574 -126.552934) (xy 420.564609 -126.584325) (xy 420.642402 -126.62306)
			(xy 420.716289 -126.668808) (xy 420.78564 -126.721178) (xy 420.849863 -126.779723) (xy 420.90841 -126.843945)
			(xy 420.960781 -126.913294) (xy 421.00653 -126.987181) (xy 421.045267 -127.064973) (xy 421.07666 -127.146007)
			(xy 421.100442 -127.229593) (xy 421.116411 -127.315016) (xy 421.12443 -127.401548) (xy 421.12443 -127.488452)
			(xy 421.116411 -127.574984) (xy 421.100442 -127.660407) (xy 421.07666 -127.743993) (xy 421.045267 -127.825027)
			(xy 421.00653 -127.902819) (xy 420.960781 -127.976706) (xy 420.90841 -128.046055) (xy 420.849863 -128.110277)
			(xy 420.78564 -128.168822) (xy 420.716289 -128.221192) (xy 420.642402 -128.26694) (xy 420.564609 -128.305675)
			(xy 420.483574 -128.337066) (xy 420.399988 -128.360847) (xy 420.314564 -128.376814) (xy 420.228032 -128.384831)
			(xy 420.18458 -128.385316) (xy 418.33038 -128.385316) (xy 418.286931 -128.384797) (xy 418.200404 -128.376778)
			(xy 418.114986 -128.360809) (xy 418.031406 -128.337026) (xy 417.950377 -128.305634) (xy 417.87259 -128.266899)
			(xy 417.798708 -128.221152) (xy 417.729363 -128.168784) (xy 417.665145 -128.11024) (xy 417.606603 -128.046022)
			(xy 417.554236 -127.976675) (xy 417.508491 -127.902793) (xy 417.469758 -127.825005) (xy 417.438367 -127.743975)
			(xy 417.414587 -127.660394) (xy 417.39862 -127.574976) (xy 417.390602 -127.488449) (xy 406.267673 -127.488449)
			(xy 409.55341 -130.774186) (xy 409.560809 -130.781032) (xy 409.579407 -130.788765) (xy 409.589478 -130.789172)
		)
		(stroke
			(width 0)
			(type solid)
		)
		(fill yes)
		(layer "B.Cu")
		(net "P3V3_NIC7")
	)
	(gr_poly
		(pts
			(xy 66.548508 -130.789172) (xy 66.558526 -130.78875) (xy 66.577035 -130.781078) (xy 66.591198 -130.766905)
			(xy 66.598858 -130.74839) (xy 66.599308 -130.738372) (xy 66.599308 -129.913634) (xy 66.599816 -129.893822)
			(xy 66.599816 -129.89306) (xy 66.599783 -129.881429) (xy 66.590523 -129.860119) (xy 66.582036 -129.852166)
			(xy 66.557652 -129.831592) (xy 66.548727 -129.824817) (xy 66.527112 -129.819013) (xy 66.515996 -129.820416)
			(xy 66.515742 -129.820416) (xy 66.498932 -129.823259) (xy 66.464972 -129.826311) (xy 66.447924 -129.826512)
			(xy 66.44767 -129.826512) (xy 66.42042 -129.826024) (xy 66.366475 -129.818264) (xy 66.314183 -129.802906)
			(xy 66.264609 -129.780263) (xy 66.218762 -129.750796) (xy 66.177575 -129.715104) (xy 66.141886 -129.673914)
			(xy 66.112422 -129.628064) (xy 66.089783 -129.578489) (xy 66.07443 -129.526196) (xy 66.066674 -129.47225)
			(xy 66.066674 -129.41775) (xy 66.07443 -129.363804) (xy 66.089783 -129.311511) (xy 66.112422 -129.261936)
			(xy 66.141886 -129.216086) (xy 66.177575 -129.174896) (xy 66.218762 -129.139204) (xy 66.264609 -129.109737)
			(xy 66.314183 -129.087094) (xy 66.366475 -129.071736) (xy 66.42042 -129.063976) (xy 66.44767 -129.063496)
			(xy 66.474674 -129.063969) (xy 66.528141 -129.071593) (xy 66.579998 -129.08668) (xy 66.629211 -129.108928)
			(xy 66.674795 -129.137893) (xy 66.71584 -129.172995) (xy 66.751525 -129.213533) (xy 66.781139 -129.258698)
			(xy 66.804089 -129.307587) (xy 66.819916 -129.359224) (xy 66.824606 -129.385822) (xy 66.826384 -129.396744)
			(xy 66.83756 -129.41427) (xy 66.906902 -129.460498) (xy 66.913289 -129.464393) (xy 66.927619 -129.468659)
			(xy 66.935096 -129.46888) (xy 66.94932 -129.46888) (xy 66.955162 -129.46761) (xy 66.98027 -129.462117)
			(xy 67.031319 -129.456135) (xy 67.057016 -129.455672) (xy 67.057524 -129.455672) (xy 67.083999 -129.456109)
			(xy 67.136582 -129.462352) (xy 67.162426 -129.468118) (xy 67.16522 -129.46888) (xy 67.171824 -129.469642)
			(xy 67.180759 -129.470267) (xy 67.198167 -129.466103) (xy 67.20586 -129.461514) (xy 67.27698 -129.41427)
			(xy 67.288156 -129.396744) (xy 67.289934 -129.385822) (xy 67.294587 -129.359215) (xy 67.310408 -129.307572)
			(xy 67.333355 -129.258677) (xy 67.36297 -129.213507) (xy 67.39866 -129.172966) (xy 67.439711 -129.137864)
			(xy 67.485303 -129.108904) (xy 67.534524 -129.086664) (xy 67.58639 -129.071589) (xy 67.639864 -129.06398)
			(xy 67.66687 -129.063496) (xy 67.694124 -129.063957) (xy 67.748078 -129.071711) (xy 67.800378 -129.087064)
			(xy 67.849962 -129.109705) (xy 67.895818 -129.139171) (xy 67.937014 -129.174865) (xy 67.972711 -129.216058)
			(xy 68.002181 -129.261912) (xy 68.024826 -129.311493) (xy 68.040183 -129.363793) (xy 68.047941 -129.417746)
			(xy 68.047941 -129.445004) (xy 69.266052 -129.445004) (xy 69.270123 -129.389382) (xy 69.282249 -129.334945)
			(xy 69.302172 -129.282854) (xy 69.329468 -129.234219) (xy 69.363554 -129.190076) (xy 69.403703 -129.151367)
			(xy 69.449061 -129.118916) (xy 69.498661 -129.093415) (xy 69.551445 -129.075408) (xy 69.606288 -129.065278)
			(xy 69.662022 -129.063241) (xy 69.717459 -129.069341) (xy 69.771416 -129.083447) (xy 69.822745 -129.105259)
			(xy 69.870351 -129.134313) (xy 69.913219 -129.169988) (xy 69.950436 -129.211525) (xy 69.981209 -129.258038)
			(xy 70.004881 -129.308535) (xy 70.020949 -129.361942) (xy 70.029069 -129.417118) (xy 70.029578 -129.445004)
			(xy 71.885046 -129.445004) (xy 71.889117 -129.389382) (xy 71.901243 -129.334945) (xy 71.921166 -129.282854)
			(xy 71.948462 -129.234219) (xy 71.982548 -129.190076) (xy 72.022697 -129.151367) (xy 72.068055 -129.118916)
			(xy 72.117655 -129.093415) (xy 72.170439 -129.075408) (xy 72.225282 -129.065278) (xy 72.281016 -129.063241)
			(xy 72.336453 -129.069341) (xy 72.39041 -129.083447) (xy 72.441739 -129.105259) (xy 72.489345 -129.134313)
			(xy 72.532213 -129.169988) (xy 72.56943 -129.211525) (xy 72.600203 -129.258038) (xy 72.623875 -129.308535)
			(xy 72.639943 -129.361942) (xy 72.648063 -129.417118) (xy 72.648572 -129.445004) (xy 73.866246 -129.445004)
			(xy 73.870317 -129.389382) (xy 73.882443 -129.334945) (xy 73.902366 -129.282854) (xy 73.929662 -129.234219)
			(xy 73.963748 -129.190076) (xy 74.003897 -129.151367) (xy 74.049255 -129.118916) (xy 74.098855 -129.093415)
			(xy 74.151639 -129.075408) (xy 74.206482 -129.065278) (xy 74.262216 -129.063241) (xy 74.317653 -129.069341)
			(xy 74.37161 -129.083447) (xy 74.422939 -129.105259) (xy 74.470545 -129.134313) (xy 74.513413 -129.169988)
			(xy 74.55063 -129.211525) (xy 74.581403 -129.258038) (xy 74.605075 -129.308535) (xy 74.621143 -129.361942)
			(xy 74.629263 -129.417118) (xy 74.629772 -129.445004) (xy 74.629263 -129.47289) (xy 74.621143 -129.528066)
			(xy 74.605075 -129.581473) (xy 74.581403 -129.63197) (xy 74.55063 -129.678483) (xy 74.513413 -129.72002)
			(xy 74.470545 -129.755695) (xy 74.422939 -129.784749) (xy 74.37161 -129.806561) (xy 74.317653 -129.820667)
			(xy 74.262216 -129.826767) (xy 74.206482 -129.82473) (xy 74.151639 -129.8146) (xy 74.098855 -129.796593)
			(xy 74.049255 -129.771092) (xy 74.003897 -129.738641) (xy 73.963748 -129.699932) (xy 73.929662 -129.655789)
			(xy 73.902366 -129.607154) (xy 73.882443 -129.555063) (xy 73.870317 -129.500626) (xy 73.866246 -129.445004)
			(xy 72.648572 -129.445004) (xy 72.648063 -129.47289) (xy 72.639943 -129.528066) (xy 72.623875 -129.581473)
			(xy 72.600203 -129.63197) (xy 72.56943 -129.678483) (xy 72.532213 -129.72002) (xy 72.489345 -129.755695)
			(xy 72.441739 -129.784749) (xy 72.39041 -129.806561) (xy 72.336453 -129.820667) (xy 72.281016 -129.826767)
			(xy 72.225282 -129.82473) (xy 72.170439 -129.8146) (xy 72.117655 -129.796593) (xy 72.068055 -129.771092)
			(xy 72.022697 -129.738641) (xy 71.982548 -129.699932) (xy 71.948462 -129.655789) (xy 71.921166 -129.607154)
			(xy 71.901243 -129.555063) (xy 71.889117 -129.500626) (xy 71.885046 -129.445004) (xy 70.029578 -129.445004)
			(xy 70.029069 -129.47289) (xy 70.020949 -129.528066) (xy 70.004881 -129.581473) (xy 69.981209 -129.63197)
			(xy 69.950436 -129.678483) (xy 69.913219 -129.72002) (xy 69.870351 -129.755695) (xy 69.822745 -129.784749)
			(xy 69.771416 -129.806561) (xy 69.717459 -129.820667) (xy 69.662022 -129.826767) (xy 69.606288 -129.82473)
			(xy 69.551445 -129.8146) (xy 69.498661 -129.796593) (xy 69.449061 -129.771092) (xy 69.403703 -129.738641)
			(xy 69.363554 -129.699932) (xy 69.329468 -129.655789) (xy 69.302172 -129.607154) (xy 69.282249 -129.555063)
			(xy 69.270123 -129.500626) (xy 69.266052 -129.445004) (xy 68.047941 -129.445004) (xy 68.047941 -129.472254)
			(xy 68.040183 -129.526207) (xy 68.024826 -129.578507) (xy 68.002181 -129.628088) (xy 67.972711 -129.673942)
			(xy 67.937014 -129.715135) (xy 67.895818 -129.750829) (xy 67.849962 -129.780295) (xy 67.800378 -129.802936)
			(xy 67.748078 -129.818289) (xy 67.694124 -129.826043) (xy 67.66687 -129.826512) (xy 67.666362 -129.826512)
			(xy 67.65041 -129.826351) (xy 67.618618 -129.82368) (xy 67.602862 -129.821178) (xy 67.598544 -129.820416)
			(xy 67.587876 -129.818384) (xy 67.567048 -129.823718) (xy 67.558412 -129.830322) (xy 67.557396 -129.831084)
			(xy 67.532504 -129.852166) (xy 67.52405 -129.860142) (xy 67.514796 -129.881437) (xy 67.514724 -129.89306)
			(xy 67.514724 -129.893822) (xy 67.515232 -129.913634) (xy 67.515232 -130.738372) (xy 67.515647 -130.748395)
			(xy 67.523313 -130.766916) (xy 67.537488 -130.781089) (xy 67.556009 -130.788753) (xy 67.566032 -130.789172)
			(xy 69.351652 -130.789172) (xy 69.369432 -130.78206) (xy 69.376798 -130.774948) (xy 69.427598 -130.72618)
			(xy 69.443092 -130.692144) (xy 69.444912 -130.664526) (xy 69.455527 -130.610208) (xy 69.473882 -130.557994)
			(xy 69.499589 -130.50898) (xy 69.532111 -130.464197) (xy 69.570763 -130.424584) (xy 69.614734 -130.390973)
			(xy 69.663102 -130.36407) (xy 69.71485 -130.344439) (xy 69.768891 -130.332493) (xy 69.824092 -130.328483)
			(xy 69.879293 -130.332493) (xy 69.933334 -130.344439) (xy 69.985082 -130.36407) (xy 70.03345 -130.390973)
			(xy 70.077421 -130.424584) (xy 70.116073 -130.464197) (xy 70.148595 -130.50898) (xy 70.174302 -130.557994)
			(xy 70.192657 -130.610208) (xy 70.203272 -130.664526) (xy 70.205092 -130.692144) (xy 70.220586 -130.72618)
			(xy 70.271386 -130.774948) (xy 70.278735 -130.781438) (xy 70.296897 -130.788774) (xy 70.306692 -130.789172)
			(xy 80.530954 -130.789172) (xy 80.542709 -130.788576) (xy 80.563762 -130.778113) (xy 80.57134 -130.769106)
			(xy 80.575912 -130.763264) (xy 80.577182 -130.761486) (xy 80.592236 -130.738699) (xy 80.627837 -130.697284)
			(xy 80.668994 -130.661384) (xy 80.714861 -130.631738) (xy 80.764496 -130.608956) (xy 80.816878 -130.593504)
			(xy 80.870931 -130.5857) (xy 80.898238 -130.58521) (xy 80.913031 -130.585354) (xy 80.942528 -130.587642)
			(xy 80.957166 -130.589782) (xy 80.968088 -130.59156) (xy 80.989424 -130.585464) (xy 81.05648 -130.528314)
			(xy 81.064509 -130.520744) (xy 81.073738 -130.500727) (xy 81.07426 -130.489706) (xy 81.07426 -130.184906)
			(xy 81.073723 -130.173885) (xy 81.064513 -130.153861) (xy 81.05648 -130.146298) (xy 80.989424 -130.089148)
			(xy 80.968088 -130.083052) (xy 80.957166 -130.08483) (xy 80.942529 -130.086976) (xy 80.913031 -130.089261)
			(xy 80.898238 -130.089402) (xy 80.870984 -130.088941) (xy 80.81703 -130.081189) (xy 80.764728 -130.065836)
			(xy 80.715144 -130.043196) (xy 80.669287 -130.01373) (xy 80.62809 -129.978037) (xy 80.592393 -129.936844)
			(xy 80.562922 -129.890989) (xy 80.540277 -129.841408) (xy 80.524919 -129.789108) (xy 80.517161 -129.735154)
			(xy 80.517161 -129.680646) (xy 80.524919 -129.626692) (xy 80.540277 -129.574392) (xy 80.562922 -129.524811)
			(xy 80.592393 -129.478956) (xy 80.62809 -129.437763) (xy 80.669287 -129.40207) (xy 80.715144 -129.372604)
			(xy 80.764728 -129.349964) (xy 80.81703 -129.334611) (xy 80.870984 -129.326859) (xy 80.898238 -129.326386)
			(xy 80.898492 -129.326386) (xy 80.928006 -129.326966) (xy 80.986324 -129.336106) (xy 81.042542 -129.354108)
			(xy 81.095321 -129.380543) (xy 81.143406 -129.414783) (xy 81.185652 -129.456011) (xy 81.2038 -129.479294)
			(xy 81.209134 -129.486406) (xy 81.238852 -129.506218) (xy 81.24825 -129.50825) (xy 81.265268 -129.512314)
			(xy 81.271321 -129.5135) (xy 81.283651 -129.513234) (xy 81.289652 -129.511806) (xy 81.3054 -129.507742)
			(xy 81.310988 -129.504694) (xy 81.336476 -129.491115) (xy 81.390138 -129.469763) (xy 81.446056 -129.455321)
			(xy 81.503346 -129.448019) (xy 81.532222 -129.447544) (xy 81.561868 -129.448024) (xy 81.620659 -129.45571)
			(xy 81.677961 -129.470937) (xy 81.732812 -129.49345) (xy 81.75879 -129.507742) (xy 81.767426 -129.512568)
			(xy 81.786476 -129.515362) (xy 81.817718 -129.507742) (xy 81.826862 -129.50571) (xy 81.85531 -129.486406)
			(xy 81.860644 -129.479294) (xy 81.878764 -129.455981) (xy 81.920986 -129.41471) (xy 81.969067 -129.380444)
			(xy 82.021857 -129.354002) (xy 82.078094 -129.336018) (xy 82.136431 -129.326921) (xy 82.165952 -129.326386)
			(xy 82.166206 -129.326386) (xy 82.193457 -129.326872) (xy 82.247405 -129.33463) (xy 82.2997 -129.349985)
			(xy 82.349277 -129.372627) (xy 82.395128 -129.402094) (xy 82.436318 -129.437786) (xy 82.472009 -129.478977)
			(xy 82.501476 -129.524828) (xy 82.524117 -129.574405) (xy 82.539472 -129.626701) (xy 82.547228 -129.680649)
			(xy 82.547228 -129.735151) (xy 82.539472 -129.789099) (xy 82.524117 -129.841395) (xy 82.501476 -129.890972)
			(xy 82.472009 -129.936823) (xy 82.436318 -129.978014) (xy 82.395128 -130.013706) (xy 82.349277 -130.043173)
			(xy 82.2997 -130.065815) (xy 82.247405 -130.08117) (xy 82.193457 -130.088928) (xy 82.166206 -130.089402)
			(xy 82.151413 -130.08926) (xy 82.121915 -130.086975) (xy 82.107278 -130.08483) (xy 82.096356 -130.083052)
			(xy 82.07502 -130.089148) (xy 82.007964 -130.146298) (xy 81.999944 -130.153872) (xy 81.99073 -130.173888)
			(xy 81.990184 -130.184906) (xy 81.990184 -130.489706) (xy 81.990725 -130.500724) (xy 81.999944 -130.52074)
			(xy 82.007964 -130.528314) (xy 82.07502 -130.585464) (xy 82.096356 -130.59156) (xy 82.107278 -130.589782)
			(xy 82.121915 -130.587634) (xy 82.151413 -130.585344) (xy 82.166206 -130.58521) (xy 82.193513 -130.585681)
			(xy 82.247566 -130.593491) (xy 82.299947 -130.608948) (xy 82.349579 -130.631735) (xy 82.395444 -130.661385)
			(xy 82.436598 -130.697288) (xy 82.472197 -130.738706) (xy 82.487262 -130.761486) (xy 82.488532 -130.763264)
			(xy 82.493104 -130.769106) (xy 82.500699 -130.778086) (xy 82.521745 -130.788527) (xy 82.53349 -130.789172)
			(xy 84.6963 -130.789172) (xy 84.711194 -130.788611) (xy 84.739696 -130.779939) (xy 84.764487 -130.76342)
			(xy 84.783465 -130.740455) (xy 84.795017 -130.712994) (xy 84.797138 -130.69824) (xy 84.797522 -130.693907)
			(xy 84.797015 -130.685225) (xy 84.796122 -130.680968) (xy 84.79422 -130.674283) (xy 84.787395 -130.662181)
			(xy 84.78266 -130.657092) (xy 75.615038 -121.48947) (xy 75.608228 -121.482125) (xy 75.6005 -121.463662)
			(xy 75.600052 -121.453656) (xy 75.600052 -118.27891) (xy 75.599578 -118.268943) (xy 75.592005 -118.250503)
			(xy 75.58532 -118.243096) (xy 75.460098 -118.11762) (xy 75.458574 -118.116096) (xy 75.451089 -118.10984)
			(xy 75.432844 -118.102985) (xy 75.413358 -118.103409) (xy 75.395428 -118.111051) (xy 75.388216 -118.11762)
			(xy 75.371706 -118.133876) (xy 75.371198 -118.134384) (xy 75.339702 -118.16588) (xy 75.316567 -118.188421)
			(xy 75.266084 -118.228716) (xy 75.211403 -118.263103) (xy 75.153215 -118.291146) (xy 75.09225 -118.312493)
			(xy 75.029278 -118.326875) (xy 74.965091 -118.334112) (xy 74.932794 -118.334536) (xy 74.895619 -118.333951)
			(xy 74.82189 -118.324371) (xy 74.750009 -118.305372) (xy 74.71537 -118.291864) (xy 74.710036 -118.292118)
			(xy 74.626216 -118.333012) (xy 74.613008 -118.348252) (xy 74.609706 -118.357904) (xy 74.600793 -118.38273)
			(xy 74.577096 -118.429855) (xy 74.547137 -118.473269) (xy 74.511486 -118.512144) (xy 74.470821 -118.545741)
			(xy 74.425919 -118.573419) (xy 74.377633 -118.594651) (xy 74.326884 -118.609032) (xy 74.274638 -118.61629)
			(xy 74.248264 -118.61673) (xy 74.220997 -118.616241) (xy 74.167019 -118.608475) (xy 74.114696 -118.593106)
			(xy 74.065092 -118.570448) (xy 74.019218 -118.54096) (xy 73.978007 -118.505245) (xy 73.942299 -118.464027)
			(xy 73.91282 -118.418148) (xy 73.89017 -118.36854) (xy 73.87481 -118.316214) (xy 73.867054 -118.262235)
			(xy 73.866502 -118.234968) (xy 73.86699 -118.207711) (xy 73.874748 -118.153751) (xy 73.890103 -118.101444)
			(xy 73.912742 -118.051852) (xy 73.942205 -118.005985) (xy 73.977892 -117.964775) (xy 74.019078 -117.92906)
			(xy 74.064925 -117.899566) (xy 74.114502 -117.876894) (xy 74.166799 -117.861503) (xy 74.220753 -117.853708)
			(xy 74.24801 -117.853206) (xy 74.248518 -117.853206) (xy 74.258678 -117.85346) (xy 74.269092 -117.853714)
			(xy 74.278744 -117.849904) (xy 74.28337 -117.847991) (xy 74.291817 -117.842619) (xy 74.295508 -117.839236)
			(xy 74.349102 -117.787928) (xy 74.35723 -117.768878) (xy 74.35723 -117.758464) (xy 74.357791 -117.722655)
			(xy 74.36671 -117.651594) (xy 74.384381 -117.582189) (xy 74.410531 -117.515515) (xy 74.444756 -117.452603)
			(xy 74.46518 -117.423184) (xy 74.470006 -117.41658) (xy 74.474832 -117.401594) (xy 74.474832 -117.253004)
			(xy 74.470006 -117.237764) (xy 74.46518 -117.231414) (xy 74.446255 -117.204183) (xy 74.414093 -117.146189)
			(xy 74.388802 -117.084885) (xy 74.379328 -117.053106) (xy 74.369874 -117.017884) (xy 74.358919 -116.945783)
			(xy 74.357484 -116.909342) (xy 74.35723 -116.898928) (xy 74.352912 -116.88953) (xy 74.350777 -116.885059)
			(xy 74.345017 -116.876999) (xy 74.341482 -116.873528) (xy 74.296016 -116.830602) (xy 74.292307 -116.827243)
			(xy 74.283867 -116.821868) (xy 74.279252 -116.819934) (xy 74.269092 -116.816124) (xy 74.248518 -116.816886)
			(xy 74.24801 -116.816886) (xy 74.220754 -116.81638) (xy 74.1668 -116.808585) (xy 74.114504 -116.793195)
			(xy 74.064929 -116.770522) (xy 74.019082 -116.741029) (xy 73.977898 -116.705314) (xy 73.942212 -116.664104)
			(xy 73.91275 -116.618238) (xy 73.890112 -116.568646) (xy 73.874759 -116.51634) (xy 73.867001 -116.462381)
			(xy 73.866502 -116.435124) (xy 73.866987 -116.407853) (xy 73.874745 -116.353864) (xy 73.890108 -116.30153)
			(xy 73.912763 -116.251915) (xy 73.942247 -116.206028) (xy 73.977962 -116.164805) (xy 74.01918 -116.129083)
			(xy 74.065062 -116.099591) (xy 74.114674 -116.076929) (xy 74.167006 -116.061558) (xy 74.220993 -116.053791)
			(xy 74.248264 -116.053362) (xy 74.27723 -116.053896) (xy 74.334499 -116.062642) (xy 74.38979 -116.079939)
			(xy 74.441833 -116.10539) (xy 74.489434 -116.13841) (xy 74.531501 -116.178242) (xy 74.567067 -116.223972)
			(xy 74.595318 -116.27455) (xy 74.605896 -116.30152) (xy 74.609452 -116.310918) (xy 74.61631 -116.318538)
			(xy 74.624184 -116.325396) (xy 74.632566 -116.330222) (xy 74.688954 -116.35613) (xy 74.693667 -116.358139)
			(xy 74.703649 -116.360442) (xy 74.708766 -116.360702) (xy 74.718672 -116.360956) (xy 74.728324 -116.3574)
			(xy 74.728578 -116.3574) (xy 74.761304 -116.345531) (xy 74.828886 -116.328825) (xy 74.897987 -116.320375)
			(xy 74.932794 -116.319808) (xy 74.965085 -116.320281) (xy 75.029259 -116.32755) (xy 75.092216 -116.341951)
			(xy 75.153167 -116.363304) (xy 75.211348 -116.391341) (xy 75.251907 -116.416836) (xy 87.260682 -116.416836)
			(xy 87.264753 -116.361214) (xy 87.276879 -116.306777) (xy 87.296802 -116.254686) (xy 87.324098 -116.206051)
			(xy 87.358184 -116.161908) (xy 87.398333 -116.123199) (xy 87.443691 -116.090748) (xy 87.493291 -116.065247)
			(xy 87.546075 -116.04724) (xy 87.600918 -116.03711) (xy 87.656652 -116.035073) (xy 87.712089 -116.041173)
			(xy 87.766046 -116.055279) (xy 87.817375 -116.077091) (xy 87.864981 -116.106145) (xy 87.907849 -116.14182)
			(xy 87.945066 -116.183357) (xy 87.975839 -116.22987) (xy 87.999511 -116.280367) (xy 88.015579 -116.333774)
			(xy 88.023699 -116.38895) (xy 88.024208 -116.416836) (xy 88.023699 -116.444722) (xy 88.015579 -116.499898)
			(xy 87.999511 -116.553305) (xy 87.975839 -116.603802) (xy 87.945066 -116.650315) (xy 87.907849 -116.691852)
			(xy 87.898313 -116.699788) (xy 89.298 -116.699788) (xy 89.298 -116.639852) (xy 89.305823 -116.58043)
			(xy 89.321336 -116.522537) (xy 89.344272 -116.467164) (xy 89.374239 -116.415258) (xy 89.410726 -116.367708)
			(xy 89.453106 -116.325328) (xy 89.500656 -116.288841) (xy 89.552562 -116.258874) (xy 89.607935 -116.235938)
			(xy 89.665828 -116.220425) (xy 89.72525 -116.212602) (xy 89.785186 -116.212602) (xy 89.844608 -116.220425)
			(xy 89.902501 -116.235938) (xy 89.957874 -116.258874) (xy 90.00978 -116.288841) (xy 90.05733 -116.325328)
			(xy 90.09971 -116.367708) (xy 90.132535 -116.410486) (xy 95.147128 -116.410486) (xy 95.151199 -116.354864)
			(xy 95.163325 -116.300427) (xy 95.183248 -116.248336) (xy 95.210544 -116.199701) (xy 95.24463 -116.155558)
			(xy 95.284779 -116.116849) (xy 95.330137 -116.084398) (xy 95.379737 -116.058897) (xy 95.432521 -116.04089)
			(xy 95.487364 -116.03076) (xy 95.543098 -116.028723) (xy 95.598535 -116.034823) (xy 95.652492 -116.048929)
			(xy 95.703821 -116.070741) (xy 95.751427 -116.099795) (xy 95.794295 -116.13547) (xy 95.831512 -116.177007)
			(xy 95.862285 -116.22352) (xy 95.885957 -116.274017) (xy 95.902025 -116.327424) (xy 95.910145 -116.3826)
			(xy 95.910654 -116.410486) (xy 95.910145 -116.438372) (xy 95.902025 -116.493548) (xy 95.885957 -116.546955)
			(xy 95.862285 -116.597452) (xy 95.831512 -116.643965) (xy 95.794295 -116.685502) (xy 95.751427 -116.721177)
			(xy 95.703821 -116.750231) (xy 95.652492 -116.772043) (xy 95.598535 -116.786149) (xy 95.543098 -116.792249)
			(xy 95.487364 -116.790212) (xy 95.432521 -116.780082) (xy 95.379737 -116.762075) (xy 95.330137 -116.736574)
			(xy 95.284779 -116.704123) (xy 95.24463 -116.665414) (xy 95.210544 -116.621271) (xy 95.183248 -116.572636)
			(xy 95.163325 -116.520545) (xy 95.151199 -116.466108) (xy 95.147128 -116.410486) (xy 90.132535 -116.410486)
			(xy 90.136197 -116.415258) (xy 90.166164 -116.467164) (xy 90.1891 -116.522537) (xy 90.204613 -116.58043)
			(xy 90.212436 -116.639852) (xy 90.212926 -116.66982) (xy 90.212436 -116.699788) (xy 90.204613 -116.75921)
			(xy 90.1891 -116.817103) (xy 90.166164 -116.872476) (xy 90.136197 -116.924382) (xy 90.09971 -116.971932)
			(xy 90.05733 -117.014312) (xy 90.00978 -117.050799) (xy 89.957874 -117.080766) (xy 89.902501 -117.103702)
			(xy 89.844608 -117.119215) (xy 89.785186 -117.127038) (xy 89.72525 -117.127038) (xy 89.665828 -117.119215)
			(xy 89.607935 -117.103702) (xy 89.552562 -117.080766) (xy 89.500656 -117.050799) (xy 89.453106 -117.014312)
			(xy 89.410726 -116.971932) (xy 89.374239 -116.924382) (xy 89.344272 -116.872476) (xy 89.321336 -116.817103)
			(xy 89.305823 -116.75921) (xy 89.298 -116.699788) (xy 87.898313 -116.699788) (xy 87.864981 -116.727527)
			(xy 87.817375 -116.756581) (xy 87.766046 -116.778393) (xy 87.712089 -116.792499) (xy 87.656652 -116.798599)
			(xy 87.600918 -116.796562) (xy 87.546075 -116.786432) (xy 87.493291 -116.768425) (xy 87.443691 -116.742924)
			(xy 87.398333 -116.710473) (xy 87.358184 -116.671764) (xy 87.324098 -116.627621) (xy 87.296802 -116.578986)
			(xy 87.276879 -116.526895) (xy 87.264753 -116.472458) (xy 87.260682 -116.416836) (xy 75.251907 -116.416836)
			(xy 75.266026 -116.425711) (xy 75.316517 -116.465981) (xy 75.339702 -116.488464) (xy 75.39101 -116.539772)
			(xy 75.391264 -116.539772) (xy 75.457304 -116.605812) (xy 75.464699 -116.612667) (xy 75.483298 -116.620414)
			(xy 75.493372 -116.620798) (xy 75.958192 -116.620798) (xy 75.96818 -116.621334) (xy 75.986614 -116.629045)
			(xy 75.994006 -116.635784) (xy 76.490826 -117.132604) (xy 92.904038 -117.132604) (xy 92.904038 -117.072668)
			(xy 92.911861 -117.013246) (xy 92.927374 -116.955353) (xy 92.95031 -116.89998) (xy 92.980277 -116.848074)
			(xy 93.016764 -116.800524) (xy 93.059144 -116.758144) (xy 93.106694 -116.721657) (xy 93.1586 -116.69169)
			(xy 93.213973 -116.668754) (xy 93.271866 -116.653241) (xy 93.331288 -116.645418) (xy 93.391224 -116.645418)
			(xy 93.450646 -116.653241) (xy 93.508539 -116.668754) (xy 93.563912 -116.69169) (xy 93.615818 -116.721657)
			(xy 93.663368 -116.758144) (xy 93.705748 -116.800524) (xy 93.742235 -116.848074) (xy 93.772202 -116.89998)
			(xy 93.795138 -116.955353) (xy 93.810651 -117.013246) (xy 93.818474 -117.072668) (xy 93.818964 -117.102636)
			(xy 93.818474 -117.132604) (xy 93.810651 -117.192026) (xy 93.795138 -117.249919) (xy 93.772202 -117.305292)
			(xy 93.742235 -117.357198) (xy 93.705748 -117.404748) (xy 93.68401 -117.426486) (xy 95.147128 -117.426486)
			(xy 95.151199 -117.370864) (xy 95.163325 -117.316427) (xy 95.183248 -117.264336) (xy 95.210544 -117.215701)
			(xy 95.24463 -117.171558) (xy 95.284779 -117.132849) (xy 95.330137 -117.100398) (xy 95.379737 -117.074897)
			(xy 95.432521 -117.05689) (xy 95.487364 -117.04676) (xy 95.543098 -117.044723) (xy 95.598535 -117.050823)
			(xy 95.652492 -117.064929) (xy 95.703821 -117.086741) (xy 95.751427 -117.115795) (xy 95.794295 -117.15147)
			(xy 95.831512 -117.193007) (xy 95.862285 -117.23952) (xy 95.885957 -117.290017) (xy 95.902025 -117.343424)
			(xy 95.910145 -117.3986) (xy 95.910654 -117.426486) (xy 95.910145 -117.454372) (xy 95.902025 -117.509548)
			(xy 95.885957 -117.562955) (xy 95.862285 -117.613452) (xy 95.831512 -117.659965) (xy 95.794295 -117.701502)
			(xy 95.751427 -117.737177) (xy 95.703821 -117.766231) (xy 95.652492 -117.788043) (xy 95.598535 -117.802149)
			(xy 95.543098 -117.808249) (xy 95.487364 -117.806212) (xy 95.432521 -117.796082) (xy 95.379737 -117.778075)
			(xy 95.330137 -117.752574) (xy 95.284779 -117.720123) (xy 95.24463 -117.681414) (xy 95.210544 -117.637271)
			(xy 95.183248 -117.588636) (xy 95.163325 -117.536545) (xy 95.151199 -117.482108) (xy 95.147128 -117.426486)
			(xy 93.68401 -117.426486) (xy 93.663368 -117.447128) (xy 93.615818 -117.483615) (xy 93.563912 -117.513582)
			(xy 93.508539 -117.536518) (xy 93.450646 -117.552031) (xy 93.391224 -117.559854) (xy 93.331288 -117.559854)
			(xy 93.271866 -117.552031) (xy 93.213973 -117.536518) (xy 93.1586 -117.513582) (xy 93.106694 -117.483615)
			(xy 93.059144 -117.447128) (xy 93.016764 -117.404748) (xy 92.980277 -117.357198) (xy 92.95031 -117.305292)
			(xy 92.927374 -117.249919) (xy 92.911861 -117.192026) (xy 92.904038 -117.132604) (xy 76.490826 -117.132604)
			(xy 77.010514 -117.652292) (xy 77.017335 -117.659633) (xy 77.025084 -117.678096) (xy 77.0255 -117.688106)
			(xy 77.0255 -118.525354) (xy 80.517167 -118.525354) (xy 80.517167 -118.470846) (xy 80.524925 -118.416894)
			(xy 80.540283 -118.364594) (xy 80.562927 -118.315013) (xy 80.592398 -118.26916) (xy 80.628094 -118.227968)
			(xy 80.66929 -118.192275) (xy 80.715147 -118.162809) (xy 80.76473 -118.140169) (xy 80.817031 -118.124817)
			(xy 80.870984 -118.117065) (xy 80.898238 -118.116604) (xy 80.924165 -118.11704) (xy 80.975543 -118.12404)
			(xy 81.025501 -118.137933) (xy 81.073117 -118.158463) (xy 81.117514 -118.185252) (xy 81.157874 -118.217807)
			(xy 81.193454 -118.255527) (xy 81.20888 -118.27637) (xy 81.214468 -118.284244) (xy 81.229962 -118.294404)
			(xy 81.279238 -118.305072) (xy 81.297526 -118.302278) (xy 81.305908 -118.297452) (xy 81.331867 -118.283212)
			(xy 81.386673 -118.260809) (xy 81.443908 -118.245651) (xy 81.502618 -118.237991) (xy 81.532222 -118.237508)
			(xy 81.561754 -118.237979) (xy 81.620324 -118.245611) (xy 81.677428 -118.260709) (xy 81.732117 -118.283021)
			(xy 81.758028 -118.297198) (xy 81.766918 -118.302278) (xy 81.77784 -118.303802) (xy 81.782288 -118.304296)
			(xy 81.791229 -118.303906) (xy 81.79562 -118.30304) (xy 81.834482 -118.294404) (xy 81.849976 -118.284244)
			(xy 81.855564 -118.27637) (xy 81.87102 -118.255553) (xy 81.906608 -118.217847) (xy 81.946968 -118.185302)
			(xy 81.991359 -118.158515) (xy 82.038966 -118.137978) (xy 82.088913 -118.124069) (xy 82.140282 -118.117044)
			(xy 82.166206 -118.116604) (xy 82.193458 -118.117066) (xy 82.247407 -118.124824) (xy 82.299702 -118.14018)
			(xy 82.34928 -118.162822) (xy 82.395131 -118.192289) (xy 82.436322 -118.227982) (xy 82.472014 -118.269173)
			(xy 82.501481 -118.315025) (xy 82.524122 -118.364603) (xy 82.539478 -118.416899) (xy 82.547234 -118.470848)
			(xy 82.547234 -118.525352) (xy 82.539478 -118.579301) (xy 82.524122 -118.631597) (xy 82.501481 -118.681175)
			(xy 82.472014 -118.727027) (xy 82.436322 -118.768218) (xy 82.395131 -118.803911) (xy 82.34928 -118.833378)
			(xy 82.299702 -118.85602) (xy 82.247407 -118.871376) (xy 82.193458 -118.879134) (xy 82.166206 -118.87962)
			(xy 82.151413 -118.879485) (xy 82.121915 -118.877196) (xy 82.107278 -118.875048) (xy 82.096356 -118.87327)
			(xy 82.07502 -118.879366) (xy 82.057436 -118.894352) (xy 93.41612 -118.894352) (xy 93.41612 -118.894098)
			(xy 93.416571 -118.867803) (xy 93.423817 -118.815714) (xy 93.438144 -118.765112) (xy 93.459281 -118.716956)
			(xy 93.486828 -118.672156) (xy 93.520263 -118.631562) (xy 93.53931 -118.613428) (xy 93.546739 -118.605846)
			(xy 93.555271 -118.586436) (xy 93.55582 -118.575836) (xy 93.55582 -118.501668) (xy 93.555414 -118.491036)
			(xy 93.546862 -118.471572) (xy 93.53931 -118.464076) (xy 93.520236 -118.445966) (xy 93.48678 -118.40538)
			(xy 93.459223 -118.36058) (xy 93.438087 -118.312416) (xy 93.423774 -118.261804) (xy 93.416555 -118.209705)
			(xy 93.41612 -118.183406) (xy 93.41612 -118.183152) (xy 93.416606 -118.155901) (xy 93.424362 -118.101953)
			(xy 93.439717 -118.049658) (xy 93.462359 -118.000081) (xy 93.491825 -117.954231) (xy 93.527516 -117.91304)
			(xy 93.568707 -117.877349) (xy 93.614557 -117.847883) (xy 93.664134 -117.825241) (xy 93.716429 -117.809886)
			(xy 93.770377 -117.80213) (xy 93.824879 -117.80213) (xy 93.878827 -117.809886) (xy 93.931122 -117.825241)
			(xy 93.980699 -117.847883) (xy 94.026549 -117.877349) (xy 94.06774 -117.91304) (xy 94.103431 -117.954231)
			(xy 94.132897 -118.000081) (xy 94.155539 -118.049658) (xy 94.170894 -118.101953) (xy 94.17865 -118.155901)
			(xy 94.179136 -118.183152) (xy 94.179136 -118.183406) (xy 94.17867 -118.2097) (xy 94.171424 -118.261788)
			(xy 94.157099 -118.312389) (xy 94.135965 -118.360545) (xy 94.108422 -118.405345) (xy 94.074991 -118.445941)
			(xy 94.055946 -118.464076) (xy 94.048524 -118.471664) (xy 94.039986 -118.491069) (xy 94.039634 -118.497854)
			(xy 97.407204 -118.497854) (xy 97.407204 -118.437918) (xy 97.415027 -118.378496) (xy 97.43054 -118.320603)
			(xy 97.453476 -118.26523) (xy 97.483443 -118.213324) (xy 97.51993 -118.165774) (xy 97.56231 -118.123394)
			(xy 97.60986 -118.086907) (xy 97.661766 -118.05694) (xy 97.717139 -118.034004) (xy 97.775032 -118.018491)
			(xy 97.834454 -118.010668) (xy 97.89439 -118.010668) (xy 97.953812 -118.018491) (xy 98.011705 -118.034004)
			(xy 98.067078 -118.05694) (xy 98.118984 -118.086907) (xy 98.166534 -118.123394) (xy 98.208914 -118.165774)
			(xy 98.245401 -118.213324) (xy 98.275368 -118.26523) (xy 98.298304 -118.320603) (xy 98.313817 -118.378496)
			(xy 98.32164 -118.437918) (xy 98.32213 -118.467886) (xy 99.65258 -118.467886) (xy 99.656651 -118.412264)
			(xy 99.668777 -118.357827) (xy 99.6887 -118.305736) (xy 99.715996 -118.257101) (xy 99.750082 -118.212958)
			(xy 99.790231 -118.174249) (xy 99.835589 -118.141798) (xy 99.885189 -118.116297) (xy 99.937973 -118.09829)
			(xy 99.992816 -118.08816) (xy 100.04855 -118.086123) (xy 100.103987 -118.092223) (xy 100.157944 -118.106329)
			(xy 100.209273 -118.128141) (xy 100.256879 -118.157195) (xy 100.299747 -118.19287) (xy 100.336964 -118.234407)
			(xy 100.367737 -118.28092) (xy 100.391409 -118.331417) (xy 100.407477 -118.384824) (xy 100.415597 -118.44)
			(xy 100.416106 -118.467886) (xy 100.415597 -118.495772) (xy 100.407477 -118.550948) (xy 100.391409 -118.604355)
			(xy 100.367737 -118.654852) (xy 100.336964 -118.701365) (xy 100.299747 -118.742902) (xy 100.256879 -118.778577)
			(xy 100.209273 -118.807631) (xy 100.157944 -118.829443) (xy 100.103987 -118.843549) (xy 100.04855 -118.849649)
			(xy 99.992816 -118.847612) (xy 99.937973 -118.837482) (xy 99.885189 -118.819475) (xy 99.835589 -118.793974)
			(xy 99.790231 -118.761523) (xy 99.750082 -118.722814) (xy 99.715996 -118.678671) (xy 99.6887 -118.630036)
			(xy 99.668777 -118.577945) (xy 99.656651 -118.523508) (xy 99.65258 -118.467886) (xy 98.32213 -118.467886)
			(xy 98.32164 -118.497854) (xy 98.313817 -118.557276) (xy 98.298304 -118.615169) (xy 98.275368 -118.670542)
			(xy 98.245401 -118.722448) (xy 98.208914 -118.769998) (xy 98.166534 -118.812378) (xy 98.118984 -118.848865)
			(xy 98.067078 -118.878832) (xy 98.011705 -118.901768) (xy 97.953812 -118.917281) (xy 97.89439 -118.925104)
			(xy 97.834454 -118.925104) (xy 97.775032 -118.917281) (xy 97.717139 -118.901768) (xy 97.661766 -118.878832)
			(xy 97.60986 -118.848865) (xy 97.56231 -118.812378) (xy 97.51993 -118.769998) (xy 97.483443 -118.722448)
			(xy 97.453476 -118.670542) (xy 97.43054 -118.615169) (xy 97.415027 -118.557276) (xy 97.407204 -118.497854)
			(xy 94.039634 -118.497854) (xy 94.039436 -118.501668) (xy 94.039436 -118.575836) (xy 94.039824 -118.586471)
			(xy 94.048387 -118.605936) (xy 94.055946 -118.613428) (xy 94.075014 -118.631544) (xy 94.108471 -118.672128)
			(xy 94.136031 -118.716926) (xy 94.157168 -118.765089) (xy 94.171482 -118.8157) (xy 94.178701 -118.8678)
			(xy 94.179136 -118.894098) (xy 94.179136 -118.894352) (xy 94.17865 -118.921603) (xy 94.170894 -118.975551)
			(xy 94.155539 -119.027846) (xy 94.132897 -119.077423) (xy 94.103431 -119.123273) (xy 94.06774 -119.164464)
			(xy 94.026549 -119.200155) (xy 93.980699 -119.229621) (xy 93.931122 -119.252263) (xy 93.878827 -119.267618)
			(xy 93.824879 -119.275374) (xy 93.770377 -119.275374) (xy 93.716429 -119.267618) (xy 93.664134 -119.252263)
			(xy 93.614557 -119.229621) (xy 93.568707 -119.200155) (xy 93.527516 -119.164464) (xy 93.491825 -119.123273)
			(xy 93.462359 -119.077423) (xy 93.439717 -119.027846) (xy 93.424362 -118.975551) (xy 93.416606 -118.921603)
			(xy 93.41612 -118.894352) (xy 82.057436 -118.894352) (xy 82.007964 -118.936516) (xy 81.99993 -118.944078)
			(xy 81.990719 -118.964103) (xy 81.990184 -118.975124) (xy 81.990184 -119.279924) (xy 81.990714 -119.290944)
			(xy 81.99994 -119.31096) (xy 82.007964 -119.318532) (xy 82.07502 -119.375682) (xy 82.096356 -119.381778)
			(xy 82.107278 -119.38) (xy 82.121915 -119.377855) (xy 82.151413 -119.37557) (xy 82.166206 -119.375428)
			(xy 82.19346 -119.375842) (xy 82.247412 -119.3836) (xy 82.299711 -119.398957) (xy 82.318535 -119.407554)
			(xy 94.499632 -119.407554) (xy 94.499632 -119.353046) (xy 94.507389 -119.299093) (xy 94.522745 -119.246794)
			(xy 94.545388 -119.197211) (xy 94.574856 -119.151356) (xy 94.61055 -119.110162) (xy 94.651743 -119.074466)
			(xy 94.697597 -119.044995) (xy 94.747179 -119.022351) (xy 94.799478 -119.006992) (xy 94.85343 -118.999233)
			(xy 94.880684 -118.998746) (xy 94.908054 -118.99921) (xy 94.962234 -119.007027) (xy 95.014738 -119.022516)
			(xy 95.064484 -119.045358) (xy 95.110451 -119.075084) (xy 95.131382 -119.092726) (xy 95.131636 -119.09298)
			(xy 95.13873 -119.098555) (xy 95.155641 -119.104807) (xy 95.164656 -119.105172) (xy 95.231712 -119.105172)
			(xy 95.24073 -119.104827) (xy 95.257647 -119.098572) (xy 95.264732 -119.09298) (xy 95.26524 -119.092472)
			(xy 95.286174 -119.07489) (xy 95.332109 -119.045251) (xy 95.381805 -119.022473) (xy 95.434243 -119.007023)
			(xy 95.48835 -118.999216) (xy 95.515684 -118.998746) (xy 95.542934 -118.9993) (xy 95.59688 -119.007054)
			(xy 95.649174 -119.022407) (xy 95.69875 -119.045046) (xy 95.7446 -119.07451) (xy 95.785789 -119.110199)
			(xy 95.82148 -119.151387) (xy 95.850946 -119.197236) (xy 95.873587 -119.246811) (xy 95.888942 -119.299104)
			(xy 95.896699 -119.35305) (xy 95.896699 -119.40755) (xy 95.888942 -119.461496) (xy 95.873587 -119.513789)
			(xy 95.850946 -119.563364) (xy 95.82148 -119.609213) (xy 95.785789 -119.650401) (xy 95.7446 -119.68609)
			(xy 95.69875 -119.715554) (xy 95.649174 -119.738193) (xy 95.59688 -119.753546) (xy 95.542934 -119.7613)
			(xy 95.515684 -119.761762) (xy 95.488313 -119.761315) (xy 95.434133 -119.753494) (xy 95.381629 -119.738001)
			(xy 95.331882 -119.715155) (xy 95.285917 -119.685426) (xy 95.264986 -119.667782) (xy 95.264732 -119.667528)
			(xy 95.257647 -119.66194) (xy 95.240729 -119.655696) (xy 95.231712 -119.655336) (xy 95.164656 -119.655336)
			(xy 95.155641 -119.655712) (xy 95.138723 -119.661946) (xy 95.131636 -119.667528) (xy 95.131128 -119.668036)
			(xy 95.110207 -119.685634) (xy 95.064268 -119.715271) (xy 95.014569 -119.738045) (xy 94.962128 -119.753492)
			(xy 94.908018 -119.761294) (xy 94.880684 -119.761762) (xy 94.85343 -119.761367) (xy 94.799478 -119.753608)
			(xy 94.747179 -119.738249) (xy 94.697597 -119.715605) (xy 94.651743 -119.686134) (xy 94.61055 -119.650438)
			(xy 94.574856 -119.609244) (xy 94.545388 -119.563389) (xy 94.522745 -119.513806) (xy 94.507389 -119.461507)
			(xy 94.499632 -119.407554) (xy 82.318535 -119.407554) (xy 82.349292 -119.421601) (xy 82.395146 -119.45107)
			(xy 82.436339 -119.486765) (xy 82.472033 -119.527959) (xy 82.501502 -119.573813) (xy 82.524145 -119.623395)
			(xy 82.539501 -119.675694) (xy 82.547258 -119.729646) (xy 82.547258 -119.784154) (xy 82.539501 -119.838106)
			(xy 82.524145 -119.890405) (xy 82.501502 -119.939987) (xy 82.472033 -119.985841) (xy 82.436339 -120.027035)
			(xy 82.395146 -120.06273) (xy 82.349292 -120.092199) (xy 82.299711 -120.114843) (xy 82.247412 -120.1302)
			(xy 82.19346 -120.137958) (xy 82.166206 -120.138444) (xy 82.136355 -120.137893) (xy 82.077386 -120.128568)
			(xy 82.020592 -120.110161) (xy 81.967363 -120.083123) (xy 81.919002 -120.048115) (xy 81.876692 -120.005994)
			(xy 81.858612 -119.982234) (xy 81.856326 -119.979186) (xy 81.84896 -119.97182) (xy 81.843745 -119.966913)
			(xy 81.83124 -119.95995) (xy 81.824322 -119.958104) (xy 81.788254 -119.949976) (xy 81.780888 -119.950484)
			(xy 81.775022 -119.950997) (xy 81.763731 -119.954319) (xy 81.758536 -119.957088) (xy 81.758282 -119.957088)
			(xy 81.732356 -119.971321) (xy 81.67761 -119.993705) (xy 81.620439 -120.008861) (xy 81.561794 -120.016536)
			(xy 81.532222 -120.017032) (xy 81.501222 -120.016497) (xy 81.439791 -120.008106) (xy 81.380051 -119.991517)
			(xy 81.323091 -119.96703) (xy 81.296256 -119.9515) (xy 81.284826 -119.950484) (xy 81.276698 -119.949722)
			(xy 81.239106 -119.958358) (xy 81.230415 -119.960675) (xy 81.215317 -119.97043) (xy 81.209642 -119.977408)
			(xy 81.204562 -119.984012) (xy 81.204308 -119.984266) (xy 81.18621 -120.007745) (xy 81.14398 -120.049344)
			(xy 81.095813 -120.083895) (xy 81.042873 -120.110564) (xy 80.98644 -120.128706) (xy 80.927877 -120.137884)
			(xy 80.898238 -120.138444) (xy 80.870986 -120.137911) (xy 80.817036 -120.130159) (xy 80.764739 -120.114808)
			(xy 80.715158 -120.09217) (xy 80.669305 -120.062706) (xy 80.628111 -120.027016) (xy 80.592417 -119.985826)
			(xy 80.562948 -119.939975) (xy 80.540305 -119.890397) (xy 80.524949 -119.838101) (xy 80.517191 -119.784152)
			(xy 80.517191 -119.729648) (xy 80.524949 -119.675699) (xy 80.540305 -119.623403) (xy 80.562948 -119.573825)
			(xy 80.592417 -119.527974) (xy 80.628111 -119.486784) (xy 80.669305 -119.451094) (xy 80.715158 -119.42163)
			(xy 80.764739 -119.398992) (xy 80.817036 -119.38364) (xy 80.870986 -119.375889) (xy 80.898238 -119.375428)
			(xy 80.913031 -119.375568) (xy 80.942529 -119.377854) (xy 80.957166 -119.38) (xy 80.968088 -119.381778)
			(xy 80.989424 -119.375682) (xy 81.05648 -119.318532) (xy 81.064499 -119.310957) (xy 81.073717 -119.290942)
			(xy 81.07426 -119.279924) (xy 81.07426 -118.975124) (xy 81.073721 -118.964105) (xy 81.064504 -118.944088)
			(xy 81.05648 -118.936516) (xy 80.989424 -118.879366) (xy 80.968088 -118.87327) (xy 80.957166 -118.875048)
			(xy 80.942528 -118.877188) (xy 80.913031 -118.879476) (xy 80.898238 -118.87962) (xy 80.870984 -118.879135)
			(xy 80.817031 -118.871383) (xy 80.76473 -118.856031) (xy 80.715147 -118.833391) (xy 80.66929 -118.803925)
			(xy 80.628094 -118.768232) (xy 80.592398 -118.72704) (xy 80.562927 -118.681187) (xy 80.540283 -118.631606)
			(xy 80.524925 -118.579306) (xy 80.517167 -118.525354) (xy 77.0255 -118.525354) (xy 77.0255 -120.331858)
			(xy 83.159215 -120.331858) (xy 83.159215 -120.277342) (xy 83.166974 -120.223381) (xy 83.182334 -120.171074)
			(xy 83.204982 -120.121486) (xy 83.234458 -120.075626) (xy 83.27016 -120.034428) (xy 83.311363 -119.99873)
			(xy 83.357226 -119.96926) (xy 83.406818 -119.946618) (xy 83.459126 -119.931264) (xy 83.513088 -119.923512)
			(xy 83.540346 -119.923052) (xy 83.5406 -119.923052) (xy 83.570414 -119.923644) (xy 83.629305 -119.932992)
			(xy 83.686027 -119.951382) (xy 83.7392 -119.978368) (xy 83.787531 -120.013292) (xy 83.829844 -120.055306)
			(xy 83.84794 -120.079008) (xy 83.850226 -120.082056) (xy 83.857592 -120.089422) (xy 83.862874 -120.094338)
			(xy 83.875506 -120.101302) (xy 83.882484 -120.103138) (xy 83.911694 -120.109742) (xy 83.920838 -120.111774)
			(xy 83.939126 -120.109234) (xy 83.948016 -120.104408) (xy 83.94827 -120.104154) (xy 83.974213 -120.089969)
			(xy 84.028963 -120.067643) (xy 84.086131 -120.052547) (xy 84.144766 -120.044931) (xy 84.17433 -120.044464)
			(xy 84.203895 -120.044926) (xy 84.262534 -120.052526) (xy 84.319705 -120.067619) (xy 84.374454 -120.089955)
			(xy 84.40039 -120.104154) (xy 84.400644 -120.104408) (xy 84.409534 -120.109234) (xy 84.427822 -120.111774)
			(xy 84.436966 -120.109742) (xy 84.467446 -120.102884) (xy 84.476028 -120.100549) (xy 84.490969 -120.090926)
			(xy 84.496656 -120.084088) (xy 84.50199 -120.076976) (xy 84.502244 -120.076722) (xy 84.520388 -120.053341)
			(xy 84.562643 -120.011907) (xy 84.610786 -119.977491) (xy 84.663663 -119.950916) (xy 84.720008 -119.93282)
			(xy 84.778471 -119.923635) (xy 84.80806 -119.923052) (xy 84.808314 -119.923052) (xy 84.835562 -119.923619)
			(xy 84.889502 -119.931376) (xy 84.905268 -119.936006) (xy 92.694504 -119.936006) (xy 92.698575 -119.880384)
			(xy 92.710701 -119.825947) (xy 92.730624 -119.773856) (xy 92.75792 -119.725221) (xy 92.792006 -119.681078)
			(xy 92.832155 -119.642369) (xy 92.877513 -119.609918) (xy 92.927113 -119.584417) (xy 92.979897 -119.56641)
			(xy 93.03474 -119.55628) (xy 93.090474 -119.554243) (xy 93.145911 -119.560343) (xy 93.199868 -119.574449)
			(xy 93.251197 -119.596261) (xy 93.298803 -119.625315) (xy 93.341671 -119.66099) (xy 93.378888 -119.702527)
			(xy 93.409661 -119.74904) (xy 93.433333 -119.799537) (xy 93.449401 -119.852944) (xy 93.457521 -119.90812)
			(xy 93.457793 -119.923048) (xy 97.493818 -119.923048) (xy 97.493818 -119.863112) (xy 97.501641 -119.80369)
			(xy 97.517154 -119.745797) (xy 97.54009 -119.690424) (xy 97.570057 -119.638518) (xy 97.606544 -119.590968)
			(xy 97.648924 -119.548588) (xy 97.696474 -119.512101) (xy 97.74838 -119.482134) (xy 97.803753 -119.459198)
			(xy 97.861646 -119.443685) (xy 97.921068 -119.435862) (xy 97.981004 -119.435862) (xy 98.040426 -119.443685)
			(xy 98.098319 -119.459198) (xy 98.153692 -119.482134) (xy 98.205598 -119.512101) (xy 98.253148 -119.548588)
			(xy 98.295528 -119.590968) (xy 98.332015 -119.638518) (xy 98.361982 -119.690424) (xy 98.384918 -119.745797)
			(xy 98.393076 -119.77624) (xy 100.535992 -119.77624) (xy 100.540063 -119.720618) (xy 100.552189 -119.666181)
			(xy 100.572112 -119.61409) (xy 100.599408 -119.565455) (xy 100.633494 -119.521312) (xy 100.673643 -119.482603)
			(xy 100.719001 -119.450152) (xy 100.768601 -119.424651) (xy 100.821385 -119.406644) (xy 100.876228 -119.396514)
			(xy 100.931962 -119.394477) (xy 100.987399 -119.400577) (xy 101.041356 -119.414683) (xy 101.092685 -119.436495)
			(xy 101.140291 -119.465549) (xy 101.183159 -119.501224) (xy 101.220376 -119.542761) (xy 101.251149 -119.589274)
			(xy 101.274821 -119.639771) (xy 101.290889 -119.693178) (xy 101.299009 -119.748354) (xy 101.299518 -119.77624)
			(xy 101.299009 -119.804126) (xy 101.290889 -119.859302) (xy 101.274821 -119.912709) (xy 101.251149 -119.963206)
			(xy 101.220376 -120.009719) (xy 101.183159 -120.051256) (xy 101.140291 -120.086931) (xy 101.092685 -120.115985)
			(xy 101.041356 -120.137797) (xy 100.987399 -120.151903) (xy 100.931962 -120.158003) (xy 100.876228 -120.155966)
			(xy 100.821385 -120.145836) (xy 100.768601 -120.127829) (xy 100.719001 -120.102328) (xy 100.673643 -120.069877)
			(xy 100.633494 -120.031168) (xy 100.599408 -119.987025) (xy 100.572112 -119.93839) (xy 100.552189 -119.886299)
			(xy 100.540063 -119.831862) (xy 100.535992 -119.77624) (xy 98.393076 -119.77624) (xy 98.400431 -119.80369)
			(xy 98.408254 -119.863112) (xy 98.408744 -119.89308) (xy 98.408254 -119.923048) (xy 98.400431 -119.98247)
			(xy 98.384918 -120.040363) (xy 98.361982 -120.095736) (xy 98.332015 -120.147642) (xy 98.295528 -120.195192)
			(xy 98.253148 -120.237572) (xy 98.205598 -120.274059) (xy 98.153692 -120.304026) (xy 98.098319 -120.326962)
			(xy 98.040426 -120.342475) (xy 97.981004 -120.350298) (xy 97.921068 -120.350298) (xy 97.861646 -120.342475)
			(xy 97.803753 -120.326962) (xy 97.74838 -120.304026) (xy 97.696474 -120.274059) (xy 97.648924 -120.237572)
			(xy 97.606544 -120.195192) (xy 97.570057 -120.147642) (xy 97.54009 -120.095736) (xy 97.517154 -120.040363)
			(xy 97.501641 -119.98247) (xy 97.493818 -119.923048) (xy 93.457793 -119.923048) (xy 93.45803 -119.936006)
			(xy 93.457521 -119.963892) (xy 93.449401 -120.019068) (xy 93.433333 -120.072475) (xy 93.409661 -120.122972)
			(xy 93.378888 -120.169485) (xy 93.341671 -120.211022) (xy 93.298803 -120.246697) (xy 93.251197 -120.275751)
			(xy 93.199868 -120.297563) (xy 93.145911 -120.311669) (xy 93.090474 -120.317769) (xy 93.03474 -120.315732)
			(xy 92.979897 -120.305602) (xy 92.927113 -120.287595) (xy 92.877513 -120.262094) (xy 92.832155 -120.229643)
			(xy 92.792006 -120.190934) (xy 92.75792 -120.146791) (xy 92.730624 -120.098156) (xy 92.710701 -120.046065)
			(xy 92.698575 -119.991628) (xy 92.694504 -119.936006) (xy 84.905268 -119.936006) (xy 84.94179 -119.946731)
			(xy 84.99136 -119.969371) (xy 85.037204 -119.998834) (xy 85.078388 -120.034522) (xy 85.114074 -120.075707)
			(xy 85.143536 -120.121552) (xy 85.166174 -120.171123) (xy 85.181527 -120.223411) (xy 85.189282 -120.277352)
			(xy 85.189282 -120.331848) (xy 85.181527 -120.385789) (xy 85.166174 -120.438077) (xy 85.143536 -120.487648)
			(xy 85.12082 -120.522996) (xy 99.528866 -120.522996) (xy 99.528866 -120.46306) (xy 99.536689 -120.403638)
			(xy 99.552202 -120.345745) (xy 99.575138 -120.290372) (xy 99.605105 -120.238466) (xy 99.641592 -120.190916)
			(xy 99.683972 -120.148536) (xy 99.731522 -120.112049) (xy 99.783428 -120.082082) (xy 99.838801 -120.059146)
			(xy 99.896694 -120.043633) (xy 99.956116 -120.03581) (xy 100.016052 -120.03581) (xy 100.075474 -120.043633)
			(xy 100.133367 -120.059146) (xy 100.18874 -120.082082) (xy 100.240646 -120.112049) (xy 100.288196 -120.148536)
			(xy 100.330576 -120.190916) (xy 100.367063 -120.238466) (xy 100.39703 -120.290372) (xy 100.419966 -120.345745)
			(xy 100.435479 -120.403638) (xy 100.443302 -120.46306) (xy 100.443792 -120.493028) (xy 100.443302 -120.522996)
			(xy 100.435479 -120.582418) (xy 100.419966 -120.640311) (xy 100.39703 -120.695684) (xy 100.367063 -120.74759)
			(xy 100.330576 -120.79514) (xy 100.288196 -120.83752) (xy 100.240646 -120.874007) (xy 100.18874 -120.903974)
			(xy 100.133367 -120.92691) (xy 100.075474 -120.942423) (xy 100.016052 -120.950246) (xy 99.956116 -120.950246)
			(xy 99.896694 -120.942423) (xy 99.838801 -120.92691) (xy 99.783428 -120.903974) (xy 99.731522 -120.874007)
			(xy 99.683972 -120.83752) (xy 99.641592 -120.79514) (xy 99.605105 -120.74759) (xy 99.575138 -120.695684)
			(xy 99.552202 -120.640311) (xy 99.536689 -120.582418) (xy 99.528866 -120.522996) (xy 85.12082 -120.522996)
			(xy 85.114074 -120.533493) (xy 85.078388 -120.574678) (xy 85.037204 -120.610366) (xy 84.99136 -120.639829)
			(xy 84.94179 -120.662469) (xy 84.889502 -120.677824) (xy 84.835562 -120.685581) (xy 84.808314 -120.686068)
			(xy 84.793521 -120.685933) (xy 84.764023 -120.683644) (xy 84.749386 -120.681496) (xy 84.738464 -120.679718)
			(xy 84.717128 -120.685814) (xy 84.650072 -120.742964) (xy 84.642063 -120.750548) (xy 84.632837 -120.770556)
			(xy 84.632292 -120.781572) (xy 84.632292 -121.086372) (xy 84.632848 -121.097389) (xy 84.642055 -121.117405)
			(xy 84.650072 -121.12498) (xy 84.717128 -121.18213) (xy 84.738464 -121.188226) (xy 84.749386 -121.186448)
			(xy 84.764023 -121.184302) (xy 84.793521 -121.182017) (xy 84.808314 -121.181876) (xy 84.835563 -121.182395)
			(xy 84.889507 -121.190153) (xy 84.941798 -121.205509) (xy 84.991371 -121.22815) (xy 85.037218 -121.257615)
			(xy 85.050056 -121.26874) (xy 97.509058 -121.26874) (xy 97.509058 -121.208804) (xy 97.516881 -121.149382)
			(xy 97.532394 -121.091489) (xy 97.55533 -121.036116) (xy 97.585297 -120.98421) (xy 97.621784 -120.93666)
			(xy 97.664164 -120.89428) (xy 97.711714 -120.857793) (xy 97.76362 -120.827826) (xy 97.818993 -120.80489)
			(xy 97.876886 -120.789377) (xy 97.936308 -120.781554) (xy 97.996244 -120.781554) (xy 98.055666 -120.789377)
			(xy 98.113559 -120.80489) (xy 98.168932 -120.827826) (xy 98.220838 -120.857793) (xy 98.268388 -120.89428)
			(xy 98.310768 -120.93666) (xy 98.347255 -120.98421) (xy 98.377222 -121.036116) (xy 98.400158 -121.091489)
			(xy 98.415671 -121.149382) (xy 98.423494 -121.208804) (xy 98.423984 -121.238772) (xy 98.423494 -121.26874)
			(xy 98.415671 -121.328162) (xy 98.400158 -121.386055) (xy 98.377222 -121.441428) (xy 98.347255 -121.493334)
			(xy 98.335212 -121.509028) (xy 99.629466 -121.509028) (xy 99.633537 -121.453406) (xy 99.645663 -121.398969)
			(xy 99.665586 -121.346878) (xy 99.692882 -121.298243) (xy 99.726968 -121.2541) (xy 99.767117 -121.215391)
			(xy 99.812475 -121.18294) (xy 99.862075 -121.157439) (xy 99.914859 -121.139432) (xy 99.969702 -121.129302)
			(xy 100.025436 -121.127265) (xy 100.080873 -121.133365) (xy 100.13483 -121.147471) (xy 100.186159 -121.169283)
			(xy 100.233765 -121.198337) (xy 100.276633 -121.234012) (xy 100.31385 -121.275549) (xy 100.344623 -121.322062)
			(xy 100.368295 -121.372559) (xy 100.384363 -121.425966) (xy 100.392483 -121.481142) (xy 100.392992 -121.509028)
			(xy 100.392483 -121.536914) (xy 100.384363 -121.59209) (xy 100.368295 -121.645497) (xy 100.344623 -121.695994)
			(xy 100.31385 -121.742507) (xy 100.276633 -121.784044) (xy 100.247558 -121.80824) (xy 100.535992 -121.80824)
			(xy 100.540063 -121.752618) (xy 100.552189 -121.698181) (xy 100.572112 -121.64609) (xy 100.599408 -121.597455)
			(xy 100.633494 -121.553312) (xy 100.673643 -121.514603) (xy 100.719001 -121.482152) (xy 100.768601 -121.456651)
			(xy 100.821385 -121.438644) (xy 100.876228 -121.428514) (xy 100.931962 -121.426477) (xy 100.987399 -121.432577)
			(xy 101.041356 -121.446683) (xy 101.092685 -121.468495) (xy 101.140291 -121.497549) (xy 101.183159 -121.533224)
			(xy 101.220376 -121.574761) (xy 101.251149 -121.621274) (xy 101.274821 -121.671771) (xy 101.290889 -121.725178)
			(xy 101.299009 -121.780354) (xy 101.299518 -121.80824) (xy 101.299009 -121.836126) (xy 101.290889 -121.891302)
			(xy 101.274821 -121.944709) (xy 101.251149 -121.995206) (xy 101.220376 -122.041719) (xy 101.183159 -122.083256)
			(xy 101.140291 -122.118931) (xy 101.092685 -122.147985) (xy 101.041356 -122.169797) (xy 100.987399 -122.183903)
			(xy 100.931962 -122.190003) (xy 100.876228 -122.187966) (xy 100.821385 -122.177836) (xy 100.768601 -122.159829)
			(xy 100.719001 -122.134328) (xy 100.673643 -122.101877) (xy 100.633494 -122.063168) (xy 100.599408 -122.019025)
			(xy 100.572112 -121.97039) (xy 100.552189 -121.918299) (xy 100.540063 -121.863862) (xy 100.535992 -121.80824)
			(xy 100.247558 -121.80824) (xy 100.233765 -121.819719) (xy 100.186159 -121.848773) (xy 100.13483 -121.870585)
			(xy 100.080873 -121.884691) (xy 100.025436 -121.890791) (xy 99.969702 -121.888754) (xy 99.914859 -121.878624)
			(xy 99.862075 -121.860617) (xy 99.812475 -121.835116) (xy 99.767117 -121.802665) (xy 99.726968 -121.763956)
			(xy 99.692882 -121.719813) (xy 99.665586 -121.671178) (xy 99.645663 -121.619087) (xy 99.633537 -121.56465)
			(xy 99.629466 -121.509028) (xy 98.335212 -121.509028) (xy 98.310768 -121.540884) (xy 98.268388 -121.583264)
			(xy 98.220838 -121.619751) (xy 98.168932 -121.649718) (xy 98.113559 -121.672654) (xy 98.055666 -121.688167)
			(xy 97.996244 -121.69599) (xy 97.936308 -121.69599) (xy 97.876886 -121.688167) (xy 97.818993 -121.672654)
			(xy 97.76362 -121.649718) (xy 97.711714 -121.619751) (xy 97.664164 -121.583264) (xy 97.621784 -121.540884)
			(xy 97.585297 -121.493334) (xy 97.55533 -121.441428) (xy 97.532394 -121.386055) (xy 97.516881 -121.328162)
			(xy 97.509058 -121.26874) (xy 85.050056 -121.26874) (xy 85.078405 -121.293305) (xy 85.114093 -121.334493)
			(xy 85.143557 -121.380341) (xy 85.166196 -121.429915) (xy 85.18155 -121.482206) (xy 85.189306 -121.536151)
			(xy 85.189306 -121.590649) (xy 85.18155 -121.644594) (xy 85.166196 -121.696885) (xy 85.143557 -121.746459)
			(xy 85.114093 -121.792307) (xy 85.078405 -121.833495) (xy 85.037218 -121.869185) (xy 84.991371 -121.89865)
			(xy 84.941798 -121.921291) (xy 84.889507 -121.936647) (xy 84.835563 -121.944405) (xy 84.808314 -121.944892)
			(xy 84.80806 -121.944892) (xy 84.778246 -121.944311) (xy 84.719355 -121.934958) (xy 84.662634 -121.916564)
			(xy 84.609461 -121.889577) (xy 84.561131 -121.854651) (xy 84.518817 -121.812637) (xy 84.50072 -121.788936)
			(xy 84.498434 -121.785888) (xy 84.491068 -121.778522) (xy 84.485802 -121.773587) (xy 84.473158 -121.766636)
			(xy 84.466176 -121.764806) (xy 84.436966 -121.758202) (xy 84.427822 -121.75617) (xy 84.409534 -121.75871)
			(xy 84.400644 -121.763536) (xy 84.40039 -121.76379) (xy 84.374453 -121.777985) (xy 84.3197 -121.80031)
			(xy 84.262531 -121.815403) (xy 84.203894 -121.823016) (xy 84.17433 -121.82348) (xy 84.144765 -121.823029)
			(xy 84.086125 -121.815426) (xy 84.028955 -121.800329) (xy 83.974206 -121.77799) (xy 83.94827 -121.76379)
			(xy 83.948016 -121.763536) (xy 83.939126 -121.75871) (xy 83.920838 -121.75617) (xy 83.911694 -121.758202)
			(xy 83.881214 -121.76506) (xy 83.872636 -121.767405) (xy 83.857692 -121.77702) (xy 83.852004 -121.783856)
			(xy 83.84667 -121.790968) (xy 83.846416 -121.791222) (xy 83.828307 -121.814632) (xy 83.786044 -121.856062)
			(xy 83.737893 -121.890474) (xy 83.685009 -121.917043) (xy 83.628658 -121.935134) (xy 83.570191 -121.944313)
			(xy 83.5406 -121.944892) (xy 83.540346 -121.944892) (xy 83.51309 -121.944464) (xy 83.459132 -121.936712)
			(xy 83.406826 -121.92136) (xy 83.357238 -121.898719) (xy 83.311377 -121.869251) (xy 83.270177 -121.833555)
			(xy 83.234477 -121.79236) (xy 83.205003 -121.746503) (xy 83.182357 -121.696917) (xy 83.166998 -121.644613)
			(xy 83.159239 -121.590656) (xy 83.159239 -121.536144) (xy 83.166998 -121.482187) (xy 83.182357 -121.429883)
			(xy 83.205003 -121.380297) (xy 83.234477 -121.33444) (xy 83.270177 -121.293245) (xy 83.311377 -121.257549)
			(xy 83.357238 -121.228081) (xy 83.406826 -121.20544) (xy 83.459132 -121.190088) (xy 83.51309 -121.182336)
			(xy 83.540346 -121.181876) (xy 83.555139 -121.182016) (xy 83.584637 -121.184302) (xy 83.599274 -121.186448)
			(xy 83.610196 -121.188226) (xy 83.631532 -121.18213) (xy 83.698588 -121.12498) (xy 83.706616 -121.117412)
			(xy 83.715832 -121.097392) (xy 83.716368 -121.086372) (xy 83.716368 -120.781572) (xy 83.715856 -120.77055)
			(xy 83.706619 -120.750533) (xy 83.698588 -120.742964) (xy 83.631532 -120.685814) (xy 83.610196 -120.679718)
			(xy 83.599274 -120.681496) (xy 83.584636 -120.683635) (xy 83.555139 -120.685924) (xy 83.540346 -120.686068)
			(xy 83.513088 -120.685688) (xy 83.459127 -120.677936) (xy 83.406818 -120.662582) (xy 83.357226 -120.63994)
			(xy 83.311363 -120.61047) (xy 83.27016 -120.574772) (xy 83.234458 -120.533574) (xy 83.204982 -120.487714)
			(xy 83.182334 -120.438126) (xy 83.166974 -120.385819) (xy 83.159215 -120.331858) (xy 77.0255 -120.331858)
			(xy 77.0255 -120.862852) (xy 77.025966 -120.872726) (xy 77.033418 -120.891016) (xy 77.039978 -120.898412)
			(xy 78.266924 -122.125358) (xy 80.517109 -122.125358) (xy 80.517109 -122.070842) (xy 80.524868 -122.016881)
			(xy 80.540228 -121.964574) (xy 80.562876 -121.914985) (xy 80.592351 -121.869125) (xy 80.628053 -121.827926)
			(xy 80.669255 -121.792228) (xy 80.715119 -121.762758) (xy 80.76471 -121.740114) (xy 80.817018 -121.72476)
			(xy 80.87098 -121.717006) (xy 80.898238 -121.716546) (xy 80.898492 -121.716546) (xy 80.928305 -121.717147)
			(xy 80.987196 -121.726493) (xy 81.043918 -121.744882) (xy 81.097091 -121.771866) (xy 81.145422 -121.806789)
			(xy 81.187735 -121.848801) (xy 81.205832 -121.872502) (xy 81.208118 -121.87555) (xy 81.215484 -121.882916)
			(xy 81.220769 -121.887829) (xy 81.233398 -121.894795) (xy 81.240376 -121.896632) (xy 81.269586 -121.903236)
			(xy 81.27873 -121.905268) (xy 81.297018 -121.902728) (xy 81.305908 -121.897902) (xy 81.306416 -121.897648)
			(xy 81.332321 -121.883444) (xy 81.387004 -121.861078) (xy 81.444106 -121.845919) (xy 81.502683 -121.83822)
			(xy 81.532222 -121.837704) (xy 81.561764 -121.838201) (xy 81.620348 -121.845872) (xy 81.677455 -121.86103)
			(xy 81.732131 -121.883424) (xy 81.758028 -121.897648) (xy 81.758536 -121.897902) (xy 81.767426 -121.902728)
			(xy 81.785714 -121.905268) (xy 81.794858 -121.903236) (xy 81.825338 -121.896378) (xy 81.833919 -121.894042)
			(xy 81.848861 -121.88442) (xy 81.854548 -121.877582) (xy 81.859882 -121.87047) (xy 81.860136 -121.870216)
			(xy 81.878283 -121.846837) (xy 81.920538 -121.805404) (xy 81.96868 -121.770988) (xy 82.021557 -121.744412)
			(xy 82.077901 -121.726315) (xy 82.136363 -121.71713) (xy 82.165952 -121.716546) (xy 82.166206 -121.716546)
			(xy 82.193454 -121.717125) (xy 82.247394 -121.724881) (xy 82.299682 -121.740235) (xy 82.349252 -121.762873)
			(xy 82.395096 -121.792336) (xy 82.436281 -121.828023) (xy 82.471967 -121.869208) (xy 82.50143 -121.915053)
			(xy 82.524067 -121.964624) (xy 82.53942 -122.016912) (xy 82.547176 -122.070852) (xy 82.547176 -122.125348)
			(xy 82.53942 -122.179288) (xy 82.524067 -122.231576) (xy 82.50143 -122.281147) (xy 82.471967 -122.326992)
			(xy 82.436281 -122.368177) (xy 82.395096 -122.403864) (xy 82.349252 -122.433327) (xy 82.299682 -122.455965)
			(xy 82.247394 -122.471319) (xy 82.193454 -122.479075) (xy 82.166206 -122.479562) (xy 82.151413 -122.479428)
			(xy 82.121915 -122.477138) (xy 82.107278 -122.47499) (xy 82.096356 -122.473212) (xy 82.07502 -122.479308)
			(xy 82.021375 -122.525028) (xy 99.60559 -122.525028) (xy 99.609661 -122.469406) (xy 99.621787 -122.414969)
			(xy 99.64171 -122.362878) (xy 99.669006 -122.314243) (xy 99.703092 -122.2701) (xy 99.743241 -122.231391)
			(xy 99.788599 -122.19894) (xy 99.838199 -122.173439) (xy 99.890983 -122.155432) (xy 99.945826 -122.145302)
			(xy 100.00156 -122.143265) (xy 100.056997 -122.149365) (xy 100.110954 -122.163471) (xy 100.162283 -122.185283)
			(xy 100.209889 -122.214337) (xy 100.252757 -122.250012) (xy 100.289974 -122.291549) (xy 100.320747 -122.338062)
			(xy 100.344419 -122.388559) (xy 100.360487 -122.441966) (xy 100.368607 -122.497142) (xy 100.369116 -122.525028)
			(xy 100.368607 -122.552914) (xy 100.360487 -122.60809) (xy 100.344419 -122.661497) (xy 100.320747 -122.711994)
			(xy 100.289974 -122.758507) (xy 100.252757 -122.800044) (xy 100.209889 -122.835719) (xy 100.162283 -122.864773)
			(xy 100.110954 -122.886585) (xy 100.056997 -122.900691) (xy 100.00156 -122.906791) (xy 99.945826 -122.904754)
			(xy 99.890983 -122.894624) (xy 99.838199 -122.876617) (xy 99.788599 -122.851116) (xy 99.743241 -122.818665)
			(xy 99.703092 -122.779956) (xy 99.669006 -122.735813) (xy 99.64171 -122.687178) (xy 99.621787 -122.635087)
			(xy 99.609661 -122.58065) (xy 99.60559 -122.525028) (xy 82.021375 -122.525028) (xy 82.007964 -122.536458)
			(xy 81.999956 -122.544043) (xy 81.990731 -122.564051) (xy 81.990184 -122.575066) (xy 81.990184 -122.879866)
			(xy 81.990746 -122.890882) (xy 81.999949 -122.910898) (xy 82.007964 -122.918474) (xy 82.07502 -122.975624)
			(xy 82.096356 -122.98172) (xy 82.107278 -122.979942) (xy 82.121915 -122.977797) (xy 82.151413 -122.975512)
			(xy 82.166206 -122.97537) (xy 82.193455 -122.975901) (xy 82.247399 -122.983657) (xy 82.29969 -122.999012)
			(xy 82.349264 -123.021652) (xy 82.395111 -123.051117) (xy 82.436298 -123.086806) (xy 82.471987 -123.127994)
			(xy 82.501451 -123.173842) (xy 82.52409 -123.223415) (xy 82.539444 -123.275707) (xy 82.5472 -123.329651)
			(xy 82.5472 -123.364553) (xy 94.064275 -123.364553) (xy 94.064275 -123.310047) (xy 94.072033 -123.256097)
			(xy 94.087389 -123.203799) (xy 94.110033 -123.15422) (xy 94.139502 -123.108368) (xy 94.175197 -123.067177)
			(xy 94.21639 -123.031485) (xy 94.262245 -123.002019) (xy 94.311826 -122.97938) (xy 94.364124 -122.964027)
			(xy 94.418075 -122.956273) (xy 94.445328 -122.955812) (xy 94.472699 -122.956259) (xy 94.526879 -122.964081)
			(xy 94.579382 -122.979574) (xy 94.629129 -123.00242) (xy 94.675095 -123.032149) (xy 94.696026 -123.049792)
			(xy 94.69628 -123.050046) (xy 94.703364 -123.055636) (xy 94.720283 -123.061879) (xy 94.7293 -123.062238)
			(xy 94.796356 -123.062238) (xy 94.80537 -123.061852) (xy 94.822286 -123.055624) (xy 94.829376 -123.050046)
			(xy 94.829884 -123.049538) (xy 94.850814 -123.03192) (xy 94.896781 -123.002258) (xy 94.946516 -122.979468)
			(xy 94.998997 -122.96402) (xy 95.053146 -122.956231) (xy 95.107854 -122.95626) (xy 95.161995 -122.964106)
			(xy 95.21446 -122.979609) (xy 95.264171 -123.002451) (xy 95.310107 -123.032162) (xy 95.331026 -123.049792)
			(xy 95.33128 -123.050046) (xy 95.338364 -123.055636) (xy 95.355283 -123.061879) (xy 95.3643 -123.062238)
			(xy 95.431356 -123.062238) (xy 95.44037 -123.061852) (xy 95.457286 -123.055624) (xy 95.464376 -123.050046)
			(xy 95.464884 -123.049538) (xy 95.48581 -123.031945) (xy 95.531746 -123.002306) (xy 95.581444 -122.979529)
			(xy 95.633885 -122.964081) (xy 95.687994 -122.956279) (xy 95.715328 -122.955812) (xy 95.742579 -122.95626)
			(xy 95.796527 -122.96402) (xy 95.848821 -122.979378) (xy 95.898397 -123.002022) (xy 95.944247 -123.031491)
			(xy 95.985436 -123.067184) (xy 96.021126 -123.108376) (xy 96.050591 -123.154227) (xy 96.073232 -123.203805)
			(xy 96.088586 -123.256101) (xy 96.096342 -123.310049) (xy 96.096342 -123.364551) (xy 96.088586 -123.4185)
			(xy 96.073232 -123.470795) (xy 96.050591 -123.520373) (xy 96.021126 -123.566224) (xy 95.985436 -123.607416)
			(xy 95.944247 -123.643109) (xy 95.898397 -123.672578) (xy 95.848821 -123.695222) (xy 95.796527 -123.71058)
			(xy 95.742579 -123.71834) (xy 95.715328 -123.718828) (xy 95.687958 -123.718363) (xy 95.633778 -123.710548)
			(xy 95.581274 -123.695059) (xy 95.531527 -123.672217) (xy 95.485561 -123.64249) (xy 95.46463 -123.624848)
			(xy 95.464376 -123.624594) (xy 95.457301 -123.618991) (xy 95.440375 -123.612754) (xy 95.431356 -123.612402)
			(xy 95.3643 -123.612402) (xy 95.355283 -123.612759) (xy 95.338366 -123.619006) (xy 95.33128 -123.624594)
			(xy 95.330772 -123.625102) (xy 95.309797 -123.642663) (xy 95.263837 -123.672325) (xy 95.214109 -123.695115)
			(xy 95.161636 -123.710566) (xy 95.107493 -123.71836) (xy 95.052792 -123.718337) (xy 94.998655 -123.710498)
			(xy 94.946194 -123.695004) (xy 94.896486 -123.672173) (xy 94.85055 -123.642473) (xy 94.82963 -123.624848)
			(xy 94.829376 -123.624594) (xy 94.822301 -123.618991) (xy 94.805375 -123.612754) (xy 94.796356 -123.612402)
			(xy 94.7293 -123.612402) (xy 94.720283 -123.612759) (xy 94.703366 -123.619006) (xy 94.69628 -123.624594)
			(xy 94.695772 -123.625102) (xy 94.67483 -123.642674) (xy 94.628898 -123.672316) (xy 94.579204 -123.695096)
			(xy 94.526767 -123.710548) (xy 94.472661 -123.718357) (xy 94.445328 -123.718828) (xy 94.418075 -123.718327)
			(xy 94.364124 -123.710573) (xy 94.311826 -123.69522) (xy 94.262245 -123.672581) (xy 94.21639 -123.643115)
			(xy 94.175197 -123.607423) (xy 94.139502 -123.566232) (xy 94.110033 -123.52038) (xy 94.087389 -123.470801)
			(xy 94.072033 -123.418503) (xy 94.064275 -123.364553) (xy 82.5472 -123.364553) (xy 82.5472 -123.384149)
			(xy 82.539444 -123.438093) (xy 82.52409 -123.490385) (xy 82.501451 -123.539958) (xy 82.471987 -123.585806)
			(xy 82.436298 -123.626994) (xy 82.395111 -123.662683) (xy 82.349264 -123.692148) (xy 82.29969 -123.714788)
			(xy 82.247399 -123.730143) (xy 82.193455 -123.737899) (xy 82.166206 -123.738386) (xy 82.165952 -123.738386)
			(xy 82.136138 -123.737813) (xy 82.077246 -123.728459) (xy 82.020525 -123.710064) (xy 81.967352 -123.683075)
			(xy 81.919022 -123.648148) (xy 81.876708 -123.606132) (xy 81.858612 -123.58243) (xy 81.856326 -123.579382)
			(xy 81.84896 -123.572016) (xy 81.843672 -123.567106) (xy 81.831045 -123.56014) (xy 81.824068 -123.5583)
			(xy 81.794858 -123.551696) (xy 81.785714 -123.549664) (xy 81.767426 -123.552204) (xy 81.758536 -123.55703)
			(xy 81.758028 -123.557284) (xy 81.732111 -123.571465) (xy 81.677433 -123.593838) (xy 81.620334 -123.609003)
			(xy 81.56176 -123.616709) (xy 81.532222 -123.617228) (xy 81.50268 -123.616751) (xy 81.444095 -123.609074)
			(xy 81.386988 -123.593909) (xy 81.332312 -123.57151) (xy 81.306416 -123.557284) (xy 81.305908 -123.55703)
			(xy 81.297018 -123.552204) (xy 81.27873 -123.549664) (xy 81.269586 -123.551696) (xy 81.239106 -123.558554)
			(xy 81.230527 -123.560898) (xy 81.215584 -123.570514) (xy 81.209896 -123.57735) (xy 81.204562 -123.584462)
			(xy 81.204308 -123.584716) (xy 81.186202 -123.608128) (xy 81.143938 -123.649558) (xy 81.095787 -123.68397)
			(xy 81.042902 -123.710539) (xy 80.986551 -123.728629) (xy 80.928083 -123.737807) (xy 80.898492 -123.738386)
			(xy 80.898238 -123.738386) (xy 80.870982 -123.73797) (xy 80.817024 -123.730217) (xy 80.764718 -123.714863)
			(xy 80.71513 -123.692221) (xy 80.66927 -123.662753) (xy 80.62807 -123.627057) (xy 80.59237 -123.585861)
			(xy 80.562897 -123.540003) (xy 80.54025 -123.490418) (xy 80.524891 -123.438114) (xy 80.517133 -123.384156)
			(xy 80.517133 -123.329644) (xy 80.524891 -123.275686) (xy 80.54025 -123.223382) (xy 80.562897 -123.173797)
			(xy 80.59237 -123.127939) (xy 80.62807 -123.086743) (xy 80.66927 -123.051047) (xy 80.71513 -123.021579)
			(xy 80.764718 -122.998937) (xy 80.817024 -122.983583) (xy 80.870982 -122.97583) (xy 80.898238 -122.97537)
			(xy 80.913031 -122.97551) (xy 80.942529 -122.977796) (xy 80.957166 -122.979942) (xy 80.968088 -122.98172)
			(xy 80.989424 -122.975624) (xy 81.05648 -122.918474) (xy 81.064525 -122.910923) (xy 81.073728 -122.890889)
			(xy 81.07426 -122.879866) (xy 81.07426 -122.575066) (xy 81.073753 -122.564043) (xy 81.064513 -122.544026)
			(xy 81.05648 -122.536458) (xy 80.989424 -122.479308) (xy 80.968088 -122.473212) (xy 80.957166 -122.47499)
			(xy 80.942528 -122.477129) (xy 80.913031 -122.479418) (xy 80.898238 -122.479562) (xy 80.87098 -122.479194)
			(xy 80.817018 -122.47144) (xy 80.76471 -122.456086) (xy 80.715119 -122.433442) (xy 80.669255 -122.403972)
			(xy 80.628053 -122.368274) (xy 80.592351 -122.327075) (xy 80.562876 -122.281215) (xy 80.540228 -122.231626)
			(xy 80.524868 -122.179319) (xy 80.517109 -122.125358) (xy 78.266924 -122.125358) (xy 80.073321 -123.931755)
			(xy 83.159257 -123.931755) (xy 83.159257 -123.877245) (xy 83.167016 -123.823291) (xy 83.182374 -123.770989)
			(xy 83.20502 -123.721406) (xy 83.234492 -123.675551) (xy 83.27019 -123.634358) (xy 83.311388 -123.598664)
			(xy 83.357247 -123.569198) (xy 83.406832 -123.546558) (xy 83.459136 -123.531206) (xy 83.513091 -123.523454)
			(xy 83.540346 -123.522994) (xy 83.5406 -123.522994) (xy 83.570412 -123.52361) (xy 83.629302 -123.532956)
			(xy 83.686022 -123.551343) (xy 83.739195 -123.578324) (xy 83.787526 -123.613244) (xy 83.829842 -123.655251)
			(xy 83.84794 -123.67895) (xy 83.850226 -123.681998) (xy 83.857592 -123.689364) (xy 83.86287 -123.694286)
			(xy 83.875505 -123.701245) (xy 83.882484 -123.70308) (xy 83.911694 -123.709684) (xy 83.920838 -123.711716)
			(xy 83.939126 -123.709176) (xy 83.948016 -123.70435) (xy 83.948524 -123.704096) (xy 83.97443 -123.689893)
			(xy 84.029112 -123.667526) (xy 84.086214 -123.652367) (xy 84.144791 -123.644668) (xy 84.17433 -123.644152)
			(xy 84.203872 -123.644652) (xy 84.262456 -123.652323) (xy 84.319562 -123.667481) (xy 84.374239 -123.689873)
			(xy 84.400136 -123.704096) (xy 84.400644 -123.70435) (xy 84.409534 -123.709176) (xy 84.427822 -123.711716)
			(xy 84.436966 -123.709684) (xy 84.467446 -123.702826) (xy 84.476023 -123.700479) (xy 84.490966 -123.690864)
			(xy 84.496656 -123.68403) (xy 84.50199 -123.676918) (xy 84.502244 -123.676664) (xy 84.520372 -123.65327)
			(xy 84.562632 -123.61184) (xy 84.610779 -123.577427) (xy 84.663659 -123.550855) (xy 84.720006 -123.53276)
			(xy 84.77847 -123.523576) (xy 84.80806 -123.522994) (xy 84.808314 -123.522994) (xy 84.835565 -123.523477)
			(xy 84.889511 -123.531235) (xy 84.941805 -123.546591) (xy 84.99138 -123.569233) (xy 85.037229 -123.5987)
			(xy 85.078418 -123.634392) (xy 85.114108 -123.675582) (xy 85.143573 -123.721432) (xy 85.166214 -123.771009)
			(xy 85.181568 -123.823302) (xy 85.189324 -123.877249) (xy 85.189324 -123.931751) (xy 85.181568 -123.985698)
			(xy 85.166214 -124.037991) (xy 85.143573 -124.087568) (xy 85.114108 -124.133418) (xy 85.078418 -124.174608)
			(xy 85.037229 -124.2103) (xy 84.99138 -124.239767) (xy 84.941805 -124.262409) (xy 84.889511 -124.277765)
			(xy 84.835565 -124.285523) (xy 84.808314 -124.28601) (xy 84.793521 -124.285875) (xy 84.764023 -124.283586)
			(xy 84.749386 -124.281438) (xy 84.738464 -124.27966) (xy 84.717128 -124.285756) (xy 84.650072 -124.342906)
			(xy 84.642044 -124.350473) (xy 84.632829 -124.370494) (xy 84.632292 -124.381514) (xy 84.632292 -124.686314)
			(xy 84.632825 -124.697333) (xy 84.642048 -124.71735) (xy 84.650072 -124.724922) (xy 84.717128 -124.782072)
			(xy 84.738464 -124.788168) (xy 84.749386 -124.78639) (xy 84.764023 -124.784244) (xy 84.793521 -124.78196)
			(xy 84.808314 -124.781818) (xy 84.835566 -124.782253) (xy 84.889516 -124.790011) (xy 84.941813 -124.805369)
			(xy 84.991392 -124.828012) (xy 85.037244 -124.857481) (xy 85.078435 -124.893175) (xy 85.114127 -124.934368)
			(xy 85.143594 -124.98022) (xy 85.166236 -125.0298) (xy 85.181592 -125.082097) (xy 85.189348 -125.136048)
			(xy 85.189348 -125.190552) (xy 85.181592 -125.244503) (xy 85.166236 -125.2968) (xy 85.143594 -125.34638)
			(xy 85.114127 -125.392232) (xy 85.078435 -125.433425) (xy 85.037244 -125.469119) (xy 84.991392 -125.498588)
			(xy 84.941813 -125.521231) (xy 84.889516 -125.536589) (xy 84.835566 -125.544347) (xy 84.808314 -125.544834)
			(xy 84.80806 -125.544834) (xy 84.778247 -125.544236) (xy 84.719358 -125.534884) (xy 84.662637 -125.516493)
			(xy 84.609465 -125.489508) (xy 84.561134 -125.454587) (xy 84.518818 -125.412577) (xy 84.50072 -125.388878)
			(xy 84.498434 -125.38583) (xy 84.491068 -125.378464) (xy 84.485797 -125.373535) (xy 84.473157 -125.366579)
			(xy 84.466176 -125.364748) (xy 84.436966 -125.358144) (xy 84.427822 -125.356112) (xy 84.409534 -125.358652)
			(xy 84.400644 -125.363478) (xy 84.400136 -125.363732) (xy 84.37424 -125.377953) (xy 84.319554 -125.400315)
			(xy 84.262448 -125.415469) (xy 84.20387 -125.423163) (xy 84.17433 -125.423676) (xy 84.144787 -125.423202)
			(xy 84.086202 -125.415525) (xy 84.029095 -125.40036) (xy 83.97442 -125.377959) (xy 83.948524 -125.363732)
			(xy 83.948016 -125.363478) (xy 83.939126 -125.358652) (xy 83.920838 -125.356112) (xy 83.911694 -125.358144)
			(xy 83.881214 -125.365002) (xy 83.872642 -125.367364) (xy 83.857696 -125.376968) (xy 83.852004 -125.383798)
			(xy 83.84667 -125.39091) (xy 83.846416 -125.391164) (xy 83.828291 -125.414561) (xy 83.786033 -125.455994)
			(xy 83.737886 -125.49041) (xy 83.685005 -125.516982) (xy 83.628656 -125.535074) (xy 83.570191 -125.544254)
			(xy 83.5406 -125.544834) (xy 83.540346 -125.544834) (xy 83.513093 -125.544322) (xy 83.459141 -125.536571)
			(xy 83.406841 -125.52122) (xy 83.357258 -125.498581) (xy 83.311403 -125.469117) (xy 83.270207 -125.433425)
			(xy 83.234511 -125.392234) (xy 83.205041 -125.346382) (xy 83.182396 -125.296802) (xy 83.167039 -125.244504)
			(xy 83.159281 -125.190553) (xy 83.159281 -125.136047) (xy 83.167039 -125.082096) (xy 83.182396 -125.029798)
			(xy 83.205041 -124.980218) (xy 83.234511 -124.934366) (xy 83.270207 -124.893175) (xy 83.311403 -124.857483)
			(xy 83.357258 -124.828019) (xy 83.406841 -124.80538) (xy 83.459141 -124.790029) (xy 83.513093 -124.782278)
			(xy 83.540346 -124.781818) (xy 83.555139 -124.781958) (xy 83.584637 -124.784244) (xy 83.599274 -124.78639)
			(xy 83.610196 -124.788168) (xy 83.631532 -124.782072) (xy 83.698588 -124.724922) (xy 83.706597 -124.717337)
			(xy 83.715824 -124.69733) (xy 83.716368 -124.686314) (xy 83.716368 -124.381514) (xy 83.715833 -124.370495)
			(xy 83.706613 -124.350477) (xy 83.698588 -124.342906) (xy 83.631532 -124.285756) (xy 83.610196 -124.27966)
			(xy 83.599274 -124.281438) (xy 83.584636 -124.283577) (xy 83.555139 -124.285866) (xy 83.540346 -124.28601)
			(xy 83.513091 -124.285546) (xy 83.459136 -124.277794) (xy 83.406832 -124.262442) (xy 83.357247 -124.239802)
			(xy 83.311388 -124.210336) (xy 83.27019 -124.174642) (xy 83.234492 -124.133449) (xy 83.20502 -124.087594)
			(xy 83.182374 -124.038011) (xy 83.167016 -123.985709) (xy 83.159257 -123.931755) (xy 80.073321 -123.931755)
			(xy 82.155538 -126.013972) (xy 89.450672 -126.013972) (xy 89.451139 -125.986638) (xy 89.458946 -125.93253)
			(xy 89.474395 -125.880091) (xy 89.497171 -125.830393) (xy 89.526807 -125.784455) (xy 89.544398 -125.763528)
			(xy 89.544652 -125.763274) (xy 89.544906 -125.76302) (xy 89.550491 -125.755932) (xy 89.556738 -125.739016)
			(xy 89.557098 -125.73) (xy 89.557098 -125.662944) (xy 89.55672 -125.653929) (xy 89.550487 -125.637012)
			(xy 89.544906 -125.629924) (xy 89.544652 -125.62967) (xy 89.544398 -125.629416) (xy 89.526769 -125.608517)
			(xy 89.497115 -125.56258) (xy 89.474326 -125.51288) (xy 89.45887 -125.460433) (xy 89.451063 -125.406317)
			(xy 89.451066 -125.351641) (xy 89.458879 -125.297525) (xy 89.474341 -125.245081) (xy 89.497135 -125.195383)
			(xy 89.526794 -125.14945) (xy 89.544398 -125.128528) (xy 89.544652 -125.128274) (xy 89.544906 -125.12802)
			(xy 89.550491 -125.120932) (xy 89.556738 -125.104016) (xy 89.557098 -125.095) (xy 89.557098 -125.027944)
			(xy 89.55672 -125.018929) (xy 89.550487 -125.002012) (xy 89.544906 -124.994924) (xy 89.544652 -124.99467)
			(xy 89.544398 -124.994416) (xy 89.526769 -124.973517) (xy 89.497115 -124.92758) (xy 89.474326 -124.87788)
			(xy 89.45887 -124.825433) (xy 89.451063 -124.771317) (xy 89.451066 -124.716641) (xy 89.458879 -124.662525)
			(xy 89.474341 -124.610081) (xy 89.497135 -124.560383) (xy 89.526794 -124.51445) (xy 89.544398 -124.493528)
			(xy 89.544652 -124.493274) (xy 89.544906 -124.49302) (xy 89.550491 -124.485932) (xy 89.556738 -124.469016)
			(xy 89.557098 -124.46) (xy 89.557098 -124.392944) (xy 89.55672 -124.383929) (xy 89.550487 -124.367012)
			(xy 89.544906 -124.359924) (xy 89.544652 -124.35967) (xy 89.544398 -124.359416) (xy 89.526799 -124.338495)
			(xy 89.497162 -124.292557) (xy 89.474387 -124.242858) (xy 89.45894 -124.190416) (xy 89.451139 -124.136307)
			(xy 89.450672 -124.108972) (xy 89.451158 -124.081721) (xy 89.458914 -124.027773) (xy 89.474269 -123.975478)
			(xy 89.496911 -123.925901) (xy 89.526377 -123.880051) (xy 89.562068 -123.83886) (xy 89.603259 -123.803169)
			(xy 89.649109 -123.773703) (xy 89.698686 -123.751061) (xy 89.750981 -123.735706) (xy 89.804929 -123.72795)
			(xy 89.859431 -123.72795) (xy 89.913379 -123.735706) (xy 89.965674 -123.751061) (xy 90.015251 -123.773703)
			(xy 90.061101 -123.803169) (xy 90.102292 -123.83886) (xy 90.137983 -123.880051) (xy 90.167449 -123.925901)
			(xy 90.190091 -123.975478) (xy 90.205446 -124.027773) (xy 90.213202 -124.081721) (xy 90.213688 -124.108972)
			(xy 90.213232 -124.136306) (xy 90.20542 -124.190414) (xy 90.189968 -124.242853) (xy 90.16719 -124.292551)
			(xy 90.137553 -124.338489) (xy 90.119962 -124.359416) (xy 90.119708 -124.35967) (xy 90.119454 -124.359924)
			(xy 90.113846 -124.366996) (xy 90.107613 -124.383924) (xy 90.107262 -124.392944) (xy 90.107262 -124.46)
			(xy 90.107627 -124.469016) (xy 90.110861 -124.47778) (xy 92.41282 -124.47778) (xy 92.413305 -124.450447)
			(xy 92.421109 -124.39634) (xy 92.436555 -124.343901) (xy 92.459327 -124.294203) (xy 92.488958 -124.248264)
			(xy 92.506546 -124.227336) (xy 92.5068 -124.227082) (xy 92.507054 -124.226828) (xy 92.512641 -124.219742)
			(xy 92.518886 -124.202825) (xy 92.519246 -124.193808) (xy 92.519246 -124.126752) (xy 92.518876 -124.117736)
			(xy 92.512639 -124.100818) (xy 92.507054 -124.093732) (xy 92.5068 -124.093478) (xy 92.506546 -124.093224)
			(xy 92.488958 -124.072294) (xy 92.459318 -124.026359) (xy 92.43654 -123.976662) (xy 92.421091 -123.924222)
			(xy 92.413288 -123.870114) (xy 92.41282 -123.84278) (xy 92.413306 -123.815529) (xy 92.421062 -123.761581)
			(xy 92.436417 -123.709286) (xy 92.459059 -123.659709) (xy 92.488525 -123.613859) (xy 92.524216 -123.572668)
			(xy 92.565407 -123.536977) (xy 92.611257 -123.507511) (xy 92.660834 -123.484869) (xy 92.713129 -123.469514)
			(xy 92.767077 -123.461758) (xy 92.821579 -123.461758) (xy 92.875527 -123.469514) (xy 92.927822 -123.484869)
			(xy 92.977399 -123.507511) (xy 93.023249 -123.536977) (xy 93.06444 -123.572668) (xy 93.100131 -123.613859)
			(xy 93.129597 -123.659709) (xy 93.152239 -123.709286) (xy 93.167594 -123.761581) (xy 93.172403 -123.795028)
			(xy 97.365566 -123.795028) (xy 97.366087 -123.765061) (xy 97.373907 -123.705638) (xy 97.389415 -123.647745)
			(xy 97.412348 -123.592371) (xy 97.442312 -123.540465) (xy 97.478795 -123.492913) (xy 97.521173 -123.450531)
			(xy 97.56872 -123.414042) (xy 97.620623 -123.384072) (xy 97.675994 -123.361133) (xy 97.733885 -123.345617)
			(xy 97.793307 -123.337791) (xy 97.823274 -123.33732) (xy 97.85096 -123.338082) (xy 97.856684 -123.338251)
			(xy 97.86797 -123.336333) (xy 97.873312 -123.334272) (xy 97.878471 -123.331952) (xy 97.887703 -123.325419)
			(xy 97.8916 -123.321318) (xy 97.943924 -123.263406) (xy 97.949888 -123.256181) (xy 97.956659 -123.238727)
			(xy 97.957132 -123.22937) (xy 97.957132 -123.219972) (xy 97.956624 -123.216162) (xy 97.956624 -123.215654)
			(xy 97.956116 -123.212098) (xy 97.954387 -123.199149) (xy 97.95248 -123.173091) (xy 97.952306 -123.160028)
			(xy 97.952781 -123.132775) (xy 97.960535 -123.078824) (xy 97.975888 -123.026525) (xy 97.998528 -122.976945)
			(xy 98.027995 -122.931091) (xy 98.063687 -122.889897) (xy 98.104879 -122.854203) (xy 98.150732 -122.824735)
			(xy 98.200312 -122.802093) (xy 98.25261 -122.786738) (xy 98.306561 -122.778982) (xy 98.333814 -122.77852)
			(xy 98.361069 -122.778942) (xy 98.415022 -122.786702) (xy 98.467323 -122.802061) (xy 98.516905 -122.824707)
			(xy 98.562759 -122.854179) (xy 98.603953 -122.889877) (xy 98.639646 -122.931074) (xy 98.669113 -122.976932)
			(xy 98.691754 -123.026517) (xy 98.707107 -123.078819) (xy 98.714861 -123.132773) (xy 98.715322 -123.160028)
			(xy 98.714829 -123.188922) (xy 98.706138 -123.246053) (xy 98.688929 -123.301219) (xy 98.663596 -123.353158)
			(xy 98.630718 -123.400681) (xy 98.591048 -123.442702) (xy 98.545493 -123.478257) (xy 98.495096 -123.506535)
			(xy 98.441011 -123.526887) (xy 98.384475 -123.538848) (xy 98.355658 -123.541028) (xy 98.343974 -123.54179)
			(xy 98.323908 -123.552712) (xy 98.273108 -123.623832) (xy 98.268778 -123.630415) (xy 98.264 -123.645422)
			(xy 98.26371 -123.653296) (xy 98.26371 -123.669806) (xy 98.265488 -123.67641) (xy 98.272722 -123.705336)
			(xy 98.280488 -123.764453) (xy 98.280982 -123.794266) (xy 98.280982 -123.795028) (xy 99.649024 -123.795028)
			(xy 99.653095 -123.739406) (xy 99.665221 -123.684969) (xy 99.685144 -123.632878) (xy 99.71244 -123.584243)
			(xy 99.746526 -123.5401) (xy 99.786675 -123.501391) (xy 99.832033 -123.46894) (xy 99.881633 -123.443439)
			(xy 99.934417 -123.425432) (xy 99.98926 -123.415302) (xy 100.044994 -123.413265) (xy 100.100431 -123.419365)
			(xy 100.154388 -123.433471) (xy 100.205717 -123.455283) (xy 100.253323 -123.484337) (xy 100.296191 -123.520012)
			(xy 100.333408 -123.561549) (xy 100.364181 -123.608062) (xy 100.387853 -123.658559) (xy 100.403921 -123.711966)
			(xy 100.412041 -123.767142) (xy 100.41255 -123.795028) (xy 100.412041 -123.822914) (xy 100.403921 -123.87809)
			(xy 100.387853 -123.931497) (xy 100.364181 -123.981994) (xy 100.333408 -124.028507) (xy 100.296191 -124.070044)
			(xy 100.253323 -124.105719) (xy 100.205717 -124.134773) (xy 100.154388 -124.156585) (xy 100.100431 -124.170691)
			(xy 100.044994 -124.176791) (xy 99.98926 -124.174754) (xy 99.934417 -124.164624) (xy 99.881633 -124.146617)
			(xy 99.832033 -124.121116) (xy 99.786675 -124.088665) (xy 99.746526 -124.049956) (xy 99.71244 -124.005813)
			(xy 99.685144 -123.957178) (xy 99.665221 -123.905087) (xy 99.653095 -123.85065) (xy 99.649024 -123.795028)
			(xy 98.280982 -123.795028) (xy 98.280492 -123.824996) (xy 98.272669 -123.884418) (xy 98.257156 -123.942311)
			(xy 98.23422 -123.997684) (xy 98.204253 -124.04959) (xy 98.167766 -124.09714) (xy 98.125386 -124.13952)
			(xy 98.077836 -124.176007) (xy 98.02593 -124.205974) (xy 97.970557 -124.22891) (xy 97.912664 -124.244423)
			(xy 97.853242 -124.252246) (xy 97.793306 -124.252246) (xy 97.733884 -124.244423) (xy 97.675991 -124.22891)
			(xy 97.620618 -124.205974) (xy 97.568712 -124.176007) (xy 97.521162 -124.13952) (xy 97.478782 -124.09714)
			(xy 97.442295 -124.04959) (xy 97.412328 -123.997684) (xy 97.389392 -123.942311) (xy 97.373879 -123.884418)
			(xy 97.366056 -123.824996) (xy 97.365566 -123.795028) (xy 93.172403 -123.795028) (xy 93.17535 -123.815529)
			(xy 93.175836 -123.84278) (xy 93.175397 -123.870115) (xy 93.167583 -123.924224) (xy 93.152127 -123.976664)
			(xy 93.129345 -124.026361) (xy 93.099704 -124.072298) (xy 93.08211 -124.093224) (xy 93.081856 -124.093478)
			(xy 93.081602 -124.093732) (xy 93.076038 -124.100834) (xy 93.069778 -124.117739) (xy 93.06941 -124.126752)
			(xy 93.06941 -124.193808) (xy 93.069761 -124.202826) (xy 93.074313 -124.215144) (xy 94.606616 -124.215144)
			(xy 94.610687 -124.159522) (xy 94.622813 -124.105085) (xy 94.642736 -124.052994) (xy 94.670032 -124.004359)
			(xy 94.704118 -123.960216) (xy 94.744267 -123.921507) (xy 94.789625 -123.889056) (xy 94.839225 -123.863555)
			(xy 94.892009 -123.845548) (xy 94.946852 -123.835418) (xy 95.002586 -123.833381) (xy 95.058023 -123.839481)
			(xy 95.11198 -123.853587) (xy 95.163309 -123.875399) (xy 95.210915 -123.904453) (xy 95.253783 -123.940128)
			(xy 95.291 -123.981665) (xy 95.321773 -124.028178) (xy 95.345445 -124.078675) (xy 95.361513 -124.132082)
			(xy 95.369633 -124.187258) (xy 95.370142 -124.215144) (xy 95.369633 -124.24303) (xy 95.361513 -124.298206)
			(xy 95.345445 -124.351613) (xy 95.321773 -124.40211) (xy 95.291 -124.448623) (xy 95.253783 -124.49016)
			(xy 95.210915 -124.525835) (xy 95.163309 -124.554889) (xy 95.11198 -124.576701) (xy 95.058023 -124.590807)
			(xy 95.002586 -124.596907) (xy 94.946852 -124.59487) (xy 94.892009 -124.58474) (xy 94.839225 -124.566733)
			(xy 94.789625 -124.541232) (xy 94.744267 -124.508781) (xy 94.704118 -124.470072) (xy 94.670032 -124.425929)
			(xy 94.642736 -124.377294) (xy 94.622813 -124.325203) (xy 94.610687 -124.270766) (xy 94.606616 -124.215144)
			(xy 93.074313 -124.215144) (xy 93.076012 -124.219743) (xy 93.081602 -124.226828) (xy 93.081856 -124.227082)
			(xy 93.08211 -124.227336) (xy 93.099687 -124.248274) (xy 93.129328 -124.294208) (xy 93.152107 -124.343902)
			(xy 93.167558 -124.39634) (xy 93.175365 -124.450447) (xy 93.175836 -124.47778) (xy 93.17535 -124.505031)
			(xy 93.167594 -124.558979) (xy 93.152239 -124.611274) (xy 93.129597 -124.660851) (xy 93.100131 -124.706701)
			(xy 93.06444 -124.747892) (xy 93.023249 -124.783583) (xy 92.977399 -124.813049) (xy 92.927822 -124.835691)
			(xy 92.875527 -124.851046) (xy 92.821579 -124.858802) (xy 92.767077 -124.858802) (xy 92.713129 -124.851046)
			(xy 92.660834 -124.835691) (xy 92.611257 -124.813049) (xy 92.565407 -124.783583) (xy 92.524216 -124.747892)
			(xy 92.488525 -124.706701) (xy 92.459059 -124.660851) (xy 92.436417 -124.611274) (xy 92.421062 -124.558979)
			(xy 92.413306 -124.505031) (xy 92.41282 -124.47778) (xy 90.110861 -124.47778) (xy 90.11387 -124.485932)
			(xy 90.119454 -124.49302) (xy 90.119708 -124.493274) (xy 90.119962 -124.493528) (xy 90.135618 -124.512047)
			(xy 90.162603 -124.552339) (xy 90.184259 -124.595728) (xy 90.192606 -124.618496) (xy 90.192606 -124.61875)
			(xy 90.197525 -124.630521) (xy 90.216459 -124.647575) (xy 90.228674 -124.651262) (xy 90.323924 -124.674376)
			(xy 90.34907 -124.667772) (xy 90.358214 -124.658882) (xy 90.379633 -124.639202) (xy 90.427342 -124.605928)
			(xy 90.479545 -124.580275) (xy 90.535036 -124.562837) (xy 90.592529 -124.554017) (xy 90.621612 -124.553472)
			(xy 90.648983 -124.553913) (xy 90.703164 -124.561735) (xy 90.755668 -124.577228) (xy 90.805415 -124.600076)
			(xy 90.85138 -124.629807) (xy 90.87231 -124.647452) (xy 90.872564 -124.647706) (xy 90.879656 -124.653284)
			(xy 90.896569 -124.659536) (xy 90.905584 -124.659898) (xy 90.97264 -124.659898) (xy 90.981659 -124.65956)
			(xy 90.998576 -124.653299) (xy 91.00566 -124.647706) (xy 91.006168 -124.647198) (xy 91.027095 -124.629607)
			(xy 91.073031 -124.599968) (xy 91.122729 -124.577192) (xy 91.175169 -124.561744) (xy 91.229278 -124.553941)
			(xy 91.256612 -124.553472) (xy 91.283851 -124.553966) (xy 91.337775 -124.561717) (xy 91.390048 -124.57706)
			(xy 91.439607 -124.599682) (xy 91.485444 -124.629124) (xy 91.526627 -124.664787) (xy 91.562319 -124.705946)
			(xy 91.591792 -124.751762) (xy 91.614449 -124.801306) (xy 91.629827 -124.853569) (xy 91.637616 -124.907487)
			(xy 91.63812 -124.934726) (xy 91.63812 -124.93498) (xy 91.637358 -124.955046) (xy 91.637358 -124.95657)
			(xy 91.637358 -124.963174) (xy 91.638006 -124.975303) (xy 91.649013 -124.996917) (xy 91.65844 -125.004576)
			(xy 91.728544 -125.054868) (xy 91.739219 -125.061654) (xy 91.764269 -125.064873) (xy 91.776296 -125.060964)
			(xy 91.778328 -125.060202) (xy 91.779598 -125.059694) (xy 91.801916 -125.051272) (xy 91.848124 -125.039424)
			(xy 91.895447 -125.033422) (xy 91.919298 -125.033024) (xy 91.946552 -125.033457) (xy 92.000506 -125.041215)
			(xy 92.052806 -125.056572) (xy 92.102389 -125.079217) (xy 92.148243 -125.108688) (xy 92.189437 -125.144385)
			(xy 92.22513 -125.185581) (xy 92.254598 -125.231438) (xy 92.277238 -125.281022) (xy 92.292592 -125.333323)
			(xy 92.300345 -125.387278) (xy 92.300806 -125.414532) (xy 92.300322 -125.441865) (xy 92.292517 -125.495972)
			(xy 92.27707 -125.54841) (xy 92.254299 -125.598108) (xy 92.224668 -125.644048) (xy 92.20708 -125.664976)
			(xy 92.206826 -125.66523) (xy 92.206572 -125.665484) (xy 92.200983 -125.672569) (xy 92.194739 -125.689487)
			(xy 92.19438 -125.698504) (xy 92.19438 -125.76556) (xy 92.19476 -125.774574) (xy 92.200992 -125.791491)
			(xy 92.206572 -125.79858) (xy 92.206826 -125.798834) (xy 92.20708 -125.799088) (xy 92.224677 -125.82001)
			(xy 92.254315 -125.865948) (xy 92.266045 -125.891544) (xy 95.17507 -125.891544) (xy 95.17507 -125.89129)
			(xy 95.175532 -125.864995) (xy 95.182778 -125.812907) (xy 95.197104 -125.762306) (xy 95.218239 -125.71415)
			(xy 95.245783 -125.669351) (xy 95.279214 -125.628755) (xy 95.29826 -125.61062) (xy 95.305685 -125.603034)
			(xy 95.314221 -125.583627) (xy 95.31477 -125.573028) (xy 95.31477 -125.49886) (xy 95.314383 -125.488225)
			(xy 95.305819 -125.468761) (xy 95.29826 -125.461268) (xy 95.279191 -125.443152) (xy 95.245734 -125.402569)
			(xy 95.218174 -125.35777) (xy 95.197037 -125.309607) (xy 95.182723 -125.258996) (xy 95.175505 -125.206897)
			(xy 95.17507 -125.180598) (xy 95.17507 -125.180344) (xy 95.175556 -125.153093) (xy 95.183312 -125.099145)
			(xy 95.198667 -125.04685) (xy 95.221309 -124.997273) (xy 95.250775 -124.951423) (xy 95.286466 -124.910232)
			(xy 95.327657 -124.874541) (xy 95.373507 -124.845075) (xy 95.423084 -124.822433) (xy 95.475379 -124.807078)
			(xy 95.529327 -124.799322) (xy 95.583829 -124.799322) (xy 95.637777 -124.807078) (xy 95.690072 -124.822433)
			(xy 95.739649 -124.845075) (xy 95.785499 -124.874541) (xy 95.82669 -124.910232) (xy 95.862381 -124.951423)
			(xy 95.891847 -124.997273) (xy 95.914489 -125.04685) (xy 95.929844 -125.099145) (xy 95.9376 -125.153093)
			(xy 95.938086 -125.180344) (xy 95.938086 -125.180598) (xy 95.93763 -125.206893) (xy 95.930385 -125.258982)
			(xy 95.916059 -125.309584) (xy 95.894923 -125.35774) (xy 95.867377 -125.402539) (xy 95.833943 -125.443134)
			(xy 95.814896 -125.461268) (xy 95.80747 -125.468852) (xy 95.798936 -125.488261) (xy 95.798386 -125.49886)
			(xy 95.798386 -125.573028) (xy 95.798793 -125.58366) (xy 95.807344 -125.603124) (xy 95.814896 -125.61062)
			(xy 95.83397 -125.62873) (xy 95.867425 -125.669316) (xy 95.894982 -125.714117) (xy 95.916118 -125.76228)
			(xy 95.930431 -125.812892) (xy 95.937651 -125.864991) (xy 95.938086 -125.89129) (xy 95.938086 -125.891544)
			(xy 95.9376 -125.918795) (xy 95.929844 -125.972743) (xy 95.914489 -126.025038) (xy 95.891847 -126.074615)
			(xy 95.862381 -126.120465) (xy 95.82669 -126.161656) (xy 95.785499 -126.197347) (xy 95.739649 -126.226813)
			(xy 95.690072 -126.249455) (xy 95.637777 -126.26481) (xy 95.583829 -126.272566) (xy 95.529327 -126.272566)
			(xy 95.475379 -126.26481) (xy 95.423084 -126.249455) (xy 95.373507 -126.226813) (xy 95.327657 -126.197347)
			(xy 95.286466 -126.161656) (xy 95.250775 -126.120465) (xy 95.221309 -126.074615) (xy 95.198667 -126.025038)
			(xy 95.183312 -125.972743) (xy 95.175556 -125.918795) (xy 95.17507 -125.891544) (xy 92.266045 -125.891544)
			(xy 92.277091 -125.915646) (xy 92.292538 -125.968088) (xy 92.300339 -126.022197) (xy 92.300806 -126.049532)
			(xy 92.30032 -126.076783) (xy 92.292564 -126.130731) (xy 92.277209 -126.183026) (xy 92.254567 -126.232603)
			(xy 92.225101 -126.278453) (xy 92.18941 -126.319644) (xy 92.148219 -126.355335) (xy 92.102369 -126.384801)
			(xy 92.052792 -126.407443) (xy 92.000497 -126.422798) (xy 91.946549 -126.430554) (xy 91.892047 -126.430554)
			(xy 91.838099 -126.422798) (xy 91.785804 -126.407443) (xy 91.736227 -126.384801) (xy 91.690377 -126.355335)
			(xy 91.649186 -126.319644) (xy 91.613495 -126.278453) (xy 91.584029 -126.232603) (xy 91.561387 -126.183026)
			(xy 91.546032 -126.130731) (xy 91.538276 -126.076783) (xy 91.53779 -126.049532) (xy 91.538254 -126.022198)
			(xy 91.546064 -125.968091) (xy 91.561516 -125.915652) (xy 91.584292 -125.865954) (xy 91.613926 -125.820016)
			(xy 91.631516 -125.799088) (xy 91.63177 -125.798834) (xy 91.632024 -125.79858) (xy 91.637628 -125.791505)
			(xy 91.643863 -125.774579) (xy 91.644216 -125.76556) (xy 91.644216 -125.698504) (xy 91.643854 -125.689488)
			(xy 91.637609 -125.672571) (xy 91.632024 -125.665484) (xy 91.63177 -125.66523) (xy 91.631516 -125.664976)
			(xy 91.613917 -125.644089) (xy 91.584312 -125.598189) (xy 91.561553 -125.548538) (xy 91.546102 -125.49615)
			(xy 91.538277 -125.442095) (xy 91.53779 -125.414786) (xy 91.53779 -125.414532) (xy 91.538552 -125.394466)
			(xy 91.538552 -125.392942) (xy 91.538552 -125.389386) (xy 91.539314 -125.37821) (xy 91.530932 -125.357636)
			(xy 91.523566 -125.35027) (xy 91.517216 -125.344936) (xy 91.447366 -125.294644) (xy 91.436721 -125.287799)
			(xy 91.411645 -125.284616) (xy 91.399614 -125.288548) (xy 91.397582 -125.28931) (xy 91.396312 -125.289818)
			(xy 91.373993 -125.298237) (xy 91.327786 -125.310086) (xy 91.280463 -125.316089) (xy 91.256612 -125.316488)
			(xy 91.229242 -125.316018) (xy 91.175063 -125.308201) (xy 91.12256 -125.292713) (xy 91.072813 -125.269873)
			(xy 91.026846 -125.240149) (xy 91.005914 -125.222508) (xy 91.00566 -125.222254) (xy 90.998564 -125.216681)
			(xy 90.981654 -125.210427) (xy 90.97264 -125.210062) (xy 90.905584 -125.210062) (xy 90.896567 -125.210419)
			(xy 90.879651 -125.216668) (xy 90.872564 -125.222254) (xy 90.872056 -125.222762) (xy 90.851115 -125.240336)
			(xy 90.805183 -125.269978) (xy 90.755489 -125.292759) (xy 90.703052 -125.308211) (xy 90.648945 -125.316018)
			(xy 90.621612 -125.316488) (xy 90.593788 -125.315955) (xy 90.538729 -125.307893) (xy 90.485426 -125.291911)
			(xy 90.435015 -125.268348) (xy 90.388565 -125.237704) (xy 90.347066 -125.200632) (xy 90.311398 -125.157919)
			(xy 90.282321 -125.110474) (xy 90.260452 -125.059304) (xy 90.246257 -125.005498) (xy 90.242644 -124.977906)
			(xy 90.241063 -124.967592) (xy 90.23077 -124.949461) (xy 90.214128 -124.936902) (xy 90.193868 -124.931979)
			(xy 90.173318 -124.935499) (xy 90.155853 -124.946885) (xy 90.14968 -124.9553) (xy 90.142754 -124.965562)
			(xy 90.127756 -124.985262) (xy 90.119708 -124.99467) (xy 90.119454 -124.994924) (xy 90.113846 -125.001996)
			(xy 90.107613 -125.018924) (xy 90.107262 -125.027944) (xy 90.107262 -125.095) (xy 90.107627 -125.104016)
			(xy 90.11387 -125.120932) (xy 90.119454 -125.12802) (xy 90.119708 -125.128274) (xy 90.119962 -125.128528)
			(xy 90.137534 -125.149473) (xy 90.167185 -125.195403) (xy 90.189974 -125.245096) (xy 90.205432 -125.297535)
			(xy 90.213242 -125.351644) (xy 90.213245 -125.406314) (xy 90.205441 -125.460424) (xy 90.189989 -125.512864)
			(xy 90.167206 -125.56256) (xy 90.137559 -125.608493) (xy 90.119962 -125.629416) (xy 90.119708 -125.62967)
			(xy 90.119454 -125.629924) (xy 90.113846 -125.636996) (xy 90.107613 -125.653924) (xy 90.107262 -125.662944)
			(xy 90.107262 -125.73) (xy 90.107627 -125.739016) (xy 90.11387 -125.755932) (xy 90.119454 -125.76302)
			(xy 90.119708 -125.763274) (xy 90.119962 -125.763528) (xy 90.137528 -125.784475) (xy 90.167172 -125.830405)
			(xy 90.189954 -125.880098) (xy 90.205408 -125.932534) (xy 90.213217 -125.986639) (xy 90.213688 -126.013972)
			(xy 90.213202 -126.041223) (xy 90.205446 -126.095171) (xy 90.190091 -126.147466) (xy 90.167449 -126.197043)
			(xy 90.137983 -126.242893) (xy 90.102292 -126.284084) (xy 90.061101 -126.319775) (xy 90.015251 -126.349241)
			(xy 89.965674 -126.371883) (xy 89.913379 -126.387238) (xy 89.859431 -126.394994) (xy 89.804929 -126.394994)
			(xy 89.750981 -126.387238) (xy 89.698686 -126.371883) (xy 89.649109 -126.349241) (xy 89.603259 -126.319775)
			(xy 89.562068 -126.284084) (xy 89.526377 -126.242893) (xy 89.496911 -126.197043) (xy 89.474269 -126.147466)
			(xy 89.458914 -126.095171) (xy 89.451158 -126.041223) (xy 89.450672 -126.013972) (xy 82.155538 -126.013972)
			(xy 86.915752 -130.774186) (xy 86.91626 -130.774694) (xy 86.923644 -130.781271) (xy 86.941942 -130.788712)
			(xy 86.95182 -130.789172) (xy 99.455732 -130.789172) (xy 99.465799 -130.788742) (xy 99.484392 -130.781017)
			(xy 99.4918 -130.774186) (xy 102.13467 -128.131062) (xy 102.135178 -128.130554) (xy 102.141759 -128.123172)
			(xy 102.149208 -128.104873) (xy 102.149656 -128.094994) (xy 102.149656 -127.189992) (xy 102.14991 -127.180848)
			(xy 102.14991 -114.780822) (xy 102.14229 -114.762026) (xy 102.134924 -114.754914) (xy 101.87178 -114.49177)
			(xy 101.864668 -114.484404) (xy 101.845872 -114.476784) (xy 100.867718 -114.476784) (xy 100.86086 -114.477292)
			(xy 100.8507 -114.478562) (xy 100.844604 -114.48034) (xy 100.838762 -114.483642) (xy 100.812092 -114.498882)
			(xy 100.803202 -114.507264) (xy 100.7999 -114.512852) (xy 100.787381 -114.532319) (xy 100.758349 -114.568365)
			(xy 100.741988 -114.584734) (xy 100.734622 -114.591592) (xy 100.722684 -114.61877) (xy 100.718366 -114.628676)
			(xy 100.718366 -114.688112) (xy 100.719382 -114.697764) (xy 100.720906 -114.706146) (xy 100.721922 -114.712496)
			(xy 100.734622 -114.740436) (xy 100.741988 -114.747294) (xy 100.760006 -114.76533) (xy 100.791581 -114.805354)
			(xy 100.817543 -114.849228) (xy 100.837429 -114.89617) (xy 100.850884 -114.945343) (xy 100.857667 -114.99587)
			(xy 100.858066 -115.02136) (xy 100.858066 -115.021868) (xy 100.857637 -115.047355) (xy 100.850843 -115.097875)
			(xy 100.837384 -115.147041) (xy 100.817501 -115.193978) (xy 100.791546 -115.237851) (xy 100.759982 -115.277878)
			(xy 100.741988 -115.295934) (xy 100.734622 -115.302792) (xy 100.722684 -115.32997) (xy 100.718366 -115.339876)
			(xy 100.718366 -115.399312) (xy 100.719382 -115.408964) (xy 100.720906 -115.417346) (xy 100.721922 -115.423696)
			(xy 100.734622 -115.451636) (xy 100.741988 -115.458494) (xy 100.760006 -115.47653) (xy 100.791581 -115.516554)
			(xy 100.817543 -115.560428) (xy 100.837429 -115.60737) (xy 100.850884 -115.656543) (xy 100.857667 -115.70707)
			(xy 100.858066 -115.73256) (xy 100.858066 -115.732814) (xy 100.85758 -115.760065) (xy 100.849824 -115.814013)
			(xy 100.834469 -115.866308) (xy 100.811827 -115.915885) (xy 100.782361 -115.961735) (xy 100.74667 -116.002926)
			(xy 100.705479 -116.038617) (xy 100.659629 -116.068083) (xy 100.610052 -116.090725) (xy 100.557757 -116.10608)
			(xy 100.503809 -116.113836) (xy 100.449307 -116.113836) (xy 100.395359 -116.10608) (xy 100.343064 -116.090725)
			(xy 100.293487 -116.068083) (xy 100.247637 -116.038617) (xy 100.206446 -116.002926) (xy 100.170755 -115.961735)
			(xy 100.141289 -115.915885) (xy 100.118647 -115.866308) (xy 100.103292 -115.814013) (xy 100.095536 -115.760065)
			(xy 100.09505 -115.732814) (xy 100.09505 -115.73256) (xy 100.095477 -115.707072) (xy 100.102268 -115.65655)
			(xy 100.115724 -115.607382) (xy 100.135606 -115.560443) (xy 100.16156 -115.516569) (xy 100.193123 -115.47654)
			(xy 100.211128 -115.458494) (xy 100.218494 -115.451636) (xy 100.230432 -115.424712) (xy 100.232429 -115.419871)
			(xy 100.234597 -115.409627) (xy 100.23475 -115.404392) (xy 100.23475 -115.356386) (xy 100.233734 -115.34648)
			(xy 100.231702 -115.33632) (xy 100.228654 -115.32616) (xy 100.218748 -115.3033) (xy 100.211382 -115.296188)
			(xy 100.193316 -115.278158) (xy 100.161676 -115.238108) (xy 100.135662 -115.194195) (xy 100.115737 -115.147204)
			(xy 100.102259 -115.097975) (xy 100.095468 -115.047388) (xy 100.09505 -115.021868) (xy 100.09505 -115.02136)
			(xy 100.095477 -114.995872) (xy 100.102268 -114.94535) (xy 100.115724 -114.896182) (xy 100.135606 -114.849243)
			(xy 100.16156 -114.805369) (xy 100.193123 -114.76534) (xy 100.211128 -114.747294) (xy 100.218494 -114.740436)
			(xy 100.230432 -114.713512) (xy 100.232429 -114.708671) (xy 100.234597 -114.698427) (xy 100.23475 -114.693192)
			(xy 100.23475 -114.645186) (xy 100.233734 -114.63528) (xy 100.231702 -114.62512) (xy 100.228654 -114.61496)
			(xy 100.218748 -114.5921) (xy 100.211382 -114.584988) (xy 100.194949 -114.568563) (xy 100.165784 -114.532393)
			(xy 100.153216 -114.512852) (xy 100.149914 -114.507518) (xy 100.141024 -114.498882) (xy 100.114608 -114.483642)
			(xy 100.1141 -114.483642) (xy 100.108512 -114.48034) (xy 100.095558 -114.476784) (xy 98.329496 -114.476784)
			(xy 98.322638 -114.477292) (xy 98.312478 -114.478562) (xy 98.306382 -114.48034) (xy 98.30054 -114.483642)
			(xy 98.27387 -114.498882) (xy 98.26498 -114.507264) (xy 98.261678 -114.512852) (xy 98.249159 -114.532318)
			(xy 98.220126 -114.568363) (xy 98.203766 -114.584734) (xy 98.1964 -114.591592) (xy 98.184462 -114.61877)
			(xy 98.180144 -114.628676) (xy 98.180144 -114.688112) (xy 98.18116 -114.697764) (xy 98.182684 -114.706146)
			(xy 98.1837 -114.712496) (xy 98.1964 -114.740436) (xy 98.203766 -114.747294) (xy 98.221785 -114.765329)
			(xy 98.253362 -114.805353) (xy 98.279326 -114.849227) (xy 98.299212 -114.896169) (xy 98.312668 -114.945342)
			(xy 98.319452 -114.99587) (xy 98.319844 -115.02136) (xy 98.319844 -115.021868) (xy 98.319415 -115.047355)
			(xy 98.312621 -115.097875) (xy 98.299161 -115.147041) (xy 98.279277 -115.193977) (xy 98.253321 -115.237848)
			(xy 98.221756 -115.277874) (xy 98.203766 -115.295934) (xy 98.1964 -115.302792) (xy 98.184462 -115.32997)
			(xy 98.180144 -115.339876) (xy 98.180144 -115.399312) (xy 98.18116 -115.408964) (xy 98.182684 -115.417346)
			(xy 98.1837 -115.423696) (xy 98.1964 -115.451636) (xy 98.203766 -115.458494) (xy 98.221785 -115.476529)
			(xy 98.253362 -115.516553) (xy 98.279326 -115.560427) (xy 98.299212 -115.607369) (xy 98.312668 -115.656542)
			(xy 98.319452 -115.70707) (xy 98.319844 -115.73256) (xy 98.319844 -115.732814) (xy 98.319358 -115.760065)
			(xy 98.311602 -115.814013) (xy 98.296247 -115.866308) (xy 98.273605 -115.915885) (xy 98.244139 -115.961735)
			(xy 98.208448 -116.002926) (xy 98.167257 -116.038617) (xy 98.121407 -116.068083) (xy 98.07183 -116.090725)
			(xy 98.019535 -116.10608) (xy 97.965587 -116.113836) (xy 97.911085 -116.113836) (xy 97.857137 -116.10608)
			(xy 97.804842 -116.090725) (xy 97.755265 -116.068083) (xy 97.709415 -116.038617) (xy 97.668224 -116.002926)
			(xy 97.632533 -115.961735) (xy 97.603067 -115.915885) (xy 97.580425 -115.866308) (xy 97.56507 -115.814013)
			(xy 97.557314 -115.760065) (xy 97.556828 -115.732814) (xy 97.556828 -115.73256) (xy 97.557255 -115.707072)
			(xy 97.564046 -115.65655) (xy 97.577501 -115.607381) (xy 97.597382 -115.560442) (xy 97.623335 -115.516566)
			(xy 97.654897 -115.476536) (xy 97.672906 -115.458494) (xy 97.680272 -115.451636) (xy 97.69221 -115.424712)
			(xy 97.694208 -115.419871) (xy 97.696377 -115.409627) (xy 97.696528 -115.404392) (xy 97.696528 -115.356386)
			(xy 97.695512 -115.34648) (xy 97.69348 -115.33632) (xy 97.690432 -115.32616) (xy 97.680526 -115.3033)
			(xy 97.67316 -115.296188) (xy 97.655095 -115.278158) (xy 97.623457 -115.238107) (xy 97.597444 -115.194193)
			(xy 97.577521 -115.147202) (xy 97.564043 -115.097974) (xy 97.557253 -115.047388) (xy 97.556828 -115.021868)
			(xy 97.556828 -115.02136) (xy 97.557255 -114.995872) (xy 97.564046 -114.94535) (xy 97.577501 -114.896181)
			(xy 97.597382 -114.849242) (xy 97.623335 -114.805366) (xy 97.654897 -114.765336) (xy 97.672906 -114.747294)
			(xy 97.680272 -114.740436) (xy 97.69221 -114.713512) (xy 97.694208 -114.708671) (xy 97.696377 -114.698427)
			(xy 97.696528 -114.693192) (xy 97.696528 -114.645186) (xy 97.695512 -114.63528) (xy 97.69348 -114.62512)
			(xy 97.690432 -114.61496) (xy 97.680526 -114.5921) (xy 97.67316 -114.584988) (xy 97.656728 -114.568563)
			(xy 97.627565 -114.532392) (xy 97.614994 -114.512852) (xy 97.611692 -114.507518) (xy 97.602802 -114.498882)
			(xy 97.576386 -114.483642) (xy 97.575878 -114.483642) (xy 97.57029 -114.48034) (xy 97.557336 -114.476784)
			(xy 93.079062 -114.476784) (xy 93.072908 -114.476951) (xy 93.06096 -114.479901) (xy 93.05544 -114.482626)
			(xy 93.048582 -114.486182) (xy 93.037914 -114.49685) (xy 93.034358 -114.503708) (xy 93.020969 -114.52765)
			(xy 92.988372 -114.57177) (xy 92.94979 -114.610764) (xy 92.90602 -114.643829) (xy 92.857964 -114.670281)
			(xy 92.806614 -114.689575) (xy 92.75303 -114.701313) (xy 92.698316 -114.705253) (xy 92.643602 -114.701313)
			(xy 92.590018 -114.689575) (xy 92.538668 -114.670281) (xy 92.490612 -114.643829) (xy 92.446842 -114.610764)
			(xy 92.40826 -114.57177) (xy 92.375663 -114.52765) (xy 92.362274 -114.503708) (xy 92.358718 -114.49685)
			(xy 92.34805 -114.486182) (xy 92.330016 -114.476784) (xy 92.266262 -114.476784) (xy 92.260108 -114.476951)
			(xy 92.24816 -114.479901) (xy 92.24264 -114.482626) (xy 92.235782 -114.486182) (xy 92.225114 -114.49685)
			(xy 92.221558 -114.503708) (xy 92.208281 -114.52744) (xy 92.176029 -114.571221) (xy 92.137883 -114.609975)
			(xy 92.094617 -114.642915) (xy 92.04711 -114.669374) (xy 91.996326 -114.688814) (xy 91.943294 -114.70084)
			(xy 91.889092 -114.705209) (xy 91.834819 -114.701833) (xy 91.781576 -114.690778) (xy 91.730444 -114.672271)
			(xy 91.682461 -114.646685) (xy 91.6386 -114.614542) (xy 91.599752 -114.576492) (xy 91.566704 -114.533309)
			(xy 91.55303 -114.509804) (xy 91.549474 -114.503454) (xy 91.539568 -114.493548) (xy 91.532533 -114.487105)
			(xy 91.515045 -114.479515) (xy 91.495993 -114.478828) (xy 91.478004 -114.485138) (xy 91.47048 -114.491008)
			(xy 91.462352 -114.49812) (xy 91.45778 -114.505994) (xy 91.444281 -114.529754) (xy 91.411524 -114.573493)
			(xy 91.372855 -114.612103) (xy 91.329066 -114.644794) (xy 91.281056 -114.670894) (xy 91.229811 -114.689867)
			(xy 91.17638 -114.701325) (xy 91.121861 -114.705033) (xy 91.067371 -114.700914) (xy 91.014028 -114.689053)
			(xy 90.962927 -114.669694) (xy 90.915116 -114.643232) (xy 90.871575 -114.610213) (xy 90.833198 -114.571311)
			(xy 90.800772 -114.527326) (xy 90.787474 -114.503454) (xy 90.782795 -114.495599) (xy 90.769018 -114.483597)
			(xy 90.751906 -114.477194) (xy 90.74277 -114.476784) (xy 90.014044 -114.476784) (xy 90.0049 -114.480594)
			(xy 89.97712 -114.491522) (xy 89.91944 -114.506903) (xy 89.86025 -114.51466) (xy 89.800554 -114.51466)
			(xy 89.741364 -114.506903) (xy 89.683684 -114.491522) (xy 89.655904 -114.480594) (xy 89.64676 -114.476784)
			(xy 75.470258 -114.476784) (xy 75.460192 -114.476353) (xy 75.4416 -114.468626) (xy 75.43419 -114.461798)
			(xy 75.218798 -114.246406) (xy 75.211686 -114.23904) (xy 75.19289 -114.23142) (xy 73.536048 -114.23142)
			(xy 73.517252 -114.23904) (xy 73.51014 -114.246406) (xy 73.403714 -114.352832) (xy 73.396348 -114.359944)
			(xy 73.388728 -114.37874) (xy 73.388728 -115.400836) (xy 87.260682 -115.400836) (xy 87.264753 -115.345214)
			(xy 87.276879 -115.290777) (xy 87.296802 -115.238686) (xy 87.324098 -115.190051) (xy 87.358184 -115.145908)
			(xy 87.398333 -115.107199) (xy 87.443691 -115.074748) (xy 87.493291 -115.049247) (xy 87.546075 -115.03124)
			(xy 87.600918 -115.02111) (xy 87.656652 -115.019073) (xy 87.712089 -115.025173) (xy 87.766046 -115.039279)
			(xy 87.817375 -115.061091) (xy 87.864981 -115.090145) (xy 87.907849 -115.12582) (xy 87.945066 -115.167357)
			(xy 87.975839 -115.21387) (xy 87.999511 -115.264367) (xy 88.015579 -115.317774) (xy 88.023699 -115.37295)
			(xy 88.024199 -115.400324) (xy 89.286062 -115.400324) (xy 89.286062 -115.340388) (xy 89.293885 -115.280966)
			(xy 89.309398 -115.223073) (xy 89.332334 -115.1677) (xy 89.362301 -115.115794) (xy 89.398788 -115.068244)
			(xy 89.441168 -115.025864) (xy 89.488718 -114.989377) (xy 89.540624 -114.95941) (xy 89.595997 -114.936474)
			(xy 89.65389 -114.920961) (xy 89.713312 -114.913138) (xy 89.773248 -114.913138) (xy 89.83267 -114.920961)
			(xy 89.890563 -114.936474) (xy 89.945936 -114.95941) (xy 89.997842 -114.989377) (xy 90.045392 -115.025864)
			(xy 90.087772 -115.068244) (xy 90.124259 -115.115794) (xy 90.154226 -115.1677) (xy 90.177162 -115.223073)
			(xy 90.192675 -115.280966) (xy 90.200498 -115.340388) (xy 90.200988 -115.370356) (xy 90.200498 -115.400324)
			(xy 90.192675 -115.459746) (xy 90.177162 -115.517639) (xy 90.154226 -115.573012) (xy 90.124259 -115.624918)
			(xy 90.087772 -115.672468) (xy 90.045392 -115.714848) (xy 89.997842 -115.751335) (xy 89.945936 -115.781302)
			(xy 89.890563 -115.804238) (xy 89.83267 -115.819751) (xy 89.773248 -115.827574) (xy 89.713312 -115.827574)
			(xy 89.65389 -115.819751) (xy 89.595997 -115.804238) (xy 89.540624 -115.781302) (xy 89.488718 -115.751335)
			(xy 89.441168 -115.714848) (xy 89.398788 -115.672468) (xy 89.362301 -115.624918) (xy 89.332334 -115.573012)
			(xy 89.309398 -115.517639) (xy 89.293885 -115.459746) (xy 89.286062 -115.400324) (xy 88.024199 -115.400324)
			(xy 88.024208 -115.400836) (xy 88.023699 -115.428722) (xy 88.015579 -115.483898) (xy 87.999511 -115.537305)
			(xy 87.975839 -115.587802) (xy 87.945066 -115.634315) (xy 87.907849 -115.675852) (xy 87.864981 -115.711527)
			(xy 87.817375 -115.740581) (xy 87.766046 -115.762393) (xy 87.712089 -115.776499) (xy 87.656652 -115.782599)
			(xy 87.600918 -115.780562) (xy 87.546075 -115.770432) (xy 87.493291 -115.752425) (xy 87.443691 -115.726924)
			(xy 87.398333 -115.694473) (xy 87.358184 -115.655764) (xy 87.324098 -115.611621) (xy 87.296802 -115.562986)
			(xy 87.276879 -115.510895) (xy 87.264753 -115.456458) (xy 87.260682 -115.400836) (xy 73.388728 -115.400836)
			(xy 73.388728 -115.832636) (xy 92.903548 -115.832636) (xy 92.9041 -115.800763) (xy 92.912942 -115.737634)
			(xy 92.930459 -115.676343) (xy 92.956313 -115.618076) (xy 92.990003 -115.563961) (xy 93.030877 -115.515046)
			(xy 93.078145 -115.472276) (xy 93.104208 -115.453922) (xy 93.108272 -115.451128) (xy 93.115892 -115.443508)
			(xy 93.122164 -115.436665) (xy 93.129717 -115.419726) (xy 93.130624 -115.410488) (xy 93.134942 -115.330986)
			(xy 93.135115 -115.324997) (xy 93.13307 -115.313194) (xy 93.130878 -115.307618) (xy 93.128338 -115.30203)
			(xy 93.12148 -115.292886) (xy 93.116908 -115.289076) (xy 93.095828 -115.270851) (xy 93.05869 -115.229304)
			(xy 93.027988 -115.1828) (xy 93.004373 -115.132327) (xy 92.988347 -115.078956) (xy 92.980251 -115.023822)
			(xy 92.979748 -114.99596) (xy 92.980234 -114.968709) (xy 92.98799 -114.914761) (xy 93.003345 -114.862466)
			(xy 93.025987 -114.812889) (xy 93.055453 -114.767039) (xy 93.091144 -114.725848) (xy 93.132335 -114.690157)
			(xy 93.178185 -114.660691) (xy 93.227762 -114.638049) (xy 93.280057 -114.622694) (xy 93.334005 -114.614938)
			(xy 93.388507 -114.614938) (xy 93.442455 -114.622694) (xy 93.49475 -114.638049) (xy 93.544327 -114.660691)
			(xy 93.590177 -114.690157) (xy 93.631368 -114.725848) (xy 93.667059 -114.767039) (xy 93.696525 -114.812889)
			(xy 93.719167 -114.862466) (xy 93.734522 -114.914761) (xy 93.742278 -114.968709) (xy 93.742764 -114.99596)
			(xy 93.742236 -115.023821) (xy 93.73414 -115.078951) (xy 93.718116 -115.132319) (xy 93.694503 -115.182789)
			(xy 93.663804 -115.229291) (xy 93.626669 -115.270835) (xy 93.605604 -115.289076) (xy 93.601032 -115.292886)
			(xy 93.594174 -115.30203) (xy 93.591634 -115.307618) (xy 93.589441 -115.313129) (xy 93.587377 -115.324805)
			(xy 93.58757 -115.330732) (xy 93.591054 -115.394486) (xy 95.147128 -115.394486) (xy 95.151199 -115.338864)
			(xy 95.163325 -115.284427) (xy 95.183248 -115.232336) (xy 95.210544 -115.183701) (xy 95.24463 -115.139558)
			(xy 95.284779 -115.100849) (xy 95.330137 -115.068398) (xy 95.379737 -115.042897) (xy 95.432521 -115.02489)
			(xy 95.487364 -115.01476) (xy 95.543098 -115.012723) (xy 95.598535 -115.018823) (xy 95.652492 -115.032929)
			(xy 95.703821 -115.054741) (xy 95.751427 -115.083795) (xy 95.794295 -115.11947) (xy 95.831512 -115.161007)
			(xy 95.862285 -115.20752) (xy 95.885957 -115.258017) (xy 95.902025 -115.311424) (xy 95.910145 -115.3666)
			(xy 95.910654 -115.394486) (xy 95.910145 -115.422372) (xy 95.902025 -115.477548) (xy 95.885957 -115.530955)
			(xy 95.862285 -115.581452) (xy 95.831512 -115.627965) (xy 95.794295 -115.669502) (xy 95.751427 -115.705177)
			(xy 95.703821 -115.734231) (xy 95.652492 -115.756043) (xy 95.598535 -115.770149) (xy 95.543098 -115.776249)
			(xy 95.487364 -115.774212) (xy 95.432521 -115.764082) (xy 95.379737 -115.746075) (xy 95.330137 -115.720574)
			(xy 95.284779 -115.688123) (xy 95.24463 -115.649414) (xy 95.210544 -115.605271) (xy 95.183248 -115.556636)
			(xy 95.163325 -115.504545) (xy 95.151199 -115.450108) (xy 95.147128 -115.394486) (xy 93.591054 -115.394486)
			(xy 93.59265 -115.423696) (xy 93.604334 -115.44427) (xy 93.614494 -115.450874) (xy 93.641023 -115.469187)
			(xy 93.689153 -115.51207) (xy 93.730803 -115.56127) (xy 93.765152 -115.615819) (xy 93.791523 -115.674641)
			(xy 93.809396 -115.736577) (xy 93.818419 -115.800405) (xy 93.818964 -115.832636) (xy 93.818474 -115.862604)
			(xy 93.810651 -115.922026) (xy 93.795138 -115.979919) (xy 93.772202 -116.035292) (xy 93.742235 -116.087198)
			(xy 93.705748 -116.134748) (xy 93.663368 -116.177128) (xy 93.615818 -116.213615) (xy 93.563912 -116.243582)
			(xy 93.508539 -116.266518) (xy 93.450646 -116.282031) (xy 93.391224 -116.289854) (xy 93.331288 -116.289854)
			(xy 93.271866 -116.282031) (xy 93.213973 -116.266518) (xy 93.1586 -116.243582) (xy 93.106694 -116.213615)
			(xy 93.059144 -116.177128) (xy 93.016764 -116.134748) (xy 92.980277 -116.087198) (xy 92.95031 -116.035292)
			(xy 92.927374 -115.979919) (xy 92.911861 -115.922026) (xy 92.904038 -115.862604) (xy 92.903548 -115.832636)
			(xy 73.388728 -115.832636) (xy 73.388728 -117.924072) (xy 73.388224 -117.934123) (xy 73.380505 -117.952686)
			(xy 73.373742 -117.96014) (xy 72.728836 -118.605046) (xy 72.721437 -118.611888) (xy 72.702838 -118.619608)
			(xy 72.692768 -118.620032) (xy 72.222868 -118.620032) (xy 72.212867 -118.620526) (xy 72.194392 -118.628192)
			(xy 72.180256 -118.642345) (xy 72.172613 -118.66083) (xy 72.172068 -118.670832) (xy 72.172068 -118.67261)
			(xy 72.172322 -118.674642) (xy 72.173592 -118.711218) (xy 72.173592 -119.414798) (xy 72.173215 -119.441896)
			(xy 72.167107 -119.495747) (xy 72.1614 -119.52224) (xy 72.159876 -119.528844) (xy 72.157983 -119.540144)
			(xy 72.163136 -119.562436) (xy 72.169782 -119.57177) (xy 72.227694 -119.643652) (xy 72.248776 -119.653558)
			(xy 72.260714 -119.653304) (xy 72.266556 -119.653304) (xy 72.267318 -119.653304) (xy 72.294578 -119.653805)
			(xy 72.34854 -119.661592) (xy 72.400845 -119.676976) (xy 72.45043 -119.699644) (xy 72.496286 -119.729135)
			(xy 72.53748 -119.76485) (xy 72.573175 -119.806061) (xy 72.602644 -119.851932) (xy 72.625289 -119.901527)
			(xy 72.640647 -119.95384) (xy 72.648408 -120.007806) (xy 72.648826 -120.035066) (xy 73.865992 -120.035066)
			(xy 73.870065 -119.979407) (xy 73.8822 -119.924934) (xy 73.902136 -119.872808) (xy 73.92945 -119.82414)
			(xy 73.963558 -119.779968) (xy 74.003735 -119.741233) (xy 74.049123 -119.708761) (xy 74.098755 -119.683243)
			(xy 74.151575 -119.665224) (xy 74.206454 -119.655087) (xy 74.262225 -119.653049) (xy 74.317699 -119.659152)
			(xy 74.371692 -119.673268) (xy 74.423055 -119.695095) (xy 74.470693 -119.724168) (xy 74.513589 -119.759867)
			(xy 74.550831 -119.801431) (xy 74.581625 -119.847975) (xy 74.605313 -119.898506) (xy 74.621391 -119.951948)
			(xy 74.629517 -120.007162) (xy 74.630026 -120.035066) (xy 74.629517 -120.06297) (xy 74.621391 -120.118184)
			(xy 74.605313 -120.171626) (xy 74.581625 -120.222157) (xy 74.550831 -120.268701) (xy 74.513589 -120.310265)
			(xy 74.470693 -120.345964) (xy 74.423055 -120.375037) (xy 74.371692 -120.396864) (xy 74.317699 -120.41098)
			(xy 74.262225 -120.417083) (xy 74.206454 -120.415045) (xy 74.151575 -120.404908) (xy 74.098755 -120.386889)
			(xy 74.049123 -120.361371) (xy 74.003735 -120.328899) (xy 73.963558 -120.290164) (xy 73.92945 -120.245992)
			(xy 73.902136 -120.197324) (xy 73.8822 -120.145198) (xy 73.870065 -120.090725) (xy 73.865992 -120.035066)
			(xy 72.648826 -120.035066) (xy 72.64834 -120.062335) (xy 72.640578 -120.116319) (xy 72.625213 -120.168649)
			(xy 72.602556 -120.218259) (xy 72.57307 -120.26414) (xy 72.537355 -120.305357) (xy 72.496138 -120.341072)
			(xy 72.450257 -120.370558) (xy 72.400647 -120.393215) (xy 72.348317 -120.40858) (xy 72.294333 -120.416342)
			(xy 72.239795 -120.416342) (xy 72.185811 -120.40858) (xy 72.133481 -120.393215) (xy 72.083871 -120.370558)
			(xy 72.03799 -120.341072) (xy 71.996773 -120.305357) (xy 71.961058 -120.26414) (xy 71.931572 -120.218259)
			(xy 71.908915 -120.168649) (xy 71.89355 -120.116319) (xy 71.885788 -120.062335) (xy 71.885302 -120.035066)
			(xy 71.886826 -119.99976) (xy 71.887842 -119.987822) (xy 71.87946 -119.966232) (xy 71.80326 -119.89562)
			(xy 71.781162 -119.889016) (xy 71.769224 -119.891048) (xy 71.749744 -119.894092) (xy 71.710453 -119.897397)
			(xy 71.690738 -119.897652) (xy 71.644764 -119.897652) (xy 71.644764 -119.89689) (xy 71.603108 -119.88927)
			(xy 71.573237 -119.883277) (xy 71.515194 -119.864757) (xy 71.459941 -119.839085) (xy 71.408355 -119.806668)
			(xy 71.361256 -119.768021) (xy 71.31939 -119.723759) (xy 71.283423 -119.674582) (xy 71.253926 -119.621273)
			(xy 71.231367 -119.564678) (xy 71.216104 -119.505695) (xy 71.20838 -119.44526) (xy 71.207884 -119.414798)
			(xy 71.207884 -119.079264) (xy 71.20739 -119.069262) (xy 71.199723 -119.050786) (xy 71.185571 -119.036648)
			(xy 71.167086 -119.029) (xy 71.157084 -119.028464) (xy 71.078852 -119.028464) (xy 71.068848 -119.02896)
			(xy 71.050366 -119.036627) (xy 71.03622 -119.050777) (xy 71.028557 -119.06926) (xy 71.028052 -119.079264)
			(xy 71.028052 -119.088408) (xy 70.760082 -119.088408) (xy 70.736747 -119.087767) (xy 70.691083 -119.078106)
			(xy 70.648357 -119.059319) (xy 70.629018 -119.046244) (xy 70.622922 -119.041926) (xy 70.592442 -119.031512)
			(xy 70.419976 -119.031512) (xy 70.406768 -119.03329) (xy 70.387718 -119.038624) (xy 70.381876 -119.041926)
			(xy 70.381622 -119.041926) (xy 70.359868 -119.054008) (xy 70.313896 -119.073054) (xy 70.265838 -119.085961)
			(xy 70.21651 -119.092512) (xy 70.19163 -119.09298) (xy 70.191122 -119.09298) (xy 70.179184 -119.092726)
			(xy 70.152823 -119.091436) (xy 70.100808 -119.082499) (xy 70.05052 -119.066482) (xy 70.002917 -119.043693)
			(xy 69.958906 -119.014564) (xy 69.919327 -118.979651) (xy 69.884933 -118.93962) (xy 69.85638 -118.895234)
			(xy 69.834212 -118.847338) (xy 69.826124 -118.822216) (xy 69.824854 -118.818152) (xy 69.820536 -118.809262)
			(xy 69.817193 -118.803188) (xy 69.807784 -118.79301) (xy 69.801994 -118.789196) (xy 69.747892 -118.75516)
			(xy 69.741752 -118.751545) (xy 69.728087 -118.747536) (xy 69.720968 -118.747286) (xy 69.711316 -118.747286)
			(xy 69.707506 -118.747794) (xy 69.692747 -118.750016) (xy 69.662995 -118.752435) (xy 69.64807 -118.75262)
			(xy 69.618248 -118.752045) (xy 69.55933 -118.742774) (xy 69.502568 -118.724461) (xy 69.44934 -118.697551)
			(xy 69.40094 -118.662698) (xy 69.379338 -118.64213) (xy 69.37248 -118.635272) (xy 69.346318 -118.624096)
			(xy 69.336666 -118.620032) (xy 67.565016 -118.620032) (xy 67.554995 -118.620449) (xy 67.536478 -118.628118)
			(xy 67.522309 -118.642292) (xy 67.514646 -118.660811) (xy 67.514216 -118.670832) (xy 67.514216 -118.68023)
			(xy 67.515232 -118.703598) (xy 67.515232 -119.567198) (xy 67.514724 -119.58066) (xy 67.514724 -119.588788)
			(xy 67.519296 -119.609616) (xy 67.523868 -119.62003) (xy 67.556126 -119.647716) (xy 67.560938 -119.651631)
			(xy 67.571981 -119.657276) (xy 67.57797 -119.658892) (xy 67.589654 -119.661432) (xy 67.599814 -119.659654)
			(xy 67.616373 -119.656849) (xy 67.649823 -119.653796) (xy 67.666616 -119.653558) (xy 67.66687 -119.653558)
			(xy 67.694127 -119.654019) (xy 67.748086 -119.661773) (xy 67.800392 -119.677128) (xy 67.84998 -119.699771)
			(xy 67.895841 -119.729241) (xy 67.937041 -119.764937) (xy 67.972741 -119.806135) (xy 68.002215 -119.851993)
			(xy 68.024862 -119.90158) (xy 68.040221 -119.953885) (xy 68.047979 -120.007843) (xy 68.047979 -120.062357)
			(xy 68.040221 -120.116315) (xy 68.024862 -120.16862) (xy 68.002215 -120.218207) (xy 67.972741 -120.264065)
			(xy 67.937041 -120.305263) (xy 67.895841 -120.340959) (xy 67.84998 -120.370429) (xy 67.800392 -120.393072)
			(xy 67.748086 -120.408427) (xy 67.694127 -120.416181) (xy 67.66687 -120.416574) (xy 67.639905 -120.416113)
			(xy 67.586511 -120.408525) (xy 67.534718 -120.393491) (xy 67.48556 -120.37131) (xy 67.440017 -120.342425)
			(xy 67.398997 -120.307412) (xy 67.363319 -120.26697) (xy 67.333695 -120.221905) (xy 67.310714 -120.173115)
			(xy 67.294836 -120.121575) (xy 67.290188 -120.09501) (xy 67.290188 -120.094756) (xy 67.287986 -120.084444)
			(xy 67.276559 -120.066752) (xy 67.26809 -120.060466) (xy 67.207892 -120.020334) (xy 67.201506 -120.016438)
			(xy 67.187175 -120.012171) (xy 67.179698 -120.011952) (xy 67.165728 -120.011952) (xy 67.159886 -120.013222)
			(xy 67.134653 -120.018735) (xy 67.083349 -120.024713) (xy 67.057524 -120.02516) (xy 67.057016 -120.02516)
			(xy 67.034443 -120.02483) (xy 66.989528 -120.020254) (xy 66.967354 -120.016016) (xy 66.9671 -120.015762)
			(xy 66.950082 -120.011952) (xy 66.925698 -120.00738) (xy 66.908426 -120.019064) (xy 66.84645 -120.060466)
			(xy 66.837976 -120.066657) (xy 66.826562 -120.084242) (xy 66.824352 -120.094502) (xy 66.824352 -120.095264)
			(xy 66.819637 -120.121801) (xy 66.803719 -120.173295) (xy 66.780712 -120.222035) (xy 66.751075 -120.267053)
			(xy 66.715398 -120.307452) (xy 66.67439 -120.342428) (xy 66.628868 -120.371285) (xy 66.579739 -120.393449)
			(xy 66.527979 -120.408477) (xy 66.474619 -120.416072) (xy 66.44767 -120.416574) (xy 66.420337 -120.416103)
			(xy 66.36623 -120.408295) (xy 66.313793 -120.392844) (xy 66.264097 -120.370065) (xy 66.218163 -120.340427)
			(xy 66.197226 -120.322848) (xy 66.196718 -120.32234) (xy 66.189633 -120.316749) (xy 66.172716 -120.310496)
			(xy 66.163698 -120.310148) (xy 66.096642 -120.310148) (xy 66.087622 -120.310499) (xy 66.070693 -120.316731)
			(xy 66.063622 -120.32234) (xy 66.063368 -120.322594) (xy 66.042436 -120.340234) (xy 65.996469 -120.369957)
			(xy 65.946722 -120.392796) (xy 65.894219 -120.408283) (xy 65.84004 -120.416097) (xy 65.81267 -120.416574)
			(xy 65.812162 -120.416574) (xy 65.79621 -120.416413) (xy 65.764418 -120.413742) (xy 65.748662 -120.41124)
			(xy 65.744344 -120.410478) (xy 65.733676 -120.408446) (xy 65.712848 -120.41378) (xy 65.704212 -120.420384)
			(xy 65.703196 -120.421146) (xy 65.678304 -120.442228) (xy 65.669843 -120.450202) (xy 65.660573 -120.471497)
			(xy 65.660524 -120.483122) (xy 65.660524 -120.483884) (xy 65.661032 -120.503696) (xy 65.661032 -120.716548)
			(xy 69.301866 -120.716548) (xy 69.305939 -120.660889) (xy 69.318074 -120.606416) (xy 69.33801 -120.55429)
			(xy 69.365324 -120.505622) (xy 69.399432 -120.46145) (xy 69.439609 -120.422715) (xy 69.484997 -120.390243)
			(xy 69.534629 -120.364725) (xy 69.587449 -120.346706) (xy 69.642328 -120.336569) (xy 69.698099 -120.334531)
			(xy 69.753573 -120.340634) (xy 69.807566 -120.35475) (xy 69.858929 -120.376577) (xy 69.906567 -120.40565)
			(xy 69.949463 -120.441349) (xy 69.986705 -120.482913) (xy 70.017499 -120.529457) (xy 70.041187 -120.579988)
			(xy 70.057265 -120.63343) (xy 70.065391 -120.688644) (xy 70.0659 -120.716548) (xy 70.065391 -120.744452)
			(xy 70.057265 -120.799666) (xy 70.041187 -120.853108) (xy 70.017499 -120.903639) (xy 69.986705 -120.950183)
			(xy 69.949463 -120.991747) (xy 69.906567 -121.027446) (xy 69.858929 -121.056519) (xy 69.807566 -121.078346)
			(xy 69.753573 -121.092462) (xy 69.698099 -121.098565) (xy 69.642328 -121.096527) (xy 69.587449 -121.08639)
			(xy 69.534629 -121.068371) (xy 69.484997 -121.042853) (xy 69.439609 -121.010381) (xy 69.399432 -120.971646)
			(xy 69.365324 -120.927474) (xy 69.33801 -120.878806) (xy 69.318074 -120.82668) (xy 69.305939 -120.772207)
			(xy 69.301866 -120.716548) (xy 65.661032 -120.716548) (xy 65.661032 -121.367296) (xy 65.660524 -121.380758)
			(xy 65.660524 -121.388886) (xy 65.665096 -121.409714) (xy 65.669668 -121.420128) (xy 65.701926 -121.447814)
			(xy 65.706738 -121.451729) (xy 65.71778 -121.457374) (xy 65.72377 -121.45899) (xy 65.735454 -121.46153)
			(xy 65.745614 -121.459752) (xy 65.762173 -121.456947) (xy 65.795623 -121.453894) (xy 65.812416 -121.453656)
			(xy 65.81267 -121.453656) (xy 65.840005 -121.454123) (xy 65.894115 -121.461924) (xy 65.946557 -121.477369)
			(xy 65.996257 -121.500144) (xy 66.042196 -121.52978) (xy 66.063114 -121.547382) (xy 66.063622 -121.54789)
			(xy 66.070709 -121.553473) (xy 66.087627 -121.559709) (xy 66.096642 -121.560082) (xy 66.163698 -121.560082)
			(xy 66.172714 -121.559723) (xy 66.18963 -121.553474) (xy 66.196718 -121.54789) (xy 66.196972 -121.547636)
			(xy 66.217902 -121.529991) (xy 66.263867 -121.500259) (xy 66.313614 -121.47741) (xy 66.366118 -121.461914)
			(xy 66.420298 -121.454091) (xy 66.44767 -121.453656) (xy 66.474675 -121.454129) (xy 66.528143 -121.461753)
			(xy 66.580003 -121.476839) (xy 66.629218 -121.499086) (xy 66.674804 -121.52805) (xy 66.715852 -121.563151)
			(xy 66.751542 -121.603688) (xy 66.781159 -121.648853) (xy 66.804114 -121.697741) (xy 66.819947 -121.749378)
			(xy 66.824606 -121.775982) (xy 66.826638 -121.788682) (xy 66.834512 -121.799096) (xy 66.837185 -121.802398)
			(xy 66.843435 -121.808152) (xy 66.846958 -121.810526) (xy 66.918586 -121.85777) (xy 66.93916 -121.861326)
			(xy 66.949574 -121.858786) (xy 66.976024 -121.852749) (xy 67.029889 -121.846259) (xy 67.057016 -121.845832)
			(xy 67.05727 -121.845832) (xy 67.084587 -121.846229) (xy 67.138835 -121.852723) (xy 67.165474 -121.858786)
			(xy 67.175888 -121.861326) (xy 67.196462 -121.85777) (xy 67.27698 -121.804176) (xy 67.288156 -121.78665)
			(xy 67.289934 -121.775728) (xy 67.294586 -121.749121) (xy 67.310407 -121.697477) (xy 67.333354 -121.648581)
			(xy 67.362968 -121.603411) (xy 67.398658 -121.562869) (xy 67.439709 -121.527767) (xy 67.485301 -121.498806)
			(xy 67.534523 -121.476565) (xy 67.586389 -121.46149) (xy 67.639863 -121.453881) (xy 67.66687 -121.453402)
			(xy 67.694124 -121.453863) (xy 67.748076 -121.461617) (xy 67.800376 -121.47697) (xy 67.849959 -121.49961)
			(xy 67.895815 -121.529076) (xy 67.93701 -121.564769) (xy 67.972706 -121.605961) (xy 68.002176 -121.651815)
			(xy 68.02482 -121.701395) (xy 68.040177 -121.753694) (xy 68.047935 -121.807646) (xy 68.047935 -121.83491)
			(xy 71.884792 -121.83491) (xy 71.888865 -121.779251) (xy 71.901 -121.724778) (xy 71.920936 -121.672652)
			(xy 71.94825 -121.623984) (xy 71.982358 -121.579812) (xy 72.022535 -121.541077) (xy 72.067923 -121.508605)
			(xy 72.117555 -121.483087) (xy 72.170375 -121.465068) (xy 72.225254 -121.454931) (xy 72.281025 -121.452893)
			(xy 72.336499 -121.458996) (xy 72.390492 -121.473112) (xy 72.441855 -121.494939) (xy 72.489493 -121.524012)
			(xy 72.532389 -121.559711) (xy 72.569631 -121.601275) (xy 72.600425 -121.647819) (xy 72.624113 -121.69835)
			(xy 72.640191 -121.751792) (xy 72.648317 -121.807006) (xy 72.648826 -121.83491) (xy 73.865992 -121.83491)
			(xy 73.870065 -121.779251) (xy 73.8822 -121.724778) (xy 73.902136 -121.672652) (xy 73.92945 -121.623984)
			(xy 73.963558 -121.579812) (xy 74.003735 -121.541077) (xy 74.049123 -121.508605) (xy 74.098755 -121.483087)
			(xy 74.151575 -121.465068) (xy 74.206454 -121.454931) (xy 74.262225 -121.452893) (xy 74.317699 -121.458996)
			(xy 74.371692 -121.473112) (xy 74.423055 -121.494939) (xy 74.470693 -121.524012) (xy 74.513589 -121.559711)
			(xy 74.550831 -121.601275) (xy 74.581625 -121.647819) (xy 74.605313 -121.69835) (xy 74.621391 -121.751792)
			(xy 74.629517 -121.807006) (xy 74.630026 -121.83491) (xy 74.629517 -121.862814) (xy 74.621391 -121.918028)
			(xy 74.605313 -121.97147) (xy 74.581625 -122.022001) (xy 74.550831 -122.068545) (xy 74.513589 -122.110109)
			(xy 74.470693 -122.145808) (xy 74.423055 -122.174881) (xy 74.371692 -122.196708) (xy 74.317699 -122.210824)
			(xy 74.262225 -122.216927) (xy 74.206454 -122.214889) (xy 74.151575 -122.204752) (xy 74.098755 -122.186733)
			(xy 74.049123 -122.161215) (xy 74.003735 -122.128743) (xy 73.963558 -122.090008) (xy 73.92945 -122.045836)
			(xy 73.902136 -121.997168) (xy 73.8822 -121.945042) (xy 73.870065 -121.890569) (xy 73.865992 -121.83491)
			(xy 72.648826 -121.83491) (xy 72.648317 -121.862814) (xy 72.640191 -121.918028) (xy 72.624113 -121.97147)
			(xy 72.600425 -122.022001) (xy 72.569631 -122.068545) (xy 72.532389 -122.110109) (xy 72.489493 -122.145808)
			(xy 72.441855 -122.174881) (xy 72.390492 -122.196708) (xy 72.336499 -122.210824) (xy 72.281025 -122.216927)
			(xy 72.225254 -122.214889) (xy 72.170375 -122.204752) (xy 72.117555 -122.186733) (xy 72.067923 -122.161215)
			(xy 72.022535 -122.128743) (xy 71.982358 -122.090008) (xy 71.94825 -122.045836) (xy 71.920936 -121.997168)
			(xy 71.901 -121.945042) (xy 71.888865 -121.890569) (xy 71.884792 -121.83491) (xy 68.047935 -121.83491)
			(xy 68.047935 -121.862153) (xy 68.040177 -121.916106) (xy 68.02482 -121.968405) (xy 68.002176 -122.017985)
			(xy 67.972706 -122.063839) (xy 67.93701 -122.105031) (xy 67.895815 -122.140724) (xy 67.849959 -122.17019)
			(xy 67.800376 -122.19283) (xy 67.748076 -122.208183) (xy 67.694124 -122.215937) (xy 67.66687 -122.216418)
			(xy 67.666362 -122.216418) (xy 67.65041 -122.216257) (xy 67.618618 -122.213586) (xy 67.602862 -122.211084)
			(xy 67.598544 -122.210322) (xy 67.587876 -122.20829) (xy 67.567048 -122.213624) (xy 67.558412 -122.220228)
			(xy 67.557396 -122.22099) (xy 67.532504 -122.242072) (xy 67.524051 -122.250048) (xy 67.514799 -122.271343)
			(xy 67.514724 -122.282966) (xy 67.514724 -122.283728) (xy 67.515232 -122.30354) (xy 67.515232 -122.597164)
			(xy 69.301866 -122.597164) (xy 69.305939 -122.541505) (xy 69.318074 -122.487032) (xy 69.33801 -122.434906)
			(xy 69.365324 -122.386238) (xy 69.399432 -122.342066) (xy 69.439609 -122.303331) (xy 69.484997 -122.270859)
			(xy 69.534629 -122.245341) (xy 69.587449 -122.227322) (xy 69.642328 -122.217185) (xy 69.698099 -122.215147)
			(xy 69.753573 -122.22125) (xy 69.807566 -122.235366) (xy 69.858929 -122.257193) (xy 69.906567 -122.286266)
			(xy 69.949463 -122.321965) (xy 69.986705 -122.363529) (xy 70.017499 -122.410073) (xy 70.041187 -122.460604)
			(xy 70.057265 -122.514046) (xy 70.065391 -122.56926) (xy 70.0659 -122.597164) (xy 70.065391 -122.625068)
			(xy 70.057265 -122.680282) (xy 70.041187 -122.733724) (xy 70.017499 -122.784255) (xy 69.986705 -122.830799)
			(xy 69.949463 -122.872363) (xy 69.906567 -122.908062) (xy 69.858929 -122.937135) (xy 69.807566 -122.958962)
			(xy 69.753573 -122.973078) (xy 69.698099 -122.979181) (xy 69.642328 -122.977143) (xy 69.587449 -122.967006)
			(xy 69.534629 -122.948987) (xy 69.484997 -122.923469) (xy 69.439609 -122.890997) (xy 69.399432 -122.852262)
			(xy 69.365324 -122.80809) (xy 69.33801 -122.759422) (xy 69.318074 -122.707296) (xy 69.305939 -122.652823)
			(xy 69.301866 -122.597164) (xy 67.515232 -122.597164) (xy 67.515232 -123.16714) (xy 67.514724 -123.180602)
			(xy 67.514724 -123.18873) (xy 67.519296 -123.209558) (xy 67.523868 -123.219972) (xy 67.556126 -123.247658)
			(xy 67.56094 -123.25157) (xy 67.571983 -123.25721) (xy 67.57797 -123.258834) (xy 67.589654 -123.261374)
			(xy 67.599814 -123.259596) (xy 67.616373 -123.256791) (xy 67.649823 -123.253738) (xy 67.666616 -123.2535)
			(xy 67.66687 -123.2535) (xy 67.694124 -123.253961) (xy 67.748077 -123.261715) (xy 67.800377 -123.277068)
			(xy 67.84996 -123.299708) (xy 67.895816 -123.329175) (xy 67.937011 -123.364868) (xy 67.972707 -123.40606)
			(xy 68.002178 -123.451914) (xy 68.024822 -123.501495) (xy 68.040179 -123.553794) (xy 68.047937 -123.607746)
			(xy 68.047937 -123.635008) (xy 71.885046 -123.635008) (xy 71.889117 -123.579386) (xy 71.901243 -123.524949)
			(xy 71.921166 -123.472858) (xy 71.948462 -123.424223) (xy 71.982548 -123.38008) (xy 72.022697 -123.341371)
			(xy 72.068055 -123.30892) (xy 72.117655 -123.283419) (xy 72.170439 -123.265412) (xy 72.225282 -123.255282)
			(xy 72.281016 -123.253245) (xy 72.336453 -123.259345) (xy 72.39041 -123.273451) (xy 72.441739 -123.295263)
			(xy 72.489345 -123.324317) (xy 72.532213 -123.359992) (xy 72.56943 -123.401529) (xy 72.600203 -123.448042)
			(xy 72.623875 -123.498539) (xy 72.639943 -123.551946) (xy 72.648063 -123.607122) (xy 72.648572 -123.635008)
			(xy 73.866246 -123.635008) (xy 73.870317 -123.579386) (xy 73.882443 -123.524949) (xy 73.902366 -123.472858)
			(xy 73.929662 -123.424223) (xy 73.963748 -123.38008) (xy 74.003897 -123.341371) (xy 74.049255 -123.30892)
			(xy 74.098855 -123.283419) (xy 74.151639 -123.265412) (xy 74.206482 -123.255282) (xy 74.262216 -123.253245)
			(xy 74.317653 -123.259345) (xy 74.37161 -123.273451) (xy 74.422939 -123.295263) (xy 74.470545 -123.324317)
			(xy 74.513413 -123.359992) (xy 74.55063 -123.401529) (xy 74.581403 -123.448042) (xy 74.605075 -123.498539)
			(xy 74.621143 -123.551946) (xy 74.629263 -123.607122) (xy 74.629772 -123.635008) (xy 74.629263 -123.662894)
			(xy 74.621143 -123.71807) (xy 74.605075 -123.771477) (xy 74.581403 -123.821974) (xy 74.55063 -123.868487)
			(xy 74.513413 -123.910024) (xy 74.470545 -123.945699) (xy 74.422939 -123.974753) (xy 74.37161 -123.996565)
			(xy 74.317653 -124.010671) (xy 74.262216 -124.016771) (xy 74.206482 -124.014734) (xy 74.151639 -124.004604)
			(xy 74.098855 -123.986597) (xy 74.049255 -123.961096) (xy 74.003897 -123.928645) (xy 73.963748 -123.889936)
			(xy 73.929662 -123.845793) (xy 73.902366 -123.797158) (xy 73.882443 -123.745067) (xy 73.870317 -123.69063)
			(xy 73.866246 -123.635008) (xy 72.648572 -123.635008) (xy 72.648063 -123.662894) (xy 72.639943 -123.71807)
			(xy 72.623875 -123.771477) (xy 72.600203 -123.821974) (xy 72.56943 -123.868487) (xy 72.532213 -123.910024)
			(xy 72.489345 -123.945699) (xy 72.441739 -123.974753) (xy 72.39041 -123.996565) (xy 72.336453 -124.010671)
			(xy 72.281016 -124.016771) (xy 72.225282 -124.014734) (xy 72.170439 -124.004604) (xy 72.117655 -123.986597)
			(xy 72.068055 -123.961096) (xy 72.022697 -123.928645) (xy 71.982548 -123.889936) (xy 71.948462 -123.845793)
			(xy 71.921166 -123.797158) (xy 71.901243 -123.745067) (xy 71.889117 -123.69063) (xy 71.885046 -123.635008)
			(xy 68.047937 -123.635008) (xy 68.047937 -123.662254) (xy 68.040179 -123.716206) (xy 68.024822 -123.768505)
			(xy 68.002178 -123.818086) (xy 67.972707 -123.86394) (xy 67.937011 -123.905132) (xy 67.895816 -123.940825)
			(xy 67.84996 -123.970292) (xy 67.800377 -123.992932) (xy 67.748077 -124.008285) (xy 67.694124 -124.016039)
			(xy 67.66687 -124.016516) (xy 67.639916 -124.016056) (xy 67.586545 -124.008475) (xy 67.534772 -123.993455)
			(xy 67.48563 -123.971295) (xy 67.440098 -123.942437) (xy 67.399083 -123.907455) (xy 67.363401 -123.867047)
			(xy 67.333765 -123.822017) (xy 67.310765 -123.773262) (xy 67.294858 -123.721755) (xy 67.290188 -123.695206)
			(xy 67.290188 -123.694444) (xy 67.28794 -123.684202) (xy 67.276525 -123.666639) (xy 67.26809 -123.660408)
			(xy 67.206114 -123.619006) (xy 67.197068 -123.6136) (xy 67.176339 -123.609942) (xy 67.165982 -123.611894)
			(xy 67.165728 -123.611894) (xy 67.13909 -123.617964) (xy 67.084842 -123.624454) (xy 67.057524 -123.624848)
			(xy 67.057016 -123.624848) (xy 67.029699 -123.62445) (xy 66.975451 -123.617956) (xy 66.948812 -123.611894)
			(xy 66.948558 -123.611894) (xy 66.938203 -123.609924) (xy 66.917469 -123.613592) (xy 66.908426 -123.619006)
			(xy 66.84645 -123.660408) (xy 66.837968 -123.666595) (xy 66.826535 -123.684176) (xy 66.824352 -123.694444)
			(xy 66.824352 -123.695206) (xy 66.819641 -123.721746) (xy 66.803728 -123.773246) (xy 66.780725 -123.821993)
			(xy 66.751091 -123.867018) (xy 66.715414 -123.907424) (xy 66.674406 -123.942406) (xy 66.628882 -123.971268)
			(xy 66.579749 -123.993435) (xy 66.527985 -124.008467) (xy 66.474621 -124.016063) (xy 66.44767 -124.016516)
			(xy 66.420337 -124.016045) (xy 66.366231 -124.008236) (xy 66.313795 -123.992783) (xy 66.264102 -123.970002)
			(xy 66.21817 -123.94036) (xy 66.197226 -123.92279) (xy 66.196718 -123.922282) (xy 66.189631 -123.916696)
			(xy 66.172714 -123.91045) (xy 66.163698 -123.91009) (xy 66.096642 -123.91009) (xy 66.087623 -123.910442)
			(xy 66.070697 -123.916678) (xy 66.063622 -123.922282) (xy 66.063368 -123.922536) (xy 66.042437 -123.940179)
			(xy 65.996471 -123.969906) (xy 65.946725 -123.992749) (xy 65.894221 -124.008237) (xy 65.840041 -124.016053)
			(xy 65.81267 -124.016516) (xy 65.812162 -124.016516) (xy 65.79621 -124.016355) (xy 65.764418 -124.013684)
			(xy 65.748662 -124.011182) (xy 65.744344 -124.01042) (xy 65.733676 -124.008388) (xy 65.712848 -124.013722)
			(xy 65.704212 -124.020326) (xy 65.703196 -124.021088) (xy 65.678304 -124.04217) (xy 65.669851 -124.050146)
			(xy 65.660598 -124.071441) (xy 65.660524 -124.083064) (xy 65.660524 -124.083826) (xy 65.661032 -124.103638)
			(xy 65.661032 -124.31649) (xy 69.30212 -124.31649) (xy 69.306191 -124.260868) (xy 69.318317 -124.206431)
			(xy 69.33824 -124.15434) (xy 69.365536 -124.105705) (xy 69.399622 -124.061562) (xy 69.439771 -124.022853)
			(xy 69.485129 -123.990402) (xy 69.534729 -123.964901) (xy 69.587513 -123.946894) (xy 69.642356 -123.936764)
			(xy 69.69809 -123.934727) (xy 69.753527 -123.940827) (xy 69.807484 -123.954933) (xy 69.858813 -123.976745)
			(xy 69.906419 -124.005799) (xy 69.949287 -124.041474) (xy 69.986504 -124.083011) (xy 70.017277 -124.129524)
			(xy 70.040949 -124.180021) (xy 70.057017 -124.233428) (xy 70.065137 -124.288604) (xy 70.065646 -124.31649)
			(xy 70.065137 -124.344376) (xy 70.057017 -124.399552) (xy 70.040949 -124.452959) (xy 70.017277 -124.503456)
			(xy 69.986504 -124.549969) (xy 69.949287 -124.591506) (xy 69.906419 -124.627181) (xy 69.858813 -124.656235)
			(xy 69.807484 -124.678047) (xy 69.753527 -124.692153) (xy 69.69809 -124.698253) (xy 69.642356 -124.696216)
			(xy 69.587513 -124.686086) (xy 69.534729 -124.668079) (xy 69.485129 -124.642578) (xy 69.439771 -124.610127)
			(xy 69.399622 -124.571418) (xy 69.365536 -124.527275) (xy 69.33824 -124.47864) (xy 69.318317 -124.426549)
			(xy 69.306191 -124.372112) (xy 69.30212 -124.31649) (xy 65.661032 -124.31649) (xy 65.661032 -124.967238)
			(xy 65.660524 -124.9807) (xy 65.660524 -124.988828) (xy 65.665096 -125.009656) (xy 65.669668 -125.02007)
			(xy 65.701926 -125.047756) (xy 65.70674 -125.051668) (xy 65.717783 -125.057309) (xy 65.72377 -125.058932)
			(xy 65.735454 -125.061472) (xy 65.745614 -125.059694) (xy 65.762173 -125.056889) (xy 65.795623 -125.053836)
			(xy 65.812416 -125.053598) (xy 65.81267 -125.053598) (xy 65.839924 -125.054059) (xy 65.893877 -125.061813)
			(xy 65.946178 -125.077166) (xy 65.995761 -125.099806) (xy 66.041617 -125.129273) (xy 66.082813 -125.164966)
			(xy 66.118509 -125.206159) (xy 66.147979 -125.252013) (xy 66.170624 -125.301594) (xy 66.185981 -125.353894)
			(xy 66.193739 -125.407846) (xy 66.193739 -125.435106) (xy 67.284852 -125.435106) (xy 67.288923 -125.379484)
			(xy 67.301049 -125.325047) (xy 67.320972 -125.272956) (xy 67.348268 -125.224321) (xy 67.382354 -125.180178)
			(xy 67.422503 -125.141469) (xy 67.467861 -125.109018) (xy 67.517461 -125.083517) (xy 67.570245 -125.06551)
			(xy 67.625088 -125.05538) (xy 67.680822 -125.053343) (xy 67.736259 -125.059443) (xy 67.790216 -125.073549)
			(xy 67.841545 -125.095361) (xy 67.889151 -125.124415) (xy 67.932019 -125.16009) (xy 67.969236 -125.201627)
			(xy 68.000009 -125.24814) (xy 68.023681 -125.298637) (xy 68.039749 -125.352044) (xy 68.047869 -125.40722)
			(xy 68.048378 -125.435106) (xy 68.047869 -125.462992) (xy 68.039749 -125.518168) (xy 68.023681 -125.571575)
			(xy 68.000009 -125.622072) (xy 67.969236 -125.668585) (xy 67.932019 -125.710122) (xy 67.889151 -125.745797)
			(xy 67.87841 -125.752352) (xy 69.255384 -125.752352) (xy 69.259455 -125.69673) (xy 69.271581 -125.642293)
			(xy 69.291504 -125.590202) (xy 69.3188 -125.541567) (xy 69.352886 -125.497424) (xy 69.393035 -125.458715)
			(xy 69.438393 -125.426264) (xy 69.487993 -125.400763) (xy 69.540777 -125.382756) (xy 69.59562 -125.372626)
			(xy 69.651354 -125.370589) (xy 69.706791 -125.376689) (xy 69.760748 -125.390795) (xy 69.812077 -125.412607)
			(xy 69.848942 -125.435106) (xy 71.885046 -125.435106) (xy 71.889117 -125.379484) (xy 71.901243 -125.325047)
			(xy 71.921166 -125.272956) (xy 71.948462 -125.224321) (xy 71.982548 -125.180178) (xy 72.022697 -125.141469)
			(xy 72.068055 -125.109018) (xy 72.117655 -125.083517) (xy 72.170439 -125.06551) (xy 72.225282 -125.05538)
			(xy 72.281016 -125.053343) (xy 72.336453 -125.059443) (xy 72.39041 -125.073549) (xy 72.441739 -125.095361)
			(xy 72.489345 -125.124415) (xy 72.532213 -125.16009) (xy 72.56943 -125.201627) (xy 72.600203 -125.24814)
			(xy 72.623875 -125.298637) (xy 72.639943 -125.352044) (xy 72.648063 -125.40722) (xy 72.648572 -125.435106)
			(xy 73.866246 -125.435106) (xy 73.870317 -125.379484) (xy 73.882443 -125.325047) (xy 73.902366 -125.272956)
			(xy 73.929662 -125.224321) (xy 73.963748 -125.180178) (xy 74.003897 -125.141469) (xy 74.049255 -125.109018)
			(xy 74.098855 -125.083517) (xy 74.151639 -125.06551) (xy 74.206482 -125.05538) (xy 74.262216 -125.053343)
			(xy 74.317653 -125.059443) (xy 74.37161 -125.073549) (xy 74.422939 -125.095361) (xy 74.470545 -125.124415)
			(xy 74.513413 -125.16009) (xy 74.55063 -125.201627) (xy 74.581403 -125.24814) (xy 74.605075 -125.298637)
			(xy 74.621143 -125.352044) (xy 74.629263 -125.40722) (xy 74.629772 -125.435106) (xy 74.629263 -125.462992)
			(xy 74.621143 -125.518168) (xy 74.605075 -125.571575) (xy 74.581403 -125.622072) (xy 74.55063 -125.668585)
			(xy 74.513413 -125.710122) (xy 74.470545 -125.745797) (xy 74.422939 -125.774851) (xy 74.37161 -125.796663)
			(xy 74.317653 -125.810769) (xy 74.262216 -125.816869) (xy 74.206482 -125.814832) (xy 74.151639 -125.804702)
			(xy 74.098855 -125.786695) (xy 74.049255 -125.761194) (xy 74.003897 -125.728743) (xy 73.963748 -125.690034)
			(xy 73.929662 -125.645891) (xy 73.902366 -125.597256) (xy 73.882443 -125.545165) (xy 73.870317 -125.490728)
			(xy 73.866246 -125.435106) (xy 72.648572 -125.435106) (xy 72.648063 -125.462992) (xy 72.639943 -125.518168)
			(xy 72.623875 -125.571575) (xy 72.600203 -125.622072) (xy 72.56943 -125.668585) (xy 72.532213 -125.710122)
			(xy 72.489345 -125.745797) (xy 72.441739 -125.774851) (xy 72.39041 -125.796663) (xy 72.336453 -125.810769)
			(xy 72.281016 -125.816869) (xy 72.225282 -125.814832) (xy 72.170439 -125.804702) (xy 72.117655 -125.786695)
			(xy 72.068055 -125.761194) (xy 72.022697 -125.728743) (xy 71.982548 -125.690034) (xy 71.948462 -125.645891)
			(xy 71.921166 -125.597256) (xy 71.901243 -125.545165) (xy 71.889117 -125.490728) (xy 71.885046 -125.435106)
			(xy 69.848942 -125.435106) (xy 69.859683 -125.441661) (xy 69.902551 -125.477336) (xy 69.939768 -125.518873)
			(xy 69.970541 -125.565386) (xy 69.994213 -125.615883) (xy 70.010281 -125.66929) (xy 70.018401 -125.724466)
			(xy 70.01891 -125.752352) (xy 70.018401 -125.780238) (xy 70.010281 -125.835414) (xy 69.994213 -125.888821)
			(xy 69.970541 -125.939318) (xy 69.939768 -125.985831) (xy 69.902551 -126.027368) (xy 69.859683 -126.063043)
			(xy 69.812077 -126.092097) (xy 69.760748 -126.113909) (xy 69.706791 -126.128015) (xy 69.651354 -126.134115)
			(xy 69.59562 -126.132078) (xy 69.540777 -126.121948) (xy 69.487993 -126.103941) (xy 69.438393 -126.07844)
			(xy 69.393035 -126.045989) (xy 69.352886 -126.00728) (xy 69.3188 -125.963137) (xy 69.291504 -125.914502)
			(xy 69.271581 -125.862411) (xy 69.259455 -125.807974) (xy 69.255384 -125.752352) (xy 67.87841 -125.752352)
			(xy 67.841545 -125.774851) (xy 67.790216 -125.796663) (xy 67.736259 -125.810769) (xy 67.680822 -125.816869)
			(xy 67.625088 -125.814832) (xy 67.570245 -125.804702) (xy 67.517461 -125.786695) (xy 67.467861 -125.761194)
			(xy 67.422503 -125.728743) (xy 67.382354 -125.690034) (xy 67.348268 -125.645891) (xy 67.320972 -125.597256)
			(xy 67.301049 -125.545165) (xy 67.288923 -125.490728) (xy 67.284852 -125.435106) (xy 66.193739 -125.435106)
			(xy 66.193739 -125.462354) (xy 66.185981 -125.516306) (xy 66.170624 -125.568606) (xy 66.147979 -125.618187)
			(xy 66.118509 -125.664041) (xy 66.082813 -125.705234) (xy 66.041617 -125.740927) (xy 65.995761 -125.770394)
			(xy 65.946178 -125.793034) (xy 65.893877 -125.808387) (xy 65.839924 -125.816141) (xy 65.81267 -125.816614)
			(xy 65.785706 -125.816153) (xy 65.732314 -125.808564) (xy 65.680525 -125.793529) (xy 65.63137 -125.771347)
			(xy 65.585831 -125.742461) (xy 65.544816 -125.707447) (xy 65.509144 -125.667003) (xy 65.479525 -125.621936)
			(xy 65.456552 -125.573147) (xy 65.440682 -125.521607) (xy 65.435988 -125.49505) (xy 65.435988 -125.494796)
			(xy 65.433793 -125.48448) (xy 65.422373 -125.466775) (xy 65.41389 -125.460506) (xy 65.353692 -125.420374)
			(xy 65.347304 -125.416482) (xy 65.332974 -125.41222) (xy 65.325498 -125.411992) (xy 65.311528 -125.411992)
			(xy 65.305686 -125.413262) (xy 65.280453 -125.418776) (xy 65.229149 -125.424754) (xy 65.203324 -125.4252)
			(xy 65.202816 -125.4252) (xy 65.180243 -125.42487) (xy 65.135328 -125.420295) (xy 65.113154 -125.416056)
			(xy 65.1129 -125.415802) (xy 65.095882 -125.411992) (xy 65.071498 -125.40742) (xy 65.054226 -125.419104)
			(xy 64.99225 -125.460506) (xy 64.983768 -125.466693) (xy 64.972334 -125.484274) (xy 64.970152 -125.494542)
			(xy 64.970152 -125.495304) (xy 64.965441 -125.521844) (xy 64.949528 -125.573344) (xy 64.926526 -125.622092)
			(xy 64.896891 -125.667117) (xy 64.861215 -125.707523) (xy 64.820206 -125.742505) (xy 64.774682 -125.771367)
			(xy 64.725549 -125.793535) (xy 64.673785 -125.808566) (xy 64.620421 -125.816163) (xy 64.59347 -125.816614)
			(xy 64.56622 -125.816126) (xy 64.512274 -125.808366) (xy 64.459982 -125.793008) (xy 64.410408 -125.770365)
			(xy 64.364561 -125.740897) (xy 64.323374 -125.705205) (xy 64.287685 -125.664015) (xy 64.258221 -125.618165)
			(xy 64.235581 -125.568589) (xy 64.220228 -125.516296) (xy 64.212472 -125.46235) (xy 64.212472 -125.40785)
			(xy 64.220228 -125.353904) (xy 64.235581 -125.301611) (xy 64.258221 -125.252035) (xy 64.287685 -125.206185)
			(xy 64.323374 -125.164995) (xy 64.364561 -125.129303) (xy 64.410408 -125.099835) (xy 64.459982 -125.077192)
			(xy 64.512274 -125.061834) (xy 64.56622 -125.054074) (xy 64.59347 -125.053598) (xy 64.593724 -125.053598)
			(xy 64.609935 -125.053789) (xy 64.642237 -125.05659) (xy 64.65824 -125.059186) (xy 64.65951 -125.05944)
			(xy 64.661542 -125.059694) (xy 64.67475 -125.061472) (xy 64.685418 -125.05817) (xy 64.690411 -125.056564)
			(xy 64.699631 -125.051566) (xy 64.703706 -125.048264) (xy 64.70396 -125.04801) (xy 64.72809 -125.027182)
			(xy 64.732111 -125.023508) (xy 64.73865 -125.014801) (xy 64.741044 -125.00991) (xy 64.746124 -124.998734)
			(xy 64.745616 -124.986288) (xy 64.745616 -124.982986) (xy 64.745108 -124.967238) (xy 64.745108 -124.103638)
			(xy 64.745616 -124.083826) (xy 64.745616 -124.083064) (xy 64.745584 -124.071432) (xy 64.736325 -124.050121)
			(xy 64.727836 -124.04217) (xy 64.703452 -124.021596) (xy 64.694527 -124.014821) (xy 64.672912 -124.009016)
			(xy 64.661796 -124.01042) (xy 64.661542 -124.01042) (xy 64.644732 -124.013263) (xy 64.610772 -124.016315)
			(xy 64.593724 -124.016516) (xy 64.59347 -124.016516) (xy 64.56622 -124.016028) (xy 64.512274 -124.008268)
			(xy 64.459982 -123.99291) (xy 64.410407 -123.970267) (xy 64.36456 -123.940799) (xy 64.323372 -123.905107)
			(xy 64.287683 -123.863916) (xy 64.258219 -123.818066) (xy 64.23558 -123.76849) (xy 64.220226 -123.716197)
			(xy 64.21247 -123.66225) (xy 64.21247 -123.60775) (xy 64.220226 -123.553803) (xy 64.23558 -123.50151)
			(xy 64.258219 -123.451934) (xy 64.287683 -123.406084) (xy 64.323372 -123.364893) (xy 64.36456 -123.329201)
			(xy 64.410407 -123.299733) (xy 64.459982 -123.27709) (xy 64.512274 -123.261732) (xy 64.56622 -123.253972)
			(xy 64.59347 -123.2535) (xy 64.620474 -123.253973) (xy 64.67394 -123.261598) (xy 64.725798 -123.276685)
			(xy 64.77501 -123.298932) (xy 64.820594 -123.327897) (xy 64.861639 -123.362999) (xy 64.897324 -123.403538)
			(xy 64.926937 -123.448703) (xy 64.949886 -123.497592) (xy 64.965713 -123.549228) (xy 64.970406 -123.575826)
			(xy 64.972184 -123.586748) (xy 64.98336 -123.604274) (xy 65.052702 -123.650502) (xy 65.059089 -123.654396)
			(xy 65.073419 -123.658662) (xy 65.080896 -123.658884) (xy 65.09512 -123.658884) (xy 65.100962 -123.657614)
			(xy 65.12607 -123.652121) (xy 65.177119 -123.646139) (xy 65.202816 -123.645676) (xy 65.203324 -123.645676)
			(xy 65.229799 -123.646113) (xy 65.282382 -123.652357) (xy 65.308226 -123.658122) (xy 65.31102 -123.658884)
			(xy 65.317624 -123.659646) (xy 65.32656 -123.660271) (xy 65.343967 -123.656107) (xy 65.35166 -123.651518)
			(xy 65.42278 -123.604274) (xy 65.433956 -123.586748) (xy 65.435734 -123.575826) (xy 65.440386 -123.549219)
			(xy 65.456207 -123.497576) (xy 65.479154 -123.44868) (xy 65.508769 -123.403509) (xy 65.544458 -123.362968)
			(xy 65.58551 -123.327866) (xy 65.631102 -123.298905) (xy 65.680323 -123.276665) (xy 65.732189 -123.261589)
			(xy 65.785664 -123.253981) (xy 65.81267 -123.2535) (xy 65.840004 -123.253967) (xy 65.894114 -123.261769)
			(xy 65.946555 -123.277216) (xy 65.996253 -123.299992) (xy 66.042191 -123.329631) (xy 66.063114 -123.347226)
			(xy 66.063622 -123.347734) (xy 66.070711 -123.353313) (xy 66.087628 -123.359543) (xy 66.096642 -123.359926)
			(xy 66.163698 -123.359926) (xy 66.172715 -123.359567) (xy 66.189633 -123.353323) (xy 66.196718 -123.347734)
			(xy 66.196972 -123.34748) (xy 66.217903 -123.329837) (xy 66.263869 -123.300109) (xy 66.313616 -123.277264)
			(xy 66.366119 -123.261771) (xy 66.420299 -123.253948) (xy 66.44767 -123.2535) (xy 66.447924 -123.2535)
			(xy 66.464135 -123.253691) (xy 66.496437 -123.256492) (xy 66.51244 -123.259088) (xy 66.51371 -123.259342)
			(xy 66.515742 -123.259596) (xy 66.52895 -123.261374) (xy 66.539618 -123.258072) (xy 66.544611 -123.256466)
			(xy 66.553831 -123.251469) (xy 66.557906 -123.248166) (xy 66.55816 -123.247912) (xy 66.58229 -123.227084)
			(xy 66.586311 -123.22341) (xy 66.59285 -123.214704) (xy 66.595244 -123.209812) (xy 66.600324 -123.198636)
			(xy 66.599816 -123.18619) (xy 66.599816 -123.182888) (xy 66.599308 -123.16714) (xy 66.599308 -122.30354)
			(xy 66.599816 -122.283982) (xy 66.599816 -122.28322) (xy 66.599775 -122.271593) (xy 66.590504 -122.250296)
			(xy 66.582036 -122.242326) (xy 66.557652 -122.221752) (xy 66.548725 -122.214982) (xy 66.527113 -122.209182)
			(xy 66.515996 -122.210576) (xy 66.515742 -122.210576) (xy 66.498932 -122.213419) (xy 66.464972 -122.21647)
			(xy 66.447924 -122.216672) (xy 66.44767 -122.216672) (xy 66.420337 -122.216201) (xy 66.36623 -122.208393)
			(xy 66.313793 -122.192942) (xy 66.264098 -122.170163) (xy 66.218163 -122.140524) (xy 66.197226 -122.122946)
			(xy 66.196718 -122.122438) (xy 66.189633 -122.116847) (xy 66.172716 -122.110594) (xy 66.163698 -122.110246)
			(xy 66.096642 -122.110246) (xy 66.087622 -122.110597) (xy 66.070693 -122.116829) (xy 66.063622 -122.122438)
			(xy 66.063368 -122.122692) (xy 66.042436 -122.140333) (xy 65.996469 -122.170055) (xy 65.946722 -122.192895)
			(xy 65.894219 -122.208381) (xy 65.84004 -122.216195) (xy 65.81267 -122.216672) (xy 65.785717 -122.216212)
			(xy 65.732348 -122.208631) (xy 65.680577 -122.19361) (xy 65.631438 -122.171449) (xy 65.585908 -122.14259)
			(xy 65.544896 -122.107607) (xy 65.509219 -122.067197) (xy 65.479588 -122.022167) (xy 65.456592 -121.973412)
			(xy 65.440692 -121.921905) (xy 65.435988 -121.895362) (xy 65.435988 -121.8946) (xy 65.43375 -121.884352)
			(xy 65.422345 -121.866772) (xy 65.41389 -121.860564) (xy 65.351914 -121.819162) (xy 65.34287 -121.813751)
			(xy 65.322139 -121.810089) (xy 65.311782 -121.81205) (xy 65.311528 -121.81205) (xy 65.28489 -121.818121)
			(xy 65.230642 -121.824611) (xy 65.203324 -121.825004) (xy 65.202816 -121.825004) (xy 65.175499 -121.824606)
			(xy 65.121251 -121.818112) (xy 65.094612 -121.81205) (xy 65.094358 -121.81205) (xy 65.084003 -121.81008)
			(xy 65.063271 -121.813751) (xy 65.054226 -121.819162) (xy 64.99225 -121.860564) (xy 64.983775 -121.866755)
			(xy 64.972361 -121.88434) (xy 64.970152 -121.8946) (xy 64.970152 -121.895362) (xy 64.965437 -121.921899)
			(xy 64.949519 -121.973393) (xy 64.926513 -122.022134) (xy 64.896876 -122.067152) (xy 64.861199 -122.107551)
			(xy 64.820191 -122.142528) (xy 64.774669 -122.171385) (xy 64.725539 -122.193548) (xy 64.673779 -122.208577)
			(xy 64.620419 -122.216172) (xy 64.59347 -122.216672) (xy 64.566223 -122.216184) (xy 64.512283 -122.208425)
			(xy 64.459997 -122.193068) (xy 64.410429 -122.170428) (xy 64.364586 -122.140963) (xy 64.323404 -122.105275)
			(xy 64.287719 -122.06409) (xy 64.258258 -122.018245) (xy 64.235621 -121.968675) (xy 64.220269 -121.916387)
			(xy 64.212514 -121.862447) (xy 64.212514 -121.807953) (xy 64.220269 -121.754013) (xy 64.235621 -121.701725)
			(xy 64.258258 -121.652155) (xy 64.287719 -121.60631) (xy 64.323404 -121.565125) (xy 64.364586 -121.529437)
			(xy 64.410429 -121.499972) (xy 64.459997 -121.477332) (xy 64.512283 -121.461975) (xy 64.566223 -121.454216)
			(xy 64.59347 -121.453656) (xy 64.593724 -121.453656) (xy 64.609935 -121.453847) (xy 64.642237 -121.456649)
			(xy 64.65824 -121.459244) (xy 64.65951 -121.459498) (xy 64.661542 -121.459752) (xy 64.67475 -121.46153)
			(xy 64.685418 -121.458228) (xy 64.690412 -121.456624) (xy 64.699636 -121.451631) (xy 64.703706 -121.448322)
			(xy 64.70396 -121.448068) (xy 64.72809 -121.42724) (xy 64.732108 -121.423564) (xy 64.738641 -121.414855)
			(xy 64.741044 -121.409968) (xy 64.746124 -121.398792) (xy 64.745616 -121.386346) (xy 64.745616 -121.383044)
			(xy 64.745108 -121.367296) (xy 64.745108 -120.503696) (xy 64.745616 -120.483884) (xy 64.745616 -120.483122)
			(xy 64.745575 -120.471494) (xy 64.736305 -120.450197) (xy 64.727836 -120.442228) (xy 64.703452 -120.421654)
			(xy 64.694526 -120.414883) (xy 64.672913 -120.409084) (xy 64.661796 -120.410478) (xy 64.661542 -120.410478)
			(xy 64.644732 -120.413321) (xy 64.610772 -120.416372) (xy 64.593724 -120.416574) (xy 64.59347 -120.416574)
			(xy 64.566223 -120.416086) (xy 64.512283 -120.408326) (xy 64.459997 -120.39297) (xy 64.410428 -120.370329)
			(xy 64.364585 -120.340865) (xy 64.323402 -120.305177) (xy 64.287717 -120.263991) (xy 64.258256 -120.218146)
			(xy 64.235619 -120.168575) (xy 64.220267 -120.116288) (xy 64.212512 -120.062347) (xy 64.212512 -120.007853)
			(xy 64.220267 -119.953912) (xy 64.235619 -119.901625) (xy 64.258256 -119.852054) (xy 64.287717 -119.806209)
			(xy 64.323402 -119.765023) (xy 64.364585 -119.729335) (xy 64.410428 -119.699871) (xy 64.459997 -119.67723)
			(xy 64.512283 -119.661874) (xy 64.566223 -119.654114) (xy 64.59347 -119.653558) (xy 64.620475 -119.654031)
			(xy 64.673943 -119.661655) (xy 64.725803 -119.676742) (xy 64.775017 -119.698989) (xy 64.820604 -119.727952)
			(xy 64.861652 -119.763053) (xy 64.897341 -119.803591) (xy 64.926958 -119.848755) (xy 64.949913 -119.897644)
			(xy 64.965745 -119.94928) (xy 64.970406 -119.975884) (xy 64.972184 -119.986806) (xy 64.98336 -120.004332)
			(xy 65.063878 -120.057926) (xy 65.084452 -120.061482) (xy 65.094866 -120.058942) (xy 65.121504 -120.052871)
			(xy 65.175752 -120.04638) (xy 65.20307 -120.045988) (xy 65.230387 -120.046385) (xy 65.284635 -120.052878)
			(xy 65.311274 -120.058942) (xy 65.321688 -120.061482) (xy 65.342262 -120.057926) (xy 65.42278 -120.004332)
			(xy 65.433956 -119.986806) (xy 65.435734 -119.975884) (xy 65.440383 -119.949274) (xy 65.456198 -119.897624)
			(xy 65.479141 -119.848722) (xy 65.508753 -119.803545) (xy 65.544442 -119.762996) (xy 65.585494 -119.727888)
			(xy 65.631089 -119.698923) (xy 65.680313 -119.676678) (xy 65.732183 -119.6616) (xy 65.785661 -119.65399)
			(xy 65.81267 -119.653558) (xy 65.840005 -119.654025) (xy 65.894115 -119.661826) (xy 65.946557 -119.677271)
			(xy 65.996257 -119.700046) (xy 66.042196 -119.729682) (xy 66.063114 -119.747284) (xy 66.063622 -119.747792)
			(xy 66.07071 -119.753375) (xy 66.087627 -119.75961) (xy 66.096642 -119.759984) (xy 66.163698 -119.759984)
			(xy 66.172714 -119.759625) (xy 66.18963 -119.753376) (xy 66.196718 -119.747792) (xy 66.196972 -119.747538)
			(xy 66.217902 -119.729893) (xy 66.263867 -119.700161) (xy 66.313613 -119.677311) (xy 66.366117 -119.661816)
			(xy 66.420298 -119.653992) (xy 66.44767 -119.653558) (xy 66.447924 -119.653558) (xy 66.464135 -119.653749)
			(xy 66.496437 -119.656551) (xy 66.51244 -119.659146) (xy 66.51371 -119.6594) (xy 66.515742 -119.659654)
			(xy 66.52895 -119.661432) (xy 66.539618 -119.65813) (xy 66.544612 -119.656526) (xy 66.553836 -119.651533)
			(xy 66.557906 -119.648224) (xy 66.55816 -119.64797) (xy 66.58229 -119.627142) (xy 66.586308 -119.623467)
			(xy 66.592842 -119.614757) (xy 66.595244 -119.60987) (xy 66.600324 -119.598694) (xy 66.599816 -119.586248)
			(xy 66.599816 -119.582946) (xy 66.599308 -119.567198) (xy 66.599308 -118.703598) (xy 66.600324 -118.68023)
			(xy 66.600324 -118.670832) (xy 66.59991 -118.660805) (xy 66.592247 -118.642273) (xy 66.578074 -118.628085)
			(xy 66.559551 -118.620401) (xy 66.549524 -118.620032) (xy 65.92697 -118.620032) (xy 65.916902 -118.619604)
			(xy 65.898302 -118.611886) (xy 65.890902 -118.605046) (xy 65.197736 -117.91188) (xy 65.190889 -117.904482)
			(xy 65.183156 -117.885884) (xy 65.18275 -117.875812) (xy 65.18275 -115.640866) (xy 65.182319 -115.6308)
			(xy 65.174591 -115.612209) (xy 65.167764 -115.604798) (xy 64.851534 -115.288314) (xy 64.844966 -115.281192)
			(xy 64.83727 -115.263432) (xy 64.836548 -115.25377) (xy 64.836238 -115.247942) (xy 64.83328 -115.236656)
			(xy 64.830706 -115.231418) (xy 64.814843 -115.200561) (xy 64.789899 -115.135817) (xy 64.773024 -115.068517)
			(xy 64.76447 -114.999663) (xy 64.763904 -114.964972) (xy 64.763904 -114.749834) (xy 64.763446 -114.740197)
			(xy 64.756278 -114.722302) (xy 64.749934 -114.715036) (xy 64.695324 -114.657378) (xy 64.677798 -114.64925)
			(xy 64.667892 -114.648742) (xy 64.640369 -114.646788) (xy 64.58627 -114.635947) (xy 64.534296 -114.617427)
			(xy 64.485531 -114.591614) (xy 64.440992 -114.559048) (xy 64.401608 -114.520406) (xy 64.3682 -114.476494)
			(xy 64.341464 -114.428229) (xy 64.321959 -114.376617) (xy 64.310091 -114.322733) (xy 64.306107 -114.267702)
			(xy 64.31009 -114.212671) (xy 64.321958 -114.158787) (xy 64.341462 -114.107175) (xy 64.368197 -114.058909)
			(xy 64.401605 -114.014998) (xy 64.440988 -113.976355) (xy 64.485527 -113.943788) (xy 64.534292 -113.917975)
			(xy 64.586266 -113.899455) (xy 64.640365 -113.888613) (xy 64.667892 -113.886742) (xy 64.677798 -113.886234)
			(xy 64.695324 -113.878106) (xy 64.749934 -113.820448) (xy 64.749934 -113.820194) (xy 64.763904 -113.820194)
			(xy 64.763904 -113.23955) (xy 64.763472 -113.229484) (xy 64.755745 -113.210892) (xy 64.748918 -113.203482)
			(xy 64.63919 -113.093754) (xy 64.632078 -113.086388) (xy 64.613282 -113.078768) (xy 64.272922 -113.078768)
			(xy 64.269366 -113.079276) (xy 64.248344 -113.082225) (xy 64.20601 -113.085406) (xy 64.184784 -113.085626)
			(xy 64.18453 -113.085626) (xy 64.150039 -113.085113) (xy 64.081552 -113.076855) (xy 64.014544 -113.060464)
			(xy 63.949978 -113.036178) (xy 63.88878 -113.004344) (xy 63.831828 -112.965419) (xy 63.779941 -112.919962)
			(xy 63.75654 -112.894618) (xy 63.749428 -112.88649) (xy 63.730886 -112.878108) (xy 63.719964 -112.876076)
			(xy 61.842396 -112.876076) (xy 61.832327 -112.875652) (xy 61.813725 -112.867933) (xy 61.806328 -112.86109)
			(xy 60.298076 -111.352838) (xy 60.291231 -111.34544) (xy 60.283507 -111.326841) (xy 60.28309 -111.31677)
			(xy 60.28309 -107.317794) (xy 60.283514 -107.307724) (xy 60.291229 -107.28912) (xy 60.298076 -107.281726)
			(xy 61.076332 -106.50347) (xy 61.083729 -106.496621) (xy 61.102328 -106.488887) (xy 61.1124 -106.488484)
			(xy 67.007232 -106.488484) (xy 67.012737 -106.488366) (xy 67.023502 -106.486067) (xy 67.028568 -106.483912)
			(xy 67.047364 -106.475022) (xy 67.052088 -106.472699) (xy 67.060541 -106.466428) (xy 67.064128 -106.462576)
			(xy 67.06489 -106.461814) (xy 67.094597 -106.428075) (xy 67.159455 -106.365817) (xy 67.229958 -106.310035)
			(xy 67.305464 -106.261237) (xy 67.385283 -106.219868) (xy 67.468686 -106.186307) (xy 67.554912 -106.16086)
			(xy 67.643173 -106.143759) (xy 67.732663 -106.13516) (xy 67.777614 -106.134662) (xy 67.821064 -106.135164)
			(xy 67.907593 -106.143184) (xy 67.993013 -106.159152) (xy 68.076596 -106.182934) (xy 68.157627 -106.214326)
			(xy 68.235417 -106.253061) (xy 68.309301 -106.298808) (xy 68.378648 -106.351176) (xy 68.442869 -106.40972)
			(xy 68.501413 -106.473939) (xy 68.553783 -106.543286) (xy 68.599531 -106.617169) (xy 68.638267 -106.694958)
			(xy 68.669661 -106.775989) (xy 68.693444 -106.859571) (xy 68.709414 -106.944991) (xy 68.717435 -107.03152)
			(xy 68.717922 -107.07497) (xy 68.71771 -107.102211) (xy 68.714531 -107.156601) (xy 68.711572 -107.183682)
			(xy 68.710302 -107.194604) (xy 68.716652 -107.214924) (xy 68.774564 -107.279948) (xy 68.782129 -107.28757)
			(xy 68.801688 -107.296377) (xy 68.81241 -107.296966) (xy 68.995544 -107.296966) (xy 69.006289 -107.296481)
			(xy 69.025882 -107.287653) (xy 69.03339 -107.279948) (xy 69.091302 -107.214924) (xy 69.097652 -107.194604)
			(xy 69.096382 -107.183682) (xy 69.093407 -107.156602) (xy 69.090228 -107.102212) (xy 69.090032 -107.07497)
			(xy 69.090535 -107.03154) (xy 69.09855 -106.945051) (xy 69.11451 -106.859669) (xy 69.138279 -106.776125)
			(xy 69.169653 -106.695129) (xy 69.208365 -106.617372) (xy 69.254085 -106.543519) (xy 69.306423 -106.474198)
			(xy 69.364932 -106.410001) (xy 69.429115 -106.351475) (xy 69.498422 -106.299119) (xy 69.572264 -106.253381)
			(xy 69.650011 -106.214649) (xy 69.730999 -106.183254) (xy 69.814538 -106.159465) (xy 69.899915 -106.143483)
			(xy 69.986402 -106.135446) (xy 70.029832 -106.134916) (xy 71.88454 -106.134916) (xy 71.927981 -106.135419)
			(xy 72.014492 -106.143438) (xy 72.099894 -106.159403) (xy 72.183459 -106.183179) (xy 72.264474 -106.214562)
			(xy 72.342249 -106.253285) (xy 72.41612 -106.299018) (xy 72.485457 -106.351371) (xy 72.549669 -106.409897)
			(xy 72.608208 -106.474097) (xy 72.660574 -106.543423) (xy 72.706322 -106.617285) (xy 72.745061 -106.695052)
			(xy 72.776461 -106.776061) (xy 72.800253 -106.859621) (xy 72.816236 -106.94502) (xy 72.824272 -107.031529)
			(xy 72.824848 -107.07497) (xy 72.824636 -107.102211) (xy 72.821457 -107.156601) (xy 72.818498 -107.183682)
			(xy 72.817228 -107.194604) (xy 72.823578 -107.214924) (xy 72.88149 -107.279948) (xy 72.889057 -107.287566)
			(xy 72.908616 -107.296363) (xy 72.919336 -107.296966) (xy 74.112628 -107.296966) (xy 74.123375 -107.296484)
			(xy 74.142973 -107.28766) (xy 74.150474 -107.279948) (xy 74.208386 -107.214924) (xy 74.214736 -107.194604)
			(xy 74.213466 -107.183682) (xy 74.210491 -107.156602) (xy 74.207312 -107.102212) (xy 74.207116 -107.07497)
			(xy 74.207618 -107.03152) (xy 74.215636 -106.944991) (xy 74.231604 -106.859571) (xy 74.255385 -106.775989)
			(xy 74.286777 -106.694957) (xy 74.325511 -106.617168) (xy 74.371258 -106.543284) (xy 74.423627 -106.473937)
			(xy 74.482171 -106.409717) (xy 74.546391 -106.351173) (xy 74.615738 -106.298804) (xy 74.689622 -106.253057)
			(xy 74.767411 -106.214323) (xy 74.848443 -106.182931) (xy 74.932025 -106.15915) (xy 75.017445 -106.143182)
			(xy 75.103974 -106.135164) (xy 75.190874 -106.135164) (xy 75.277403 -106.143182) (xy 75.362823 -106.15915)
			(xy 75.446405 -106.182931) (xy 75.527437 -106.214323) (xy 75.605226 -106.253057) (xy 75.67911 -106.298804)
			(xy 75.748457 -106.351173) (xy 75.785401 -106.384852) (xy 77.512924 -106.384852) (xy 77.516995 -106.32923)
			(xy 77.529121 -106.274793) (xy 77.549044 -106.222702) (xy 77.57634 -106.174067) (xy 77.610426 -106.129924)
			(xy 77.650575 -106.091215) (xy 77.695933 -106.058764) (xy 77.745533 -106.033263) (xy 77.798317 -106.015256)
			(xy 77.85316 -106.005126) (xy 77.908894 -106.003089) (xy 77.964331 -106.009189) (xy 78.018288 -106.023295)
			(xy 78.069617 -106.045107) (xy 78.117223 -106.074161) (xy 78.160091 -106.109836) (xy 78.197308 -106.151373)
			(xy 78.228081 -106.197886) (xy 78.251753 -106.248383) (xy 78.267821 -106.30179) (xy 78.275941 -106.356966)
			(xy 78.27645 -106.384852) (xy 78.275941 -106.412738) (xy 78.267821 -106.467914) (xy 78.251753 -106.521321)
			(xy 78.228081 -106.571818) (xy 78.197308 -106.618331) (xy 78.160091 -106.659868) (xy 78.117223 -106.695543)
			(xy 78.069617 -106.724597) (xy 78.018288 -106.746409) (xy 77.964331 -106.760515) (xy 77.908894 -106.766615)
			(xy 77.85316 -106.764578) (xy 77.798317 -106.754448) (xy 77.745533 -106.736441) (xy 77.695933 -106.71094)
			(xy 77.650575 -106.678489) (xy 77.610426 -106.63978) (xy 77.57634 -106.595637) (xy 77.549044 -106.547002)
			(xy 77.529121 -106.494911) (xy 77.516995 -106.440474) (xy 77.512924 -106.384852) (xy 75.785401 -106.384852)
			(xy 75.812677 -106.409717) (xy 75.871221 -106.473937) (xy 75.92359 -106.543284) (xy 75.969337 -106.617168)
			(xy 76.008071 -106.694957) (xy 76.039463 -106.775989) (xy 76.063244 -106.859571) (xy 76.079212 -106.944991)
			(xy 76.08723 -107.03152) (xy 76.087732 -107.07497) (xy 76.08752 -107.102211) (xy 76.084341 -107.156601)
			(xy 76.081382 -107.183682) (xy 76.080112 -107.194604) (xy 76.086462 -107.214924) (xy 76.144374 -107.279948)
			(xy 76.15194 -107.287568) (xy 76.171499 -107.296372) (xy 76.18222 -107.296966) (xy 81.195926 -107.296966)
			(xy 81.204308 -107.296204) (xy 81.211912 -107.294688) (xy 81.225745 -107.2877) (xy 81.231486 -107.282488)
			(xy 85.159088 -103.354886) (xy 85.159596 -103.354378) (xy 85.166179 -103.346996) (xy 85.173634 -103.328698)
			(xy 85.174074 -103.318818) (xy 85.174074 -77.897736) (xy 85.166454 -77.87894) (xy 85.159088 -77.871828)
			(xy 83.596226 -76.308966) (xy 83.589114 -76.3016) (xy 83.570318 -76.29398) (xy 56.713374 -76.29398)
			(xy 56.694578 -76.3016) (xy 56.687466 -76.308966) (xy 55.821326 -77.175106) (xy 81.88401 -77.175106)
			(xy 81.888081 -77.119484) (xy 81.900207 -77.065047) (xy 81.92013 -77.012956) (xy 81.947426 -76.964321)
			(xy 81.981512 -76.920178) (xy 82.021661 -76.881469) (xy 82.067019 -76.849018) (xy 82.116619 -76.823517)
			(xy 82.169403 -76.80551) (xy 82.224246 -76.79538) (xy 82.27998 -76.793343) (xy 82.335417 -76.799443)
			(xy 82.389374 -76.813549) (xy 82.440703 -76.835361) (xy 82.488309 -76.864415) (xy 82.531177 -76.90009)
			(xy 82.568394 -76.941627) (xy 82.599167 -76.98814) (xy 82.622839 -77.038637) (xy 82.638907 -77.092044)
			(xy 82.647027 -77.14722) (xy 82.647536 -77.175106) (xy 82.647027 -77.202992) (xy 82.638907 -77.258168)
			(xy 82.622839 -77.311575) (xy 82.599167 -77.362072) (xy 82.568394 -77.408585) (xy 82.531177 -77.450122)
			(xy 82.488309 -77.485797) (xy 82.440703 -77.514851) (xy 82.389374 -77.536663) (xy 82.335417 -77.550769)
			(xy 82.27998 -77.556869) (xy 82.224246 -77.554832) (xy 82.169403 -77.544702) (xy 82.116619 -77.526695)
			(xy 82.067019 -77.501194) (xy 82.021661 -77.468743) (xy 81.981512 -77.430034) (xy 81.947426 -77.385891)
			(xy 81.92013 -77.337256) (xy 81.900207 -77.285165) (xy 81.888081 -77.230728) (xy 81.88401 -77.175106)
			(xy 55.821326 -77.175106) (xy 54.80939 -78.187042) (xy 54.802024 -78.194154) (xy 54.794404 -78.21295)
			(xy 54.794404 -78.230476) (xy 65.148204 -78.230476) (xy 65.152275 -78.174854) (xy 65.164401 -78.120417)
			(xy 65.184324 -78.068326) (xy 65.21162 -78.019691) (xy 65.245706 -77.975548) (xy 65.285855 -77.936839)
			(xy 65.331213 -77.904388) (xy 65.380813 -77.878887) (xy 65.433597 -77.86088) (xy 65.48844 -77.85075)
			(xy 65.544174 -77.848713) (xy 65.599611 -77.854813) (xy 65.653568 -77.868919) (xy 65.704897 -77.890731)
			(xy 65.752503 -77.919785) (xy 65.795371 -77.95546) (xy 65.832588 -77.996997) (xy 65.863361 -78.04351)
			(xy 65.887033 -78.094007) (xy 65.903101 -78.147414) (xy 65.911221 -78.20259) (xy 65.91173 -78.230476)
			(xy 65.911221 -78.258362) (xy 65.903101 -78.313538) (xy 65.887033 -78.366945) (xy 65.863361 -78.417442)
			(xy 65.832588 -78.463955) (xy 65.795371 -78.505492) (xy 65.752503 -78.541167) (xy 65.704897 -78.570221)
			(xy 65.653568 -78.592033) (xy 65.599611 -78.606139) (xy 65.544174 -78.612239) (xy 65.48844 -78.610202)
			(xy 65.433597 -78.600072) (xy 65.380813 -78.582065) (xy 65.331213 -78.556564) (xy 65.285855 -78.524113)
			(xy 65.245706 -78.485404) (xy 65.21162 -78.441261) (xy 65.184324 -78.392626) (xy 65.164401 -78.340535)
			(xy 65.152275 -78.286098) (xy 65.148204 -78.230476) (xy 54.794404 -78.230476) (xy 54.794404 -79.268574)
			(xy 64.953386 -79.268574) (xy 64.957457 -79.212952) (xy 64.969583 -79.158515) (xy 64.989506 -79.106424)
			(xy 65.016802 -79.057789) (xy 65.050888 -79.013646) (xy 65.091037 -78.974937) (xy 65.136395 -78.942486)
			(xy 65.185995 -78.916985) (xy 65.238779 -78.898978) (xy 65.293622 -78.888848) (xy 65.349356 -78.886811)
			(xy 65.404793 -78.892911) (xy 65.45875 -78.907017) (xy 65.510079 -78.928829) (xy 65.557685 -78.957883)
			(xy 65.600553 -78.993558) (xy 65.63777 -79.035095) (xy 65.668543 -79.081608) (xy 65.692215 -79.132105)
			(xy 65.708283 -79.185512) (xy 65.716403 -79.240688) (xy 65.716912 -79.268574) (xy 65.716403 -79.29646)
			(xy 65.708283 -79.351636) (xy 65.692215 -79.405043) (xy 65.668543 -79.45554) (xy 65.63777 -79.502053)
			(xy 65.600553 -79.54359) (xy 65.557685 -79.579265) (xy 65.510079 -79.608319) (xy 65.45875 -79.630131)
			(xy 65.404793 -79.644237) (xy 65.349356 -79.650337) (xy 65.293622 -79.6483) (xy 65.238779 -79.63817)
			(xy 65.185995 -79.620163) (xy 65.136395 -79.594662) (xy 65.091037 -79.562211) (xy 65.050888 -79.523502)
			(xy 65.016802 -79.479359) (xy 64.989506 -79.430724) (xy 64.969583 -79.378633) (xy 64.957457 -79.324196)
			(xy 64.953386 -79.268574) (xy 54.794404 -79.268574) (xy 54.794404 -80.294988) (xy 57.723532 -80.294988)
			(xy 57.723944 -80.267733) (xy 57.731703 -80.213778) (xy 57.747063 -80.161477) (xy 57.76971 -80.111894)
			(xy 57.799183 -80.066039) (xy 57.834882 -80.024845) (xy 57.876081 -79.989152) (xy 57.92194 -79.959685)
			(xy 57.971526 -79.937045) (xy 58.023829 -79.921692) (xy 58.077785 -79.91394) (xy 58.10504 -79.91348)
			(xy 58.115666 -79.91354) (xy 58.136887 -79.914681) (xy 58.147458 -79.915766) (xy 58.160963 -79.916823)
			(xy 58.187721 -79.912685) (xy 58.212446 -79.901649) (xy 58.233393 -79.884493) (xy 58.249086 -79.862428)
			(xy 58.258417 -79.837011) (xy 58.260727 -79.810034) (xy 58.25871 -79.79664) (xy 58.255747 -79.779522)
			(xy 58.252569 -79.744924) (xy 58.25236 -79.727552) (xy 58.252833 -79.700301) (xy 58.260595 -79.646355)
			(xy 58.275955 -79.594062) (xy 58.298599 -79.544486) (xy 58.328068 -79.498638) (xy 58.36376 -79.457449)
			(xy 58.40495 -79.421758) (xy 58.4508 -79.392292) (xy 58.500377 -79.369649) (xy 58.55267 -79.354292)
			(xy 58.606617 -79.346532) (xy 58.633868 -79.346044) (xy 58.661116 -79.346608) (xy 58.715059 -79.354359)
			(xy 58.767349 -79.369707) (xy 58.816923 -79.392341) (xy 58.862771 -79.4218) (xy 58.90396 -79.457483)
			(xy 58.939652 -79.498665) (xy 58.96912 -79.544507) (xy 58.991765 -79.594076) (xy 59.007124 -79.646363)
			(xy 59.014886 -79.700304) (xy 59.015376 -79.727552) (xy 59.0149 -79.754805) (xy 59.007149 -79.808757)
			(xy 58.991797 -79.861057) (xy 58.969158 -79.910639) (xy 58.939692 -79.956494) (xy 58.903999 -79.997688)
			(xy 58.878359 -80.019906) (xy 72.500742 -80.019906) (xy 72.504813 -79.964284) (xy 72.516939 -79.909847)
			(xy 72.536862 -79.857756) (xy 72.564158 -79.809121) (xy 72.598244 -79.764978) (xy 72.638393 -79.726269)
			(xy 72.683751 -79.693818) (xy 72.733351 -79.668317) (xy 72.786135 -79.65031) (xy 72.840978 -79.64018)
			(xy 72.896712 -79.638143) (xy 72.952149 -79.644243) (xy 73.006106 -79.658349) (xy 73.057435 -79.680161)
			(xy 73.105041 -79.709215) (xy 73.147909 -79.74489) (xy 73.185126 -79.786427) (xy 73.215899 -79.83294)
			(xy 73.239571 -79.883437) (xy 73.255639 -79.936844) (xy 73.263759 -79.99202) (xy 73.264124 -80.012028)
			(xy 79.572848 -80.012028) (xy 79.572848 -79.952092) (xy 79.580671 -79.89267) (xy 79.596184 -79.834777)
			(xy 79.61912 -79.779404) (xy 79.649087 -79.727498) (xy 79.685574 -79.679948) (xy 79.727954 -79.637568)
			(xy 79.775504 -79.601081) (xy 79.82741 -79.571114) (xy 79.882783 -79.548178) (xy 79.940676 -79.532665)
			(xy 80.000098 -79.524842) (xy 80.060034 -79.524842) (xy 80.119456 -79.532665) (xy 80.177349 -79.548178)
			(xy 80.232722 -79.571114) (xy 80.284628 -79.601081) (xy 80.332178 -79.637568) (xy 80.374558 -79.679948)
			(xy 80.411045 -79.727498) (xy 80.441012 -79.779404) (xy 80.463948 -79.834777) (xy 80.479461 -79.89267)
			(xy 80.487284 -79.952092) (xy 80.487774 -79.98206) (xy 80.487284 -80.012028) (xy 80.479461 -80.07145)
			(xy 80.463948 -80.129343) (xy 80.441012 -80.184716) (xy 80.411045 -80.236622) (xy 80.374558 -80.284172)
			(xy 80.332178 -80.326552) (xy 80.284628 -80.363039) (xy 80.232722 -80.393006) (xy 80.177349 -80.415942)
			(xy 80.119456 -80.431455) (xy 80.060034 -80.439278) (xy 80.000098 -80.439278) (xy 79.940676 -80.431455)
			(xy 79.882783 -80.415942) (xy 79.82741 -80.393006) (xy 79.775504 -80.363039) (xy 79.727954 -80.326552)
			(xy 79.685574 -80.284172) (xy 79.649087 -80.236622) (xy 79.61912 -80.184716) (xy 79.596184 -80.129343)
			(xy 79.580671 -80.07145) (xy 79.572848 -80.012028) (xy 73.264124 -80.012028) (xy 73.264268 -80.019906)
			(xy 73.263759 -80.047792) (xy 73.255639 -80.102968) (xy 73.239571 -80.156375) (xy 73.215899 -80.206872)
			(xy 73.185126 -80.253385) (xy 73.147909 -80.294922) (xy 73.105041 -80.330597) (xy 73.057435 -80.359651)
			(xy 73.006106 -80.381463) (xy 72.952149 -80.395569) (xy 72.896712 -80.401669) (xy 72.840978 -80.399632)
			(xy 72.786135 -80.389502) (xy 72.733351 -80.371495) (xy 72.683751 -80.345994) (xy 72.638393 -80.313543)
			(xy 72.598244 -80.274834) (xy 72.564158 -80.230691) (xy 72.536862 -80.182056) (xy 72.516939 -80.129965)
			(xy 72.504813 -80.075528) (xy 72.500742 -80.019906) (xy 58.878359 -80.019906) (xy 58.862807 -80.033382)
			(xy 58.816953 -80.06285) (xy 58.767372 -80.085492) (xy 58.715073 -80.100845) (xy 58.661121 -80.108599)
			(xy 58.633868 -80.10906) (xy 58.623242 -80.109007) (xy 58.602021 -80.107861) (xy 58.59145 -80.106774)
			(xy 58.577946 -80.105678) (xy 58.55118 -80.109816) (xy 58.526449 -80.120855) (xy 58.505497 -80.138018)
			(xy 58.489804 -80.160091) (xy 58.480477 -80.185518) (xy 58.478175 -80.212503) (xy 58.480198 -80.2259)
			(xy 58.483153 -80.24302) (xy 58.486337 -80.277617) (xy 58.486548 -80.294988) (xy 58.486011 -80.322237)
			(xy 58.478257 -80.376181) (xy 58.462905 -80.428472) (xy 58.453224 -80.449674) (xy 78.361284 -80.449674)
			(xy 78.365355 -80.394052) (xy 78.377481 -80.339615) (xy 78.397404 -80.287524) (xy 78.4247 -80.238889)
			(xy 78.458786 -80.194746) (xy 78.498935 -80.156037) (xy 78.544293 -80.123586) (xy 78.593893 -80.098085)
			(xy 78.646677 -80.080078) (xy 78.70152 -80.069948) (xy 78.757254 -80.067911) (xy 78.812691 -80.074011)
			(xy 78.866648 -80.088117) (xy 78.917977 -80.109929) (xy 78.965583 -80.138983) (xy 79.008451 -80.174658)
			(xy 79.045668 -80.216195) (xy 79.076441 -80.262708) (xy 79.100113 -80.313205) (xy 79.116181 -80.366612)
			(xy 79.124301 -80.421788) (xy 79.12481 -80.449674) (xy 79.124301 -80.47756) (xy 79.116181 -80.532736)
			(xy 79.100113 -80.586143) (xy 79.076441 -80.63664) (xy 79.045668 -80.683153) (xy 79.008451 -80.72469)
			(xy 78.965583 -80.760365) (xy 78.917977 -80.789419) (xy 78.866648 -80.811231) (xy 78.812691 -80.825337)
			(xy 78.757254 -80.831437) (xy 78.70152 -80.8294) (xy 78.646677 -80.81927) (xy 78.593893 -80.801263)
			(xy 78.544293 -80.775762) (xy 78.498935 -80.743311) (xy 78.458786 -80.704602) (xy 78.4247 -80.660459)
			(xy 78.397404 -80.611824) (xy 78.377481 -80.559733) (xy 78.365355 -80.505296) (xy 78.361284 -80.449674)
			(xy 58.453224 -80.449674) (xy 58.440268 -80.478047) (xy 58.410807 -80.523895) (xy 58.375121 -80.565084)
			(xy 58.333937 -80.600776) (xy 58.288092 -80.630244) (xy 58.238521 -80.652887) (xy 58.186232 -80.668246)
			(xy 58.132289 -80.676007) (xy 58.10504 -80.676496) (xy 58.077788 -80.676007) (xy 58.023837 -80.668256)
			(xy 57.971539 -80.652904) (xy 57.921958 -80.630265) (xy 57.876104 -80.6008) (xy 57.834911 -80.565109)
			(xy 57.799216 -80.523918) (xy 57.769748 -80.478067) (xy 57.747106 -80.428487) (xy 57.73175 -80.37619)
			(xy 57.723995 -80.32224) (xy 57.723532 -80.294988) (xy 54.794404 -80.294988) (xy 54.794404 -82.331306)
			(xy 76.571346 -82.331306) (xy 76.575417 -82.275684) (xy 76.587543 -82.221247) (xy 76.607466 -82.169156)
			(xy 76.634762 -82.120521) (xy 76.668848 -82.076378) (xy 76.708997 -82.037669) (xy 76.754355 -82.005218)
			(xy 76.803955 -81.979717) (xy 76.856739 -81.96171) (xy 76.911582 -81.95158) (xy 76.967316 -81.949543)
			(xy 77.022753 -81.955643) (xy 77.07671 -81.969749) (xy 77.128039 -81.991561) (xy 77.175645 -82.020615)
			(xy 77.218513 -82.05629) (xy 77.25573 -82.097827) (xy 77.286503 -82.14434) (xy 77.310175 -82.194837)
			(xy 77.326243 -82.248244) (xy 77.334363 -82.30342) (xy 77.334872 -82.331306) (xy 77.334363 -82.359192)
			(xy 77.326243 -82.414368) (xy 77.313254 -82.45754) (xy 78.857584 -82.45754) (xy 78.857584 -82.397604)
			(xy 78.865407 -82.338182) (xy 78.88092 -82.280289) (xy 78.903856 -82.224916) (xy 78.933823 -82.17301)
			(xy 78.97031 -82.12546) (xy 79.01269 -82.08308) (xy 79.06024 -82.046593) (xy 79.112146 -82.016626)
			(xy 79.167519 -81.99369) (xy 79.225412 -81.978177) (xy 79.284834 -81.970354) (xy 79.34477 -81.970354)
			(xy 79.404192 -81.978177) (xy 79.462085 -81.99369) (xy 79.517458 -82.016626) (xy 79.569364 -82.046593)
			(xy 79.616914 -82.08308) (xy 79.659294 -82.12546) (xy 79.695781 -82.17301) (xy 79.725748 -82.224916)
			(xy 79.748684 -82.280289) (xy 79.764197 -82.338182) (xy 79.769411 -82.377788) (xy 80.443324 -82.377788)
			(xy 80.443852 -82.346844) (xy 80.452181 -82.285519) (xy 80.468698 -82.225875) (xy 80.493102 -82.169002)
			(xy 80.524947 -82.115936) (xy 80.563654 -82.067646) (xy 80.608515 -82.025012) (xy 80.658713 -81.988813)
			(xy 80.71333 -81.959709) (xy 80.771372 -81.938231) (xy 80.801464 -81.931002) (xy 80.811878 -81.928716)
			(xy 80.828388 -81.916778) (xy 80.877156 -81.83499) (xy 80.878426 -81.824068) (xy 80.879696 -81.813908)
			(xy 80.876902 -81.803748) (xy 80.875124 -81.797144) (xy 80.869099 -81.773081) (xy 80.8626 -81.723902)
			(xy 80.86217 -81.6991) (xy 80.86217 -81.698846) (xy 80.862656 -81.671595) (xy 80.870412 -81.617647)
			(xy 80.885767 -81.565352) (xy 80.908409 -81.515775) (xy 80.937875 -81.469925) (xy 80.973566 -81.428734)
			(xy 81.014757 -81.393043) (xy 81.060607 -81.363577) (xy 81.110184 -81.340935) (xy 81.162479 -81.32558)
			(xy 81.216427 -81.317824) (xy 81.270929 -81.317824) (xy 81.324877 -81.32558) (xy 81.377172 -81.340935)
			(xy 81.426749 -81.363577) (xy 81.472599 -81.393043) (xy 81.51379 -81.428734) (xy 81.549481 -81.469925)
			(xy 81.578947 -81.515775) (xy 81.601589 -81.565352) (xy 81.616944 -81.617647) (xy 81.6247 -81.671595)
			(xy 81.625186 -81.698846) (xy 81.624663 -81.727797) (xy 81.615893 -81.785031) (xy 81.598578 -81.840283)
			(xy 81.573115 -81.892285) (xy 81.540088 -81.939844) (xy 81.500255 -81.981867) (xy 81.45453 -82.017391)
			(xy 81.403964 -82.045599) (xy 81.377028 -82.056224) (xy 81.367122 -82.060034) (xy 81.359248 -82.067654)
			(xy 81.351628 -82.074766) (xy 81.31683 -82.157062) (xy 81.315814 -82.163666) (xy 81.315016 -82.170359)
			(xy 81.316564 -82.183745) (xy 81.318862 -82.190082) (xy 81.323434 -82.20202) (xy 81.323688 -82.202528)
			(xy 81.334735 -82.230414) (xy 81.350315 -82.288338) (xy 81.358212 -82.347798) (xy 81.35874 -82.377788)
			(xy 81.358207 -82.407754) (xy 81.350386 -82.467174) (xy 81.334876 -82.525064) (xy 81.311943 -82.580435)
			(xy 81.281979 -82.632339) (xy 81.245497 -82.679888) (xy 81.203121 -82.722268) (xy 81.155575 -82.758755)
			(xy 81.103674 -82.788724) (xy 81.048306 -82.811662) (xy 80.990417 -82.827177) (xy 80.930998 -82.835004)
			(xy 80.901032 -82.835496) (xy 80.871063 -82.835009) (xy 80.811638 -82.827189) (xy 80.753742 -82.811679)
			(xy 80.698366 -82.788745) (xy 80.646457 -82.758778) (xy 80.598905 -82.722292) (xy 80.556521 -82.67991)
			(xy 80.520033 -82.632359) (xy 80.490064 -82.580452) (xy 80.467127 -82.525077) (xy 80.451615 -82.467182)
			(xy 80.443792 -82.407757) (xy 80.443324 -82.377788) (xy 79.769411 -82.377788) (xy 79.77202 -82.397604)
			(xy 79.77251 -82.427572) (xy 79.77202 -82.45754) (xy 79.764197 -82.516962) (xy 79.748684 -82.574855)
			(xy 79.725748 -82.630228) (xy 79.695781 -82.682134) (xy 79.659294 -82.729684) (xy 79.616914 -82.772064)
			(xy 79.569364 -82.808551) (xy 79.517458 -82.838518) (xy 79.462085 -82.861454) (xy 79.404192 -82.876967)
			(xy 79.34477 -82.88479) (xy 79.284834 -82.88479) (xy 79.225412 -82.876967) (xy 79.167519 -82.861454)
			(xy 79.112146 -82.838518) (xy 79.06024 -82.808551) (xy 79.01269 -82.772064) (xy 78.97031 -82.729684)
			(xy 78.933823 -82.682134) (xy 78.903856 -82.630228) (xy 78.88092 -82.574855) (xy 78.865407 -82.516962)
			(xy 78.857584 -82.45754) (xy 77.313254 -82.45754) (xy 77.310175 -82.467775) (xy 77.286503 -82.518272)
			(xy 77.25573 -82.564785) (xy 77.218513 -82.606322) (xy 77.175645 -82.641997) (xy 77.128039 -82.671051)
			(xy 77.07671 -82.692863) (xy 77.022753 -82.706969) (xy 76.967316 -82.713069) (xy 76.911582 -82.711032)
			(xy 76.856739 -82.700902) (xy 76.803955 -82.682895) (xy 76.754355 -82.657394) (xy 76.708997 -82.624943)
			(xy 76.668848 -82.586234) (xy 76.634762 -82.542091) (xy 76.607466 -82.493456) (xy 76.587543 -82.441365)
			(xy 76.575417 -82.386928) (xy 76.571346 -82.331306) (xy 54.794404 -82.331306) (xy 54.794404 -84.332318)
			(xy 76.312014 -84.332318) (xy 76.31247 -84.305714) (xy 76.31985 -84.253021) (xy 76.334482 -84.201865)
			(xy 76.356084 -84.15324) (xy 76.384234 -84.10809) (xy 76.418387 -84.067291) (xy 76.45788 -84.031635)
			(xy 76.479654 -84.016342) (xy 76.49117 -84.00805) (xy 76.509382 -83.9863) (xy 76.520903 -83.960376)
			(xy 76.524841 -83.932282) (xy 76.520893 -83.90419) (xy 76.509363 -83.87827) (xy 76.491143 -83.856526)
			(xy 76.479654 -83.848194) (xy 76.457875 -83.832911) (xy 76.418396 -83.797243) (xy 76.384253 -83.756437)
			(xy 76.356108 -83.711286) (xy 76.334507 -83.662662) (xy 76.319868 -83.61151) (xy 76.312476 -83.558821)
			(xy 76.312014 -83.532218) (xy 76.3125 -83.504967) (xy 76.320256 -83.451019) (xy 76.335611 -83.398724)
			(xy 76.358253 -83.349147) (xy 76.387719 -83.303297) (xy 76.42341 -83.262106) (xy 76.464601 -83.226415)
			(xy 76.510451 -83.196949) (xy 76.560028 -83.174307) (xy 76.612323 -83.158952) (xy 76.666271 -83.151196)
			(xy 76.720773 -83.151196) (xy 76.774721 -83.158952) (xy 76.827016 -83.174307) (xy 76.876593 -83.196949)
			(xy 76.922443 -83.226415) (xy 76.963634 -83.262106) (xy 76.999325 -83.303297) (xy 77.028791 -83.349147)
			(xy 77.051433 -83.398724) (xy 77.066788 -83.451019) (xy 77.074544 -83.504967) (xy 77.07503 -83.532218)
			(xy 77.074625 -83.558824) (xy 77.06724 -83.61152) (xy 77.0526 -83.662678) (xy 77.030991 -83.711304)
			(xy 77.002832 -83.756454) (xy 76.96867 -83.797252) (xy 76.929168 -83.832904) (xy 76.90739 -83.848194)
			(xy 76.895942 -83.856569) (xy 76.877741 -83.878304) (xy 76.866224 -83.904208) (xy 76.86228 -83.932282)
			(xy 76.866214 -83.960357) (xy 76.877722 -83.986266) (xy 76.895915 -84.008007) (xy 76.90739 -84.016342)
			(xy 76.929149 -84.031652) (xy 76.968627 -84.067317) (xy 77.00277 -84.108118) (xy 77.030916 -84.153266)
			(xy 77.052521 -84.201884) (xy 77.067164 -84.253032) (xy 77.074563 -84.305717) (xy 77.07503 -84.332318)
			(xy 77.074544 -84.359569) (xy 77.066788 -84.413517) (xy 77.051433 -84.465812) (xy 77.03294 -84.506304)
			(xy 79.792558 -84.506304) (xy 79.792558 -84.446368) (xy 79.800381 -84.386946) (xy 79.815894 -84.329053)
			(xy 79.83883 -84.27368) (xy 79.868797 -84.221774) (xy 79.905284 -84.174224) (xy 79.947664 -84.131844)
			(xy 79.995214 -84.095357) (xy 80.04712 -84.06539) (xy 80.102493 -84.042454) (xy 80.160386 -84.026941)
			(xy 80.219808 -84.019118) (xy 80.279744 -84.019118) (xy 80.339166 -84.026941) (xy 80.397059 -84.042454)
			(xy 80.452432 -84.06539) (xy 80.504338 -84.095357) (xy 80.551888 -84.131844) (xy 80.594268 -84.174224)
			(xy 80.630755 -84.221774) (xy 80.660722 -84.27368) (xy 80.683658 -84.329053) (xy 80.699171 -84.386946)
			(xy 80.706994 -84.446368) (xy 80.707484 -84.476336) (xy 80.706994 -84.506304) (xy 80.699171 -84.565726)
			(xy 80.683658 -84.623619) (xy 80.660722 -84.678992) (xy 80.630755 -84.730898) (xy 80.594268 -84.778448)
			(xy 80.551888 -84.820828) (xy 80.504338 -84.857315) (xy 80.452432 -84.887282) (xy 80.397059 -84.910218)
			(xy 80.339166 -84.925731) (xy 80.279744 -84.933554) (xy 80.219808 -84.933554) (xy 80.160386 -84.925731)
			(xy 80.102493 -84.910218) (xy 80.04712 -84.887282) (xy 79.995214 -84.857315) (xy 79.947664 -84.820828)
			(xy 79.905284 -84.778448) (xy 79.868797 -84.730898) (xy 79.83883 -84.678992) (xy 79.815894 -84.623619)
			(xy 79.800381 -84.565726) (xy 79.792558 -84.506304) (xy 77.03294 -84.506304) (xy 77.028791 -84.515389)
			(xy 76.999325 -84.561239) (xy 76.963634 -84.60243) (xy 76.922443 -84.638121) (xy 76.876593 -84.667587)
			(xy 76.827016 -84.690229) (xy 76.774721 -84.705584) (xy 76.720773 -84.71334) (xy 76.666271 -84.71334)
			(xy 76.612323 -84.705584) (xy 76.560028 -84.690229) (xy 76.510451 -84.667587) (xy 76.464601 -84.638121)
			(xy 76.42341 -84.60243) (xy 76.387719 -84.561239) (xy 76.358253 -84.515389) (xy 76.335611 -84.465812)
			(xy 76.320256 -84.413517) (xy 76.3125 -84.359569) (xy 76.312014 -84.332318) (xy 54.794404 -84.332318)
			(xy 54.794404 -85.384894) (xy 59.228736 -85.384894) (xy 59.229226 -85.354926) (xy 59.237049 -85.295504)
			(xy 59.252562 -85.237611) (xy 59.275498 -85.182238) (xy 59.305465 -85.130332) (xy 59.341952 -85.082782)
			(xy 59.384332 -85.040402) (xy 59.431882 -85.003915) (xy 59.483788 -84.973948) (xy 59.539161 -84.951012)
			(xy 59.597054 -84.935499) (xy 59.656476 -84.927676) (xy 59.716412 -84.927676) (xy 59.775834 -84.935499)
			(xy 59.833727 -84.951012) (xy 59.8891 -84.973948) (xy 59.941006 -85.003915) (xy 59.988556 -85.040402)
			(xy 60.030936 -85.082782) (xy 60.067423 -85.130332) (xy 60.09739 -85.182238) (xy 60.120326 -85.237611)
			(xy 60.135839 -85.295504) (xy 60.143662 -85.354926) (xy 60.144152 -85.384894) (xy 60.143598 -85.416322)
			(xy 60.142222 -85.426296) (xy 79.857598 -85.426296) (xy 79.861669 -85.370674) (xy 79.873795 -85.316237)
			(xy 79.893718 -85.264146) (xy 79.921014 -85.215511) (xy 79.9551 -85.171368) (xy 79.995249 -85.132659)
			(xy 80.040607 -85.100208) (xy 80.090207 -85.074707) (xy 80.142991 -85.0567) (xy 80.197834 -85.04657)
			(xy 80.253568 -85.044533) (xy 80.309005 -85.050633) (xy 80.362962 -85.064739) (xy 80.414291 -85.086551)
			(xy 80.461897 -85.115605) (xy 80.504765 -85.15128) (xy 80.541982 -85.192817) (xy 80.572755 -85.23933)
			(xy 80.596427 -85.289827) (xy 80.612495 -85.343234) (xy 80.620615 -85.39841) (xy 80.621124 -85.426296)
			(xy 80.620615 -85.454182) (xy 80.612495 -85.509358) (xy 80.596427 -85.562765) (xy 80.572755 -85.613262)
			(xy 80.541982 -85.659775) (xy 80.504765 -85.701312) (xy 80.461897 -85.736987) (xy 80.414291 -85.766041)
			(xy 80.362962 -85.787853) (xy 80.309005 -85.801959) (xy 80.253568 -85.808059) (xy 80.197834 -85.806022)
			(xy 80.142991 -85.795892) (xy 80.090207 -85.777885) (xy 80.040607 -85.752384) (xy 79.995249 -85.719933)
			(xy 79.9551 -85.681224) (xy 79.921014 -85.637081) (xy 79.893718 -85.588446) (xy 79.873795 -85.536355)
			(xy 79.861669 -85.481918) (xy 79.857598 -85.426296) (xy 60.142222 -85.426296) (xy 60.13501 -85.478588)
			(xy 60.11798 -85.539093) (xy 60.092829 -85.596698) (xy 60.060031 -85.650319) (xy 60.04052 -85.674962)
			(xy 60.040266 -85.675216) (xy 60.034992 -85.682298) (xy 60.029192 -85.698962) (xy 60.029397 -85.716606)
			(xy 60.032138 -85.725) (xy 60.067444 -85.819742) (xy 60.087764 -85.83676) (xy 60.101226 -85.8393)
			(xy 60.12725 -85.844491) (xy 60.177625 -85.861178) (xy 60.225202 -85.884685) (xy 60.269062 -85.914558)
			(xy 60.308359 -85.950221) (xy 60.342335 -85.990985) (xy 60.370334 -86.036064) (xy 60.391816 -86.084588)
			(xy 60.406367 -86.135621) (xy 60.413705 -86.188178) (xy 60.414154 -86.214712) (xy 60.413707 -86.24017)
			(xy 60.408644 -86.277954) (xy 75.163408 -86.277954) (xy 75.163408 -86.218018) (xy 75.171231 -86.158596)
			(xy 75.186744 -86.100703) (xy 75.20968 -86.04533) (xy 75.239647 -85.993424) (xy 75.276134 -85.945874)
			(xy 75.318514 -85.903494) (xy 75.366064 -85.867007) (xy 75.41797 -85.83704) (xy 75.473343 -85.814104)
			(xy 75.531236 -85.798591) (xy 75.590658 -85.790768) (xy 75.650594 -85.790768) (xy 75.710016 -85.798591)
			(xy 75.767909 -85.814104) (xy 75.823282 -85.83704) (xy 75.875188 -85.867007) (xy 75.922738 -85.903494)
			(xy 75.965118 -85.945874) (xy 76.001605 -85.993424) (xy 76.031572 -86.04533) (xy 76.054508 -86.100703)
			(xy 76.070021 -86.158596) (xy 76.077844 -86.218018) (xy 76.078334 -86.247986) (xy 76.077844 -86.277954)
			(xy 76.070021 -86.337376) (xy 76.054508 -86.395269) (xy 76.031572 -86.450642) (xy 76.001605 -86.502548)
			(xy 75.965118 -86.550098) (xy 75.922738 -86.592478) (xy 75.875188 -86.628965) (xy 75.823282 -86.658932)
			(xy 75.767909 -86.681868) (xy 75.710016 -86.697381) (xy 75.650594 -86.705204) (xy 75.590658 -86.705204)
			(xy 75.531236 -86.697381) (xy 75.473343 -86.681868) (xy 75.41797 -86.658932) (xy 75.366064 -86.628965)
			(xy 75.318514 -86.592478) (xy 75.276134 -86.550098) (xy 75.239647 -86.502548) (xy 75.20968 -86.450642)
			(xy 75.186744 -86.395269) (xy 75.171231 -86.337376) (xy 75.163408 -86.277954) (xy 60.408644 -86.277954)
			(xy 60.406945 -86.290635) (xy 60.393528 -86.339752) (xy 60.373697 -86.386647) (xy 60.347802 -86.430486)
			(xy 60.316305 -86.470491) (xy 60.29833 -86.488524) (xy 60.298076 -86.488778) (xy 60.296552 -86.490302)
			(xy 60.289556 -86.498046) (xy 60.281953 -86.517458) (xy 60.28182 -86.527894) (xy 60.284614 -86.60384)
			(xy 60.285502 -86.614518) (xy 60.29497 -86.63372) (xy 60.302902 -86.640924) (xy 60.324794 -86.659577)
			(xy 60.36416 -86.701513) (xy 60.39796 -86.748051) (xy 60.42566 -86.798458) (xy 60.446824 -86.85194)
			(xy 60.461118 -86.907653) (xy 60.466338 -86.949026) (xy 77.54823 -86.949026) (xy 77.552301 -86.893404)
			(xy 77.564427 -86.838967) (xy 77.58435 -86.786876) (xy 77.611646 -86.738241) (xy 77.645732 -86.694098)
			(xy 77.685881 -86.655389) (xy 77.731239 -86.622938) (xy 77.780839 -86.597437) (xy 77.833623 -86.57943)
			(xy 77.888466 -86.5693) (xy 77.9442 -86.567263) (xy 77.999637 -86.573363) (xy 78.053594 -86.587469)
			(xy 78.104923 -86.609281) (xy 78.152529 -86.638335) (xy 78.195397 -86.67401) (xy 78.232614 -86.715547)
			(xy 78.263387 -86.76206) (xy 78.287059 -86.812557) (xy 78.303127 -86.865964) (xy 78.311247 -86.92114)
			(xy 78.311756 -86.949026) (xy 78.311247 -86.976912) (xy 78.303127 -87.032088) (xy 78.287059 -87.085495)
			(xy 78.263387 -87.135992) (xy 78.232614 -87.182505) (xy 78.195397 -87.224042) (xy 78.152529 -87.259717)
			(xy 78.104923 -87.288771) (xy 78.053594 -87.310583) (xy 77.999637 -87.324689) (xy 77.9442 -87.330789)
			(xy 77.888466 -87.328752) (xy 77.833623 -87.318622) (xy 77.780839 -87.300615) (xy 77.731239 -87.275114)
			(xy 77.685881 -87.242663) (xy 77.645732 -87.203954) (xy 77.611646 -87.159811) (xy 77.58435 -87.111176)
			(xy 77.564427 -87.059085) (xy 77.552301 -87.004648) (xy 77.54823 -86.949026) (xy 60.466338 -86.949026)
			(xy 60.468318 -86.964717) (xy 60.468764 -86.993476) (xy 60.468316 -87.023446) (xy 60.460495 -87.082874)
			(xy 60.444983 -87.140773) (xy 60.422045 -87.196151) (xy 60.392075 -87.248061) (xy 60.355585 -87.295615)
			(xy 60.3132 -87.337998) (xy 60.265645 -87.374486) (xy 60.213733 -87.404454) (xy 60.158354 -87.427389)
			(xy 60.100455 -87.442899) (xy 60.041026 -87.450718) (xy 60.011056 -87.451184) (xy 59.981086 -87.450759)
			(xy 59.92166 -87.44293) (xy 59.863765 -87.427411) (xy 59.80839 -87.404469) (xy 59.756483 -87.374495)
			(xy 59.708933 -87.338002) (xy 59.666553 -87.295616) (xy 59.630067 -87.24806) (xy 59.600101 -87.196149)
			(xy 59.577167 -87.140771) (xy 59.561657 -87.082873) (xy 59.553837 -87.023446) (xy 59.553348 -86.993476)
			(xy 59.55384 -86.963156) (xy 59.561866 -86.903049) (xy 59.577762 -86.844529) (xy 59.601248 -86.788621)
			(xy 59.631913 -86.736306) (xy 59.66922 -86.6885) (xy 59.712515 -86.64604) (xy 59.736482 -86.627462)
			(xy 59.739276 -86.625176) (xy 59.744864 -86.619588) (xy 59.751214 -86.613238) (xy 59.758834 -86.597236)
			(xy 59.76747 -86.50224) (xy 59.760612 -86.482174) (xy 59.752992 -86.474046) (xy 59.733965 -86.452775)
			(xy 59.701828 -86.405616) (xy 59.677066 -86.3542) (xy 59.660229 -86.299672) (xy 59.651692 -86.243246)
			(xy 59.651138 -86.214712) (xy 59.651138 -86.214458) (xy 59.651689 -86.185944) (xy 59.660225 -86.129556)
			(xy 59.677057 -86.075067) (xy 59.701809 -86.023688) (xy 59.717432 -85.999828) (xy 59.717686 -85.999574)
			(xy 59.725306 -85.988144) (xy 59.726322 -85.974174) (xy 59.727338 -85.960966) (xy 59.684666 -85.86978)
			(xy 59.680705 -85.861919) (xy 59.668368 -85.849376) (xy 59.652491 -85.841799) (xy 59.643772 -85.84057)
			(xy 59.643264 -85.84057) (xy 59.612715 -85.83722) (xy 59.552859 -85.823281) (xy 59.495406 -85.801458)
			(xy 59.441389 -85.772145) (xy 59.39178 -85.735868) (xy 59.347471 -85.693279) (xy 59.309259 -85.645145)
			(xy 59.277831 -85.59233) (xy 59.253751 -85.535786) (xy 59.237454 -85.476528) (xy 59.229232 -85.415623)
			(xy 59.228736 -85.384894) (xy 54.794404 -85.384894) (xy 54.794404 -88.405966) (xy 79.8238 -88.405966)
			(xy 79.8238 -88.34603) (xy 79.831623 -88.286608) (xy 79.847136 -88.228715) (xy 79.870072 -88.173342)
			(xy 79.900039 -88.121436) (xy 79.936526 -88.073886) (xy 79.978906 -88.031506) (xy 80.026456 -87.995019)
			(xy 80.078362 -87.965052) (xy 80.133735 -87.942116) (xy 80.191628 -87.926603) (xy 80.25105 -87.91878)
			(xy 80.310986 -87.91878) (xy 80.370408 -87.926603) (xy 80.428301 -87.942116) (xy 80.483674 -87.965052)
			(xy 80.53558 -87.995019) (xy 80.58313 -88.031506) (xy 80.62551 -88.073886) (xy 80.661997 -88.121436)
			(xy 80.691964 -88.173342) (xy 80.7149 -88.228715) (xy 80.730413 -88.286608) (xy 80.738236 -88.34603)
			(xy 80.738726 -88.375998) (xy 80.738236 -88.405966) (xy 80.735628 -88.425778) (xy 81.182446 -88.425778)
			(xy 81.182446 -88.365842) (xy 81.190269 -88.30642) (xy 81.205782 -88.248527) (xy 81.228718 -88.193154)
			(xy 81.258685 -88.141248) (xy 81.295172 -88.093698) (xy 81.337552 -88.051318) (xy 81.385102 -88.014831)
			(xy 81.437008 -87.984864) (xy 81.492381 -87.961928) (xy 81.550274 -87.946415) (xy 81.609696 -87.938592)
			(xy 81.669632 -87.938592) (xy 81.729054 -87.946415) (xy 81.786947 -87.961928) (xy 81.84232 -87.984864)
			(xy 81.894226 -88.014831) (xy 81.941776 -88.051318) (xy 81.984156 -88.093698) (xy 82.020643 -88.141248)
			(xy 82.05061 -88.193154) (xy 82.073546 -88.248527) (xy 82.089059 -88.30642) (xy 82.096882 -88.365842)
			(xy 82.097372 -88.39581) (xy 82.096882 -88.425778) (xy 82.089059 -88.4852) (xy 82.073546 -88.543093)
			(xy 82.05061 -88.598466) (xy 82.020643 -88.650372) (xy 81.984156 -88.697922) (xy 81.941776 -88.740302)
			(xy 81.894226 -88.776789) (xy 81.84232 -88.806756) (xy 81.786947 -88.829692) (xy 81.729054 -88.845205)
			(xy 81.669632 -88.853028) (xy 81.609696 -88.853028) (xy 81.550274 -88.845205) (xy 81.492381 -88.829692)
			(xy 81.437008 -88.806756) (xy 81.385102 -88.776789) (xy 81.337552 -88.740302) (xy 81.295172 -88.697922)
			(xy 81.258685 -88.650372) (xy 81.228718 -88.598466) (xy 81.205782 -88.543093) (xy 81.190269 -88.4852)
			(xy 81.182446 -88.425778) (xy 80.735628 -88.425778) (xy 80.730413 -88.465388) (xy 80.7149 -88.523281)
			(xy 80.691964 -88.578654) (xy 80.661997 -88.63056) (xy 80.62551 -88.67811) (xy 80.58313 -88.72049)
			(xy 80.53558 -88.756977) (xy 80.483674 -88.786944) (xy 80.428301 -88.80988) (xy 80.370408 -88.825393)
			(xy 80.310986 -88.833216) (xy 80.25105 -88.833216) (xy 80.191628 -88.825393) (xy 80.133735 -88.80988)
			(xy 80.078362 -88.786944) (xy 80.026456 -88.756977) (xy 79.978906 -88.72049) (xy 79.936526 -88.67811)
			(xy 79.900039 -88.63056) (xy 79.870072 -88.578654) (xy 79.847136 -88.523281) (xy 79.831623 -88.465388)
			(xy 79.8238 -88.405966) (xy 54.794404 -88.405966) (xy 54.794404 -88.98661) (xy 73.557366 -88.98661)
			(xy 73.557366 -88.926674) (xy 73.565189 -88.867252) (xy 73.580702 -88.809359) (xy 73.603638 -88.753986)
			(xy 73.633605 -88.70208) (xy 73.670092 -88.65453) (xy 73.712472 -88.61215) (xy 73.760022 -88.575663)
			(xy 73.811928 -88.545696) (xy 73.867301 -88.52276) (xy 73.925194 -88.507247) (xy 73.984616 -88.499424)
			(xy 74.044552 -88.499424) (xy 74.103974 -88.507247) (xy 74.161867 -88.52276) (xy 74.21724 -88.545696)
			(xy 74.269146 -88.575663) (xy 74.316696 -88.61215) (xy 74.359076 -88.65453) (xy 74.395563 -88.70208)
			(xy 74.42553 -88.753986) (xy 74.448466 -88.809359) (xy 74.463979 -88.867252) (xy 74.471802 -88.926674)
			(xy 74.472292 -88.956642) (xy 74.471802 -88.98661) (xy 74.463979 -89.046032) (xy 74.448466 -89.103925)
			(xy 74.42553 -89.159298) (xy 74.395563 -89.211204) (xy 74.359076 -89.258754) (xy 74.316696 -89.301134)
			(xy 74.269146 -89.337621) (xy 74.21724 -89.367588) (xy 74.161867 -89.390524) (xy 74.103974 -89.406037)
			(xy 74.044552 -89.41386) (xy 73.984616 -89.41386) (xy 73.925194 -89.406037) (xy 73.867301 -89.390524)
			(xy 73.811928 -89.367588) (xy 73.760022 -89.337621) (xy 73.712472 -89.301134) (xy 73.670092 -89.258754)
			(xy 73.633605 -89.211204) (xy 73.603638 -89.159298) (xy 73.580702 -89.103925) (xy 73.565189 -89.046032)
			(xy 73.557366 -88.98661) (xy 54.794404 -88.98661) (xy 54.794404 -90.67345) (xy 78.092805 -90.67345)
			(xy 78.092805 -90.61895) (xy 78.100561 -90.565006) (xy 78.115916 -90.512714) (xy 78.138556 -90.46314)
			(xy 78.168021 -90.417292) (xy 78.203711 -90.376105) (xy 78.244899 -90.340416) (xy 78.290747 -90.310952)
			(xy 78.340322 -90.288313) (xy 78.392614 -90.27296) (xy 78.446558 -90.265205) (xy 78.473808 -90.264742)
			(xy 78.502403 -90.265284) (xy 78.558952 -90.273808) (xy 78.613596 -90.29068) (xy 78.665108 -90.31552)
			(xy 78.712334 -90.347773) (xy 78.754216 -90.386715) (xy 78.789815 -90.431473) (xy 78.804516 -90.456004)
			(xy 78.804516 -90.456258) (xy 78.80818 -90.462022) (xy 78.817959 -90.471548) (xy 78.82382 -90.475054)
			(xy 78.829997 -90.478257) (xy 78.843531 -90.481473) (xy 78.85049 -90.481404) (xy 78.95463 -90.47734)
			(xy 78.977744 -90.4621) (xy 78.984094 -90.449146) (xy 78.99612 -90.425159) (xy 79.025818 -90.38047)
			(xy 79.061486 -90.340385) (xy 79.102419 -90.305692) (xy 79.147809 -90.277078) (xy 79.196761 -90.255107)
			(xy 79.248309 -90.240213) (xy 79.301436 -90.232689) (xy 79.328264 -90.23223) (xy 79.356708 -90.232791)
			(xy 79.412966 -90.24124) (xy 79.467344 -90.257954) (xy 79.518634 -90.282563) (xy 79.565698 -90.314521)
			(xy 79.607491 -90.353118) (xy 79.625698 -90.374978) (xy 79.633064 -90.384122) (xy 79.654146 -90.394028)
			(xy 79.757778 -90.392758) (xy 79.778606 -90.382344) (xy 79.785718 -90.372946) (xy 79.803889 -90.350096)
			(xy 79.84603 -90.309696) (xy 79.893832 -90.276184) (xy 79.94618 -90.250343) (xy 80.001852 -90.232776)
			(xy 80.059551 -90.223892) (xy 80.08874 -90.22334) (xy 80.118181 -90.223899) (xy 80.176365 -90.232938)
			(xy 80.232469 -90.250811) (xy 80.28516 -90.277093) (xy 80.333187 -90.311161) (xy 80.354678 -90.33129)
			(xy 80.36306 -90.339418) (xy 80.38465 -90.34653) (xy 80.48625 -90.334338) (xy 80.505554 -90.321892)
			(xy 80.51165 -90.311986) (xy 80.523334 -90.294206) (xy 80.530192 -90.2843) (xy 80.533494 -90.261186)
			(xy 80.50149 -90.161364) (xy 80.485234 -90.1446) (xy 80.473804 -90.140536) (xy 80.446454 -90.130121)
			(xy 80.395033 -90.10218) (xy 80.348482 -90.066716) (xy 80.307889 -90.024561) (xy 80.274208 -89.976703)
			(xy 80.248228 -89.924264) (xy 80.230558 -89.868474) (xy 80.221612 -89.810641) (xy 80.221074 -89.78138)
			(xy 80.221559 -89.754129) (xy 80.229318 -89.700182) (xy 80.244675 -89.647889) (xy 80.267317 -89.598313)
			(xy 80.296784 -89.552463) (xy 80.332475 -89.511274) (xy 80.373665 -89.475582) (xy 80.419514 -89.446116)
			(xy 80.46909 -89.423474) (xy 80.521384 -89.408117) (xy 80.575331 -89.400359) (xy 80.602582 -89.399872)
			(xy 80.629156 -89.400348) (xy 80.681789 -89.407734) (xy 80.732887 -89.422353) (xy 80.781463 -89.44392)
			(xy 80.826576 -89.47202) (xy 80.867353 -89.506108) (xy 80.903005 -89.545525) (xy 80.918304 -89.567258)
			(xy 80.921098 -89.571322) (xy 80.928972 -89.579196) (xy 80.936084 -89.586308) (xy 80.954372 -89.594182)
			(xy 81.059274 -89.594944) (xy 81.081626 -89.583514) (xy 81.088738 -89.5731) (xy 81.104103 -89.551727)
			(xy 81.139805 -89.513044) (xy 81.180474 -89.479623) (xy 81.225342 -89.452095) (xy 81.273561 -89.43098)
			(xy 81.32422 -89.416677) (xy 81.376362 -89.409456) (xy 81.402682 -89.409016) (xy 81.429935 -89.409472)
			(xy 81.483888 -89.417227) (xy 81.536187 -89.432582) (xy 81.585769 -89.455224) (xy 81.631623 -89.484693)
			(xy 81.672817 -89.520387) (xy 81.708511 -89.561581) (xy 81.737978 -89.607436) (xy 81.76062 -89.657018)
			(xy 81.775974 -89.709318) (xy 81.783728 -89.76327) (xy 81.78419 -89.790524) (xy 81.783745 -89.817765)
			(xy 81.775992 -89.871693) (xy 81.760645 -89.923969) (xy 81.738019 -89.973531) (xy 81.708572 -90.01937)
			(xy 81.672904 -90.060554) (xy 81.63174 -90.096245) (xy 81.585917 -90.125717) (xy 81.536368 -90.148371)
			(xy 81.4841 -90.163746) (xy 81.430177 -90.17153) (xy 81.402936 -90.172032) (xy 81.402174 -90.172032)
			(xy 81.386172 -90.171778) (xy 81.372202 -90.171016) (xy 81.347564 -90.18397) (xy 81.286858 -90.2843)
			(xy 81.286858 -90.311986) (xy 81.29397 -90.324178) (xy 81.308856 -90.350611) (xy 81.332316 -90.406556)
			(xy 81.348192 -90.465107) (xy 81.356209 -90.52524) (xy 81.356708 -90.555572) (xy 81.356708 -90.555826)
			(xy 81.356242 -90.585794) (xy 81.348416 -90.645218) (xy 81.3329 -90.703111) (xy 81.309961 -90.758484)
			(xy 81.279991 -90.81039) (xy 81.243502 -90.857939) (xy 81.20112 -90.90032) (xy 81.153568 -90.936806)
			(xy 81.101661 -90.966773) (xy 81.046286 -90.989709) (xy 80.988392 -91.005221) (xy 80.928968 -91.013044)
			(xy 80.899 -91.013534) (xy 80.869923 -91.013055) (xy 80.812239 -91.005674) (xy 80.755955 -90.991045)
			(xy 80.701978 -90.969403) (xy 80.651178 -90.941097) (xy 80.604374 -90.906582) (xy 80.562319 -90.866416)
			(xy 80.543654 -90.844116) (xy 80.536542 -90.835226) (xy 80.515714 -90.82532) (xy 80.503522 -90.82532)
			(xy 80.413606 -90.825574) (xy 80.392778 -90.83548) (xy 80.385666 -90.84437) (xy 80.367481 -90.866155)
			(xy 80.325701 -90.904558) (xy 80.278694 -90.936347) (xy 80.227496 -90.960822) (xy 80.173236 -90.977442)
			(xy 80.117114 -90.98584) (xy 80.08874 -90.986356) (xy 80.060293 -90.985868) (xy 80.004031 -90.977405)
			(xy 79.949652 -90.960676) (xy 79.898362 -90.936053) (xy 79.8513 -90.904082) (xy 79.809511 -90.865473)
			(xy 79.791306 -90.843608) (xy 79.78394 -90.834464) (xy 79.762858 -90.824558) (xy 79.659226 -90.825828)
			(xy 79.638398 -90.836242) (xy 79.631286 -90.84564) (xy 79.613109 -90.868485) (xy 79.57097 -90.908886)
			(xy 79.523169 -90.942399) (xy 79.470823 -90.968241) (xy 79.415151 -90.985809) (xy 79.357453 -90.994694)
			(xy 79.328264 -90.995246) (xy 79.299668 -90.994733) (xy 79.243117 -90.986204) (xy 79.188472 -90.969328)
			(xy 79.13696 -90.944483) (xy 79.089734 -90.912226) (xy 79.047853 -90.87328) (xy 79.012256 -90.828517)
			(xy 78.997556 -90.803984) (xy 78.997556 -90.80373) (xy 78.993902 -90.79796) (xy 78.984116 -90.788437)
			(xy 78.978252 -90.784934) (xy 78.972063 -90.781756) (xy 78.958538 -90.778524) (xy 78.951582 -90.778584)
			(xy 78.847442 -90.782648) (xy 78.824328 -90.797888) (xy 78.817978 -90.810842) (xy 78.805968 -90.834838)
			(xy 78.776268 -90.879527) (xy 78.740599 -90.919614) (xy 78.699664 -90.954306) (xy 78.654271 -90.982919)
			(xy 78.605316 -91.004888) (xy 78.553766 -91.01978) (xy 78.500637 -91.027301) (xy 78.473808 -91.027758)
			(xy 78.446558 -91.027195) (xy 78.392614 -91.01944) (xy 78.340322 -91.004087) (xy 78.290747 -90.981448)
			(xy 78.244899 -90.951984) (xy 78.203711 -90.916295) (xy 78.168021 -90.875108) (xy 78.138556 -90.82926)
			(xy 78.115916 -90.779686) (xy 78.100561 -90.727394) (xy 78.092805 -90.67345) (xy 54.794404 -90.67345)
			(xy 54.794404 -91.263212) (xy 58.790314 -91.263212) (xy 58.790314 -91.203276) (xy 58.798137 -91.143854)
			(xy 58.81365 -91.085961) (xy 58.836586 -91.030588) (xy 58.866553 -90.978682) (xy 58.90304 -90.931132)
			(xy 58.94542 -90.888752) (xy 58.99297 -90.852265) (xy 59.044876 -90.822298) (xy 59.100249 -90.799362)
			(xy 59.158142 -90.783849) (xy 59.217564 -90.776026) (xy 59.2775 -90.776026) (xy 59.336922 -90.783849)
			(xy 59.394815 -90.799362) (xy 59.450188 -90.822298) (xy 59.502094 -90.852265) (xy 59.549644 -90.888752)
			(xy 59.592024 -90.931132) (xy 59.628511 -90.978682) (xy 59.658478 -91.030588) (xy 59.681414 -91.085961)
			(xy 59.696927 -91.143854) (xy 59.70475 -91.203276) (xy 59.70524 -91.233244) (xy 59.70475 -91.263212)
			(xy 59.696927 -91.322634) (xy 59.681414 -91.380527) (xy 59.658478 -91.4359) (xy 59.628511 -91.487806)
			(xy 59.592024 -91.535356) (xy 59.549644 -91.577736) (xy 59.502094 -91.614223) (xy 59.450188 -91.64419)
			(xy 59.394815 -91.667126) (xy 59.336922 -91.682639) (xy 59.2775 -91.690462) (xy 59.217564 -91.690462)
			(xy 59.158142 -91.682639) (xy 59.100249 -91.667126) (xy 59.044876 -91.64419) (xy 58.99297 -91.614223)
			(xy 58.94542 -91.577736) (xy 58.90304 -91.535356) (xy 58.866553 -91.487806) (xy 58.836586 -91.4359)
			(xy 58.81365 -91.380527) (xy 58.798137 -91.322634) (xy 58.790314 -91.263212) (xy 54.794404 -91.263212)
			(xy 54.794404 -93.70845) (xy 69.090518 -93.70845) (xy 69.090518 -93.62155) (xy 69.098537 -93.535021)
			(xy 69.114505 -93.449601) (xy 69.138287 -93.366019) (xy 69.169679 -93.284987) (xy 69.208415 -93.207198)
			(xy 69.254163 -93.133315) (xy 69.306533 -93.063969) (xy 69.365078 -92.99975) (xy 69.429299 -92.941207)
			(xy 69.498648 -92.88884) (xy 69.572533 -92.843096) (xy 69.650324 -92.804363) (xy 69.731357 -92.772974)
			(xy 69.81494 -92.749196) (xy 69.900361 -92.733231) (xy 69.98689 -92.725217) (xy 70.03034 -92.724732)
			(xy 71.88454 -92.724732) (xy 71.927992 -92.725156) (xy 72.014524 -92.733178) (xy 72.099947 -92.74915)
			(xy 72.183532 -92.772936) (xy 72.264566 -92.804332) (xy 72.342357 -92.843072) (xy 72.416242 -92.888824)
			(xy 72.48559 -92.941198) (xy 72.54981 -92.999747) (xy 72.608353 -93.063972) (xy 72.660721 -93.133324)
			(xy 72.706467 -93.207213) (xy 72.7452 -93.285008) (xy 72.77659 -93.366044) (xy 72.800368 -93.449631)
			(xy 72.816333 -93.535055) (xy 72.824348 -93.621588) (xy 72.824848 -93.66504) (xy 72.824291 -93.710119)
			(xy 72.815647 -93.799862) (xy 72.798461 -93.888368) (xy 72.772891 -93.974824) (xy 72.756522 -94.01683)
			(xy 72.75195 -94.028006) (xy 72.753728 -94.05112) (xy 72.800718 -94.13113) (xy 72.807138 -94.140866)
			(xy 72.82658 -94.153698) (xy 72.838056 -94.155768) (xy 72.83831 -94.155768) (xy 72.883974 -94.161963)
			(xy 72.974122 -94.181108) (xy 73.062284 -94.207954) (xy 73.147803 -94.242301) (xy 73.230042 -94.283894)
			(xy 73.30839 -94.332421) (xy 73.382261 -94.387523) (xy 73.451107 -94.448789) (xy 73.514415 -94.515762)
			(xy 73.571712 -94.587943) (xy 73.622573 -94.664796) (xy 73.666619 -94.745748) (xy 73.703522 -94.830196)
			(xy 73.733006 -94.917511) (xy 73.754853 -95.007042) (xy 73.768899 -95.098124) (xy 73.77504 -95.190078)
			(xy 73.773231 -95.282219) (xy 73.763484 -95.373861) (xy 73.745873 -95.464321) (xy 73.720528 -95.552926)
			(xy 73.687638 -95.639016) (xy 73.647448 -95.72195) (xy 73.600258 -95.80111) (xy 73.546419 -95.875907)
			(xy 73.516744 -95.911162) (xy 73.506838 -95.922592) (xy 73.502774 -95.951802) (xy 73.544684 -96.042988)
			(xy 73.548494 -96.0501) (xy 73.555121 -96.059038) (xy 73.574094 -96.070622) (xy 73.58507 -96.072452)
			(xy 73.590912 -96.072706) (xy 74.572114 -96.072706) (xy 74.582184 -96.073123) (xy 74.600782 -96.08085)
			(xy 74.608182 -96.087692) (xy 75.094592 -96.574102) (xy 75.112372 -96.581976) (xy 75.122278 -96.58223)
			(xy 75.15162 -96.583619) (xy 75.209609 -96.592995) (xy 75.265924 -96.60971) (xy 75.319638 -96.633489)
			(xy 75.36987 -96.663942) (xy 75.415796 -96.700569) (xy 75.45666 -96.742769) (xy 75.491792 -96.789847)
			(xy 75.520616 -96.841033) (xy 75.542656 -96.895483) (xy 75.557553 -96.952306) (xy 75.56506 -97.010567)
			(xy 75.565508 -97.039938) (xy 75.565008 -97.069921) (xy 75.557176 -97.129374) (xy 75.541653 -97.187297)
			(xy 75.518703 -97.242698) (xy 75.488718 -97.29463) (xy 75.452212 -97.342204) (xy 75.40981 -97.384607)
			(xy 75.362236 -97.421114) (xy 75.310305 -97.451099) (xy 75.254904 -97.47405) (xy 75.196982 -97.489575)
			(xy 75.137529 -97.497407) (xy 75.107546 -97.4979) (xy 75.078178 -97.497427) (xy 75.019924 -97.48991)
			(xy 74.963109 -97.475008) (xy 74.908666 -97.452964) (xy 74.857488 -97.42414) (xy 74.810415 -97.389009)
			(xy 74.76822 -97.348149) (xy 74.731595 -97.302229) (xy 74.701142 -97.252004) (xy 74.67736 -97.198297)
			(xy 74.660639 -97.14199) (xy 74.651255 -97.084008) (xy 74.649838 -97.05467) (xy 74.649584 -97.044764)
			(xy 74.64171 -97.026984) (xy 74.342498 -96.728026) (xy 74.342244 -96.727772) (xy 74.334838 -96.721225)
			(xy 74.316556 -96.713766) (xy 74.306684 -96.713294) (xy 72.717406 -96.713294) (xy 72.708262 -96.71685)
			(xy 72.702795 -96.71919) (xy 72.693047 -96.725994) (xy 72.688958 -96.730312) (xy 72.687942 -96.731328)
			(xy 72.63638 -96.792034) (xy 72.630284 -96.81337) (xy 72.632062 -96.824292) (xy 72.634867 -96.843343)
			(xy 72.637788 -96.881744) (xy 72.637904 -96.901) (xy 72.637904 -97.663) (xy 72.637347 -97.696267)
			(xy 72.628205 -97.762171) (xy 72.610107 -97.826197) (xy 72.583396 -97.887134) (xy 72.548578 -97.943831)
			(xy 72.506309 -97.995214) (xy 72.457391 -98.040312) (xy 72.430386 -98.059748) (xy 72.42556 -98.06305)
			(xy 72.41794 -98.071432) (xy 72.414638 -98.077274) (xy 72.411754 -98.082765) (xy 72.408414 -98.094705)
			(xy 72.408034 -98.100896) (xy 72.407272 -98.127058) (xy 72.407272 -98.140643) (xy 72.413665 -98.167039)
			(xy 72.426786 -98.190819) (xy 72.445708 -98.210302) (xy 72.469094 -98.224112) (xy 72.495292 -98.231274)
			(xy 72.508872 -98.231706) (xy 72.93102 -98.231706) (xy 72.940637 -98.231331) (xy 72.958527 -98.224274)
			(xy 72.965818 -98.21799) (xy 72.990322 -98.195791) (xy 73.044542 -98.157949) (xy 73.103644 -98.128308)
			(xy 73.166399 -98.107485) (xy 73.231497 -98.095913) (xy 73.264522 -98.094292) (xy 73.274428 -98.094038)
			(xy 73.2917 -98.086418) (xy 73.512426 -97.865692) (xy 73.519822 -97.858847) (xy 73.538424 -97.85113)
			(xy 73.548494 -97.850706) (xy 73.615296 -97.850706) (xy 73.625177 -97.850272) (xy 73.643477 -97.842815)
			(xy 73.650856 -97.836228) (xy 73.651364 -97.83572) (xy 73.83399 -97.653094) (xy 73.92162 -97.565718)
			(xy 73.928478 -97.553272) (xy 73.930002 -97.546414) (xy 73.937483 -97.519016) (xy 73.959401 -97.466625)
			(xy 73.988842 -97.418061) (xy 74.025156 -97.374397) (xy 74.067539 -97.336596) (xy 74.115056 -97.305494)
			(xy 74.166659 -97.281778) (xy 74.221206 -97.265971) (xy 74.24928 -97.26168) (xy 74.261921 -97.260112)
			(xy 74.287342 -97.258457) (xy 74.30008 -97.258378) (xy 74.327352 -97.25882) (xy 74.381342 -97.266581)
			(xy 74.433678 -97.281946) (xy 74.483293 -97.304605) (xy 74.529179 -97.334094) (xy 74.5704 -97.369814)
			(xy 74.606118 -97.411037) (xy 74.635605 -97.456924) (xy 74.658261 -97.506541) (xy 74.673624 -97.558878)
			(xy 74.681381 -97.612868) (xy 74.681842 -97.64014) (xy 74.681348 -97.668288) (xy 74.67308 -97.723974)
			(xy 74.656731 -97.777844) (xy 74.632653 -97.828731) (xy 74.601369 -97.875534) (xy 74.563555 -97.91724)
			(xy 74.52003 -97.952945) (xy 74.471737 -97.981876) (xy 74.419721 -98.003407) (xy 74.392536 -98.010726)
			(xy 74.385678 -98.012504) (xy 74.373994 -98.019108) (xy 73.916794 -98.476308) (xy 73.909391 -98.483144)
			(xy 73.890794 -98.490866) (xy 73.880726 -98.491294) (xy 73.813924 -98.491294) (xy 73.803853 -98.491707)
			(xy 73.785254 -98.499433) (xy 73.777856 -98.50628) (xy 73.77049 -98.513646) (xy 73.770236 -98.513646)
			(xy 73.744836 -98.539046) (xy 73.736962 -98.556826) (xy 73.736708 -98.566732) (xy 73.73531 -98.596072)
			(xy 73.725929 -98.654057) (xy 73.709211 -98.710367) (xy 73.685429 -98.764077) (xy 73.654975 -98.814305)
			(xy 73.618348 -98.860227) (xy 73.576151 -98.901088) (xy 73.529074 -98.936219) (xy 73.477893 -98.965041)
			(xy 73.423445 -98.987083) (xy 73.366627 -99.001981) (xy 73.30837 -99.009492) (xy 73.279 -99.009962)
			(xy 73.250247 -99.00951) (xy 73.193196 -99.002296) (xy 73.137497 -98.987995) (xy 73.084028 -98.966832)
			(xy 73.033629 -98.93914) (xy 72.987095 -98.905355) (xy 72.965818 -98.88601) (xy 72.958498 -98.879773)
			(xy 72.940626 -98.872715) (xy 72.93102 -98.872294) (xy 72.453246 -98.872294) (xy 72.44497 -98.872629)
			(xy 72.429294 -98.877951) (xy 72.422512 -98.882708) (xy 72.402558 -98.897203) (xy 72.357881 -98.918066)
			(xy 72.309751 -98.928783) (xy 72.285098 -98.929444) (xy 72.017636 -98.929444) (xy 72.017636 -98.9203)
			(xy 72.017113 -98.910297) (xy 72.00946 -98.891812) (xy 71.995318 -98.87766) (xy 71.976839 -98.869994)
			(xy 71.966836 -98.8695) (xy 71.519034 -98.8695) (xy 71.494142 -98.885756) (xy 71.487792 -98.899472)
			(xy 71.483473 -98.908225) (xy 71.469421 -98.921755) (xy 71.451319 -98.929025) (xy 71.441564 -98.929444)
			(xy 71.224902 -98.929444) (xy 71.200246 -98.928796) (xy 71.152109 -98.918089) (xy 71.107428 -98.897225)
			(xy 71.087488 -98.882708) (xy 71.080709 -98.877944) (xy 71.065032 -98.872619) (xy 71.056754 -98.872294)
			(xy 70.84441 -98.872294) (xy 70.838194 -98.876032) (xy 70.828011 -98.886355) (xy 70.824344 -98.892614)
			(xy 70.824344 -100.003356) (xy 70.824739 -100.012971) (xy 70.831781 -100.030862) (xy 70.83806 -100.038154)
			(xy 70.857407 -100.05943) (xy 70.865001 -100.069885) (xy 73.801439 -100.069885) (xy 73.801439 -100.009915)
			(xy 73.809267 -99.950458) (xy 73.824789 -99.892532) (xy 73.84774 -99.837128) (xy 73.877726 -99.785193)
			(xy 73.914234 -99.737617) (xy 73.956641 -99.695213) (xy 74.00422 -99.658708) (xy 74.056156 -99.628725)
			(xy 74.111563 -99.605779) (xy 74.16949 -99.590261) (xy 74.228947 -99.582437) (xy 74.258932 -99.58197)
			(xy 74.287686 -99.582394) (xy 74.344738 -99.589612) (xy 74.400438 -99.603918) (xy 74.453908 -99.625086)
			(xy 74.504306 -99.652784) (xy 74.550838 -99.686574) (xy 74.572114 -99.705922) (xy 74.579421 -99.712177)
			(xy 74.597303 -99.719223) (xy 74.606912 -99.719638) (xy 75.04303 -99.719638) (xy 75.053035 -99.719138)
			(xy 75.07152 -99.711475) (xy 75.085671 -99.697327) (xy 75.093336 -99.678843) (xy 75.09383 -99.668838)
			(xy 75.09383 -99.00666) (xy 75.094226 -98.996587) (xy 75.101966 -98.977989) (xy 75.108816 -98.970592)
			(xy 75.57135 -98.508058) (xy 75.57389 -98.505264) (xy 75.585828 -98.491548) (xy 75.587352 -98.456242)
			(xy 75.576684 -98.441764) (xy 75.559914 -98.418123) (xy 75.531805 -98.367431) (xy 75.510319 -98.313597)
			(xy 75.495802 -98.257481) (xy 75.488484 -98.199982) (xy 75.488038 -98.171) (xy 75.488527 -98.141026)
			(xy 75.496349 -98.081591) (xy 75.511859 -98.023685) (xy 75.534793 -97.968298) (xy 75.564757 -97.916376)
			(xy 75.60124 -97.868808) (xy 75.643617 -97.826407) (xy 75.691165 -97.789898) (xy 75.74307 -97.759905)
			(xy 75.798444 -97.736941) (xy 75.856342 -97.721399) (xy 75.915773 -97.713544) (xy 75.945746 -97.713038)
			(xy 75.946254 -97.713038) (xy 75.958192 -97.713292) (xy 75.96886 -97.713546) (xy 75.978512 -97.709736)
			(xy 75.983375 -97.707693) (xy 75.992212 -97.701937) (xy 75.996038 -97.698306) (xy 76.167488 -97.526856)
			(xy 76.167742 -97.526602) (xy 76.174309 -97.519212) (xy 76.181756 -97.500918) (xy 76.18222 -97.491042)
			(xy 76.18222 -96.976438) (xy 76.18266 -96.96637) (xy 76.19037 -96.947772) (xy 76.197206 -96.94037)
			(xy 76.225654 -96.911922) (xy 76.22667 -96.871282) (xy 76.2127 -96.856042) (xy 76.19391 -96.83481)
			(xy 76.16222 -96.787799) (xy 76.137824 -96.73662) (xy 76.121257 -96.682399) (xy 76.112884 -96.626326)
			(xy 76.11237 -96.597978) (xy 76.11237 -96.59747) (xy 76.114402 -96.558862) (xy 76.114656 -96.556322)
			(xy 76.114656 -96.555052) (xy 76.115926 -96.543876) (xy 76.108052 -96.522032) (xy 76.044044 -96.458786)
			(xy 76.04379 -96.458532) (xy 76.035187 -96.450708) (xy 76.01322 -96.443161) (xy 76.001626 -96.444054)
			(xy 75.987777 -96.445687) (xy 75.959944 -96.447468) (xy 75.946 -96.44761) (xy 75.916018 -96.447072)
			(xy 75.856566 -96.439246) (xy 75.798644 -96.423727) (xy 75.743244 -96.400781) (xy 75.691312 -96.3708)
			(xy 75.643737 -96.334298) (xy 75.601334 -96.291899) (xy 75.564827 -96.244328) (xy 75.534841 -96.192399)
			(xy 75.511889 -96.137001) (xy 75.496364 -96.079081) (xy 75.488531 -96.01963) (xy 75.488038 -95.989648)
			(xy 75.488552 -95.959663) (xy 75.496374 -95.900207) (xy 75.51189 -95.84228) (xy 75.534835 -95.786874)
			(xy 75.564816 -95.734937) (xy 75.60132 -95.687358) (xy 75.643722 -95.644951) (xy 75.691297 -95.608442)
			(xy 75.743231 -95.578456) (xy 75.798634 -95.555505) (xy 75.85656 -95.539983) (xy 75.916015 -95.532155)
			(xy 75.946 -95.531686) (xy 75.974753 -95.532125) (xy 76.031805 -95.53934) (xy 76.087505 -95.553642)
			(xy 76.140975 -95.574808) (xy 76.191373 -95.602503) (xy 76.237906 -95.636291) (xy 76.259182 -95.655638)
			(xy 76.266507 -95.661868) (xy 76.284375 -95.668931) (xy 76.29398 -95.669354) (xy 76.488798 -95.669354)
			(xy 76.49798 -95.669) (xy 76.515197 -95.662622) (xy 76.529055 -95.650578) (xy 76.533756 -95.642684)
			(xy 76.538395 -95.634768) (xy 76.552147 -95.622645) (xy 76.569294 -95.616158) (xy 76.57846 -95.61576)
			(xy 76.971906 -95.61576) (xy 76.97597 -95.614998) (xy 76.984676 -95.613706) (xy 77.002222 -95.612309)
			(xy 77.011022 -95.612204) (xy 77.2795 -95.612204) (xy 77.2795 -95.61576) (xy 77.54239 -95.61576)
			(xy 77.552461 -95.616175) (xy 77.571059 -95.623901) (xy 77.578458 -95.630746) (xy 77.601572 -95.65386)
			(xy 77.608383 -95.661283) (xy 77.61612 -95.679865) (xy 77.616558 -95.689928) (xy 77.616558 -97.140522)
			(xy 77.616957 -97.150595) (xy 77.624694 -97.169193) (xy 77.631544 -97.17659) (xy 77.978508 -97.523554)
			(xy 77.985917 -97.530384) (xy 78.004509 -97.538111) (xy 78.014576 -97.53854) (xy 78.551532 -97.53854)
			(xy 78.583167 -97.538957) (xy 78.645895 -97.54722) (xy 78.707008 -97.5636) (xy 78.765459 -97.587816)
			(xy 78.82025 -97.619455) (xy 78.870442 -97.657976) (xy 78.915177 -97.702718) (xy 78.953689 -97.752916)
			(xy 78.985319 -97.807712) (xy 79.009526 -97.866168) (xy 79.025896 -97.927284) (xy 79.034148 -97.990013)
			(xy 79.03464 -98.021648) (xy 79.034083 -98.053868) (xy 79.025495 -98.117734) (xy 79.008492 -98.179891)
			(xy 78.983374 -98.239236) (xy 78.950589 -98.294713) (xy 78.910719 -98.345339) (xy 78.864471 -98.390214)
			(xy 78.812666 -98.428541) (xy 78.784704 -98.444558) (xy 78.779878 -98.449384) (xy 78.773049 -98.456793)
			(xy 78.765323 -98.475385) (xy 78.764892 -98.485452) (xy 78.764892 -98.573844) (xy 78.765287 -98.582052)
			(xy 78.770588 -98.597596) (xy 78.775306 -98.604324) (xy 78.781656 -98.61296) (xy 78.7908 -98.61804)
			(xy 78.818165 -98.634231) (xy 78.868806 -98.672684) (xy 78.913961 -98.71745) (xy 78.95285 -98.767756)
			(xy 78.984799 -98.822731) (xy 79.009256 -98.881425) (xy 79.025797 -98.94282) (xy 79.034137 -99.005856)
			(xy 79.03464 -99.037648) (xy 79.034143 -99.069627) (xy 79.025699 -99.133026) (xy 79.008963 -99.194756)
			(xy 78.984229 -99.253739) (xy 78.951929 -99.308942) (xy 78.912629 -99.359402) (xy 78.867014 -99.404235)
			(xy 78.815883 -99.442658) (xy 78.78826 -99.45878) (xy 78.780584 -99.463464) (xy 78.768908 -99.477126)
			(xy 78.762699 -99.49399) (xy 78.762352 -99.502976) (xy 78.762352 -99.591368) (xy 78.762785 -99.600338)
			(xy 78.769004 -99.617169) (xy 78.780626 -99.630839) (xy 78.78826 -99.635564) (xy 78.815889 -99.651675)
			(xy 78.867018 -99.6901) (xy 78.91263 -99.734936) (xy 78.951927 -99.785397) (xy 78.984223 -99.840603)
			(xy 79.008952 -99.899587) (xy 79.025683 -99.961318) (xy 79.034122 -100.024717) (xy 79.03464 -100.056696)
			(xy 79.034087 -100.088325) (xy 79.025831 -100.151043) (xy 79.00946 -100.212146) (xy 78.985253 -100.27059)
			(xy 78.953625 -100.325374) (xy 78.915118 -100.375562) (xy 78.870389 -100.420294) (xy 78.820204 -100.458805)
			(xy 78.765422 -100.490437) (xy 78.70698 -100.514648) (xy 78.645878 -100.531024) (xy 78.583161 -100.539285)
			(xy 78.551532 -100.539804) (xy 77.941932 -100.539804) (xy 77.912353 -100.53934) (xy 77.85364 -100.532079)
			(xy 77.824838 -100.525326) (xy 77.811884 -100.522024) (xy 77.78623 -100.529136) (xy 77.673454 -100.641912)
			(xy 77.66661 -100.649309) (xy 77.658894 -100.667911) (xy 77.658468 -100.67798) (xy 77.658468 -100.70592)
			(xy 77.658468 -100.716588) (xy 77.665072 -100.731828) (xy 77.666852 -100.736453) (xy 77.668766 -100.746177)
			(xy 77.668882 -100.751132) (xy 77.668882 -101.529896) (xy 77.669377 -101.54346) (xy 77.676551 -101.569624)
			(xy 77.690366 -101.592973) (xy 77.709845 -101.611857) (xy 77.733611 -101.62494) (xy 77.759986 -101.631298)
			(xy 77.787103 -101.630481) (xy 77.8002 -101.626924) (xy 77.834788 -101.616985) (xy 77.90595 -101.60627)
			(xy 77.941932 -101.605588) (xy 78.551532 -101.605588) (xy 78.583163 -101.606079) (xy 78.645884 -101.61434)
			(xy 78.70699 -101.630717) (xy 78.765436 -101.654929) (xy 78.820222 -101.686563) (xy 78.87041 -101.725077)
			(xy 78.915142 -101.769811) (xy 78.953653 -101.820002) (xy 78.985283 -101.874789) (xy 79.009492 -101.933236)
			(xy 79.025865 -101.994343) (xy 79.034123 -102.057065) (xy 79.03464 -102.088696) (xy 79.034041 -102.120915)
			(xy 79.02546 -102.184779) (xy 79.008463 -102.246935) (xy 78.983352 -102.306279) (xy 78.950573 -102.361757)
			(xy 78.910707 -102.412384) (xy 78.864464 -102.45726) (xy 78.812664 -102.495588) (xy 78.784704 -102.511606)
			(xy 78.779878 -102.516432) (xy 78.773028 -102.523824) (xy 78.765315 -102.54243) (xy 78.764892 -102.5525)
			(xy 78.764892 -102.640892) (xy 78.765266 -102.649102) (xy 78.770582 -102.664646) (xy 78.775306 -102.671372)
			(xy 78.781656 -102.680008) (xy 78.7908 -102.685088) (xy 78.818187 -102.701245) (xy 78.868827 -102.739702)
			(xy 78.913982 -102.784474) (xy 78.952869 -102.834785) (xy 78.984816 -102.889765) (xy 79.009269 -102.948463)
			(xy 79.025806 -103.009863) (xy 79.03414 -103.072902) (xy 79.03464 -103.104696) (xy 79.034041 -103.136915)
			(xy 79.02546 -103.200779) (xy 79.008463 -103.262935) (xy 78.983352 -103.322279) (xy 78.950573 -103.377757)
			(xy 78.910707 -103.428384) (xy 78.864464 -103.47326) (xy 78.812664 -103.511588) (xy 78.784704 -103.527606)
			(xy 78.779878 -103.532432) (xy 78.773028 -103.539824) (xy 78.765315 -103.55843) (xy 78.764892 -103.5685)
			(xy 78.764892 -103.656892) (xy 78.765266 -103.665102) (xy 78.770582 -103.680646) (xy 78.775306 -103.687372)
			(xy 78.781656 -103.696008) (xy 78.7908 -103.701088) (xy 78.818187 -103.717245) (xy 78.868827 -103.755702)
			(xy 78.913982 -103.800474) (xy 78.952869 -103.850785) (xy 78.984816 -103.905765) (xy 79.009269 -103.964463)
			(xy 79.025806 -104.025863) (xy 79.03414 -104.088902) (xy 79.03464 -104.120696) (xy 79.034087 -104.152325)
			(xy 79.025831 -104.215043) (xy 79.00946 -104.276146) (xy 78.985253 -104.33459) (xy 78.953625 -104.389374)
			(xy 78.915118 -104.439562) (xy 78.870389 -104.484294) (xy 78.820204 -104.522805) (xy 78.765422 -104.554437)
			(xy 78.70698 -104.578648) (xy 78.645878 -104.595024) (xy 78.583161 -104.603285) (xy 78.551532 -104.603804)
			(xy 77.941932 -104.603804) (xy 77.909325 -104.603305) (xy 77.844706 -104.594524) (xy 77.781855 -104.577131)
			(xy 77.721915 -104.551441) (xy 77.665975 -104.517922) (xy 77.615052 -104.477184) (xy 77.592174 -104.453944)
			(xy 77.584692 -104.446798) (xy 77.56568 -104.438678) (xy 77.555344 -104.438196) (xy 77.306424 -104.438196)
			(xy 77.281278 -104.454452) (xy 77.275182 -104.468168) (xy 77.270754 -104.476897) (xy 77.256626 -104.490419)
			(xy 77.238478 -104.497704) (xy 77.2287 -104.49814) (xy 77.011784 -104.49814) (xy 76.987127 -104.497502)
			(xy 76.93899 -104.486791) (xy 76.894309 -104.465923) (xy 76.87437 -104.451404) (xy 76.867596 -104.446632)
			(xy 76.851915 -104.441313) (xy 76.843636 -104.44099) (xy 76.32319 -104.44099) (xy 76.31312 -104.440572)
			(xy 76.294522 -104.432846) (xy 76.287122 -104.426004) (xy 76.08189 -104.221026) (xy 76.07446 -104.214371)
			(xy 76.056037 -104.206782) (xy 76.046076 -104.206294) (xy 76.030074 -104.206294) (xy 76.012294 -104.213152)
			(xy 76.005182 -104.22001) (xy 75.983922 -104.239376) (xy 75.937393 -104.273178) (xy 75.886994 -104.300879)
			(xy 75.83352 -104.322044) (xy 75.777814 -104.336338) (xy 75.720755 -104.343535) (xy 75.692 -104.343962)
			(xy 75.662016 -104.343472) (xy 75.60256 -104.335644) (xy 75.544635 -104.320123) (xy 75.489231 -104.297174)
			(xy 75.437297 -104.26719) (xy 75.389721 -104.230684) (xy 75.347316 -104.188279) (xy 75.31081 -104.140703)
			(xy 75.280826 -104.088769) (xy 75.257877 -104.033365) (xy 75.242356 -103.97544) (xy 75.234528 -103.915984)
			(xy 75.234038 -103.886) (xy 75.234566 -103.856383) (xy 75.242211 -103.797643) (xy 75.25736 -103.740379)
			(xy 75.27976 -103.685543) (xy 75.309039 -103.63405) (xy 75.344708 -103.586759) (xy 75.386173 -103.544457)
			(xy 75.432742 -103.507851) (xy 75.48364 -103.477549) (xy 75.510644 -103.465376) (xy 75.5235 -103.459376)
			(xy 75.545489 -103.441466) (xy 75.561696 -103.418194) (xy 75.57087 -103.391359) (xy 75.572301 -103.363035)
			(xy 75.565878 -103.335412) (xy 75.552099 -103.310625) (xy 75.542394 -103.300276) (xy 75.196954 -102.954836)
			(xy 75.179174 -102.946962) (xy 75.169268 -102.946708) (xy 75.138096 -102.945157) (xy 75.076561 -102.934736)
			(xy 75.017011 -102.916053) (xy 74.960551 -102.889455) (xy 74.908227 -102.855434) (xy 74.861009 -102.814622)
			(xy 74.819772 -102.767775) (xy 74.78528 -102.715761) (xy 74.77125 -102.687882) (xy 74.765662 -102.67569)
			(xy 74.744072 -102.660704) (xy 74.646282 -102.65029) (xy 74.634868 -102.649733) (xy 74.613366 -102.657371)
			(xy 74.60488 -102.665022) (xy 74.599292 -102.67061) (xy 74.59726 -102.67315) (xy 74.579044 -102.695828)
			(xy 74.536951 -102.735968) (xy 74.489254 -102.769256) (xy 74.437058 -102.79492) (xy 74.381573 -102.812368)
			(xy 74.324082 -102.821193) (xy 74.295 -102.82174) (xy 74.267729 -102.821298) (xy 74.213742 -102.813535)
			(xy 74.16141 -102.798169) (xy 74.111797 -102.775512) (xy 74.065913 -102.746024) (xy 74.024693 -102.710307)
			(xy 73.988976 -102.669087) (xy 73.959488 -102.623203) (xy 73.936831 -102.57359) (xy 73.921465 -102.521258)
			(xy 73.913702 -102.467271) (xy 73.913702 -102.412729) (xy 73.921465 -102.358742) (xy 73.936831 -102.30641)
			(xy 73.959488 -102.256797) (xy 73.988976 -102.210913) (xy 74.024693 -102.169693) (xy 74.065913 -102.133976)
			(xy 74.111797 -102.104488) (xy 74.16141 -102.081831) (xy 74.213742 -102.066465) (xy 74.267729 -102.058702)
			(xy 74.295 -102.058216) (xy 74.323188 -102.058665) (xy 74.378951 -102.066944) (xy 74.43289 -102.083336)
			(xy 74.483831 -102.107485) (xy 74.530665 -102.138865) (xy 74.572373 -102.176793) (xy 74.608047 -102.220445)
			(xy 74.622914 -102.244398) (xy 74.629772 -102.256082) (xy 74.652378 -102.269036) (xy 74.751946 -102.270052)
			(xy 74.76065 -102.269812) (xy 74.777119 -102.264202) (xy 74.790739 -102.253376) (xy 74.795634 -102.246176)
			(xy 74.811313 -102.222049) (xy 74.847698 -102.177474) (xy 74.889378 -102.137805) (xy 74.935697 -102.103668)
			(xy 74.985925 -102.075599) (xy 75.039273 -102.05404) (xy 75.094901 -102.03933) (xy 75.151932 -102.031702)
			(xy 75.180698 -102.031038) (xy 75.195938 -102.031038) (xy 75.221592 -102.013766) (xy 75.251056 -101.942392)
			(xy 75.252834 -101.937766) (xy 75.254749 -101.928043) (xy 75.254866 -101.923088) (xy 75.254866 -101.89083)
			(xy 75.254434 -101.880761) (xy 75.246719 -101.862163) (xy 75.23988 -101.854762) (xy 74.991976 -101.606604)
			(xy 74.955146 -101.603556) (xy 74.939906 -101.614224) (xy 74.91667 -101.6301) (xy 74.867059 -101.656666)
			(xy 74.814568 -101.676958) (xy 74.759987 -101.690671) (xy 74.704138 -101.697597) (xy 74.676 -101.698044)
			(xy 74.646014 -101.697593) (xy 74.586554 -101.689765) (xy 74.528625 -101.674242) (xy 74.473217 -101.651291)
			(xy 74.42128 -101.621304) (xy 74.373701 -101.584794) (xy 74.331294 -101.542386) (xy 74.294786 -101.494805)
			(xy 74.264801 -101.442867) (xy 74.241852 -101.387458) (xy 74.226332 -101.329528) (xy 74.218506 -101.270068)
			(xy 74.218038 -101.240082) (xy 74.218511 -101.210097) (xy 74.226341 -101.150641) (xy 74.241864 -101.092716)
			(xy 74.264815 -101.037312) (xy 74.294801 -100.985378) (xy 74.331309 -100.937801) (xy 74.373715 -100.895397)
			(xy 74.421293 -100.858891) (xy 74.473228 -100.828907) (xy 74.528633 -100.805958) (xy 74.586559 -100.790437)
			(xy 74.646015 -100.78261) (xy 74.676 -100.78212) (xy 74.704752 -100.782577) (xy 74.761803 -100.78979)
			(xy 74.817502 -100.804091) (xy 74.870971 -100.825253) (xy 74.92137 -100.852944) (xy 74.967905 -100.886728)
			(xy 74.989182 -100.906072) (xy 74.996504 -100.912307) (xy 75.014374 -100.919366) (xy 75.02398 -100.919788)
			(xy 75.06716 -100.919788) (xy 75.075033 -100.915131) (xy 75.087042 -100.901347) (xy 75.093451 -100.884225)
			(xy 75.09383 -100.875084) (xy 75.09383 -100.411026) (xy 75.093292 -100.401024) (xy 75.085646 -100.382538)
			(xy 75.071509 -100.368385) (xy 75.053032 -100.360719) (xy 75.04303 -100.360226) (xy 74.606912 -100.360226)
			(xy 74.597295 -100.36061) (xy 74.579405 -100.36766) (xy 74.572114 -100.373942) (xy 74.550849 -100.393301)
			(xy 74.504318 -100.427096) (xy 74.453919 -100.454793) (xy 74.400446 -100.475955) (xy 74.344742 -100.490248)
			(xy 74.287686 -100.497447) (xy 74.258932 -100.497894) (xy 74.228947 -100.497363) (xy 74.16949 -100.489539)
			(xy 74.111562 -100.474021) (xy 74.056156 -100.451075) (xy 74.00422 -100.421092) (xy 73.956641 -100.384587)
			(xy 73.914234 -100.342183) (xy 73.877726 -100.294607) (xy 73.84774 -100.242672) (xy 73.824789 -100.187268)
			(xy 73.809267 -100.129342) (xy 73.801439 -100.069885) (xy 70.865001 -100.069885) (xy 70.891203 -100.105958)
			(xy 70.918901 -100.156356) (xy 70.940065 -100.209827) (xy 70.954361 -100.265528) (xy 70.961563 -100.322582)
			(xy 70.962012 -100.351336) (xy 70.961522 -100.38132) (xy 70.953694 -100.440776) (xy 70.938173 -100.498701)
			(xy 70.915224 -100.554105) (xy 70.88524 -100.606039) (xy 70.848734 -100.653615) (xy 70.806329 -100.69602)
			(xy 70.758753 -100.732526) (xy 70.706819 -100.76251) (xy 70.651415 -100.785459) (xy 70.59349 -100.80098)
			(xy 70.534034 -100.808808) (xy 70.474066 -100.808808) (xy 70.41461 -100.80098) (xy 70.356685 -100.785459)
			(xy 70.301281 -100.76251) (xy 70.249347 -100.732526) (xy 70.201771 -100.69602) (xy 70.159366 -100.653615)
			(xy 70.12286 -100.606039) (xy 70.092876 -100.554105) (xy 70.069927 -100.498701) (xy 70.054406 -100.440776)
			(xy 70.046578 -100.38132) (xy 70.046088 -100.351336) (xy 70.046549 -100.322584) (xy 70.053759 -100.265532)
			(xy 70.068057 -100.209833) (xy 70.089219 -100.156363) (xy 70.11691 -100.105964) (xy 70.150695 -100.05943)
			(xy 70.17004 -100.038154) (xy 70.176298 -100.030849) (xy 70.183345 -100.012966) (xy 70.183756 -100.003356)
			(xy 70.183756 -99.624642) (xy 70.183328 -99.614928) (xy 70.176111 -99.59689) (xy 70.162699 -99.582834)
			(xy 70.154038 -99.578414) (xy 70.062344 -99.536504) (xy 70.03288 -99.540822) (xy 70.02145 -99.550728)
			(xy 70.011257 -99.559499) (xy 69.990037 -99.57602) (xy 69.979032 -99.583748) (xy 69.954725 -99.600092)
			(xy 69.902937 -99.62746) (xy 69.848219 -99.648363) (xy 69.791374 -99.662494) (xy 69.733237 -99.669646)
			(xy 69.70395 -99.670108) (xy 69.672346 -99.669591) (xy 69.609677 -99.661349) (xy 69.54862 -99.644999)
			(xy 69.490218 -99.620821) (xy 69.435472 -99.589228) (xy 69.385316 -99.550762) (xy 69.340609 -99.506078)
			(xy 69.302115 -99.455943) (xy 69.270493 -99.401213) (xy 69.246284 -99.342825) (xy 69.229902 -99.281776)
			(xy 69.221626 -99.219112) (xy 69.221096 -99.187508) (xy 69.221096 -98.552) (xy 69.221614 -98.518677)
			(xy 69.230782 -98.452666) (xy 69.24893 -98.388539) (xy 69.275715 -98.327513) (xy 69.310628 -98.270744)
			(xy 69.353008 -98.219309) (xy 69.402051 -98.174183) (xy 69.429122 -98.154744) (xy 69.439028 -98.147886)
			(xy 69.450458 -98.126804) (xy 69.45376 -98.021648) (xy 69.4436 -97.999804) (xy 69.434202 -97.992184)
			(xy 69.418243 -97.979054) (xy 69.390898 -97.948076) (xy 69.369628 -97.91265) (xy 69.355138 -97.873953)
			(xy 69.34791 -97.833269) (xy 69.347588 -97.812606) (xy 69.347588 -97.513394) (xy 69.347881 -97.493646)
			(xy 69.354456 -97.454706) (xy 69.367684 -97.417497) (xy 69.377052 -97.40011) (xy 69.380354 -97.394268)
			(xy 69.383656 -97.381822) (xy 69.383656 -97.122488) (xy 69.3836 -97.118819) (xy 69.382586 -97.111551)
			(xy 69.381624 -97.10801) (xy 69.380514 -97.104532) (xy 69.377458 -97.097901) (xy 69.375528 -97.094802)
			(xy 69.374766 -97.093532) (xy 69.374258 -97.092516) (xy 69.361939 -97.070637) (xy 69.342541 -97.024322)
			(xy 69.329371 -96.975867) (xy 69.322656 -96.926105) (xy 69.322188 -96.901) (xy 69.322724 -96.873733)
			(xy 69.330485 -96.819754) (xy 69.345847 -96.767428) (xy 69.3685 -96.717821) (xy 69.397981 -96.671943)
			(xy 69.433691 -96.630726) (xy 69.474903 -96.595011) (xy 69.520777 -96.565524) (xy 69.570381 -96.542865)
			(xy 69.622705 -96.527495) (xy 69.676683 -96.519728) (xy 69.70395 -96.519238) (xy 69.731221 -96.519678)
			(xy 69.785206 -96.527446) (xy 69.837536 -96.542818) (xy 69.887147 -96.56548) (xy 69.933027 -96.594971)
			(xy 69.974244 -96.630691) (xy 70.009959 -96.671913) (xy 70.039444 -96.717797) (xy 70.062099 -96.767411)
			(xy 70.077464 -96.819743) (xy 70.085226 -96.873729) (xy 70.085712 -96.901) (xy 70.085265 -96.926613)
			(xy 70.078376 -96.977374) (xy 70.06475 -97.026754) (xy 70.044631 -97.073864) (xy 70.031864 -97.096072)
			(xy 70.028816 -97.100898) (xy 70.025514 -97.111312) (xy 70.024498 -97.120202) (xy 70.024244 -97.125536)
			(xy 70.024244 -97.31883) (xy 70.030726 -97.329516) (xy 70.051512 -97.343352) (xy 70.063868 -97.345246)
			(xy 70.106794 -97.345246) (xy 70.106794 -97.3455) (xy 70.339966 -97.3455) (xy 70.364858 -97.329244)
			(xy 70.371208 -97.315528) (xy 70.375527 -97.306775) (xy 70.389579 -97.293245) (xy 70.407681 -97.285975)
			(xy 70.417436 -97.285556) (xy 70.634098 -97.285556) (xy 70.658754 -97.286204) (xy 70.706891 -97.296911)
			(xy 70.751572 -97.317775) (xy 70.771512 -97.332292) (xy 70.778291 -97.337056) (xy 70.793968 -97.342381)
			(xy 70.802246 -97.342706) (xy 71.01459 -97.342706) (xy 71.020806 -97.338968) (xy 71.030989 -97.328645)
			(xy 71.034656 -97.322386) (xy 71.034656 -96.681544) (xy 71.035089 -96.671475) (xy 71.042803 -96.652877)
			(xy 71.049642 -96.645476) (xy 71.607426 -96.087692) (xy 71.614822 -96.080847) (xy 71.633424 -96.07313)
			(xy 71.643494 -96.072706) (xy 71.824088 -96.072706) (xy 71.82993 -96.072452) (xy 71.840913 -96.070636)
			(xy 71.859888 -96.05905) (xy 71.866506 -96.0501) (xy 71.870316 -96.042988) (xy 71.912226 -95.951802)
			(xy 71.908162 -95.922592) (xy 71.898256 -95.911162) (xy 71.867907 -95.875014) (xy 71.812927 -95.798286)
			(xy 71.764938 -95.717004) (xy 71.724313 -95.631801) (xy 71.691369 -95.543345) (xy 71.666365 -95.452325)
			(xy 71.649495 -95.359453) (xy 71.640891 -95.265454) (xy 71.64062 -95.171062) (xy 71.648685 -95.077015)
			(xy 71.665023 -94.984048) (xy 71.689505 -94.892886) (xy 71.721941 -94.804242) (xy 71.741538 -94.761304)
			(xy 71.746364 -94.75089) (xy 71.746364 -94.717362) (xy 71.745856 -94.713552) (xy 71.743316 -94.703646)
			(xy 71.73849 -94.69374) (xy 71.698104 -94.629224) (xy 71.691246 -94.618048) (xy 71.668132 -94.605348)
			(xy 70.03034 -94.605348) (xy 69.98689 -94.604783) (xy 69.900361 -94.596769) (xy 69.81494 -94.580804)
			(xy 69.731357 -94.557026) (xy 69.650324 -94.525637) (xy 69.572533 -94.486904) (xy 69.498648 -94.44116)
			(xy 69.429299 -94.388793) (xy 69.365078 -94.33025) (xy 69.306533 -94.266031) (xy 69.254163 -94.196685)
			(xy 69.208415 -94.122802) (xy 69.169679 -94.045013) (xy 69.138287 -93.963981) (xy 69.114505 -93.880399)
			(xy 69.098537 -93.794979) (xy 69.090518 -93.70845) (xy 54.794404 -93.70845) (xy 54.794404 -98.43516)
			(xy 54.794471 -98.439168) (xy 54.795743 -98.447083) (xy 54.796944 -98.450908) (xy 54.800754 -98.462846)
			(xy 54.817518 -98.47961) (xy 54.828948 -98.48342) (xy 54.855249 -98.492859) (xy 54.904983 -98.518336)
			(xy 54.95047 -98.550791) (xy 54.99074 -98.589531) (xy 55.024931 -98.633729) (xy 55.052313 -98.682439)
			(xy 55.072302 -98.73462) (xy 55.084469 -98.789158) (xy 55.088555 -98.844888) (xy 55.084473 -98.900617)
			(xy 55.072309 -98.955156) (xy 55.052324 -99.007339) (xy 55.024945 -99.056051) (xy 54.990756 -99.10025)
			(xy 54.950489 -99.138993) (xy 54.905003 -99.171452) (xy 54.855272 -99.196932) (xy 54.828948 -99.206304)
			(xy 54.813454 -99.211638) (xy 54.794404 -99.238054) (xy 54.794404 -99.750372) (xy 57.5978 -99.750372)
			(xy 57.601871 -99.69475) (xy 57.613997 -99.640313) (xy 57.63392 -99.588222) (xy 57.661216 -99.539587)
			(xy 57.695302 -99.495444) (xy 57.735451 -99.456735) (xy 57.780809 -99.424284) (xy 57.830409 -99.398783)
			(xy 57.883193 -99.380776) (xy 57.938036 -99.370646) (xy 57.99377 -99.368609) (xy 58.049207 -99.374709)
			(xy 58.103164 -99.388815) (xy 58.154493 -99.410627) (xy 58.202099 -99.439681) (xy 58.244967 -99.475356)
			(xy 58.282184 -99.516893) (xy 58.312957 -99.563406) (xy 58.336629 -99.613903) (xy 58.352697 -99.66731)
			(xy 58.360817 -99.722486) (xy 58.361326 -99.750372) (xy 58.360817 -99.778258) (xy 58.352697 -99.833434)
			(xy 58.336629 -99.886841) (xy 58.312957 -99.937338) (xy 58.282184 -99.983851) (xy 58.244967 -100.025388)
			(xy 58.202099 -100.061063) (xy 58.154493 -100.090117) (xy 58.103164 -100.111929) (xy 58.049207 -100.126035)
			(xy 57.99377 -100.132135) (xy 57.938036 -100.130098) (xy 57.883193 -100.119968) (xy 57.830409 -100.101961)
			(xy 57.780809 -100.07646) (xy 57.735451 -100.044009) (xy 57.695302 -100.0053) (xy 57.661216 -99.961157)
			(xy 57.63392 -99.912522) (xy 57.613997 -99.860431) (xy 57.601871 -99.805994) (xy 57.5978 -99.750372)
			(xy 54.794404 -99.750372) (xy 54.794404 -100.235258) (xy 54.794471 -100.239266) (xy 54.795742 -100.247181)
			(xy 54.796944 -100.251006) (xy 54.800754 -100.262944) (xy 54.817518 -100.279708) (xy 54.828948 -100.283518)
			(xy 54.85525 -100.292957) (xy 54.904983 -100.318434) (xy 54.950471 -100.350889) (xy 54.990741 -100.38963)
			(xy 55.024932 -100.433827) (xy 55.052315 -100.482537) (xy 55.072304 -100.534719) (xy 55.084471 -100.589257)
			(xy 55.088557 -100.644987) (xy 55.084475 -100.700717) (xy 55.072311 -100.755256) (xy 55.052326 -100.807439)
			(xy 55.024946 -100.856151) (xy 54.990758 -100.900351) (xy 54.95049 -100.939094) (xy 54.905005 -100.971553)
			(xy 54.855273 -100.997033) (xy 54.828948 -101.006402) (xy 54.813454 -101.011736) (xy 54.794404 -101.038152)
			(xy 54.794404 -101.782372) (xy 57.5978 -101.782372) (xy 57.601871 -101.72675) (xy 57.613997 -101.672313)
			(xy 57.63392 -101.620222) (xy 57.661216 -101.571587) (xy 57.695302 -101.527444) (xy 57.735451 -101.488735)
			(xy 57.780809 -101.456284) (xy 57.830409 -101.430783) (xy 57.883193 -101.412776) (xy 57.938036 -101.402646)
			(xy 57.99377 -101.400609) (xy 58.049207 -101.406709) (xy 58.103164 -101.420815) (xy 58.154493 -101.442627)
			(xy 58.202099 -101.471681) (xy 58.244967 -101.507356) (xy 58.282184 -101.548893) (xy 58.312957 -101.595406)
			(xy 58.336629 -101.645903) (xy 58.352697 -101.69931) (xy 58.360817 -101.754486) (xy 58.361326 -101.782372)
			(xy 58.360817 -101.810258) (xy 58.352697 -101.865434) (xy 58.336629 -101.918841) (xy 58.312957 -101.969338)
			(xy 58.282184 -102.015851) (xy 58.244967 -102.057388) (xy 58.202099 -102.093063) (xy 58.154493 -102.122117)
			(xy 58.103164 -102.143929) (xy 58.049207 -102.158035) (xy 57.99377 -102.164135) (xy 57.938036 -102.162098)
			(xy 57.883193 -102.151968) (xy 57.830409 -102.133961) (xy 57.780809 -102.10846) (xy 57.735451 -102.076009)
			(xy 57.695302 -102.0373) (xy 57.661216 -101.993157) (xy 57.63392 -101.944522) (xy 57.613997 -101.892431)
			(xy 57.601871 -101.837994) (xy 57.5978 -101.782372) (xy 54.794404 -101.782372) (xy 54.794404 -102.035102)
			(xy 54.794474 -102.03911) (xy 54.795753 -102.047023) (xy 54.796944 -102.05085) (xy 54.800754 -102.062788)
			(xy 54.817518 -102.079552) (xy 54.828948 -102.083362) (xy 54.855246 -102.092801) (xy 54.904973 -102.118277)
			(xy 54.950455 -102.15073) (xy 54.990719 -102.189468) (xy 55.024905 -102.233662) (xy 55.052283 -102.282368)
			(xy 55.072268 -102.334545) (xy 55.084432 -102.389078) (xy 55.088515 -102.444801) (xy 55.084431 -102.500525)
			(xy 55.072267 -102.555058) (xy 55.052282 -102.607235) (xy 55.024904 -102.65594) (xy 54.990717 -102.700134)
			(xy 54.950453 -102.738871) (xy 54.904971 -102.771325) (xy 54.855244 -102.7968) (xy 54.828948 -102.806246)
			(xy 54.813454 -102.81158) (xy 54.801367 -102.82834) (xy 57.5226 -102.82834) (xy 57.5226 -102.768404)
			(xy 57.530423 -102.708982) (xy 57.545936 -102.651089) (xy 57.568872 -102.595716) (xy 57.598839 -102.54381)
			(xy 57.635326 -102.49626) (xy 57.677706 -102.45388) (xy 57.725256 -102.417393) (xy 57.777162 -102.387426)
			(xy 57.832535 -102.36449) (xy 57.890428 -102.348977) (xy 57.94985 -102.341154) (xy 58.009786 -102.341154)
			(xy 58.069208 -102.348977) (xy 58.127101 -102.36449) (xy 58.182474 -102.387426) (xy 58.23438 -102.417393)
			(xy 58.28193 -102.45388) (xy 58.297996 -102.469946) (xy 66.855576 -102.469946) (xy 66.855576 -102.41001)
			(xy 66.863399 -102.350588) (xy 66.878912 -102.292695) (xy 66.901848 -102.237322) (xy 66.931815 -102.185416)
			(xy 66.968302 -102.137866) (xy 67.010682 -102.095486) (xy 67.058232 -102.058999) (xy 67.110138 -102.029032)
			(xy 67.165511 -102.006096) (xy 67.223404 -101.990583) (xy 67.282826 -101.98276) (xy 67.342762 -101.98276)
			(xy 67.402184 -101.990583) (xy 67.460077 -102.006096) (xy 67.51545 -102.029032) (xy 67.567356 -102.058999)
			(xy 67.614906 -102.095486) (xy 67.657286 -102.137866) (xy 67.693773 -102.185416) (xy 67.72374 -102.237322)
			(xy 67.746676 -102.292695) (xy 67.762189 -102.350588) (xy 67.770012 -102.41001) (xy 67.770502 -102.439978)
			(xy 67.770012 -102.469946) (xy 67.762189 -102.529368) (xy 67.746676 -102.587261) (xy 67.72374 -102.642634)
			(xy 67.693773 -102.69454) (xy 67.657286 -102.74209) (xy 67.614906 -102.78447) (xy 67.567356 -102.820957)
			(xy 67.51545 -102.850924) (xy 67.460077 -102.87386) (xy 67.402184 -102.889373) (xy 67.342762 -102.897196)
			(xy 67.282826 -102.897196) (xy 67.223404 -102.889373) (xy 67.165511 -102.87386) (xy 67.110138 -102.850924)
			(xy 67.058232 -102.820957) (xy 67.010682 -102.78447) (xy 66.968302 -102.74209) (xy 66.931815 -102.69454)
			(xy 66.901848 -102.642634) (xy 66.878912 -102.587261) (xy 66.863399 -102.529368) (xy 66.855576 -102.469946)
			(xy 58.297996 -102.469946) (xy 58.32431 -102.49626) (xy 58.360797 -102.54381) (xy 58.390764 -102.595716)
			(xy 58.4137 -102.651089) (xy 58.429213 -102.708982) (xy 58.437036 -102.768404) (xy 58.437526 -102.798372)
			(xy 58.437036 -102.82834) (xy 58.429213 -102.887762) (xy 58.4137 -102.945655) (xy 58.390764 -103.001028)
			(xy 58.360797 -103.052934) (xy 58.32431 -103.100484) (xy 58.28193 -103.142864) (xy 58.23438 -103.179351)
			(xy 58.182474 -103.209318) (xy 58.127101 -103.232254) (xy 58.069208 -103.247767) (xy 58.009786 -103.25559)
			(xy 57.94985 -103.25559) (xy 57.890428 -103.247767) (xy 57.832535 -103.232254) (xy 57.777162 -103.209318)
			(xy 57.725256 -103.179351) (xy 57.677706 -103.142864) (xy 57.635326 -103.100484) (xy 57.598839 -103.052934)
			(xy 57.568872 -103.001028) (xy 57.545936 -102.945655) (xy 57.530423 -102.887762) (xy 57.5226 -102.82834)
			(xy 54.801367 -102.82834) (xy 54.794404 -102.837996) (xy 54.794404 -103.814372) (xy 57.5978 -103.814372)
			(xy 57.601871 -103.75875) (xy 57.613997 -103.704313) (xy 57.63392 -103.652222) (xy 57.661216 -103.603587)
			(xy 57.695302 -103.559444) (xy 57.735451 -103.520735) (xy 57.780809 -103.488284) (xy 57.830409 -103.462783)
			(xy 57.883193 -103.444776) (xy 57.938036 -103.434646) (xy 57.99377 -103.432609) (xy 58.049207 -103.438709)
			(xy 58.103164 -103.452815) (xy 58.154493 -103.474627) (xy 58.202099 -103.503681) (xy 58.244967 -103.539356)
			(xy 58.282184 -103.580893) (xy 58.312957 -103.627406) (xy 58.336629 -103.677903) (xy 58.352697 -103.73131)
			(xy 58.360817 -103.786486) (xy 58.361326 -103.814372) (xy 58.360817 -103.842258) (xy 58.352697 -103.897434)
			(xy 58.336629 -103.950841) (xy 58.312957 -104.001338) (xy 58.282184 -104.047851) (xy 58.244967 -104.089388)
			(xy 58.202099 -104.125063) (xy 58.154493 -104.154117) (xy 58.103164 -104.175929) (xy 58.049207 -104.190035)
			(xy 57.99377 -104.196135) (xy 57.938036 -104.194098) (xy 57.883193 -104.183968) (xy 57.830409 -104.165961)
			(xy 57.780809 -104.14046) (xy 57.735451 -104.108009) (xy 57.695302 -104.0693) (xy 57.661216 -104.025157)
			(xy 57.63392 -103.976522) (xy 57.613997 -103.924431) (xy 57.601871 -103.869994) (xy 57.5978 -103.814372)
			(xy 54.794404 -103.814372) (xy 54.794404 -103.8352) (xy 54.794474 -103.839208) (xy 54.795752 -103.847121)
			(xy 54.796944 -103.850948) (xy 54.800754 -103.862886) (xy 54.817518 -103.87965) (xy 54.828948 -103.88346)
			(xy 54.855247 -103.892899) (xy 54.904974 -103.918375) (xy 54.950456 -103.950828) (xy 54.99072 -103.989566)
			(xy 55.024907 -104.03376) (xy 55.052285 -104.082466) (xy 55.072269 -104.134643) (xy 55.084434 -104.189177)
			(xy 55.088163 -104.240076) (xy 66.930776 -104.240076) (xy 66.934847 -104.184454) (xy 66.946973 -104.130017)
			(xy 66.966896 -104.077926) (xy 66.994192 -104.029291) (xy 67.028278 -103.985148) (xy 67.068427 -103.946439)
			(xy 67.113785 -103.913988) (xy 67.163385 -103.888487) (xy 67.216169 -103.87048) (xy 67.271012 -103.86035)
			(xy 67.326746 -103.858313) (xy 67.382183 -103.864413) (xy 67.43614 -103.878519) (xy 67.487469 -103.900331)
			(xy 67.535075 -103.929385) (xy 67.577943 -103.96506) (xy 67.61516 -104.006597) (xy 67.645933 -104.05311)
			(xy 67.669605 -104.103607) (xy 67.685673 -104.157014) (xy 67.693793 -104.21219) (xy 67.694302 -104.240076)
			(xy 73.912728 -104.240076) (xy 73.916801 -104.184417) (xy 73.928936 -104.129944) (xy 73.948872 -104.077818)
			(xy 73.976186 -104.02915) (xy 74.010294 -103.984978) (xy 74.050471 -103.946243) (xy 74.095859 -103.913771)
			(xy 74.145491 -103.888253) (xy 74.198311 -103.870234) (xy 74.25319 -103.860097) (xy 74.308961 -103.858059)
			(xy 74.364435 -103.864162) (xy 74.418428 -103.878278) (xy 74.469791 -103.900105) (xy 74.517429 -103.929178)
			(xy 74.560325 -103.964877) (xy 74.597567 -104.006441) (xy 74.628361 -104.052985) (xy 74.652049 -104.103516)
			(xy 74.668127 -104.156958) (xy 74.676253 -104.212172) (xy 74.676762 -104.240076) (xy 74.676253 -104.26798)
			(xy 74.668127 -104.323194) (xy 74.652049 -104.376636) (xy 74.628361 -104.427167) (xy 74.597567 -104.473711)
			(xy 74.560325 -104.515275) (xy 74.517429 -104.550974) (xy 74.469791 -104.580047) (xy 74.418428 -104.601874)
			(xy 74.364435 -104.61599) (xy 74.308961 -104.622093) (xy 74.25319 -104.620055) (xy 74.198311 -104.609918)
			(xy 74.145491 -104.591899) (xy 74.095859 -104.566381) (xy 74.050471 -104.533909) (xy 74.010294 -104.495174)
			(xy 73.976186 -104.451002) (xy 73.948872 -104.402334) (xy 73.928936 -104.350208) (xy 73.916801 -104.295735)
			(xy 73.912728 -104.240076) (xy 67.694302 -104.240076) (xy 67.693793 -104.267962) (xy 67.685673 -104.323138)
			(xy 67.669605 -104.376545) (xy 67.645933 -104.427042) (xy 67.61516 -104.473555) (xy 67.577943 -104.515092)
			(xy 67.535075 -104.550767) (xy 67.487469 -104.579821) (xy 67.43614 -104.601633) (xy 67.382183 -104.615739)
			(xy 67.326746 -104.621839) (xy 67.271012 -104.619802) (xy 67.216169 -104.609672) (xy 67.163385 -104.591665)
			(xy 67.113785 -104.566164) (xy 67.068427 -104.533713) (xy 67.028278 -104.495004) (xy 66.994192 -104.450861)
			(xy 66.966896 -104.402226) (xy 66.946973 -104.350135) (xy 66.934847 -104.295698) (xy 66.930776 -104.240076)
			(xy 55.088163 -104.240076) (xy 55.088517 -104.244901) (xy 55.084433 -104.300625) (xy 55.072269 -104.355158)
			(xy 55.052284 -104.407335) (xy 55.024906 -104.456041) (xy 54.990719 -104.500235) (xy 54.950455 -104.538972)
			(xy 54.904973 -104.571426) (xy 54.855245 -104.596902) (xy 54.828948 -104.606344) (xy 54.813454 -104.611678)
			(xy 54.794404 -104.638094) (xy 54.794404 -104.86034) (xy 57.5226 -104.86034) (xy 57.5226 -104.800404)
			(xy 57.530423 -104.740982) (xy 57.545936 -104.683089) (xy 57.568872 -104.627716) (xy 57.598839 -104.57581)
			(xy 57.635326 -104.52826) (xy 57.677706 -104.48588) (xy 57.725256 -104.449393) (xy 57.777162 -104.419426)
			(xy 57.832535 -104.39649) (xy 57.890428 -104.380977) (xy 57.94985 -104.373154) (xy 58.009786 -104.373154)
			(xy 58.069208 -104.380977) (xy 58.127101 -104.39649) (xy 58.182474 -104.419426) (xy 58.23438 -104.449393)
			(xy 58.28193 -104.48588) (xy 58.32431 -104.52826) (xy 58.360797 -104.57581) (xy 58.390764 -104.627716)
			(xy 58.4137 -104.683089) (xy 58.429213 -104.740982) (xy 58.437036 -104.800404) (xy 58.437526 -104.830372)
			(xy 58.437036 -104.86034) (xy 58.429213 -104.919762) (xy 58.4137 -104.977655) (xy 58.390764 -105.033028)
			(xy 58.360797 -105.084934) (xy 58.32431 -105.132484) (xy 58.28193 -105.174864) (xy 58.23438 -105.211351)
			(xy 58.182474 -105.241318) (xy 58.127101 -105.264254) (xy 58.069208 -105.279767) (xy 58.009786 -105.28759)
			(xy 57.94985 -105.28759) (xy 57.890428 -105.279767) (xy 57.832535 -105.264254) (xy 57.777162 -105.241318)
			(xy 57.725256 -105.211351) (xy 57.677706 -105.174864) (xy 57.635326 -105.132484) (xy 57.598839 -105.084934)
			(xy 57.568872 -105.033028) (xy 57.545936 -104.977655) (xy 57.530423 -104.919762) (xy 57.5226 -104.86034)
			(xy 54.794404 -104.86034) (xy 54.794404 -105.635044) (xy 54.794469 -105.639053) (xy 54.795739 -105.646968)
			(xy 54.796944 -105.650792) (xy 54.800754 -105.66273) (xy 54.817518 -105.679494) (xy 54.828948 -105.683304)
			(xy 54.855243 -105.692742) (xy 54.904964 -105.718218) (xy 54.95044 -105.750669) (xy 54.990698 -105.789405)
			(xy 55.02488 -105.833595) (xy 55.052253 -105.882297) (xy 55.072234 -105.934469) (xy 55.084394 -105.988997)
			(xy 55.088476 -106.044715) (xy 55.08439 -106.100433) (xy 55.072225 -106.154959) (xy 55.05224 -106.20713)
			(xy 55.024863 -106.25583) (xy 54.990679 -106.300017) (xy 54.950417 -106.338749) (xy 54.904939 -106.371198)
			(xy 54.855216 -106.396669) (xy 54.828948 -106.406188) (xy 54.813454 -106.411522) (xy 54.794404 -106.437938)
			(xy 54.794404 -107.435142) (xy 54.794469 -107.439151) (xy 54.795739 -107.447067) (xy 54.796944 -107.45089)
			(xy 54.800754 -107.462828) (xy 54.817518 -107.479592) (xy 54.828948 -107.483402) (xy 54.855243 -107.49284)
			(xy 54.904965 -107.518316) (xy 54.950441 -107.550768) (xy 54.990699 -107.589503) (xy 55.024881 -107.633694)
			(xy 55.052254 -107.682395) (xy 55.072235 -107.734568) (xy 55.084396 -107.789096) (xy 55.088478 -107.844814)
			(xy 55.084392 -107.900532) (xy 55.072227 -107.955059) (xy 55.052242 -108.00723) (xy 55.024865 -108.05593)
			(xy 54.990681 -108.100118) (xy 54.950419 -108.13885) (xy 54.904941 -108.171299) (xy 54.855217 -108.196771)
			(xy 54.828948 -108.206286) (xy 54.813454 -108.21162) (xy 54.794404 -108.238036) (xy 54.794404 -109.23524)
			(xy 54.794469 -109.239249) (xy 54.795738 -109.247165) (xy 54.796944 -109.250988) (xy 54.800754 -109.262926)
			(xy 54.817518 -109.27969) (xy 54.828948 -109.2835) (xy 54.855244 -109.292938) (xy 54.904965 -109.318414)
			(xy 54.950441 -109.350866) (xy 54.9907 -109.389601) (xy 55.024882 -109.433792) (xy 55.052256 -109.482494)
			(xy 55.072237 -109.534667) (xy 55.084398 -109.589195) (xy 55.088479 -109.644914) (xy 55.084394 -109.700632)
			(xy 55.072229 -109.755159) (xy 55.052244 -109.80733) (xy 55.024867 -109.856031) (xy 54.990682 -109.900219)
			(xy 54.950421 -109.938952) (xy 54.904942 -109.9714) (xy 54.855219 -109.996872) (xy 54.828948 -110.006384)
			(xy 54.813454 -110.011718) (xy 54.794404 -110.038134) (xy 54.794404 -111.035338) (xy 54.794469 -111.039347)
			(xy 54.795738 -111.047263) (xy 54.796944 -111.051086) (xy 54.800754 -111.063024) (xy 54.817518 -111.079788)
			(xy 54.828948 -111.083598) (xy 54.855244 -111.093036) (xy 54.904966 -111.118512) (xy 54.950442 -111.150964)
			(xy 54.990701 -111.189699) (xy 55.024883 -111.23389) (xy 55.052257 -111.282593) (xy 55.072238 -111.334766)
			(xy 55.0844 -111.389294) (xy 55.088481 -111.445013) (xy 55.084396 -111.500731) (xy 55.072231 -111.555259)
			(xy 55.052246 -111.607431) (xy 55.024869 -111.656131) (xy 54.990684 -111.70032) (xy 54.950422 -111.739053)
			(xy 54.904944 -111.771502) (xy 54.85522 -111.796974) (xy 54.828948 -111.806482) (xy 54.813454 -111.811816)
			(xy 54.794404 -111.838232) (xy 54.794404 -115.576096) (xy 55.847232 -115.576096) (xy 55.851303 -115.520474)
			(xy 55.863429 -115.466037) (xy 55.883352 -115.413946) (xy 55.910648 -115.365311) (xy 55.944734 -115.321168)
			(xy 55.984883 -115.282459) (xy 56.030241 -115.250008) (xy 56.079841 -115.224507) (xy 56.132625 -115.2065)
			(xy 56.187468 -115.19637) (xy 56.243202 -115.194333) (xy 56.298639 -115.200433) (xy 56.352596 -115.214539)
			(xy 56.403925 -115.236351) (xy 56.451531 -115.265405) (xy 56.494399 -115.30108) (xy 56.531616 -115.342617)
			(xy 56.562389 -115.38913) (xy 56.586061 -115.439627) (xy 56.602129 -115.493034) (xy 56.610249 -115.54821)
			(xy 56.610758 -115.576096) (xy 56.610249 -115.603982) (xy 56.602129 -115.659158) (xy 56.586061 -115.712565)
			(xy 56.562389 -115.763062) (xy 56.531616 -115.809575) (xy 56.494399 -115.851112) (xy 56.451531 -115.886787)
			(xy 56.403925 -115.915841) (xy 56.389328 -115.922044) (xy 63.203326 -115.922044) (xy 63.207397 -115.866422)
			(xy 63.219523 -115.811985) (xy 63.239446 -115.759894) (xy 63.266742 -115.711259) (xy 63.300828 -115.667116)
			(xy 63.340977 -115.628407) (xy 63.386335 -115.595956) (xy 63.435935 -115.570455) (xy 63.488719 -115.552448)
			(xy 63.543562 -115.542318) (xy 63.599296 -115.540281) (xy 63.654733 -115.546381) (xy 63.70869 -115.560487)
			(xy 63.760019 -115.582299) (xy 63.807625 -115.611353) (xy 63.850493 -115.647028) (xy 63.88771 -115.688565)
			(xy 63.918483 -115.735078) (xy 63.942155 -115.785575) (xy 63.958223 -115.838982) (xy 63.966343 -115.894158)
			(xy 63.966852 -115.922044) (xy 63.966343 -115.94993) (xy 63.958223 -116.005106) (xy 63.942155 -116.058513)
			(xy 63.918483 -116.10901) (xy 63.88771 -116.155523) (xy 63.850493 -116.19706) (xy 63.807625 -116.232735)
			(xy 63.760019 -116.261789) (xy 63.70869 -116.283601) (xy 63.654733 -116.297707) (xy 63.599296 -116.303807)
			(xy 63.543562 -116.30177) (xy 63.488719 -116.29164) (xy 63.435935 -116.273633) (xy 63.386335 -116.248132)
			(xy 63.340977 -116.215681) (xy 63.300828 -116.176972) (xy 63.266742 -116.132829) (xy 63.239446 -116.084194)
			(xy 63.219523 -116.032103) (xy 63.207397 -115.977666) (xy 63.203326 -115.922044) (xy 56.389328 -115.922044)
			(xy 56.352596 -115.937653) (xy 56.298639 -115.951759) (xy 56.243202 -115.957859) (xy 56.187468 -115.955822)
			(xy 56.132625 -115.945692) (xy 56.079841 -115.927685) (xy 56.030241 -115.902184) (xy 55.984883 -115.869733)
			(xy 55.944734 -115.831024) (xy 55.910648 -115.786881) (xy 55.883352 -115.738246) (xy 55.863429 -115.686155)
			(xy 55.851303 -115.631718) (xy 55.847232 -115.576096) (xy 54.794404 -115.576096) (xy 54.794404 -118.267988)
			(xy 55.586628 -118.267988) (xy 55.590699 -118.212366) (xy 55.602825 -118.157929) (xy 55.622748 -118.105838)
			(xy 55.650044 -118.057203) (xy 55.68413 -118.01306) (xy 55.724279 -117.974351) (xy 55.769637 -117.9419)
			(xy 55.819237 -117.916399) (xy 55.872021 -117.898392) (xy 55.926864 -117.888262) (xy 55.982598 -117.886225)
			(xy 56.038035 -117.892325) (xy 56.091992 -117.906431) (xy 56.143321 -117.928243) (xy 56.190927 -117.957297)
			(xy 56.233795 -117.992972) (xy 56.271012 -118.034509) (xy 56.301785 -118.081022) (xy 56.325457 -118.131519)
			(xy 56.341525 -118.184926) (xy 56.349645 -118.240102) (xy 56.350154 -118.267988) (xy 56.349645 -118.295874)
			(xy 56.344329 -118.331996) (xy 62.895732 -118.331996) (xy 62.899803 -118.276374) (xy 62.911929 -118.221937)
			(xy 62.931852 -118.169846) (xy 62.959148 -118.121211) (xy 62.993234 -118.077068) (xy 63.033383 -118.038359)
			(xy 63.078741 -118.005908) (xy 63.128341 -117.980407) (xy 63.181125 -117.9624) (xy 63.235968 -117.95227)
			(xy 63.291702 -117.950233) (xy 63.347139 -117.956333) (xy 63.401096 -117.970439) (xy 63.452425 -117.992251)
			(xy 63.500031 -118.021305) (xy 63.542899 -118.05698) (xy 63.580116 -118.098517) (xy 63.610889 -118.14503)
			(xy 63.634561 -118.195527) (xy 63.650629 -118.248934) (xy 63.658749 -118.30411) (xy 63.659258 -118.331996)
			(xy 63.658749 -118.359882) (xy 63.650629 -118.415058) (xy 63.634561 -118.468465) (xy 63.610889 -118.518962)
			(xy 63.580116 -118.565475) (xy 63.542899 -118.607012) (xy 63.500031 -118.642687) (xy 63.452425 -118.671741)
			(xy 63.401096 -118.693553) (xy 63.347139 -118.707659) (xy 63.291702 -118.713759) (xy 63.235968 -118.711722)
			(xy 63.181125 -118.701592) (xy 63.128341 -118.683585) (xy 63.078741 -118.658084) (xy 63.033383 -118.625633)
			(xy 62.993234 -118.586924) (xy 62.959148 -118.542781) (xy 62.931852 -118.494146) (xy 62.911929 -118.442055)
			(xy 62.899803 -118.387618) (xy 62.895732 -118.331996) (xy 56.344329 -118.331996) (xy 56.341525 -118.35105)
			(xy 56.325457 -118.404457) (xy 56.301785 -118.454954) (xy 56.271012 -118.501467) (xy 56.233795 -118.543004)
			(xy 56.190927 -118.578679) (xy 56.143321 -118.607733) (xy 56.091992 -118.629545) (xy 56.038035 -118.643651)
			(xy 55.982598 -118.649751) (xy 55.926864 -118.647714) (xy 55.872021 -118.637584) (xy 55.819237 -118.619577)
			(xy 55.769637 -118.594076) (xy 55.724279 -118.561625) (xy 55.68413 -118.522916) (xy 55.650044 -118.478773)
			(xy 55.622748 -118.430138) (xy 55.602825 -118.378047) (xy 55.590699 -118.32361) (xy 55.586628 -118.267988)
			(xy 54.794404 -118.267988) (xy 54.794404 -118.345204) (xy 54.794474 -118.349212) (xy 54.795753 -118.357124)
			(xy 54.796944 -118.360952) (xy 54.800754 -118.37289) (xy 54.817518 -118.389654) (xy 54.828948 -118.393464)
			(xy 54.855246 -118.402903) (xy 54.904973 -118.428379) (xy 54.950454 -118.460832) (xy 54.990718 -118.49957)
			(xy 55.024904 -118.543763) (xy 55.052282 -118.592469) (xy 55.072266 -118.644646) (xy 55.08443 -118.699178)
			(xy 55.088514 -118.754902) (xy 55.084429 -118.810625) (xy 55.072265 -118.865158) (xy 55.05228 -118.917334)
			(xy 55.024902 -118.96604) (xy 54.990715 -119.010233) (xy 54.950451 -119.04897) (xy 54.90497 -119.081423)
			(xy 54.855243 -119.106899) (xy 54.828948 -119.116348) (xy 54.813454 -119.121682) (xy 54.794404 -119.148098)
			(xy 54.794404 -120.145302) (xy 54.794474 -120.14931) (xy 54.795753 -120.157223) (xy 54.796944 -120.16105)
			(xy 54.800754 -120.172988) (xy 54.817518 -120.189752) (xy 54.828948 -120.193562) (xy 54.855246 -120.203001)
			(xy 54.904973 -120.228477) (xy 54.950455 -120.26093) (xy 54.990719 -120.299668) (xy 55.024905 -120.343862)
			(xy 55.052283 -120.392568) (xy 55.072268 -120.444745) (xy 55.084432 -120.499278) (xy 55.088515 -120.555001)
			(xy 55.084431 -120.610725) (xy 55.072267 -120.665258) (xy 55.052282 -120.717435) (xy 55.024904 -120.76614)
			(xy 54.990717 -120.810334) (xy 54.950453 -120.849071) (xy 54.904971 -120.881525) (xy 54.855244 -120.907)
			(xy 54.828948 -120.916446) (xy 54.813454 -120.92178) (xy 54.794404 -120.948196) (xy 54.794404 -121.945146)
			(xy 54.79447 -121.949155) (xy 54.79574 -121.95707) (xy 54.796944 -121.960894) (xy 54.800754 -121.972832)
			(xy 54.817518 -121.989596) (xy 54.828948 -121.993406) (xy 54.855243 -122.002844) (xy 54.904964 -122.02832)
			(xy 54.950439 -122.060771) (xy 54.990697 -122.099506) (xy 55.024878 -122.143697) (xy 55.052252 -122.192398)
			(xy 55.072232 -122.24457) (xy 55.084393 -122.299098) (xy 55.088474 -122.354815) (xy 55.084388 -122.410533)
			(xy 55.072223 -122.465059) (xy 55.052238 -122.51723) (xy 55.024861 -122.565929) (xy 54.990677 -122.610117)
			(xy 54.950415 -122.648848) (xy 54.904937 -122.681296) (xy 54.855215 -122.706768) (xy 54.828948 -122.71629)
			(xy 54.813454 -122.721624) (xy 54.794404 -122.74804) (xy 54.794404 -123.745244) (xy 54.794469 -123.749253)
			(xy 54.795739 -123.757168) (xy 54.796944 -123.760992) (xy 54.800754 -123.77293) (xy 54.817518 -123.789694)
			(xy 54.828948 -123.793504) (xy 54.853788 -123.802407) (xy 54.900944 -123.826087) (xy 54.94439 -123.856034)
			(xy 54.983299 -123.891679) (xy 55.01693 -123.932341) (xy 55.044642 -123.977246) (xy 55.065907 -124.025539)
			(xy 55.08032 -124.0763) (xy 55.087606 -124.128562) (xy 55.088028 -124.154946) (xy 55.087484 -124.184006)
			(xy 55.078666 -124.241453) (xy 55.061226 -124.296894) (xy 55.035568 -124.349044) (xy 55.002288 -124.396692)
			(xy 54.982618 -124.41809) (xy 54.976268 -124.424948) (xy 54.96814 -124.443998) (xy 54.96489 -124.452716)
			(xy 54.964195 -124.471295) (xy 54.970138 -124.488911) (xy 54.97576 -124.496322) (xy 54.977538 -124.498354)
			(xy 57.967635 -127.488451) (xy 69.090486 -127.488451) (xy 69.090486 -127.401549) (xy 69.098505 -127.315017)
			(xy 69.114474 -127.229594) (xy 69.138256 -127.146008) (xy 69.16965 -127.064974) (xy 69.208387 -126.987183)
			(xy 69.254137 -126.913297) (xy 69.306508 -126.843948) (xy 69.365056 -126.779727) (xy 69.429279 -126.721183)
			(xy 69.49863 -126.668814) (xy 69.572518 -126.623068) (xy 69.650311 -126.584334) (xy 69.731346 -126.552944)
			(xy 69.814933 -126.529165) (xy 69.900356 -126.513199) (xy 69.986889 -126.505185) (xy 70.03034 -126.5047)
			(xy 71.88454 -126.5047) (xy 71.927989 -126.505188) (xy 72.014516 -126.513209) (xy 72.099934 -126.52918)
			(xy 72.183514 -126.552963) (xy 72.264543 -126.584357) (xy 72.34233 -126.623094) (xy 72.416211 -126.668841)
			(xy 72.485556 -126.721211) (xy 72.549773 -126.779755) (xy 72.608315 -126.843975) (xy 72.660681 -126.913322)
			(xy 72.706426 -126.987205) (xy 72.745159 -127.064994) (xy 72.776549 -127.146024) (xy 72.800329 -127.229605)
			(xy 72.816296 -127.315024) (xy 72.824314 -127.401551) (xy 72.824314 -127.488449) (xy 72.816296 -127.574976)
			(xy 72.800329 -127.660395) (xy 72.776549 -127.743976) (xy 72.745159 -127.825006) (xy 72.706426 -127.902795)
			(xy 72.660681 -127.976678) (xy 72.608315 -128.046025) (xy 72.549773 -128.110245) (xy 72.485556 -128.168789)
			(xy 72.416211 -128.221159) (xy 72.34233 -128.266906) (xy 72.264543 -128.305643) (xy 72.183514 -128.337037)
			(xy 72.099934 -128.36082) (xy 72.014516 -128.376791) (xy 71.927989 -128.384812) (xy 71.88454 -128.385316)
			(xy 70.03034 -128.385316) (xy 69.986889 -128.384815) (xy 69.900356 -128.376801) (xy 69.814933 -128.360835)
			(xy 69.731346 -128.337056) (xy 69.650311 -128.305666) (xy 69.572518 -128.266932) (xy 69.49863 -128.221186)
			(xy 69.429279 -128.168817) (xy 69.365056 -128.110273) (xy 69.306508 -128.046052) (xy 69.254137 -127.976703)
			(xy 69.208387 -127.902817) (xy 69.16965 -127.825026) (xy 69.138256 -127.743992) (xy 69.114474 -127.660406)
			(xy 69.098505 -127.574983) (xy 69.090486 -127.488451) (xy 57.967635 -127.488451) (xy 61.25337 -130.774186)
			(xy 61.253878 -130.774694) (xy 61.261262 -130.781268) (xy 61.279561 -130.788703) (xy 61.289438 -130.789172)
		)
		(stroke
			(width 0)
			(type solid)
		)
		(fill yes)
		(layer "B.Cu")
		(net "P3V3_NIC1")
	)
	(gr_poly
		(pts
			(xy 14.22019 -65.811908) (xy 14.230213 -65.81149) (xy 14.248735 -65.803822) (xy 14.262912 -65.78965)
			(xy 14.270587 -65.771131) (xy 14.27099 -65.761108) (xy 14.27099 -65.75552) (xy 14.27148 -65.725552)
			(xy 14.279303 -65.66613) (xy 14.294816 -65.608237) (xy 14.317752 -65.552864) (xy 14.347719 -65.500958)
			(xy 14.384206 -65.453408) (xy 14.426586 -65.411028) (xy 14.474136 -65.374541) (xy 14.526042 -65.344574)
			(xy 14.581415 -65.321638) (xy 14.639308 -65.306125) (xy 14.69873 -65.298302) (xy 14.758666 -65.298302)
			(xy 14.818088 -65.306125) (xy 14.875981 -65.321638) (xy 14.931354 -65.344574) (xy 14.98326 -65.374541)
			(xy 15.03081 -65.411028) (xy 15.07319 -65.453408) (xy 15.109677 -65.500958) (xy 15.139644 -65.552864)
			(xy 15.16258 -65.608237) (xy 15.178093 -65.66613) (xy 15.185916 -65.725552) (xy 15.186406 -65.75552)
			(xy 15.186406 -65.761108) (xy 15.186896 -65.771114) (xy 15.194557 -65.789602) (xy 15.20871 -65.803751)
			(xy 15.2272 -65.811407) (xy 15.237206 -65.811908) (xy 40.220138 -65.811908) (xy 40.230141 -65.811413)
			(xy 40.248621 -65.803747) (xy 40.262764 -65.789596) (xy 40.270419 -65.771111) (xy 40.270938 -65.761108)
			(xy 40.270938 -65.75552) (xy 40.271428 -65.725552) (xy 40.279251 -65.66613) (xy 40.294764 -65.608237)
			(xy 40.3177 -65.552864) (xy 40.347667 -65.500958) (xy 40.384154 -65.453408) (xy 40.426534 -65.411028)
			(xy 40.474084 -65.374541) (xy 40.52599 -65.344574) (xy 40.581363 -65.321638) (xy 40.639256 -65.306125)
			(xy 40.698678 -65.298302) (xy 40.758614 -65.298302) (xy 40.818036 -65.306125) (xy 40.875929 -65.321638)
			(xy 40.931302 -65.344574) (xy 40.983208 -65.374541) (xy 41.030758 -65.411028) (xy 41.073138 -65.453408)
			(xy 41.109625 -65.500958) (xy 41.139592 -65.552864) (xy 41.162528 -65.608237) (xy 41.178041 -65.66613)
			(xy 41.185864 -65.725552) (xy 41.186354 -65.75552) (xy 41.186354 -65.761108) (xy 41.186843 -65.771118)
			(xy 41.194502 -65.789615) (xy 41.208653 -65.803777) (xy 41.227144 -65.81145) (xy 41.237154 -65.811908)
			(xy 66.296286 -65.811908) (xy 66.30631 -65.811491) (xy 66.324833 -65.803824) (xy 66.339011 -65.789651)
			(xy 66.346687 -65.771132) (xy 66.347086 -65.761108) (xy 66.347086 -65.75552) (xy 66.347572 -65.728269)
			(xy 66.355328 -65.674321) (xy 66.370683 -65.622026) (xy 66.393325 -65.572449) (xy 66.422791 -65.526599)
			(xy 66.458482 -65.485408) (xy 66.499673 -65.449717) (xy 66.545523 -65.420251) (xy 66.5951 -65.397609)
			(xy 66.647395 -65.382254) (xy 66.701343 -65.374498) (xy 66.755845 -65.374498) (xy 66.809793 -65.382254)
			(xy 66.862088 -65.397609) (xy 66.911665 -65.420251) (xy 66.957515 -65.449717) (xy 66.998706 -65.485408)
			(xy 67.034397 -65.526599) (xy 67.063863 -65.572449) (xy 67.086505 -65.622026) (xy 67.10186 -65.674321)
			(xy 67.109616 -65.728269) (xy 67.110102 -65.75552) (xy 67.110102 -65.761108) (xy 67.110592 -65.771114)
			(xy 67.118253 -65.789603) (xy 67.132405 -65.803753) (xy 67.150895 -65.81141) (xy 67.160902 -65.811908)
			(xy 92.296234 -65.811908) (xy 92.306238 -65.811414) (xy 92.324719 -65.803749) (xy 92.338863 -65.789597)
			(xy 92.346519 -65.771112) (xy 92.347034 -65.761108) (xy 92.347034 -65.75552) (xy 92.34752 -65.728269)
			(xy 92.355276 -65.674321) (xy 92.370631 -65.622026) (xy 92.393273 -65.572449) (xy 92.422739 -65.526599)
			(xy 92.45843 -65.485408) (xy 92.499621 -65.449717) (xy 92.545471 -65.420251) (xy 92.595048 -65.397609)
			(xy 92.647343 -65.382254) (xy 92.701291 -65.374498) (xy 92.755793 -65.374498) (xy 92.809741 -65.382254)
			(xy 92.862036 -65.397609) (xy 92.911613 -65.420251) (xy 92.957463 -65.449717) (xy 92.998654 -65.485408)
			(xy 93.034345 -65.526599) (xy 93.063811 -65.572449) (xy 93.086453 -65.622026) (xy 93.101808 -65.674321)
			(xy 93.109564 -65.728269) (xy 93.11005 -65.75552) (xy 93.11005 -65.761108) (xy 93.110539 -65.771118)
			(xy 93.118198 -65.789616) (xy 93.132349 -65.803778) (xy 93.15084 -65.811453) (xy 93.16085 -65.811908)
			(xy 130.320288 -65.811908) (xy 130.330311 -65.811491) (xy 130.348834 -65.803823) (xy 130.363012 -65.789651)
			(xy 130.370687 -65.771131) (xy 130.371088 -65.761108) (xy 130.371088 -65.75552) (xy 130.371578 -65.725552)
			(xy 130.379401 -65.66613) (xy 130.394914 -65.608237) (xy 130.41785 -65.552864) (xy 130.447817 -65.500958)
			(xy 130.484304 -65.453408) (xy 130.526684 -65.411028) (xy 130.574234 -65.374541) (xy 130.62614 -65.344574)
			(xy 130.681513 -65.321638) (xy 130.739406 -65.306125) (xy 130.798828 -65.298302) (xy 130.858764 -65.298302)
			(xy 130.918186 -65.306125) (xy 130.976079 -65.321638) (xy 131.031452 -65.344574) (xy 131.083358 -65.374541)
			(xy 131.130908 -65.411028) (xy 131.173288 -65.453408) (xy 131.209775 -65.500958) (xy 131.239742 -65.552864)
			(xy 131.262678 -65.608237) (xy 131.278191 -65.66613) (xy 131.286014 -65.725552) (xy 131.286504 -65.75552)
			(xy 131.286504 -65.761108) (xy 131.286994 -65.771114) (xy 131.294655 -65.789603) (xy 131.308807 -65.803752)
			(xy 131.327298 -65.811409) (xy 131.337304 -65.811908) (xy 156.396436 -65.811908) (xy 156.406439 -65.811414)
			(xy 156.42492 -65.803748) (xy 156.439064 -65.789597) (xy 156.446719 -65.771112) (xy 156.447236 -65.761108)
			(xy 156.447236 -65.75552) (xy 156.447722 -65.728269) (xy 156.455478 -65.674321) (xy 156.470833 -65.622026)
			(xy 156.493475 -65.572449) (xy 156.522941 -65.526599) (xy 156.558632 -65.485408) (xy 156.599823 -65.449717)
			(xy 156.645673 -65.420251) (xy 156.69525 -65.397609) (xy 156.747545 -65.382254) (xy 156.801493 -65.374498)
			(xy 156.855995 -65.374498) (xy 156.909943 -65.382254) (xy 156.962238 -65.397609) (xy 157.011815 -65.420251)
			(xy 157.057665 -65.449717) (xy 157.098856 -65.485408) (xy 157.134547 -65.526599) (xy 157.164013 -65.572449)
			(xy 157.186655 -65.622026) (xy 157.20201 -65.674321) (xy 157.209766 -65.728269) (xy 157.210252 -65.75552)
			(xy 157.210252 -65.761108) (xy 157.210741 -65.771118) (xy 157.2184 -65.789615) (xy 157.232551 -65.803777)
			(xy 157.251042 -65.811451) (xy 157.261052 -65.811908) (xy 182.396384 -65.811908) (xy 182.406408 -65.811491)
			(xy 182.424932 -65.803824) (xy 182.439111 -65.789652) (xy 182.446787 -65.771132) (xy 182.447184 -65.761108)
			(xy 182.447184 -65.75552) (xy 182.44767 -65.728269) (xy 182.455426 -65.674321) (xy 182.470781 -65.622026)
			(xy 182.493423 -65.572449) (xy 182.522889 -65.526599) (xy 182.55858 -65.485408) (xy 182.599771 -65.449717)
			(xy 182.645621 -65.420251) (xy 182.695198 -65.397609) (xy 182.747493 -65.382254) (xy 182.801441 -65.374498)
			(xy 182.855943 -65.374498) (xy 182.909891 -65.382254) (xy 182.962186 -65.397609) (xy 183.011763 -65.420251)
			(xy 183.057613 -65.449717) (xy 183.098804 -65.485408) (xy 183.134495 -65.526599) (xy 183.163961 -65.572449)
			(xy 183.186603 -65.622026) (xy 183.201958 -65.674321) (xy 183.209714 -65.728269) (xy 183.2102 -65.75552)
			(xy 183.2102 -65.761108) (xy 183.21069 -65.771115) (xy 183.21835 -65.789604) (xy 183.232503 -65.803754)
			(xy 183.250993 -65.811412) (xy 183.261 -65.811908) (xy 208.320132 -65.811908) (xy 208.330136 -65.811414)
			(xy 208.348618 -65.803749) (xy 208.362763 -65.789598) (xy 208.370419 -65.771112) (xy 208.370932 -65.761108)
			(xy 208.370932 -65.75552) (xy 208.371422 -65.725552) (xy 208.379245 -65.66613) (xy 208.394758 -65.608237)
			(xy 208.417694 -65.552864) (xy 208.447661 -65.500958) (xy 208.484148 -65.453408) (xy 208.526528 -65.411028)
			(xy 208.574078 -65.374541) (xy 208.625984 -65.344574) (xy 208.681357 -65.321638) (xy 208.73925 -65.306125)
			(xy 208.798672 -65.298302) (xy 208.858608 -65.298302) (xy 208.91803 -65.306125) (xy 208.975923 -65.321638)
			(xy 209.031296 -65.344574) (xy 209.083202 -65.374541) (xy 209.130752 -65.411028) (xy 209.173132 -65.453408)
			(xy 209.209619 -65.500958) (xy 209.239586 -65.552864) (xy 209.262522 -65.608237) (xy 209.278035 -65.66613)
			(xy 209.285858 -65.725552) (xy 209.286348 -65.75552) (xy 209.286348 -65.761108) (xy 209.28677 -65.771125)
			(xy 209.294443 -65.789631) (xy 209.308616 -65.803789) (xy 209.327131 -65.811441) (xy 209.337148 -65.811908)
			(xy 226.590352 -65.811908) (xy 226.595432 -65.810892) (xy 226.619022 -65.806146) (xy 226.666875 -65.801058)
			(xy 226.690936 -65.800732) (xy 226.724972 -65.802002) (xy 226.732592 -65.802002) (xy 226.76612 -65.800732)
			(xy 226.79018 -65.801078) (xy 226.83803 -65.806169) (xy 226.861624 -65.810892) (xy 226.866704 -65.811908)
			(xy 227.448872 -65.811908) (xy 227.457 -65.8114) (xy 227.468562 -65.80891) (xy 227.487745 -65.795128)
			(xy 227.49383 -65.784984) (xy 227.505514 -65.763394) (xy 227.50994 -65.754034) (xy 227.511672 -65.733423)
			(xy 227.50516 -65.71379) (xy 227.498656 -65.705736) (xy 227.498402 -65.705482) (xy 227.480074 -65.684449)
			(xy 227.448124 -65.638712) (xy 227.421975 -65.589429) (xy 227.402015 -65.537331) (xy 227.388541 -65.483192)
			(xy 227.381752 -65.427815) (xy 227.381308 -65.39992) (xy 227.381776 -65.369951) (xy 227.389597 -65.310524)
			(xy 227.405109 -65.252627) (xy 227.428045 -65.19725) (xy 227.458014 -65.145341) (xy 227.494502 -65.097788)
			(xy 227.536885 -65.055404) (xy 227.584438 -65.018916) (xy 227.636346 -64.988947) (xy 227.691723 -64.96601)
			(xy 227.74962 -64.950498) (xy 227.809047 -64.942676) (xy 227.839016 -64.942212) (xy 227.839524 -64.942212)
			(xy 227.872798 -64.943482) (xy 227.880418 -64.943482) (xy 227.913692 -64.942212) (xy 227.9142 -64.942212)
			(xy 227.947224 -64.94277) (xy 228.012592 -64.952223) (xy 228.075922 -64.970976) (xy 228.135898 -64.998639)
			(xy 228.191273 -65.034637) (xy 228.21646 -65.056004) (xy 228.216968 -65.056512) (xy 228.22408 -65.062608)
			(xy 228.25329 -65.066672) (xy 228.350826 -65.021968) (xy 228.359452 -65.017573) (xy 228.372828 -65.0036)
			(xy 228.380069 -64.985664) (xy 228.380544 -64.975994) (xy 228.380544 -64.729868) (xy 228.38008 -64.719621)
			(xy 228.372093 -64.700748) (xy 228.36505 -64.693292) (xy 228.327712 -64.657478) (xy 228.313488 -64.657732)
			(xy 228.280214 -64.656462) (xy 228.271578 -64.656462) (xy 228.238304 -64.657732) (xy 228.211049 -64.657269)
			(xy 228.157094 -64.649512) (xy 228.104793 -64.634156) (xy 228.055209 -64.611512) (xy 228.009352 -64.582042)
			(xy 227.968157 -64.546346) (xy 227.93246 -64.505151) (xy 227.90299 -64.459295) (xy 227.880346 -64.409711)
			(xy 227.864988 -64.35741) (xy 227.857231 -64.303455) (xy 227.857231 -64.248945) (xy 227.864988 -64.19499)
			(xy 227.880346 -64.142689) (xy 227.90299 -64.093105) (xy 227.93246 -64.047249) (xy 227.968157 -64.006054)
			(xy 228.009352 -63.970358) (xy 228.055209 -63.940888) (xy 228.104793 -63.918244) (xy 228.157094 -63.902888)
			(xy 228.211049 -63.895131) (xy 228.238304 -63.894716) (xy 228.271578 -63.895986) (xy 228.280214 -63.895986)
			(xy 228.313488 -63.894716) (xy 228.327712 -63.89497) (xy 228.36505 -63.859156) (xy 228.372101 -63.851704)
			(xy 228.380095 -63.83283) (xy 228.380544 -63.82258) (xy 228.380544 -62.882018) (xy 228.380128 -62.87241)
			(xy 228.373073 -62.854534) (xy 228.366828 -62.84722) (xy 228.318822 -62.79642) (xy 228.311925 -62.78977)
			(xy 228.294567 -62.78169) (xy 228.28504 -62.780672) (xy 228.257676 -62.77853) (xy 228.203933 -62.76738)
			(xy 228.152343 -62.748643) (xy 228.10397 -62.722705) (xy 228.059815 -62.690103) (xy 228.020787 -62.651509)
			(xy 227.987694 -62.60772) (xy 227.961219 -62.55964) (xy 227.941907 -62.508262) (xy 227.930158 -62.454647)
			(xy 227.926214 -62.399902) (xy 227.930157 -62.345156) (xy 227.941906 -62.291541) (xy 227.961217 -62.240163)
			(xy 227.987693 -62.192083) (xy 228.020785 -62.148293) (xy 228.059812 -62.109699) (xy 228.103968 -62.077096)
			(xy 228.15234 -62.051158) (xy 228.20393 -62.032421) (xy 228.257673 -62.021271) (xy 228.28504 -62.01918)
			(xy 228.294946 -62.018672) (xy 228.311964 -62.010544) (xy 228.366828 -61.952632) (xy 228.37312 -61.945345)
			(xy 228.380191 -61.927454) (xy 228.380544 -61.917834) (xy 228.380544 -61.082174) (xy 228.380138 -61.072562)
			(xy 228.373097 -61.054673) (xy 228.366828 -61.047376) (xy 228.318822 -60.996576) (xy 228.311927 -60.989921)
			(xy 228.29457 -60.981831) (xy 228.28504 -60.980828) (xy 228.256207 -60.97854) (xy 228.199666 -60.966358)
			(xy 228.14561 -60.945784) (xy 228.095279 -60.917289) (xy 228.049823 -60.881525) (xy 228.010285 -60.839312)
			(xy 227.977569 -60.791615) (xy 227.952426 -60.739528) (xy 227.93543 -60.684244) (xy 227.93071 -60.655708)
			(xy 227.928678 -60.641484) (xy 227.910644 -60.619894) (xy 227.89515 -60.61456) (xy 227.888987 -60.612667)
			(xy 227.876138 -60.611649) (xy 227.86975 -60.612528) (xy 227.856796 -60.614814) (xy 227.846382 -60.62345)
			(xy 227.825772 -60.639894) (xy 227.780884 -60.667553) (xy 227.732617 -60.688772) (xy 227.68189 -60.703146)
			(xy 227.629666 -60.710402) (xy 227.603304 -60.710826) (xy 227.602796 -60.710826) (xy 227.578326 -60.71047)
			(xy 227.529785 -60.704229) (xy 227.506022 -60.69838) (xy 227.497386 -60.696856) (xy 227.469184 -60.693992)
			(xy 227.414076 -60.680718) (xy 227.387658 -60.67044) (xy 227.379116 -60.667285) (xy 227.360933 -60.666622)
			(xy 227.343678 -60.672397) (xy 227.33635 -60.677806) (xy 227.305021 -60.702479) (xy 227.237777 -60.745353)
			(xy 227.166111 -60.780336) (xy 227.090945 -60.80698) (xy 227.013244 -60.82494) (xy 226.93401 -60.833986)
			(xy 226.894136 -60.834524) (xy 226.857332 -60.83406) (xy 226.784126 -60.826368) (xy 226.712126 -60.811063)
			(xy 226.642121 -60.788313) (xy 226.574878 -60.758369) (xy 226.511135 -60.721558) (xy 226.45159 -60.678284)
			(xy 226.396897 -60.629021) (xy 226.347654 -60.574309) (xy 226.304401 -60.514748) (xy 226.267614 -60.450992)
			(xy 226.237694 -60.383738) (xy 226.214971 -60.313725) (xy 226.199692 -60.241719) (xy 226.192026 -60.168511)
			(xy 226.191572 -60.131706) (xy 226.192018 -60.095975) (xy 226.199279 -60.024882) (xy 226.213715 -59.954893)
			(xy 226.235179 -59.88673) (xy 226.263448 -59.821096) (xy 226.29823 -59.75867) (xy 226.318318 -59.729116)
			(xy 226.323895 -59.720305) (xy 226.328117 -59.699905) (xy 226.323899 -59.679504) (xy 226.318318 -59.670696)
			(xy 226.298227 -59.641194) (xy 226.263469 -59.578848) (xy 226.235216 -59.513297) (xy 226.213758 -59.445218)
			(xy 226.199318 -59.375313) (xy 226.192045 -59.304304) (xy 226.191572 -59.268614) (xy 226.191572 -59.268106)
			(xy 226.192082 -59.229785) (xy 226.200421 -59.153598) (xy 226.217002 -59.078771) (xy 226.241626 -59.006193)
			(xy 226.274003 -58.936725) (xy 226.313746 -58.871193) (xy 226.360384 -58.810375) (xy 226.413364 -58.754993)
			(xy 226.472056 -58.705705) (xy 226.535762 -58.663097) (xy 226.603727 -58.627674) (xy 226.675143 -58.599857)
			(xy 226.712018 -58.589418) (xy 226.722924 -58.585934) (xy 226.740238 -58.570989) (xy 226.745292 -58.560716)
			(xy 226.781868 -58.47715) (xy 226.781106 -58.45429) (xy 226.775518 -58.443876) (xy 226.759205 -58.412049)
			(xy 226.732121 -58.345853) (xy 226.711583 -58.277342) (xy 226.697785 -58.207162) (xy 226.690858 -58.135976)
			(xy 226.690428 -58.100214) (xy 226.690428 -58.09996) (xy 226.690933 -58.061356) (xy 226.699003 -57.984572)
			(xy 226.715056 -57.909051) (xy 226.738914 -57.835623) (xy 226.770317 -57.76509) (xy 226.808921 -57.698227)
			(xy 226.854302 -57.635764) (xy 226.905964 -57.578388) (xy 226.96334 -57.526726) (xy 227.025803 -57.481345)
			(xy 227.092666 -57.442741) (xy 227.163199 -57.411338) (xy 227.236627 -57.38748) (xy 227.312148 -57.371427)
			(xy 227.388932 -57.363357) (xy 227.46614 -57.363357) (xy 227.542924 -57.371427) (xy 227.618445 -57.38748)
			(xy 227.691873 -57.411338) (xy 227.762406 -57.442741) (xy 227.829269 -57.481345) (xy 227.891732 -57.526726)
			(xy 227.949108 -57.578388) (xy 228.00077 -57.635764) (xy 228.046151 -57.698227) (xy 228.084755 -57.76509)
			(xy 228.116158 -57.835623) (xy 228.140016 -57.909051) (xy 228.156069 -57.984572) (xy 228.164139 -58.061356)
			(xy 228.164644 -58.09996) (xy 228.164267 -58.132915) (xy 228.158362 -58.19856) (xy 228.14662 -58.263415)
			(xy 228.138228 -58.295286) (xy 228.13552 -58.30774) (xy 228.141235 -58.332544) (xy 228.14915 -58.34253)
			(xy 228.214428 -58.415936) (xy 228.238304 -58.424826) (xy 228.251258 -58.422794) (xy 228.265397 -58.420786)
			(xy 228.293874 -58.418622) (xy 228.308154 -58.418476) (xy 228.341428 -58.419746) (xy 228.350064 -58.419746)
			(xy 228.383338 -58.418476) (xy 228.410588 -58.418964) (xy 228.464532 -58.426725) (xy 228.516823 -58.442083)
			(xy 228.566397 -58.464727) (xy 228.612244 -58.494194) (xy 228.653431 -58.529885) (xy 228.68912 -58.571074)
			(xy 228.718584 -58.616922) (xy 228.741224 -58.666497) (xy 228.750613 -58.698471) (xy 229.808523 -58.698471)
			(xy 229.808523 -58.601777) (xy 229.816508 -58.505414) (xy 229.832424 -58.410039) (xy 229.85616 -58.316305)
			(xy 229.887557 -58.22485) (xy 229.926398 -58.136301) (xy 229.972419 -58.051261) (xy 230.025305 -57.970313)
			(xy 230.084696 -57.894008) (xy 230.150184 -57.822868) (xy 230.221324 -57.75738) (xy 230.297629 -57.697989)
			(xy 230.378577 -57.645103) (xy 230.463617 -57.599082) (xy 230.552166 -57.560241) (xy 230.643621 -57.528844)
			(xy 230.737355 -57.505108) (xy 230.83273 -57.489192) (xy 230.929093 -57.481207) (xy 231.025787 -57.481207)
			(xy 231.12215 -57.489192) (xy 231.217525 -57.505108) (xy 231.311259 -57.528844) (xy 231.402714 -57.560241)
			(xy 231.491263 -57.599082) (xy 231.564456 -57.638692) (xy 233.790741 -57.638692) (xy 233.790741 -57.561484)
			(xy 233.798811 -57.4847) (xy 233.814864 -57.409179) (xy 233.838722 -57.335751) (xy 233.870125 -57.265218)
			(xy 233.908729 -57.198355) (xy 233.95411 -57.135892) (xy 234.005772 -57.078516) (xy 234.063148 -57.026854)
			(xy 234.125611 -56.981473) (xy 234.192474 -56.942869) (xy 234.263007 -56.911466) (xy 234.336435 -56.887608)
			(xy 234.411956 -56.871555) (xy 234.48874 -56.863485) (xy 234.565948 -56.863485) (xy 234.642732 -56.871555)
			(xy 234.718253 -56.887608) (xy 234.791681 -56.911466) (xy 234.862214 -56.942869) (xy 234.929077 -56.981473)
			(xy 234.99154 -57.026854) (xy 235.048916 -57.078516) (xy 235.100578 -57.135892) (xy 235.145959 -57.198355)
			(xy 235.184563 -57.265218) (xy 235.215966 -57.335751) (xy 235.239824 -57.409179) (xy 235.255877 -57.4847)
			(xy 235.263947 -57.561484) (xy 235.264452 -57.600088) (xy 235.263947 -57.638692) (xy 235.255877 -57.715476)
			(xy 235.239824 -57.790997) (xy 235.215966 -57.864425) (xy 235.184563 -57.934958) (xy 235.145959 -58.001821)
			(xy 235.100578 -58.064284) (xy 235.048916 -58.12166) (xy 234.99154 -58.173322) (xy 234.929077 -58.218703)
			(xy 234.862214 -58.257307) (xy 234.791681 -58.28871) (xy 234.718253 -58.312568) (xy 234.642732 -58.328621)
			(xy 234.565948 -58.336691) (xy 234.48874 -58.336691) (xy 234.411956 -58.328621) (xy 234.336435 -58.312568)
			(xy 234.263007 -58.28871) (xy 234.192474 -58.257307) (xy 234.125611 -58.218703) (xy 234.063148 -58.173322)
			(xy 234.005772 -58.12166) (xy 233.95411 -58.064284) (xy 233.908729 -58.001821) (xy 233.870125 -57.934958)
			(xy 233.838722 -57.864425) (xy 233.814864 -57.790997) (xy 233.798811 -57.715476) (xy 233.790741 -57.638692)
			(xy 231.564456 -57.638692) (xy 231.576303 -57.645103) (xy 231.657251 -57.697989) (xy 231.733556 -57.75738)
			(xy 231.804696 -57.822868) (xy 231.870184 -57.894008) (xy 231.929575 -57.970313) (xy 231.982461 -58.051261)
			(xy 232.028482 -58.136301) (xy 232.067323 -58.22485) (xy 232.09872 -58.316305) (xy 232.122456 -58.410039)
			(xy 232.138372 -58.505414) (xy 232.146357 -58.601777) (xy 232.146856 -58.650124) (xy 232.146357 -58.698471)
			(xy 232.138372 -58.794834) (xy 232.122456 -58.890209) (xy 232.09872 -58.983943) (xy 232.067323 -59.075398)
			(xy 232.028482 -59.163947) (xy 231.982461 -59.248987) (xy 231.929575 -59.329935) (xy 231.875094 -59.399932)
			(xy 233.19105 -59.399932) (xy 233.19105 -59.399678) (xy 233.191567 -59.372332) (xy 233.19939 -59.318203)
			(xy 233.214858 -59.265744) (xy 233.237655 -59.216031) (xy 233.267314 -59.170079) (xy 233.303228 -59.128831)
			(xy 233.323638 -59.110626) (xy 233.33202 -59.103514) (xy 233.341164 -59.083702) (xy 233.34218 -58.99658)
			(xy 233.341757 -58.985742) (xy 233.333097 -58.965881) (xy 233.325416 -58.958226) (xy 233.325162 -58.957972)
			(xy 233.305584 -58.939806) (xy 233.271191 -58.898946) (xy 233.242834 -58.853689) (xy 233.221066 -58.804919)
			(xy 233.206313 -58.753589) (xy 233.198864 -58.700704) (xy 233.198416 -58.674) (xy 233.198902 -58.646749)
			(xy 233.206658 -58.592801) (xy 233.222013 -58.540506) (xy 233.244655 -58.490929) (xy 233.274121 -58.445079)
			(xy 233.309812 -58.403888) (xy 233.351003 -58.368197) (xy 233.396853 -58.338731) (xy 233.44643 -58.316089)
			(xy 233.498725 -58.300734) (xy 233.552673 -58.292978) (xy 233.607175 -58.292978) (xy 233.661123 -58.300734)
			(xy 233.713418 -58.316089) (xy 233.762995 -58.338731) (xy 233.808845 -58.368197) (xy 233.850036 -58.403888)
			(xy 233.885727 -58.445079) (xy 233.915193 -58.490929) (xy 233.937835 -58.540506) (xy 233.95319 -58.592801)
			(xy 233.960883 -58.646314) (xy 237.901732 -58.646314) (xy 237.905803 -58.590692) (xy 237.917929 -58.536255)
			(xy 237.937852 -58.484164) (xy 237.965148 -58.435529) (xy 237.999234 -58.391386) (xy 238.039383 -58.352677)
			(xy 238.084741 -58.320226) (xy 238.134341 -58.294725) (xy 238.187125 -58.276718) (xy 238.241968 -58.266588)
			(xy 238.297702 -58.264551) (xy 238.353139 -58.270651) (xy 238.407096 -58.284757) (xy 238.458425 -58.306569)
			(xy 238.471977 -58.31484) (xy 240.522996 -58.31484) (xy 240.522996 -58.254904) (xy 240.530819 -58.195482)
			(xy 240.546332 -58.137589) (xy 240.569268 -58.082216) (xy 240.599235 -58.03031) (xy 240.635722 -57.98276)
			(xy 240.678102 -57.94038) (xy 240.725652 -57.903893) (xy 240.777558 -57.873926) (xy 240.832931 -57.85099)
			(xy 240.890824 -57.835477) (xy 240.950246 -57.827654) (xy 241.010182 -57.827654) (xy 241.069604 -57.835477)
			(xy 241.127497 -57.85099) (xy 241.18287 -57.873926) (xy 241.234776 -57.903893) (xy 241.282326 -57.94038)
			(xy 241.324706 -57.98276) (xy 241.361193 -58.03031) (xy 241.39116 -58.082216) (xy 241.414096 -58.137589)
			(xy 241.429609 -58.195482) (xy 241.437432 -58.254904) (xy 241.437922 -58.284872) (xy 241.437432 -58.31484)
			(xy 241.429609 -58.374262) (xy 241.414096 -58.432155) (xy 241.39116 -58.487528) (xy 241.361193 -58.539434)
			(xy 241.324706 -58.586984) (xy 241.282326 -58.629364) (xy 241.234776 -58.665851) (xy 241.18287 -58.695818)
			(xy 241.127497 -58.718754) (xy 241.080288 -58.731404) (xy 245.720616 -58.731404) (xy 245.721081 -58.704034)
			(xy 245.728898 -58.649854) (xy 245.744387 -58.597351) (xy 245.76723 -58.547604) (xy 245.796955 -58.501638)
			(xy 245.814596 -58.480706) (xy 245.81485 -58.480452) (xy 245.820427 -58.473359) (xy 245.826678 -58.456447)
			(xy 245.827042 -58.447432) (xy 245.827042 -58.380376) (xy 245.826709 -58.371356) (xy 245.820446 -58.354439)
			(xy 245.81485 -58.347356) (xy 245.814596 -58.347356) (xy 245.814596 -58.347102) (xy 245.796961 -58.326165)
			(xy 245.767238 -58.280198) (xy 245.744394 -58.230452) (xy 245.728899 -58.177951) (xy 245.721071 -58.123773)
			(xy 245.72107 -58.069033) (xy 245.728898 -58.014855) (xy 245.744392 -57.962354) (xy 245.767235 -57.912608)
			(xy 245.796957 -57.866639) (xy 245.814596 -57.845706) (xy 245.81485 -57.845452) (xy 245.820427 -57.838359)
			(xy 245.826678 -57.821447) (xy 245.827042 -57.812432) (xy 245.827042 -57.745376) (xy 245.826709 -57.736356)
			(xy 245.820446 -57.719439) (xy 245.81485 -57.712356) (xy 245.814596 -57.712356) (xy 245.814596 -57.712102)
			(xy 245.796961 -57.691165) (xy 245.767238 -57.645198) (xy 245.744394 -57.595452) (xy 245.728899 -57.542951)
			(xy 245.721071 -57.488773) (xy 245.72107 -57.434033) (xy 245.728898 -57.379855) (xy 245.744392 -57.327354)
			(xy 245.767235 -57.277608) (xy 245.796957 -57.231639) (xy 245.814596 -57.210706) (xy 245.81485 -57.210452)
			(xy 245.820427 -57.203359) (xy 245.826678 -57.186447) (xy 245.827042 -57.177432) (xy 245.827042 -57.110376)
			(xy 245.826709 -57.101356) (xy 245.820446 -57.084439) (xy 245.81485 -57.077356) (xy 245.814596 -57.077356)
			(xy 245.814596 -57.077102) (xy 245.796944 -57.056181) (xy 245.767234 -57.010205) (xy 245.744401 -56.960455)
			(xy 245.728913 -56.907952) (xy 245.721088 -56.853774) (xy 245.720616 -56.826404) (xy 245.721102 -56.799153)
			(xy 245.728858 -56.745205) (xy 245.744213 -56.69291) (xy 245.766855 -56.643333) (xy 245.796321 -56.597483)
			(xy 245.832012 -56.556292) (xy 245.873203 -56.520601) (xy 245.919053 -56.491135) (xy 245.96863 -56.468493)
			(xy 246.020925 -56.453138) (xy 246.074873 -56.445382) (xy 246.129375 -56.445382) (xy 246.183323 -56.453138)
			(xy 246.235618 -56.468493) (xy 246.285195 -56.491135) (xy 246.331045 -56.520601) (xy 246.372236 -56.556292)
			(xy 246.407927 -56.597483) (xy 246.437393 -56.643333) (xy 246.460035 -56.69291) (xy 246.47539 -56.745205)
			(xy 246.483146 -56.799153) (xy 246.483342 -56.810148) (xy 248.30024 -56.810148) (xy 248.30024 -56.809894)
			(xy 248.30073 -56.779926) (xy 248.308553 -56.720504) (xy 248.324066 -56.662611) (xy 248.347002 -56.607238)
			(xy 248.376969 -56.555332) (xy 248.413456 -56.507782) (xy 248.455836 -56.465402) (xy 248.503386 -56.428915)
			(xy 248.555292 -56.398948) (xy 248.610665 -56.376012) (xy 248.668558 -56.360499) (xy 248.72798 -56.352676)
			(xy 248.787916 -56.352676) (xy 248.847338 -56.360499) (xy 248.905231 -56.376012) (xy 248.960604 -56.398948)
			(xy 249.01251 -56.428915) (xy 249.06006 -56.465402) (xy 249.10244 -56.507782) (xy 249.138927 -56.555332)
			(xy 249.168894 -56.607238) (xy 249.19183 -56.662611) (xy 249.207343 -56.720504) (xy 249.215166 -56.779926)
			(xy 249.215656 -56.809894) (xy 249.215656 -56.810148) (xy 249.215097 -56.841672) (xy 249.206427 -56.904121)
			(xy 249.189272 -56.96479) (xy 249.163957 -57.022533) (xy 249.130959 -57.076256) (xy 249.090904 -57.124945)
			(xy 249.068082 -57.146698) (xy 249.06097 -57.153302) (xy 249.052588 -57.17032) (xy 249.046238 -57.248806)
			(xy 249.045863 -57.258372) (xy 249.051485 -57.276655) (xy 249.05716 -57.284366) (xy 249.072702 -57.304646)
			(xy 249.098759 -57.348597) (xy 249.118721 -57.395632) (xy 249.132231 -57.444908) (xy 249.135212 -57.467053)
			(xy 249.318469 -57.467053) (xy 249.318469 -57.412547) (xy 249.326227 -57.358596) (xy 249.341584 -57.306298)
			(xy 249.364227 -57.256718) (xy 249.393696 -57.210865) (xy 249.429392 -57.169673) (xy 249.470586 -57.133981)
			(xy 249.516441 -57.104515) (xy 249.566022 -57.081874) (xy 249.618321 -57.066521) (xy 249.672273 -57.058768)
			(xy 249.699526 -57.058306) (xy 249.725075 -57.058685) (xy 249.775716 -57.065499) (xy 249.824993 -57.079015)
			(xy 249.872024 -57.098991) (xy 249.915966 -57.125068) (xy 249.936254 -57.140602) (xy 249.943993 -57.146218)
			(xy 249.962257 -57.151831) (xy 249.971814 -57.151524) (xy 250.0503 -57.145174) (xy 250.067318 -57.136792)
			(xy 250.073922 -57.12968) (xy 250.095663 -57.106842) (xy 250.144341 -57.066763) (xy 250.198062 -57.03375)
			(xy 250.255809 -57.008429) (xy 250.316487 -56.99128) (xy 250.378945 -56.982629) (xy 250.410472 -56.982106)
			(xy 250.410726 -56.982106) (xy 250.440695 -56.982558) (xy 250.500119 -56.990384) (xy 250.558014 -57.005901)
			(xy 250.613388 -57.02884) (xy 250.665294 -57.058812) (xy 250.688797 -57.076848) (xy 251.338588 -57.076848)
			(xy 251.339085 -57.049479) (xy 251.346896 -56.995301) (xy 251.362378 -56.942799) (xy 251.385213 -56.893051)
			(xy 251.41493 -56.847083) (xy 251.432568 -56.82615) (xy 251.432822 -56.825896) (xy 251.438419 -56.818817)
			(xy 251.444659 -56.801894) (xy 251.445014 -56.792876) (xy 251.445014 -56.72582) (xy 251.444644 -56.716804)
			(xy 251.438405 -56.699888) (xy 251.432822 -56.6928) (xy 251.432568 -56.6928) (xy 251.432568 -56.692546)
			(xy 251.414932 -56.671612) (xy 251.385221 -56.625639) (xy 251.362385 -56.575892) (xy 251.346893 -56.523392)
			(xy 251.339063 -56.469217) (xy 251.338588 -56.441848) (xy 251.339074 -56.414597) (xy 251.34683 -56.360649)
			(xy 251.362185 -56.308354) (xy 251.384827 -56.258777) (xy 251.414293 -56.212927) (xy 251.449984 -56.171736)
			(xy 251.491175 -56.136045) (xy 251.537025 -56.106579) (xy 251.586602 -56.083937) (xy 251.638897 -56.068582)
			(xy 251.692845 -56.060826) (xy 251.747347 -56.060826) (xy 251.801295 -56.068582) (xy 251.85359 -56.083937)
			(xy 251.903167 -56.106579) (xy 251.949017 -56.136045) (xy 251.990208 -56.171736) (xy 252.025899 -56.212927)
			(xy 252.055365 -56.258777) (xy 252.078007 -56.308354) (xy 252.093362 -56.360649) (xy 252.101118 -56.414597)
			(xy 252.101604 -56.441848) (xy 252.101106 -56.469217) (xy 252.093296 -56.523395) (xy 252.077814 -56.575898)
			(xy 252.05498 -56.625645) (xy 252.025262 -56.671613) (xy 252.007624 -56.692546) (xy 252.00737 -56.6928)
			(xy 252.001774 -56.69988) (xy 251.995534 -56.716802) (xy 251.995178 -56.72582) (xy 251.995178 -56.792876)
			(xy 251.995551 -56.801891) (xy 252.001788 -56.818808) (xy 252.00737 -56.825896) (xy 252.007624 -56.825896)
			(xy 252.007624 -56.82615) (xy 252.025257 -56.847087) (xy 252.054969 -56.893059) (xy 252.077806 -56.942805)
			(xy 252.093298 -56.995305) (xy 252.094401 -57.002934) (xy 253.763526 -57.002934) (xy 253.764026 -56.974842)
			(xy 253.77225 -56.919265) (xy 253.788538 -56.865495) (xy 253.81254 -56.814696) (xy 253.843734 -56.767969)
			(xy 253.881447 -56.726325) (xy 253.924861 -56.690664) (xy 253.948692 -56.675782) (xy 253.957582 -56.670448)
			(xy 253.969774 -56.65343) (xy 253.990094 -56.560212) (xy 253.985776 -56.539638) (xy 253.979934 -56.531002)
			(xy 253.963937 -56.506936) (xy 253.938592 -56.455006) (xy 253.921366 -56.399848) (xy 253.91265 -56.342724)
			(xy 253.912116 -56.313832) (xy 253.912585 -56.286579) (xy 253.920338 -56.232627) (xy 253.935692 -56.180328)
			(xy 253.958332 -56.130746) (xy 253.987799 -56.084892) (xy 254.023492 -56.043698) (xy 254.064685 -56.008004)
			(xy 254.110539 -55.978536) (xy 254.16012 -55.955894) (xy 254.212419 -55.94054) (xy 254.266371 -55.932786)
			(xy 254.293624 -55.932324) (xy 254.320995 -55.93277) (xy 254.375175 -55.940592) (xy 254.427679 -55.956085)
			(xy 254.477425 -55.978932) (xy 254.523391 -56.008661) (xy 254.544322 -56.026304) (xy 254.544576 -56.026558)
			(xy 254.55166 -56.032148) (xy 254.568579 -56.038391) (xy 254.577596 -56.03875) (xy 254.644652 -56.03875)
			(xy 254.653668 -56.038381) (xy 254.670586 -56.032143) (xy 254.677672 -56.026558) (xy 254.677672 -56.026304)
			(xy 254.677926 -56.026304) (xy 254.698859 -56.008663) (xy 254.744827 -55.978939) (xy 254.794573 -55.956093)
			(xy 254.847075 -55.940597) (xy 254.901253 -55.932768) (xy 254.955995 -55.932768) (xy 255.010173 -55.940597)
			(xy 255.062675 -55.956093) (xy 255.112421 -55.978939) (xy 255.158389 -56.008663) (xy 255.179322 -56.026304)
			(xy 255.179576 -56.026558) (xy 255.18666 -56.032148) (xy 255.203579 -56.038391) (xy 255.212596 -56.03875)
			(xy 255.279652 -56.03875) (xy 255.288668 -56.038381) (xy 255.305586 -56.032143) (xy 255.312672 -56.026558)
			(xy 255.312672 -56.026304) (xy 255.312926 -56.026304) (xy 255.333876 -56.008687) (xy 255.379844 -55.978971)
			(xy 255.429587 -55.956131) (xy 255.482083 -55.940635) (xy 255.536256 -55.932801) (xy 255.563624 -55.932324)
			(xy 255.590876 -55.932747) (xy 255.644826 -55.940507) (xy 255.697122 -55.955866) (xy 255.746701 -55.97851)
			(xy 255.792552 -56.00798) (xy 255.833743 -56.043674) (xy 255.869435 -56.084867) (xy 255.898901 -56.13072)
			(xy 255.921542 -56.1803) (xy 255.936898 -56.232597) (xy 255.944654 -56.286548) (xy 255.944654 -56.297068)
			(xy 256.286506 -56.297068) (xy 256.290577 -56.241446) (xy 256.302703 -56.187009) (xy 256.322626 -56.134918)
			(xy 256.349922 -56.086283) (xy 256.384008 -56.04214) (xy 256.424157 -56.003431) (xy 256.469515 -55.97098)
			(xy 256.519115 -55.945479) (xy 256.571899 -55.927472) (xy 256.626742 -55.917342) (xy 256.682476 -55.915305)
			(xy 256.737913 -55.921405) (xy 256.79187 -55.935511) (xy 256.843199 -55.957323) (xy 256.890805 -55.986377)
			(xy 256.933673 -56.022052) (xy 256.97089 -56.063589) (xy 257.001663 -56.110102) (xy 257.025335 -56.160599)
			(xy 257.041403 -56.214006) (xy 257.049523 -56.269182) (xy 257.050032 -56.297068) (xy 257.049523 -56.324954)
			(xy 257.045328 -56.353456) (xy 259.141212 -56.353456) (xy 259.145283 -56.297834) (xy 259.157409 -56.243397)
			(xy 259.177332 -56.191306) (xy 259.204628 -56.142671) (xy 259.238714 -56.098528) (xy 259.278863 -56.059819)
			(xy 259.324221 -56.027368) (xy 259.373821 -56.001867) (xy 259.426605 -55.98386) (xy 259.481448 -55.97373)
			(xy 259.537182 -55.971693) (xy 259.592619 -55.977793) (xy 259.646576 -55.991899) (xy 259.697905 -56.013711)
			(xy 259.745511 -56.042765) (xy 259.788379 -56.07844) (xy 259.825596 -56.119977) (xy 259.856369 -56.16649)
			(xy 259.880041 -56.216987) (xy 259.896109 -56.270394) (xy 259.904229 -56.32557) (xy 259.904738 -56.353456)
			(xy 259.904229 -56.381342) (xy 259.896109 -56.436518) (xy 259.880041 -56.489925) (xy 259.856369 -56.540422)
			(xy 259.825596 -56.586935) (xy 259.788379 -56.628472) (xy 259.745511 -56.664147) (xy 259.697905 -56.693201)
			(xy 259.646576 -56.715013) (xy 259.592619 -56.729119) (xy 259.537182 -56.735219) (xy 259.481448 -56.733182)
			(xy 259.426605 -56.723052) (xy 259.373821 -56.705045) (xy 259.324221 -56.679544) (xy 259.278863 -56.647093)
			(xy 259.238714 -56.608384) (xy 259.204628 -56.564241) (xy 259.177332 -56.515606) (xy 259.157409 -56.463515)
			(xy 259.145283 -56.409078) (xy 259.141212 -56.353456) (xy 257.045328 -56.353456) (xy 257.041403 -56.38013)
			(xy 257.025335 -56.433537) (xy 257.001663 -56.484034) (xy 256.97089 -56.530547) (xy 256.933673 -56.572084)
			(xy 256.890805 -56.607759) (xy 256.843199 -56.636813) (xy 256.79187 -56.658625) (xy 256.737913 -56.672731)
			(xy 256.682476 -56.678831) (xy 256.626742 -56.676794) (xy 256.571899 -56.666664) (xy 256.519115 -56.648657)
			(xy 256.469515 -56.623156) (xy 256.424157 -56.590705) (xy 256.384008 -56.551996) (xy 256.349922 -56.507853)
			(xy 256.322626 -56.459218) (xy 256.302703 -56.407127) (xy 256.290577 -56.35269) (xy 256.286506 -56.297068)
			(xy 255.944654 -56.297068) (xy 255.944654 -56.341052) (xy 255.936898 -56.395003) (xy 255.921542 -56.4473)
			(xy 255.898901 -56.49688) (xy 255.869435 -56.542733) (xy 255.833743 -56.583926) (xy 255.792552 -56.61962)
			(xy 255.746701 -56.64909) (xy 255.697122 -56.671734) (xy 255.644826 -56.687093) (xy 255.590876 -56.694853)
			(xy 255.563624 -56.69534) (xy 255.536254 -56.694874) (xy 255.482074 -56.687059) (xy 255.42957 -56.67157)
			(xy 255.379823 -56.648728) (xy 255.333857 -56.619002) (xy 255.312926 -56.60136) (xy 255.312672 -56.601106)
			(xy 255.305568 -56.595544) (xy 255.288665 -56.589282) (xy 255.279652 -56.588914) (xy 255.212596 -56.588914)
			(xy 255.203579 -56.589266) (xy 255.186661 -56.595517) (xy 255.179576 -56.601106) (xy 255.179576 -56.60136)
			(xy 255.179322 -56.60136) (xy 255.158389 -56.619001) (xy 255.112421 -56.648725) (xy 255.062675 -56.671571)
			(xy 255.010173 -56.687067) (xy 254.955995 -56.694896) (xy 254.901253 -56.694896) (xy 254.847075 -56.687067)
			(xy 254.794573 -56.671571) (xy 254.744827 -56.648725) (xy 254.698859 -56.619001) (xy 254.677926 -56.60136)
			(xy 254.677672 -56.601106) (xy 254.670568 -56.595544) (xy 254.653665 -56.589282) (xy 254.644652 -56.588914)
			(xy 254.577596 -56.588914) (xy 254.568579 -56.589266) (xy 254.551661 -56.595517) (xy 254.544576 -56.601106)
			(xy 254.544068 -56.60136) (xy 254.531333 -56.612303) (xy 254.504242 -56.632145) (xy 254.489966 -56.640984)
			(xy 254.481076 -56.646318) (xy 254.468884 -56.663336) (xy 254.448564 -56.756554) (xy 254.452882 -56.777128)
			(xy 254.458724 -56.785764) (xy 254.474714 -56.809834) (xy 254.500058 -56.861764) (xy 254.517286 -56.91692)
			(xy 254.526005 -56.974042) (xy 254.526542 -57.002934) (xy 254.526056 -57.030185) (xy 254.5183 -57.084133)
			(xy 254.502945 -57.136428) (xy 254.480303 -57.186005) (xy 254.450837 -57.231855) (xy 254.415146 -57.273046)
			(xy 254.373955 -57.308737) (xy 254.328105 -57.338203) (xy 254.278528 -57.360845) (xy 254.226233 -57.3762)
			(xy 254.172285 -57.383956) (xy 254.117783 -57.383956) (xy 254.063835 -57.3762) (xy 254.01154 -57.360845)
			(xy 253.961963 -57.338203) (xy 253.916113 -57.308737) (xy 253.874922 -57.273046) (xy 253.839231 -57.231855)
			(xy 253.809765 -57.186005) (xy 253.787123 -57.136428) (xy 253.771768 -57.084133) (xy 253.764012 -57.030185)
			(xy 253.763526 -57.002934) (xy 252.094401 -57.002934) (xy 252.101129 -57.049479) (xy 252.101604 -57.076848)
			(xy 252.101118 -57.104099) (xy 252.093362 -57.158047) (xy 252.078007 -57.210342) (xy 252.055365 -57.259919)
			(xy 252.025899 -57.305769) (xy 251.990208 -57.34696) (xy 251.949017 -57.382651) (xy 251.903167 -57.412117)
			(xy 251.85359 -57.434759) (xy 251.801295 -57.450114) (xy 251.747347 -57.45787) (xy 251.692845 -57.45787)
			(xy 251.638897 -57.450114) (xy 251.586602 -57.434759) (xy 251.537025 -57.412117) (xy 251.491175 -57.382651)
			(xy 251.449984 -57.34696) (xy 251.414293 -57.305769) (xy 251.384827 -57.259919) (xy 251.362185 -57.210342)
			(xy 251.34683 -57.158047) (xy 251.339074 -57.104099) (xy 251.338588 -57.076848) (xy 250.688797 -57.076848)
			(xy 250.712844 -57.095302) (xy 250.755225 -57.137686) (xy 250.79171 -57.185239) (xy 250.821677 -57.237148)
			(xy 250.844612 -57.292524) (xy 250.860123 -57.35042) (xy 250.867945 -57.409845) (xy 250.868434 -57.439814)
			(xy 250.868001 -57.468047) (xy 250.865866 -57.48528) (xy 262.805924 -57.48528) (xy 262.809995 -57.429658)
			(xy 262.822121 -57.375221) (xy 262.842044 -57.32313) (xy 262.86934 -57.274495) (xy 262.903426 -57.230352)
			(xy 262.943575 -57.191643) (xy 262.988933 -57.159192) (xy 263.038533 -57.133691) (xy 263.091317 -57.115684)
			(xy 263.14616 -57.105554) (xy 263.201894 -57.103517) (xy 263.257331 -57.109617) (xy 263.311288 -57.123723)
			(xy 263.362617 -57.145535) (xy 263.410223 -57.174589) (xy 263.453091 -57.210264) (xy 263.490308 -57.251801)
			(xy 263.521081 -57.298314) (xy 263.544753 -57.348811) (xy 263.560821 -57.402218) (xy 263.568941 -57.457394)
			(xy 263.56945 -57.48528) (xy 263.568941 -57.513166) (xy 263.560821 -57.568342) (xy 263.544753 -57.621749)
			(xy 263.521081 -57.672246) (xy 263.490308 -57.718759) (xy 263.453091 -57.760296) (xy 263.410223 -57.795971)
			(xy 263.362617 -57.825025) (xy 263.311288 -57.846837) (xy 263.257331 -57.860943) (xy 263.201894 -57.867043)
			(xy 263.14616 -57.865006) (xy 263.091317 -57.854876) (xy 263.038533 -57.836869) (xy 262.988933 -57.811368)
			(xy 262.943575 -57.778917) (xy 262.903426 -57.740208) (xy 262.86934 -57.696065) (xy 262.842044 -57.64743)
			(xy 262.822121 -57.595339) (xy 262.809995 -57.540902) (xy 262.805924 -57.48528) (xy 250.865866 -57.48528)
			(xy 250.86106 -57.524085) (xy 250.847272 -57.578841) (xy 250.826848 -57.631484) (xy 250.800098 -57.681211)
			(xy 250.784106 -57.704482) (xy 250.77674 -57.71515) (xy 250.773692 -57.740804) (xy 250.81611 -57.844436)
			(xy 250.836176 -57.860692) (xy 250.84913 -57.862978) (xy 250.875238 -57.868126) (xy 250.925809 -57.884684)
			(xy 250.973589 -57.908106) (xy 251.017653 -57.937938) (xy 251.057146 -57.973602) (xy 251.091302 -58.014406)
			(xy 251.119458 -58.059559) (xy 251.14107 -58.108185) (xy 251.155717 -58.159342) (xy 251.163117 -58.212038)
			(xy 251.163582 -58.238644) (xy 251.163087 -58.266013) (xy 251.155277 -58.320191) (xy 251.139795 -58.372694)
			(xy 251.116959 -58.422442) (xy 251.087241 -58.46841) (xy 251.069602 -58.489342) (xy 251.069348 -58.489596)
			(xy 251.063751 -58.496675) (xy 251.057512 -58.513598) (xy 251.057156 -58.522616) (xy 251.057156 -58.589672)
			(xy 251.057514 -58.598689) (xy 251.06376 -58.615607) (xy 251.069348 -58.622692) (xy 251.069602 -58.622692)
			(xy 251.069602 -58.622946) (xy 251.08723 -58.643887) (xy 251.110141 -58.679334) (xy 254.195326 -58.679334)
			(xy 254.195741 -58.653018) (xy 254.202985 -58.600887) (xy 254.217314 -58.550243) (xy 254.238456 -58.502044)
			(xy 254.266012 -58.457202) (xy 254.29946 -58.416565) (xy 254.318516 -58.39841) (xy 254.325918 -58.390889)
			(xy 254.334442 -58.371608) (xy 254.335026 -58.361072) (xy 254.335026 -58.286396) (xy 254.334505 -58.275846)
			(xy 254.325963 -58.256551) (xy 254.318516 -58.249058) (xy 254.29945 -58.230913) (xy 254.265993 -58.190281)
			(xy 254.238435 -58.145439) (xy 254.217298 -58.097236) (xy 254.202984 -58.046587) (xy 254.195762 -57.994451)
			(xy 254.195326 -57.968134) (xy 254.195812 -57.940883) (xy 254.203568 -57.886935) (xy 254.218923 -57.83464)
			(xy 254.241565 -57.785063) (xy 254.271031 -57.739213) (xy 254.306722 -57.698022) (xy 254.347913 -57.662331)
			(xy 254.393763 -57.632865) (xy 254.44334 -57.610223) (xy 254.495635 -57.594868) (xy 254.549583 -57.587112)
			(xy 254.604085 -57.587112) (xy 254.658033 -57.594868) (xy 254.710328 -57.610223) (xy 254.759905 -57.632865)
			(xy 254.805755 -57.662331) (xy 254.846946 -57.698022) (xy 254.882637 -57.739213) (xy 254.912103 -57.785063)
			(xy 254.934745 -57.83464) (xy 254.9501 -57.886935) (xy 254.957856 -57.940883) (xy 254.958342 -57.968134)
			(xy 254.957916 -57.99445) (xy 254.950675 -58.046581) (xy 254.936349 -58.097225) (xy 254.934149 -58.102242)
			(xy 258.118338 -58.102242) (xy 258.118338 -58.042306) (xy 258.126161 -57.982884) (xy 258.141674 -57.924991)
			(xy 258.16461 -57.869618) (xy 258.194577 -57.817712) (xy 258.231064 -57.770162) (xy 258.273444 -57.727782)
			(xy 258.320994 -57.691295) (xy 258.3729 -57.661328) (xy 258.428273 -57.638392) (xy 258.486166 -57.622879)
			(xy 258.545588 -57.615056) (xy 258.605524 -57.615056) (xy 258.664946 -57.622879) (xy 258.722839 -57.638392)
			(xy 258.778212 -57.661328) (xy 258.830118 -57.691295) (xy 258.877668 -57.727782) (xy 258.920048 -57.770162)
			(xy 258.956535 -57.817712) (xy 258.986502 -57.869618) (xy 259.009438 -57.924991) (xy 259.024951 -57.982884)
			(xy 259.032774 -58.042306) (xy 259.033264 -58.072274) (xy 259.032774 -58.102242) (xy 259.032272 -58.106052)
			(xy 263.482818 -58.106052) (xy 263.482818 -58.046116) (xy 263.490641 -57.986694) (xy 263.506154 -57.928801)
			(xy 263.52909 -57.873428) (xy 263.559057 -57.821522) (xy 263.595544 -57.773972) (xy 263.637924 -57.731592)
			(xy 263.685474 -57.695105) (xy 263.73738 -57.665138) (xy 263.792753 -57.642202) (xy 263.850646 -57.626689)
			(xy 263.910068 -57.618866) (xy 263.970004 -57.618866) (xy 264.029426 -57.626689) (xy 264.087319 -57.642202)
			(xy 264.142692 -57.665138) (xy 264.194598 -57.695105) (xy 264.242148 -57.731592) (xy 264.284528 -57.773972)
			(xy 264.321015 -57.821522) (xy 264.350982 -57.873428) (xy 264.360855 -57.897264) (xy 265.767802 -57.897264)
			(xy 265.767802 -57.837328) (xy 265.775625 -57.777906) (xy 265.791138 -57.720013) (xy 265.814074 -57.66464)
			(xy 265.844041 -57.612734) (xy 265.880528 -57.565184) (xy 265.922908 -57.522804) (xy 265.970458 -57.486317)
			(xy 266.022364 -57.45635) (xy 266.077737 -57.433414) (xy 266.13563 -57.417901) (xy 266.195052 -57.410078)
			(xy 266.254988 -57.410078) (xy 266.31441 -57.417901) (xy 266.372303 -57.433414) (xy 266.427676 -57.45635)
			(xy 266.479582 -57.486317) (xy 266.527132 -57.522804) (xy 266.569512 -57.565184) (xy 266.605999 -57.612734)
			(xy 266.635966 -57.66464) (xy 266.658902 -57.720013) (xy 266.674415 -57.777906) (xy 266.682238 -57.837328)
			(xy 266.682728 -57.867296) (xy 266.682238 -57.897264) (xy 266.674415 -57.956686) (xy 266.658902 -58.014579)
			(xy 266.635966 -58.069952) (xy 266.605999 -58.121858) (xy 266.569512 -58.169408) (xy 266.527132 -58.211788)
			(xy 266.479582 -58.248275) (xy 266.427676 -58.278242) (xy 266.372303 -58.301178) (xy 266.31441 -58.316691)
			(xy 266.254988 -58.324514) (xy 266.195052 -58.324514) (xy 266.13563 -58.316691) (xy 266.077737 -58.301178)
			(xy 266.022364 -58.278242) (xy 265.970458 -58.248275) (xy 265.922908 -58.211788) (xy 265.880528 -58.169408)
			(xy 265.844041 -58.121858) (xy 265.814074 -58.069952) (xy 265.791138 -58.014579) (xy 265.775625 -57.956686)
			(xy 265.767802 -57.897264) (xy 264.360855 -57.897264) (xy 264.373918 -57.928801) (xy 264.389431 -57.986694)
			(xy 264.397254 -58.046116) (xy 264.397744 -58.076084) (xy 264.397254 -58.106052) (xy 264.389431 -58.165474)
			(xy 264.373918 -58.223367) (xy 264.350982 -58.27874) (xy 264.321015 -58.330646) (xy 264.284528 -58.378196)
			(xy 264.242148 -58.420576) (xy 264.194598 -58.457063) (xy 264.142692 -58.48703) (xy 264.087319 -58.509966)
			(xy 264.029426 -58.525479) (xy 263.970004 -58.533302) (xy 263.910068 -58.533302) (xy 263.850646 -58.525479)
			(xy 263.792753 -58.509966) (xy 263.73738 -58.48703) (xy 263.685474 -58.457063) (xy 263.637924 -58.420576)
			(xy 263.595544 -58.378196) (xy 263.559057 -58.330646) (xy 263.52909 -58.27874) (xy 263.506154 -58.223367)
			(xy 263.490641 -58.165474) (xy 263.482818 -58.106052) (xy 259.032272 -58.106052) (xy 259.024951 -58.161664)
			(xy 259.009438 -58.219557) (xy 258.986502 -58.27493) (xy 258.956535 -58.326836) (xy 258.920048 -58.374386)
			(xy 258.877668 -58.416766) (xy 258.830118 -58.453253) (xy 258.778212 -58.48322) (xy 258.722839 -58.506156)
			(xy 258.664946 -58.521669) (xy 258.605524 -58.529492) (xy 258.545588 -58.529492) (xy 258.486166 -58.521669)
			(xy 258.428273 -58.506156) (xy 258.3729 -58.48322) (xy 258.320994 -58.453253) (xy 258.273444 -58.416766)
			(xy 258.231064 -58.374386) (xy 258.194577 -58.326836) (xy 258.16461 -58.27493) (xy 258.141674 -58.219557)
			(xy 258.126161 -58.161664) (xy 258.118338 -58.102242) (xy 254.934149 -58.102242) (xy 254.915209 -58.145424)
			(xy 254.887655 -58.190266) (xy 254.854208 -58.230903) (xy 254.835152 -58.249058) (xy 254.827775 -58.2566)
			(xy 254.819235 -58.275864) (xy 254.818642 -58.286396) (xy 254.818642 -58.361072) (xy 254.819161 -58.371623)
			(xy 254.827702 -58.390919) (xy 254.835152 -58.39841) (xy 254.854215 -58.416558) (xy 254.88767 -58.45719)
			(xy 254.915226 -58.502032) (xy 254.936363 -58.550235) (xy 254.94794 -58.591192) (xy 264.687032 -58.591192)
			(xy 264.687032 -58.531256) (xy 264.694855 -58.471834) (xy 264.710368 -58.413941) (xy 264.733304 -58.358568)
			(xy 264.763271 -58.306662) (xy 264.799758 -58.259112) (xy 264.842138 -58.216732) (xy 264.889688 -58.180245)
			(xy 264.941594 -58.150278) (xy 264.996967 -58.127342) (xy 265.05486 -58.111829) (xy 265.114282 -58.104006)
			(xy 265.174218 -58.104006) (xy 265.23364 -58.111829) (xy 265.291533 -58.127342) (xy 265.346906 -58.150278)
			(xy 265.398812 -58.180245) (xy 265.446362 -58.216732) (xy 265.488742 -58.259112) (xy 265.525229 -58.306662)
			(xy 265.555196 -58.358568) (xy 265.578132 -58.413941) (xy 265.593645 -58.471834) (xy 265.594679 -58.479686)
			(xy 266.933662 -58.479686) (xy 266.933662 -58.41975) (xy 266.941485 -58.360328) (xy 266.956998 -58.302435)
			(xy 266.979934 -58.247062) (xy 267.009901 -58.195156) (xy 267.046388 -58.147606) (xy 267.088768 -58.105226)
			(xy 267.136318 -58.068739) (xy 267.188224 -58.038772) (xy 267.243597 -58.015836) (xy 267.30149 -58.000323)
			(xy 267.360912 -57.9925) (xy 267.420848 -57.9925) (xy 267.48027 -58.000323) (xy 267.538163 -58.015836)
			(xy 267.593536 -58.038772) (xy 267.645442 -58.068739) (xy 267.692992 -58.105226) (xy 267.735372 -58.147606)
			(xy 267.771859 -58.195156) (xy 267.801826 -58.247062) (xy 267.824762 -58.302435) (xy 267.840275 -58.360328)
			(xy 267.848098 -58.41975) (xy 267.848588 -58.449718) (xy 267.848098 -58.479686) (xy 267.840275 -58.539108)
			(xy 267.824762 -58.597001) (xy 267.801826 -58.652374) (xy 267.771859 -58.70428) (xy 267.751046 -58.731404)
			(xy 271.720564 -58.731404) (xy 271.721017 -58.704033) (xy 271.728835 -58.649853) (xy 271.744327 -58.597349)
			(xy 271.767172 -58.547602) (xy 271.796901 -58.501637) (xy 271.814544 -58.480706) (xy 271.814798 -58.480452)
			(xy 271.820369 -58.473355) (xy 271.826625 -58.456446) (xy 271.82699 -58.447432) (xy 271.82699 -58.380376)
			(xy 271.826647 -58.371358) (xy 271.82039 -58.354441) (xy 271.814798 -58.347356) (xy 271.814544 -58.347356)
			(xy 271.814544 -58.347102) (xy 271.796907 -58.326166) (xy 271.76718 -58.2802) (xy 271.744334 -58.230454)
			(xy 271.728836 -58.177952) (xy 271.721007 -58.123774) (xy 271.721007 -58.069032) (xy 271.728835 -58.014854)
			(xy 271.744332 -57.962352) (xy 271.767177 -57.912606) (xy 271.796903 -57.866638) (xy 271.814544 -57.845706)
			(xy 271.814798 -57.845452) (xy 271.820369 -57.838355) (xy 271.826625 -57.821446) (xy 271.82699 -57.812432)
			(xy 271.82699 -57.745376) (xy 271.826647 -57.736358) (xy 271.82039 -57.719441) (xy 271.814798 -57.712356)
			(xy 271.814544 -57.712356) (xy 271.814544 -57.712102) (xy 271.796907 -57.691166) (xy 271.76718 -57.6452)
			(xy 271.744334 -57.595454) (xy 271.728836 -57.542952) (xy 271.721007 -57.488774) (xy 271.721007 -57.434032)
			(xy 271.728835 -57.379854) (xy 271.744332 -57.327352) (xy 271.767177 -57.277606) (xy 271.796903 -57.231638)
			(xy 271.814544 -57.210706) (xy 271.814798 -57.210452) (xy 271.820369 -57.203355) (xy 271.826625 -57.186446)
			(xy 271.82699 -57.177432) (xy 271.82699 -57.110376) (xy 271.826647 -57.101358) (xy 271.82039 -57.084441)
			(xy 271.814798 -57.077356) (xy 271.814544 -57.077356) (xy 271.814544 -57.077102) (xy 271.796899 -57.056174)
			(xy 271.767187 -57.010201) (xy 271.744351 -56.960452) (xy 271.728862 -56.907951) (xy 271.721036 -56.853774)
			(xy 271.720564 -56.826404) (xy 271.72105 -56.799153) (xy 271.728806 -56.745205) (xy 271.744161 -56.69291)
			(xy 271.766803 -56.643333) (xy 271.796269 -56.597483) (xy 271.83196 -56.556292) (xy 271.873151 -56.520601)
			(xy 271.919001 -56.491135) (xy 271.968578 -56.468493) (xy 272.020873 -56.453138) (xy 272.074821 -56.445382)
			(xy 272.129323 -56.445382) (xy 272.183271 -56.453138) (xy 272.235566 -56.468493) (xy 272.285143 -56.491135)
			(xy 272.330993 -56.520601) (xy 272.372184 -56.556292) (xy 272.407875 -56.597483) (xy 272.437341 -56.643333)
			(xy 272.459983 -56.69291) (xy 272.475338 -56.745205) (xy 272.483094 -56.799153) (xy 272.48329 -56.810148)
			(xy 274.300188 -56.810148) (xy 274.300188 -56.809894) (xy 274.300678 -56.779926) (xy 274.308501 -56.720504)
			(xy 274.324014 -56.662611) (xy 274.34695 -56.607238) (xy 274.376917 -56.555332) (xy 274.413404 -56.507782)
			(xy 274.455784 -56.465402) (xy 274.503334 -56.428915) (xy 274.55524 -56.398948) (xy 274.610613 -56.376012)
			(xy 274.668506 -56.360499) (xy 274.727928 -56.352676) (xy 274.787864 -56.352676) (xy 274.847286 -56.360499)
			(xy 274.905179 -56.376012) (xy 274.960552 -56.398948) (xy 275.012458 -56.428915) (xy 275.060008 -56.465402)
			(xy 275.102388 -56.507782) (xy 275.138875 -56.555332) (xy 275.168842 -56.607238) (xy 275.191778 -56.662611)
			(xy 275.207291 -56.720504) (xy 275.215114 -56.779926) (xy 275.215604 -56.809894) (xy 275.215604 -56.810148)
			(xy 275.215029 -56.841671) (xy 275.206361 -56.904119) (xy 275.189208 -56.964787) (xy 275.163895 -57.022529)
			(xy 275.130901 -57.076253) (xy 275.09085 -57.124943) (xy 275.06803 -57.146698) (xy 275.060918 -57.153302)
			(xy 275.052536 -57.17032) (xy 275.046186 -57.248806) (xy 275.045822 -57.258371) (xy 275.051438 -57.276654)
			(xy 275.057108 -57.284366) (xy 275.072642 -57.304652) (xy 275.098702 -57.348601) (xy 275.118666 -57.395633)
			(xy 275.132178 -57.444909) (xy 275.135159 -57.467049) (xy 275.318492 -57.467049) (xy 275.318492 -57.412551)
			(xy 275.326248 -57.358608) (xy 275.341601 -57.306317) (xy 275.364239 -57.256743) (xy 275.393702 -57.210896)
			(xy 275.429389 -57.169708) (xy 275.470575 -57.134018) (xy 275.51642 -57.104552) (xy 275.565992 -57.08191)
			(xy 275.618282 -57.066553) (xy 275.672225 -57.058794) (xy 275.699474 -57.058306) (xy 275.725022 -57.058714)
			(xy 275.775662 -57.065521) (xy 275.824939 -57.07903) (xy 275.87197 -57.098999) (xy 275.915913 -57.125071)
			(xy 275.936202 -57.140602) (xy 275.943927 -57.14624) (xy 275.962202 -57.15184) (xy 275.971762 -57.151524)
			(xy 276.050248 -57.145174) (xy 276.067266 -57.136792) (xy 276.07387 -57.12968) (xy 276.095636 -57.106867)
			(xy 276.144309 -57.066786) (xy 276.198025 -57.03377) (xy 276.255767 -57.008444) (xy 276.31644 -56.99129)
			(xy 276.378894 -56.982633) (xy 276.41042 -56.982106) (xy 276.410674 -56.982106) (xy 276.440643 -56.982585)
			(xy 276.500069 -56.990406) (xy 276.557965 -57.005917) (xy 276.613341 -57.028852) (xy 276.66525 -57.058819)
			(xy 276.688747 -57.076848) (xy 277.338536 -57.076848) (xy 277.339021 -57.049478) (xy 277.346833 -56.9953)
			(xy 277.362317 -56.942797) (xy 277.385155 -56.893049) (xy 277.414876 -56.847082) (xy 277.432516 -56.82615)
			(xy 277.43277 -56.825896) (xy 277.438373 -56.818821) (xy 277.444608 -56.801895) (xy 277.444962 -56.792876)
			(xy 277.444962 -56.72582) (xy 277.444604 -56.716803) (xy 277.438358 -56.699886) (xy 277.43277 -56.6928)
			(xy 277.432516 -56.6928) (xy 277.432516 -56.692546) (xy 277.414887 -56.671605) (xy 277.385174 -56.625635)
			(xy 277.362335 -56.57589) (xy 277.346842 -56.523391) (xy 277.339011 -56.469217) (xy 277.338536 -56.441848)
			(xy 277.339022 -56.414597) (xy 277.346778 -56.360649) (xy 277.362133 -56.308354) (xy 277.384775 -56.258777)
			(xy 277.414241 -56.212927) (xy 277.449932 -56.171736) (xy 277.491123 -56.136045) (xy 277.536973 -56.106579)
			(xy 277.58655 -56.083937) (xy 277.638845 -56.068582) (xy 277.692793 -56.060826) (xy 277.747295 -56.060826)
			(xy 277.801243 -56.068582) (xy 277.853538 -56.083937) (xy 277.903115 -56.106579) (xy 277.948965 -56.136045)
			(xy 277.990156 -56.171736) (xy 278.025847 -56.212927) (xy 278.055313 -56.258777) (xy 278.077955 -56.308354)
			(xy 278.09331 -56.360649) (xy 278.101066 -56.414597) (xy 278.101552 -56.441848) (xy 278.101067 -56.469218)
			(xy 278.093256 -56.523396) (xy 278.077772 -56.5759) (xy 278.054934 -56.625647) (xy 278.025212 -56.671614)
			(xy 278.007572 -56.692546) (xy 278.007318 -56.6928) (xy 278.001728 -56.699884) (xy 277.995483 -56.716803)
			(xy 277.995126 -56.72582) (xy 277.995126 -56.792876) (xy 277.995489 -56.801892) (xy 278.001732 -56.81881)
			(xy 278.007318 -56.825896) (xy 278.007572 -56.825896) (xy 278.007572 -56.82615) (xy 278.025197 -56.847094)
			(xy 278.054912 -56.893063) (xy 278.077751 -56.942807) (xy 278.093245 -56.995306) (xy 278.094348 -57.002934)
			(xy 279.763474 -57.002934) (xy 279.764 -56.974844) (xy 279.772222 -56.919268) (xy 279.788508 -56.8655)
			(xy 279.812505 -56.814703) (xy 279.843695 -56.767976) (xy 279.881403 -56.726329) (xy 279.924812 -56.690666)
			(xy 279.94864 -56.675782) (xy 279.95753 -56.670448) (xy 279.969722 -56.65343) (xy 279.990042 -56.560212)
			(xy 279.985724 -56.539638) (xy 279.979882 -56.531002) (xy 279.963879 -56.50694) (xy 279.938537 -56.455008)
			(xy 279.921313 -56.399849) (xy 279.912598 -56.342725) (xy 279.912064 -56.313832) (xy 279.912585 -56.286581)
			(xy 279.920337 -56.232634) (xy 279.935687 -56.180339) (xy 279.958324 -56.130761) (xy 279.987786 -56.084909)
			(xy 280.023474 -56.043716) (xy 280.064661 -56.008022) (xy 280.110508 -55.978553) (xy 280.160082 -55.955908)
			(xy 280.212375 -55.94055) (xy 280.266321 -55.932789) (xy 280.293572 -55.932324) (xy 280.320942 -55.932801)
			(xy 280.375121 -55.940615) (xy 280.427624 -55.956101) (xy 280.477371 -55.978941) (xy 280.523338 -56.008664)
			(xy 280.54427 -56.026304) (xy 280.544524 -56.026558) (xy 280.551595 -56.032168) (xy 280.568524 -56.038399)
			(xy 280.577544 -56.03875) (xy 280.6446 -56.03875) (xy 280.653618 -56.038404) (xy 280.670536 -56.03215)
			(xy 280.67762 -56.026558) (xy 280.67762 -56.026304) (xy 280.677874 -56.026304) (xy 280.698807 -56.008663)
			(xy 280.744775 -55.978939) (xy 280.794521 -55.956093) (xy 280.847023 -55.940597) (xy 280.901201 -55.932768)
			(xy 280.955943 -55.932768) (xy 281.010121 -55.940597) (xy 281.062623 -55.956093) (xy 281.112369 -55.978939)
			(xy 281.158337 -56.008663) (xy 281.17927 -56.026304) (xy 281.179524 -56.026558) (xy 281.186595 -56.032168)
			(xy 281.203524 -56.038399) (xy 281.212544 -56.03875) (xy 281.2796 -56.03875) (xy 281.288618 -56.038404)
			(xy 281.305536 -56.03215) (xy 281.31262 -56.026558) (xy 281.31262 -56.026304) (xy 281.312874 -56.026304)
			(xy 281.333806 -56.008664) (xy 281.379778 -55.978952) (xy 281.429526 -55.956116) (xy 281.482027 -55.940626)
			(xy 281.536203 -55.932798) (xy 281.563572 -55.932324) (xy 281.590828 -55.932721) (xy 281.644787 -55.940475)
			(xy 281.697093 -55.95583) (xy 281.746681 -55.978473) (xy 281.792541 -56.007943) (xy 281.833741 -56.04364)
			(xy 281.86944 -56.084836) (xy 281.898913 -56.130695) (xy 281.92156 -56.180281) (xy 281.936919 -56.232586)
			(xy 281.944677 -56.286544) (xy 281.944677 -56.297068) (xy 282.286454 -56.297068) (xy 282.290525 -56.241446)
			(xy 282.302651 -56.187009) (xy 282.322574 -56.134918) (xy 282.34987 -56.086283) (xy 282.383956 -56.04214)
			(xy 282.424105 -56.003431) (xy 282.469463 -55.97098) (xy 282.519063 -55.945479) (xy 282.571847 -55.927472)
			(xy 282.62669 -55.917342) (xy 282.682424 -55.915305) (xy 282.737861 -55.921405) (xy 282.791818 -55.935511)
			(xy 282.843147 -55.957323) (xy 282.890753 -55.986377) (xy 282.933621 -56.022052) (xy 282.970838 -56.063589)
			(xy 283.001611 -56.110102) (xy 283.025283 -56.160599) (xy 283.041351 -56.214006) (xy 283.049471 -56.269182)
			(xy 283.04998 -56.297068) (xy 283.049471 -56.324954) (xy 283.045276 -56.353456) (xy 285.14116 -56.353456)
			(xy 285.145231 -56.297834) (xy 285.157357 -56.243397) (xy 285.17728 -56.191306) (xy 285.204576 -56.142671)
			(xy 285.238662 -56.098528) (xy 285.278811 -56.059819) (xy 285.324169 -56.027368) (xy 285.373769 -56.001867)
			(xy 285.426553 -55.98386) (xy 285.481396 -55.97373) (xy 285.53713 -55.971693) (xy 285.592567 -55.977793)
			(xy 285.646524 -55.991899) (xy 285.697853 -56.013711) (xy 285.745459 -56.042765) (xy 285.788327 -56.07844)
			(xy 285.825544 -56.119977) (xy 285.856317 -56.16649) (xy 285.879989 -56.216987) (xy 285.896057 -56.270394)
			(xy 285.904177 -56.32557) (xy 285.904686 -56.353456) (xy 285.904177 -56.381342) (xy 285.896057 -56.436518)
			(xy 285.879989 -56.489925) (xy 285.856317 -56.540422) (xy 285.825544 -56.586935) (xy 285.788327 -56.628472)
			(xy 285.745459 -56.664147) (xy 285.697853 -56.693201) (xy 285.646524 -56.715013) (xy 285.592567 -56.729119)
			(xy 285.53713 -56.735219) (xy 285.481396 -56.733182) (xy 285.426553 -56.723052) (xy 285.373769 -56.705045)
			(xy 285.324169 -56.679544) (xy 285.278811 -56.647093) (xy 285.238662 -56.608384) (xy 285.204576 -56.564241)
			(xy 285.17728 -56.515606) (xy 285.157357 -56.463515) (xy 285.145231 -56.409078) (xy 285.14116 -56.353456)
			(xy 283.045276 -56.353456) (xy 283.041351 -56.38013) (xy 283.025283 -56.433537) (xy 283.001611 -56.484034)
			(xy 282.970838 -56.530547) (xy 282.933621 -56.572084) (xy 282.890753 -56.607759) (xy 282.843147 -56.636813)
			(xy 282.791818 -56.658625) (xy 282.737861 -56.672731) (xy 282.682424 -56.678831) (xy 282.62669 -56.676794)
			(xy 282.571847 -56.666664) (xy 282.519063 -56.648657) (xy 282.469463 -56.623156) (xy 282.424105 -56.590705)
			(xy 282.383956 -56.551996) (xy 282.34987 -56.507853) (xy 282.322574 -56.459218) (xy 282.302651 -56.407127)
			(xy 282.290525 -56.35269) (xy 282.286454 -56.297068) (xy 281.944677 -56.297068) (xy 281.944677 -56.341056)
			(xy 281.936919 -56.395014) (xy 281.92156 -56.447319) (xy 281.898913 -56.496905) (xy 281.86944 -56.542764)
			(xy 281.833741 -56.58396) (xy 281.792541 -56.619657) (xy 281.746681 -56.649127) (xy 281.697093 -56.67177)
			(xy 281.644787 -56.687125) (xy 281.590828 -56.694879) (xy 281.563572 -56.69534) (xy 281.5362 -56.694905)
			(xy 281.482019 -56.687082) (xy 281.429515 -56.671586) (xy 281.379769 -56.648737) (xy 281.333804 -56.619005)
			(xy 281.312874 -56.60136) (xy 281.31262 -56.601106) (xy 281.305531 -56.595522) (xy 281.288616 -56.589274)
			(xy 281.2796 -56.588914) (xy 281.212544 -56.588914) (xy 281.203529 -56.589289) (xy 281.186612 -56.595524)
			(xy 281.179524 -56.601106) (xy 281.179524 -56.60136) (xy 281.17927 -56.60136) (xy 281.158337 -56.619001)
			(xy 281.112369 -56.648725) (xy 281.062623 -56.671571) (xy 281.010121 -56.687067) (xy 280.955943 -56.694896)
			(xy 280.901201 -56.694896) (xy 280.847023 -56.687067) (xy 280.794521 -56.671571) (xy 280.744775 -56.648725)
			(xy 280.698807 -56.619001) (xy 280.677874 -56.60136) (xy 280.67762 -56.601106) (xy 280.670531 -56.595522)
			(xy 280.653616 -56.589274) (xy 280.6446 -56.588914) (xy 280.577544 -56.588914) (xy 280.568529 -56.589289)
			(xy 280.551612 -56.595524) (xy 280.544524 -56.601106) (xy 280.544016 -56.60136) (xy 280.531285 -56.612308)
			(xy 280.504191 -56.632147) (xy 280.489914 -56.640984) (xy 280.481024 -56.646318) (xy 280.468832 -56.663336)
			(xy 280.448512 -56.756554) (xy 280.45283 -56.777128) (xy 280.458672 -56.785764) (xy 280.474656 -56.809838)
			(xy 280.500003 -56.861766) (xy 280.517233 -56.91692) (xy 280.525953 -56.974042) (xy 280.52649 -57.002934)
			(xy 280.526004 -57.030185) (xy 280.518248 -57.084133) (xy 280.502893 -57.136428) (xy 280.480251 -57.186005)
			(xy 280.450785 -57.231855) (xy 280.415094 -57.273046) (xy 280.373903 -57.308737) (xy 280.328053 -57.338203)
			(xy 280.278476 -57.360845) (xy 280.226181 -57.3762) (xy 280.172233 -57.383956) (xy 280.117731 -57.383956)
			(xy 280.063783 -57.3762) (xy 280.011488 -57.360845) (xy 279.961911 -57.338203) (xy 279.916061 -57.308737)
			(xy 279.87487 -57.273046) (xy 279.839179 -57.231855) (xy 279.809713 -57.186005) (xy 279.787071 -57.136428)
			(xy 279.771716 -57.084133) (xy 279.76396 -57.030185) (xy 279.763474 -57.002934) (xy 278.094348 -57.002934)
			(xy 278.101076 -57.04948) (xy 278.101552 -57.076848) (xy 278.101066 -57.104099) (xy 278.09331 -57.158047)
			(xy 278.077955 -57.210342) (xy 278.055313 -57.259919) (xy 278.025847 -57.305769) (xy 277.990156 -57.34696)
			(xy 277.948965 -57.382651) (xy 277.903115 -57.412117) (xy 277.853538 -57.434759) (xy 277.801243 -57.450114)
			(xy 277.747295 -57.45787) (xy 277.692793 -57.45787) (xy 277.638845 -57.450114) (xy 277.58655 -57.434759)
			(xy 277.536973 -57.412117) (xy 277.491123 -57.382651) (xy 277.449932 -57.34696) (xy 277.414241 -57.305769)
			(xy 277.384775 -57.259919) (xy 277.362133 -57.210342) (xy 277.346778 -57.158047) (xy 277.339022 -57.104099)
			(xy 277.338536 -57.076848) (xy 276.688747 -57.076848) (xy 276.712803 -57.095306) (xy 276.755186 -57.137688)
			(xy 276.791674 -57.18524) (xy 276.821643 -57.237148) (xy 276.84458 -57.292524) (xy 276.860092 -57.35042)
			(xy 276.867914 -57.409845) (xy 276.868382 -57.439814) (xy 276.86794 -57.468047) (xy 276.865806 -57.48528)
			(xy 288.805872 -57.48528) (xy 288.809943 -57.429658) (xy 288.822069 -57.375221) (xy 288.841992 -57.32313)
			(xy 288.869288 -57.274495) (xy 288.903374 -57.230352) (xy 288.943523 -57.191643) (xy 288.988881 -57.159192)
			(xy 289.038481 -57.133691) (xy 289.091265 -57.115684) (xy 289.146108 -57.105554) (xy 289.201842 -57.103517)
			(xy 289.257279 -57.109617) (xy 289.311236 -57.123723) (xy 289.362565 -57.145535) (xy 289.410171 -57.174589)
			(xy 289.453039 -57.210264) (xy 289.490256 -57.251801) (xy 289.521029 -57.298314) (xy 289.544701 -57.348811)
			(xy 289.560769 -57.402218) (xy 289.568889 -57.457394) (xy 289.569398 -57.48528) (xy 289.568889 -57.513166)
			(xy 289.560769 -57.568342) (xy 289.544701 -57.621749) (xy 289.521029 -57.672246) (xy 289.490256 -57.718759)
			(xy 289.453039 -57.760296) (xy 289.410171 -57.795971) (xy 289.362565 -57.825025) (xy 289.311236 -57.846837)
			(xy 289.257279 -57.860943) (xy 289.201842 -57.867043) (xy 289.146108 -57.865006) (xy 289.091265 -57.854876)
			(xy 289.038481 -57.836869) (xy 288.988881 -57.811368) (xy 288.943523 -57.778917) (xy 288.903374 -57.740208)
			(xy 288.869288 -57.696065) (xy 288.841992 -57.64743) (xy 288.822069 -57.595339) (xy 288.809943 -57.540902)
			(xy 288.805872 -57.48528) (xy 276.865806 -57.48528) (xy 276.861 -57.524084) (xy 276.847214 -57.57884)
			(xy 276.826792 -57.631482) (xy 276.800045 -57.681211) (xy 276.784054 -57.704482) (xy 276.776688 -57.71515)
			(xy 276.77364 -57.740804) (xy 276.816058 -57.844436) (xy 276.836124 -57.860692) (xy 276.849078 -57.862978)
			(xy 276.875193 -57.86809) (xy 276.925764 -57.884655) (xy 276.973544 -57.908082) (xy 277.017607 -57.937919)
			(xy 277.057098 -57.973588) (xy 277.091253 -58.014395) (xy 277.119408 -58.059551) (xy 277.141019 -58.10818)
			(xy 277.155666 -58.159339) (xy 277.163065 -58.212037) (xy 277.16353 -58.238644) (xy 277.163048 -58.266014)
			(xy 277.155237 -58.320193) (xy 277.139752 -58.372697) (xy 277.116914 -58.422444) (xy 277.087191 -58.468411)
			(xy 277.06955 -58.489342) (xy 277.069296 -58.489596) (xy 277.063705 -58.496679) (xy 277.057461 -58.513599)
			(xy 277.057104 -58.522616) (xy 277.057104 -58.589672) (xy 277.057473 -58.598688) (xy 277.063712 -58.615605)
			(xy 277.069296 -58.622692) (xy 277.06955 -58.622692) (xy 277.06955 -58.622946) (xy 277.087169 -58.643894)
			(xy 277.11008 -58.679334) (xy 280.195274 -58.679334) (xy 280.195706 -58.653019) (xy 280.202949 -58.600889)
			(xy 280.217276 -58.550246) (xy 280.238415 -58.502047) (xy 280.265967 -58.457205) (xy 280.29941 -58.416566)
			(xy 280.318464 -58.39841) (xy 280.325858 -58.390882) (xy 280.334388 -58.371607) (xy 280.334974 -58.361072)
			(xy 280.334974 -58.286396) (xy 280.334468 -58.275843) (xy 280.325917 -58.256548) (xy 280.318464 -58.249058)
			(xy 280.299388 -58.230923) (xy 280.265934 -58.190288) (xy 280.238379 -58.145443) (xy 280.217244 -58.097239)
			(xy 280.202931 -58.046588) (xy 280.19571 -57.994451) (xy 280.195274 -57.968134) (xy 280.19576 -57.940883)
			(xy 280.203516 -57.886935) (xy 280.218871 -57.83464) (xy 280.241513 -57.785063) (xy 280.270979 -57.739213)
			(xy 280.30667 -57.698022) (xy 280.347861 -57.662331) (xy 280.393711 -57.632865) (xy 280.443288 -57.610223)
			(xy 280.495583 -57.594868) (xy 280.549531 -57.587112) (xy 280.604033 -57.587112) (xy 280.657981 -57.594868)
			(xy 280.710276 -57.610223) (xy 280.759853 -57.632865) (xy 280.805703 -57.662331) (xy 280.846894 -57.698022)
			(xy 280.882585 -57.739213) (xy 280.912051 -57.785063) (xy 280.934693 -57.83464) (xy 280.950048 -57.886935)
			(xy 280.957804 -57.940883) (xy 280.95829 -57.968134) (xy 280.957848 -57.994449) (xy 280.950609 -58.046579)
			(xy 280.936285 -58.097222) (xy 280.934084 -58.102242) (xy 284.118286 -58.102242) (xy 284.118286 -58.042306)
			(xy 284.126109 -57.982884) (xy 284.141622 -57.924991) (xy 284.164558 -57.869618) (xy 284.194525 -57.817712)
			(xy 284.231012 -57.770162) (xy 284.273392 -57.727782) (xy 284.320942 -57.691295) (xy 284.372848 -57.661328)
			(xy 284.428221 -57.638392) (xy 284.486114 -57.622879) (xy 284.545536 -57.615056) (xy 284.605472 -57.615056)
			(xy 284.664894 -57.622879) (xy 284.722787 -57.638392) (xy 284.77816 -57.661328) (xy 284.830066 -57.691295)
			(xy 284.877616 -57.727782) (xy 284.919996 -57.770162) (xy 284.956483 -57.817712) (xy 284.98645 -57.869618)
			(xy 285.009386 -57.924991) (xy 285.024899 -57.982884) (xy 285.032722 -58.042306) (xy 285.033212 -58.072274)
			(xy 285.032722 -58.102242) (xy 285.03222 -58.106052) (xy 289.482766 -58.106052) (xy 289.482766 -58.046116)
			(xy 289.490589 -57.986694) (xy 289.506102 -57.928801) (xy 289.529038 -57.873428) (xy 289.559005 -57.821522)
			(xy 289.595492 -57.773972) (xy 289.637872 -57.731592) (xy 289.685422 -57.695105) (xy 289.737328 -57.665138)
			(xy 289.792701 -57.642202) (xy 289.850594 -57.626689) (xy 289.910016 -57.618866) (xy 289.969952 -57.618866)
			(xy 290.029374 -57.626689) (xy 290.087267 -57.642202) (xy 290.14264 -57.665138) (xy 290.194546 -57.695105)
			(xy 290.242096 -57.731592) (xy 290.284476 -57.773972) (xy 290.320963 -57.821522) (xy 290.35093 -57.873428)
			(xy 290.360803 -57.897264) (xy 291.76775 -57.897264) (xy 291.76775 -57.837328) (xy 291.775573 -57.777906)
			(xy 291.791086 -57.720013) (xy 291.814022 -57.66464) (xy 291.843989 -57.612734) (xy 291.880476 -57.565184)
			(xy 291.922856 -57.522804) (xy 291.970406 -57.486317) (xy 292.022312 -57.45635) (xy 292.077685 -57.433414)
			(xy 292.135578 -57.417901) (xy 292.195 -57.410078) (xy 292.254936 -57.410078) (xy 292.314358 -57.417901)
			(xy 292.372251 -57.433414) (xy 292.427624 -57.45635) (xy 292.47953 -57.486317) (xy 292.52708 -57.522804)
			(xy 292.56946 -57.565184) (xy 292.605947 -57.612734) (xy 292.635914 -57.66464) (xy 292.65885 -57.720013)
			(xy 292.674363 -57.777906) (xy 292.682186 -57.837328) (xy 292.682676 -57.867296) (xy 292.682186 -57.897264)
			(xy 292.674363 -57.956686) (xy 292.65885 -58.014579) (xy 292.635914 -58.069952) (xy 292.605947 -58.121858)
			(xy 292.56946 -58.169408) (xy 292.52708 -58.211788) (xy 292.47953 -58.248275) (xy 292.427624 -58.278242)
			(xy 292.372251 -58.301178) (xy 292.314358 -58.316691) (xy 292.254936 -58.324514) (xy 292.195 -58.324514)
			(xy 292.135578 -58.316691) (xy 292.077685 -58.301178) (xy 292.022312 -58.278242) (xy 291.970406 -58.248275)
			(xy 291.922856 -58.211788) (xy 291.880476 -58.169408) (xy 291.843989 -58.121858) (xy 291.814022 -58.069952)
			(xy 291.791086 -58.014579) (xy 291.775573 -57.956686) (xy 291.76775 -57.897264) (xy 290.360803 -57.897264)
			(xy 290.373866 -57.928801) (xy 290.389379 -57.986694) (xy 290.397202 -58.046116) (xy 290.397692 -58.076084)
			(xy 290.397202 -58.106052) (xy 290.389379 -58.165474) (xy 290.373866 -58.223367) (xy 290.35093 -58.27874)
			(xy 290.320963 -58.330646) (xy 290.284476 -58.378196) (xy 290.242096 -58.420576) (xy 290.194546 -58.457063)
			(xy 290.14264 -58.48703) (xy 290.087267 -58.509966) (xy 290.029374 -58.525479) (xy 289.969952 -58.533302)
			(xy 289.910016 -58.533302) (xy 289.850594 -58.525479) (xy 289.792701 -58.509966) (xy 289.737328 -58.48703)
			(xy 289.685422 -58.457063) (xy 289.637872 -58.420576) (xy 289.595492 -58.378196) (xy 289.559005 -58.330646)
			(xy 289.529038 -58.27874) (xy 289.506102 -58.223367) (xy 289.490589 -58.165474) (xy 289.482766 -58.106052)
			(xy 285.03222 -58.106052) (xy 285.024899 -58.161664) (xy 285.009386 -58.219557) (xy 284.98645 -58.27493)
			(xy 284.956483 -58.326836) (xy 284.919996 -58.374386) (xy 284.877616 -58.416766) (xy 284.830066 -58.453253)
			(xy 284.77816 -58.48322) (xy 284.722787 -58.506156) (xy 284.664894 -58.521669) (xy 284.605472 -58.529492)
			(xy 284.545536 -58.529492) (xy 284.486114 -58.521669) (xy 284.428221 -58.506156) (xy 284.372848 -58.48322)
			(xy 284.320942 -58.453253) (xy 284.273392 -58.416766) (xy 284.231012 -58.374386) (xy 284.194525 -58.326836)
			(xy 284.164558 -58.27493) (xy 284.141622 -58.219557) (xy 284.126109 -58.161664) (xy 284.118286 -58.102242)
			(xy 280.934084 -58.102242) (xy 280.915148 -58.145421) (xy 280.887597 -58.190264) (xy 280.854154 -58.230902)
			(xy 280.8351 -58.249058) (xy 280.827715 -58.256593) (xy 280.819181 -58.275863) (xy 280.81859 -58.286396)
			(xy 280.81859 -58.361072) (xy 280.819124 -58.371621) (xy 280.827656 -58.390916) (xy 280.8351 -58.39841)
			(xy 280.854153 -58.416568) (xy 280.887611 -58.457197) (xy 280.91517 -58.502037) (xy 280.936309 -58.550237)
			(xy 280.947886 -58.591192) (xy 290.68698 -58.591192) (xy 290.68698 -58.531256) (xy 290.694803 -58.471834)
			(xy 290.710316 -58.413941) (xy 290.733252 -58.358568) (xy 290.763219 -58.306662) (xy 290.799706 -58.259112)
			(xy 290.842086 -58.216732) (xy 290.889636 -58.180245) (xy 290.941542 -58.150278) (xy 290.996915 -58.127342)
			(xy 291.054808 -58.111829) (xy 291.11423 -58.104006) (xy 291.174166 -58.104006) (xy 291.233588 -58.111829)
			(xy 291.291481 -58.127342) (xy 291.346854 -58.150278) (xy 291.39876 -58.180245) (xy 291.44631 -58.216732)
			(xy 291.48869 -58.259112) (xy 291.525177 -58.306662) (xy 291.555144 -58.358568) (xy 291.57808 -58.413941)
			(xy 291.593593 -58.471834) (xy 291.594627 -58.479686) (xy 292.93361 -58.479686) (xy 292.93361 -58.41975)
			(xy 292.941433 -58.360328) (xy 292.956946 -58.302435) (xy 292.979882 -58.247062) (xy 293.009849 -58.195156)
			(xy 293.046336 -58.147606) (xy 293.088716 -58.105226) (xy 293.136266 -58.068739) (xy 293.188172 -58.038772)
			(xy 293.243545 -58.015836) (xy 293.301438 -58.000323) (xy 293.36086 -57.9925) (xy 293.420796 -57.9925)
			(xy 293.480218 -58.000323) (xy 293.538111 -58.015836) (xy 293.593484 -58.038772) (xy 293.64539 -58.068739)
			(xy 293.69294 -58.105226) (xy 293.73532 -58.147606) (xy 293.771807 -58.195156) (xy 293.801774 -58.247062)
			(xy 293.82471 -58.302435) (xy 293.840223 -58.360328) (xy 293.848046 -58.41975) (xy 293.848536 -58.449718)
			(xy 293.848046 -58.479686) (xy 293.840223 -58.539108) (xy 293.82471 -58.597001) (xy 293.801774 -58.652374)
			(xy 293.771807 -58.70428) (xy 293.750994 -58.731404) (xy 297.720512 -58.731404) (xy 297.720977 -58.704034)
			(xy 297.728795 -58.649854) (xy 297.744284 -58.597351) (xy 297.767126 -58.547604) (xy 297.796851 -58.501638)
			(xy 297.814492 -58.480706) (xy 297.814746 -58.480452) (xy 297.820323 -58.473359) (xy 297.826574 -58.456447)
			(xy 297.826938 -58.447432) (xy 297.826938 -58.380376) (xy 297.826584 -58.371359) (xy 297.820334 -58.354442)
			(xy 297.814746 -58.347356) (xy 297.814492 -58.347356) (xy 297.814492 -58.347102) (xy 297.796857 -58.326165)
			(xy 297.767134 -58.280197) (xy 297.744291 -58.230452) (xy 297.728796 -58.17795) (xy 297.720968 -58.123773)
			(xy 297.720967 -58.069033) (xy 297.728795 -58.014855) (xy 297.744289 -57.962354) (xy 297.767131 -57.912608)
			(xy 297.796853 -57.866639) (xy 297.814492 -57.845706) (xy 297.814746 -57.845452) (xy 297.820323 -57.838359)
			(xy 297.826574 -57.821447) (xy 297.826938 -57.812432) (xy 297.826938 -57.745376) (xy 297.826584 -57.736359)
			(xy 297.820334 -57.719442) (xy 297.814746 -57.712356) (xy 297.814492 -57.712356) (xy 297.814492 -57.712102)
			(xy 297.796857 -57.691165) (xy 297.767134 -57.645197) (xy 297.744291 -57.595452) (xy 297.728796 -57.54295)
			(xy 297.720968 -57.488773) (xy 297.720967 -57.434033) (xy 297.728795 -57.379855) (xy 297.744289 -57.327354)
			(xy 297.767131 -57.277608) (xy 297.796853 -57.231639) (xy 297.814492 -57.210706) (xy 297.814746 -57.210452)
			(xy 297.820323 -57.203359) (xy 297.826574 -57.186447) (xy 297.826938 -57.177432) (xy 297.826938 -57.110376)
			(xy 297.826584 -57.101359) (xy 297.820334 -57.084442) (xy 297.814746 -57.077356) (xy 297.814492 -57.077356)
			(xy 297.814492 -57.077102) (xy 297.796839 -57.056181) (xy 297.76713 -57.010205) (xy 297.744296 -56.960455)
			(xy 297.728809 -56.907952) (xy 297.720984 -56.853774) (xy 297.720512 -56.826404) (xy 297.720998 -56.799153)
			(xy 297.728754 -56.745205) (xy 297.744109 -56.69291) (xy 297.766751 -56.643333) (xy 297.796217 -56.597483)
			(xy 297.831908 -56.556292) (xy 297.873099 -56.520601) (xy 297.918949 -56.491135) (xy 297.968526 -56.468493)
			(xy 298.020821 -56.453138) (xy 298.074769 -56.445382) (xy 298.129271 -56.445382) (xy 298.183219 -56.453138)
			(xy 298.235514 -56.468493) (xy 298.285091 -56.491135) (xy 298.330941 -56.520601) (xy 298.372132 -56.556292)
			(xy 298.407823 -56.597483) (xy 298.437289 -56.643333) (xy 298.459931 -56.69291) (xy 298.475286 -56.745205)
			(xy 298.483042 -56.799153) (xy 298.483238 -56.810148) (xy 300.300136 -56.810148) (xy 300.300136 -56.809894)
			(xy 300.300626 -56.779926) (xy 300.308449 -56.720504) (xy 300.323962 -56.662611) (xy 300.346898 -56.607238)
			(xy 300.376865 -56.555332) (xy 300.413352 -56.507782) (xy 300.455732 -56.465402) (xy 300.503282 -56.428915)
			(xy 300.555188 -56.398948) (xy 300.610561 -56.376012) (xy 300.668454 -56.360499) (xy 300.727876 -56.352676)
			(xy 300.787812 -56.352676) (xy 300.847234 -56.360499) (xy 300.905127 -56.376012) (xy 300.9605 -56.398948)
			(xy 301.012406 -56.428915) (xy 301.059956 -56.465402) (xy 301.102336 -56.507782) (xy 301.138823 -56.555332)
			(xy 301.16879 -56.607238) (xy 301.191726 -56.662611) (xy 301.207239 -56.720504) (xy 301.215062 -56.779926)
			(xy 301.215552 -56.809894) (xy 301.215552 -56.810148) (xy 301.214994 -56.841672) (xy 301.206324 -56.904121)
			(xy 301.18917 -56.96479) (xy 301.163854 -57.022533) (xy 301.130856 -57.076256) (xy 301.0908 -57.124945)
			(xy 301.067978 -57.146698) (xy 301.060866 -57.153302) (xy 301.052484 -57.17032) (xy 301.046134 -57.248806)
			(xy 301.04576 -57.258372) (xy 301.051382 -57.276655) (xy 301.057056 -57.284366) (xy 301.072597 -57.304646)
			(xy 301.098655 -57.348598) (xy 301.118617 -57.395632) (xy 301.132127 -57.444908) (xy 301.135108 -57.467053)
			(xy 301.318369 -57.467053) (xy 301.318369 -57.412547) (xy 301.326127 -57.358596) (xy 301.341483 -57.306299)
			(xy 301.364126 -57.256719) (xy 301.393595 -57.210866) (xy 301.42929 -57.169675) (xy 301.470484 -57.133982)
			(xy 301.516338 -57.104516) (xy 301.565919 -57.081876) (xy 301.618218 -57.066522) (xy 301.672169 -57.058768)
			(xy 301.699422 -57.058306) (xy 301.724971 -57.058688) (xy 301.775612 -57.065501) (xy 301.824889 -57.079016)
			(xy 301.87192 -57.098991) (xy 301.915862 -57.125068) (xy 301.93615 -57.140602) (xy 301.94389 -57.146216)
			(xy 301.962154 -57.151831) (xy 301.97171 -57.151524) (xy 302.050196 -57.145174) (xy 302.067214 -57.136792)
			(xy 302.073818 -57.12968) (xy 302.095561 -57.106844) (xy 302.144238 -57.066765) (xy 302.197959 -57.033751)
			(xy 302.255706 -57.00843) (xy 302.316383 -56.991281) (xy 302.378841 -56.982629) (xy 302.410368 -56.982106)
			(xy 302.410622 -56.982106) (xy 302.440591 -56.982562) (xy 302.500015 -56.990388) (xy 302.55791 -57.005903)
			(xy 302.613284 -57.028843) (xy 302.66519 -57.058814) (xy 302.688691 -57.076848) (xy 303.338484 -57.076848)
			(xy 303.338958 -57.049478) (xy 303.346771 -56.995298) (xy 303.362257 -56.942794) (xy 303.385097 -56.893047)
			(xy 303.414822 -56.847081) (xy 303.432464 -56.82615) (xy 303.432718 -56.825896) (xy 303.438314 -56.818816)
			(xy 303.444555 -56.801894) (xy 303.44491 -56.792876) (xy 303.44491 -56.72582) (xy 303.444541 -56.716804)
			(xy 303.438302 -56.699887) (xy 303.432718 -56.6928) (xy 303.432464 -56.6928) (xy 303.432464 -56.692546)
			(xy 303.414827 -56.671612) (xy 303.385116 -56.625639) (xy 303.362281 -56.575892) (xy 303.346789 -56.523392)
			(xy 303.338959 -56.469217) (xy 303.338484 -56.441848) (xy 303.33897 -56.414597) (xy 303.346726 -56.360649)
			(xy 303.362081 -56.308354) (xy 303.384723 -56.258777) (xy 303.414189 -56.212927) (xy 303.44988 -56.171736)
			(xy 303.491071 -56.136045) (xy 303.536921 -56.106579) (xy 303.586498 -56.083937) (xy 303.638793 -56.068582)
			(xy 303.692741 -56.060826) (xy 303.747243 -56.060826) (xy 303.801191 -56.068582) (xy 303.853486 -56.083937)
			(xy 303.903063 -56.106579) (xy 303.948913 -56.136045) (xy 303.990104 -56.171736) (xy 304.025795 -56.212927)
			(xy 304.055261 -56.258777) (xy 304.077903 -56.308354) (xy 304.093258 -56.360649) (xy 304.101014 -56.414597)
			(xy 304.1015 -56.441848) (xy 304.101003 -56.469217) (xy 304.093193 -56.523395) (xy 304.077711 -56.575898)
			(xy 304.054876 -56.625645) (xy 304.025158 -56.671613) (xy 304.00752 -56.692546) (xy 304.007266 -56.6928)
			(xy 304.00167 -56.69988) (xy 303.99543 -56.716802) (xy 303.995074 -56.72582) (xy 303.995074 -56.792876)
			(xy 303.995448 -56.801891) (xy 304.001684 -56.818808) (xy 304.007266 -56.825896) (xy 304.00752 -56.825896)
			(xy 304.00752 -56.82615) (xy 304.025152 -56.847088) (xy 304.054864 -56.893059) (xy 304.077701 -56.942805)
			(xy 304.093194 -56.995305) (xy 304.094297 -57.002934) (xy 305.763422 -57.002934) (xy 305.763924 -56.974842)
			(xy 305.772148 -56.919265) (xy 305.788436 -56.865495) (xy 305.812437 -56.814697) (xy 305.843631 -56.76797)
			(xy 305.881343 -56.726325) (xy 305.924757 -56.690664) (xy 305.948588 -56.675782) (xy 305.957478 -56.670448)
			(xy 305.96967 -56.65343) (xy 305.98999 -56.560212) (xy 305.985672 -56.539638) (xy 305.97983 -56.531002)
			(xy 305.963832 -56.506937) (xy 305.938488 -56.455006) (xy 305.921262 -56.399849) (xy 305.912546 -56.342724)
			(xy 305.912012 -56.313832) (xy 305.912485 -56.286579) (xy 305.920238 -56.232627) (xy 305.935591 -56.180329)
			(xy 305.958231 -56.130747) (xy 305.987698 -56.084893) (xy 306.023391 -56.043699) (xy 306.064583 -56.008005)
			(xy 306.110437 -55.978537) (xy 306.160017 -55.955895) (xy 306.212316 -55.940541) (xy 306.266267 -55.932786)
			(xy 306.29352 -55.932324) (xy 306.320891 -55.932772) (xy 306.375071 -55.940594) (xy 306.427575 -55.956087)
			(xy 306.477321 -55.978932) (xy 306.523287 -56.008661) (xy 306.544218 -56.026304) (xy 306.544472 -56.026558)
			(xy 306.551557 -56.032146) (xy 306.568475 -56.03839) (xy 306.577492 -56.03875) (xy 306.644548 -56.03875)
			(xy 306.653564 -56.038379) (xy 306.670481 -56.032142) (xy 306.677568 -56.026558) (xy 306.677568 -56.026304)
			(xy 306.677822 -56.026304) (xy 306.698755 -56.008663) (xy 306.744723 -55.978939) (xy 306.794469 -55.956093)
			(xy 306.846971 -55.940597) (xy 306.901149 -55.932768) (xy 306.955891 -55.932768) (xy 307.010069 -55.940597)
			(xy 307.062571 -55.956093) (xy 307.112317 -55.978939) (xy 307.158285 -56.008663) (xy 307.179218 -56.026304)
			(xy 307.179472 -56.026558) (xy 307.186557 -56.032146) (xy 307.203475 -56.03839) (xy 307.212492 -56.03875)
			(xy 307.279548 -56.03875) (xy 307.288564 -56.038379) (xy 307.305481 -56.032142) (xy 307.312568 -56.026558)
			(xy 307.312568 -56.026304) (xy 307.312822 -56.026304) (xy 307.333773 -56.008689) (xy 307.379741 -55.978973)
			(xy 307.429483 -55.956133) (xy 307.48198 -55.940636) (xy 307.536152 -55.932801) (xy 307.56352 -55.932324)
			(xy 307.590773 -55.932747) (xy 307.644723 -55.940507) (xy 307.697019 -55.955865) (xy 307.746598 -55.978509)
			(xy 307.79245 -56.007978) (xy 307.833641 -56.043673) (xy 307.869334 -56.084866) (xy 307.898801 -56.130719)
			(xy 307.921442 -56.180299) (xy 307.936798 -56.232597) (xy 307.944554 -56.286547) (xy 307.944554 -56.297068)
			(xy 308.286402 -56.297068) (xy 308.290473 -56.241446) (xy 308.302599 -56.187009) (xy 308.322522 -56.134918)
			(xy 308.349818 -56.086283) (xy 308.383904 -56.04214) (xy 308.424053 -56.003431) (xy 308.469411 -55.97098)
			(xy 308.519011 -55.945479) (xy 308.571795 -55.927472) (xy 308.626638 -55.917342) (xy 308.682372 -55.915305)
			(xy 308.737809 -55.921405) (xy 308.791766 -55.935511) (xy 308.843095 -55.957323) (xy 308.890701 -55.986377)
			(xy 308.933569 -56.022052) (xy 308.970786 -56.063589) (xy 309.001559 -56.110102) (xy 309.025231 -56.160599)
			(xy 309.041299 -56.214006) (xy 309.049419 -56.269182) (xy 309.049928 -56.297068) (xy 309.049419 -56.324954)
			(xy 309.045224 -56.353456) (xy 311.141108 -56.353456) (xy 311.145179 -56.297834) (xy 311.157305 -56.243397)
			(xy 311.177228 -56.191306) (xy 311.204524 -56.142671) (xy 311.23861 -56.098528) (xy 311.278759 -56.059819)
			(xy 311.324117 -56.027368) (xy 311.373717 -56.001867) (xy 311.426501 -55.98386) (xy 311.481344 -55.97373)
			(xy 311.537078 -55.971693) (xy 311.592515 -55.977793) (xy 311.646472 -55.991899) (xy 311.697801 -56.013711)
			(xy 311.745407 -56.042765) (xy 311.788275 -56.07844) (xy 311.825492 -56.119977) (xy 311.856265 -56.16649)
			(xy 311.879937 -56.216987) (xy 311.896005 -56.270394) (xy 311.904125 -56.32557) (xy 311.904634 -56.353456)
			(xy 311.904125 -56.381342) (xy 311.896005 -56.436518) (xy 311.879937 -56.489925) (xy 311.856265 -56.540422)
			(xy 311.825492 -56.586935) (xy 311.788275 -56.628472) (xy 311.745407 -56.664147) (xy 311.697801 -56.693201)
			(xy 311.646472 -56.715013) (xy 311.592515 -56.729119) (xy 311.537078 -56.735219) (xy 311.481344 -56.733182)
			(xy 311.426501 -56.723052) (xy 311.373717 -56.705045) (xy 311.324117 -56.679544) (xy 311.278759 -56.647093)
			(xy 311.23861 -56.608384) (xy 311.204524 -56.564241) (xy 311.177228 -56.515606) (xy 311.157305 -56.463515)
			(xy 311.145179 -56.409078) (xy 311.141108 -56.353456) (xy 309.045224 -56.353456) (xy 309.041299 -56.38013)
			(xy 309.025231 -56.433537) (xy 309.001559 -56.484034) (xy 308.970786 -56.530547) (xy 308.933569 -56.572084)
			(xy 308.890701 -56.607759) (xy 308.843095 -56.636813) (xy 308.791766 -56.658625) (xy 308.737809 -56.672731)
			(xy 308.682372 -56.678831) (xy 308.626638 -56.676794) (xy 308.571795 -56.666664) (xy 308.519011 -56.648657)
			(xy 308.469411 -56.623156) (xy 308.424053 -56.590705) (xy 308.383904 -56.551996) (xy 308.349818 -56.507853)
			(xy 308.322522 -56.459218) (xy 308.302599 -56.407127) (xy 308.290473 -56.35269) (xy 308.286402 -56.297068)
			(xy 307.944554 -56.297068) (xy 307.944554 -56.341053) (xy 307.936798 -56.395003) (xy 307.921442 -56.447301)
			(xy 307.898801 -56.496881) (xy 307.869334 -56.542734) (xy 307.833641 -56.583927) (xy 307.79245 -56.619622)
			(xy 307.746598 -56.649091) (xy 307.697019 -56.671735) (xy 307.644723 -56.687093) (xy 307.590773 -56.694853)
			(xy 307.56352 -56.69534) (xy 307.536149 -56.694877) (xy 307.48197 -56.687061) (xy 307.429466 -56.671572)
			(xy 307.379719 -56.648729) (xy 307.333753 -56.619002) (xy 307.312822 -56.60136) (xy 307.312568 -56.601106)
			(xy 307.305466 -56.595542) (xy 307.288561 -56.589282) (xy 307.279548 -56.588914) (xy 307.212492 -56.588914)
			(xy 307.203474 -56.589264) (xy 307.186557 -56.595516) (xy 307.179472 -56.601106) (xy 307.179472 -56.60136)
			(xy 307.179218 -56.60136) (xy 307.158285 -56.619001) (xy 307.112317 -56.648725) (xy 307.062571 -56.671571)
			(xy 307.010069 -56.687067) (xy 306.955891 -56.694896) (xy 306.901149 -56.694896) (xy 306.846971 -56.687067)
			(xy 306.794469 -56.671571) (xy 306.744723 -56.648725) (xy 306.698755 -56.619001) (xy 306.677822 -56.60136)
			(xy 306.677568 -56.601106) (xy 306.670466 -56.595542) (xy 306.653561 -56.589282) (xy 306.644548 -56.588914)
			(xy 306.577492 -56.588914) (xy 306.568474 -56.589264) (xy 306.551557 -56.595516) (xy 306.544472 -56.601106)
			(xy 306.543964 -56.60136) (xy 306.531229 -56.612304) (xy 306.504138 -56.632145) (xy 306.489862 -56.640984)
			(xy 306.480972 -56.646318) (xy 306.46878 -56.663336) (xy 306.44846 -56.756554) (xy 306.452778 -56.777128)
			(xy 306.45862 -56.785764) (xy 306.474609 -56.809835) (xy 306.499954 -56.861764) (xy 306.517182 -56.91692)
			(xy 306.525901 -56.974042) (xy 306.526438 -57.002934) (xy 306.525952 -57.030185) (xy 306.518196 -57.084133)
			(xy 306.502841 -57.136428) (xy 306.480199 -57.186005) (xy 306.450733 -57.231855) (xy 306.415042 -57.273046)
			(xy 306.373851 -57.308737) (xy 306.328001 -57.338203) (xy 306.278424 -57.360845) (xy 306.226129 -57.3762)
			(xy 306.172181 -57.383956) (xy 306.117679 -57.383956) (xy 306.063731 -57.3762) (xy 306.011436 -57.360845)
			(xy 305.961859 -57.338203) (xy 305.916009 -57.308737) (xy 305.874818 -57.273046) (xy 305.839127 -57.231855)
			(xy 305.809661 -57.186005) (xy 305.787019 -57.136428) (xy 305.771664 -57.084133) (xy 305.763908 -57.030185)
			(xy 305.763422 -57.002934) (xy 304.094297 -57.002934) (xy 304.101025 -57.049479) (xy 304.1015 -57.076848)
			(xy 304.101014 -57.104099) (xy 304.093258 -57.158047) (xy 304.077903 -57.210342) (xy 304.055261 -57.259919)
			(xy 304.025795 -57.305769) (xy 303.990104 -57.34696) (xy 303.948913 -57.382651) (xy 303.903063 -57.412117)
			(xy 303.853486 -57.434759) (xy 303.801191 -57.450114) (xy 303.747243 -57.45787) (xy 303.692741 -57.45787)
			(xy 303.638793 -57.450114) (xy 303.586498 -57.434759) (xy 303.536921 -57.412117) (xy 303.491071 -57.382651)
			(xy 303.44988 -57.34696) (xy 303.414189 -57.305769) (xy 303.384723 -57.259919) (xy 303.362081 -57.210342)
			(xy 303.346726 -57.158047) (xy 303.33897 -57.104099) (xy 303.338484 -57.076848) (xy 302.688691 -57.076848)
			(xy 302.71274 -57.095303) (xy 302.75512 -57.137687) (xy 302.791606 -57.18524) (xy 302.821573 -57.237149)
			(xy 302.844508 -57.292525) (xy 302.860019 -57.35042) (xy 302.867841 -57.409845) (xy 302.86833 -57.439814)
			(xy 302.867898 -57.468047) (xy 302.865763 -57.48528) (xy 314.80582 -57.48528) (xy 314.809891 -57.429658)
			(xy 314.822017 -57.375221) (xy 314.84194 -57.32313) (xy 314.869236 -57.274495) (xy 314.903322 -57.230352)
			(xy 314.943471 -57.191643) (xy 314.988829 -57.159192) (xy 315.038429 -57.133691) (xy 315.091213 -57.115684)
			(xy 315.146056 -57.105554) (xy 315.20179 -57.103517) (xy 315.257227 -57.109617) (xy 315.311184 -57.123723)
			(xy 315.362513 -57.145535) (xy 315.410119 -57.174589) (xy 315.452987 -57.210264) (xy 315.490204 -57.251801)
			(xy 315.520977 -57.298314) (xy 315.544649 -57.348811) (xy 315.560717 -57.402218) (xy 315.568837 -57.457394)
			(xy 315.569346 -57.48528) (xy 315.568837 -57.513166) (xy 315.560717 -57.568342) (xy 315.544649 -57.621749)
			(xy 315.520977 -57.672246) (xy 315.490204 -57.718759) (xy 315.452987 -57.760296) (xy 315.410119 -57.795971)
			(xy 315.362513 -57.825025) (xy 315.311184 -57.846837) (xy 315.257227 -57.860943) (xy 315.20179 -57.867043)
			(xy 315.146056 -57.865006) (xy 315.091213 -57.854876) (xy 315.038429 -57.836869) (xy 314.988829 -57.811368)
			(xy 314.943471 -57.778917) (xy 314.903322 -57.740208) (xy 314.869236 -57.696065) (xy 314.84194 -57.64743)
			(xy 314.822017 -57.595339) (xy 314.809891 -57.540902) (xy 314.80582 -57.48528) (xy 302.865763 -57.48528)
			(xy 302.860956 -57.524085) (xy 302.847169 -57.578841) (xy 302.826744 -57.631484) (xy 302.799994 -57.681211)
			(xy 302.784002 -57.704482) (xy 302.776636 -57.71515) (xy 302.773588 -57.740804) (xy 302.816006 -57.844436)
			(xy 302.836072 -57.860692) (xy 302.849026 -57.862978) (xy 302.875133 -57.868129) (xy 302.925704 -57.884686)
			(xy 302.973485 -57.908108) (xy 303.017549 -57.93794) (xy 303.057041 -57.973603) (xy 303.091197 -58.014407)
			(xy 303.119354 -58.05956) (xy 303.140966 -58.108186) (xy 303.155613 -58.159342) (xy 303.163013 -58.212038)
			(xy 303.163478 -58.238644) (xy 303.162984 -58.266013) (xy 303.155174 -58.320191) (xy 303.139692 -58.372694)
			(xy 303.116856 -58.422442) (xy 303.087137 -58.46841) (xy 303.069498 -58.489342) (xy 303.069244 -58.489596)
			(xy 303.063646 -58.496675) (xy 303.057408 -58.513598) (xy 303.057052 -58.522616) (xy 303.057052 -58.589672)
			(xy 303.057411 -58.598689) (xy 303.063656 -58.615606) (xy 303.069244 -58.622692) (xy 303.069498 -58.622692)
			(xy 303.069498 -58.622946) (xy 303.087125 -58.643888) (xy 303.110037 -58.679334) (xy 306.195222 -58.679334)
			(xy 306.195638 -58.653018) (xy 306.202883 -58.600887) (xy 306.217211 -58.550243) (xy 306.238353 -58.502044)
			(xy 306.265909 -58.457202) (xy 306.299356 -58.416565) (xy 306.318412 -58.39841) (xy 306.325813 -58.390888)
			(xy 306.334337 -58.371608) (xy 306.334922 -58.361072) (xy 306.334922 -58.286396) (xy 306.334402 -58.275845)
			(xy 306.32586 -58.256551) (xy 306.318412 -58.249058) (xy 306.299345 -58.230913) (xy 306.265889 -58.190282)
			(xy 306.238331 -58.145439) (xy 306.217194 -58.097236) (xy 306.20288 -58.046587) (xy 306.195658 -57.994451)
			(xy 306.195222 -57.968134) (xy 306.195708 -57.940883) (xy 306.203464 -57.886935) (xy 306.218819 -57.83464)
			(xy 306.241461 -57.785063) (xy 306.270927 -57.739213) (xy 306.306618 -57.698022) (xy 306.347809 -57.662331)
			(xy 306.393659 -57.632865) (xy 306.443236 -57.610223) (xy 306.495531 -57.594868) (xy 306.549479 -57.587112)
			(xy 306.603981 -57.587112) (xy 306.657929 -57.594868) (xy 306.710224 -57.610223) (xy 306.759801 -57.632865)
			(xy 306.805651 -57.662331) (xy 306.846842 -57.698022) (xy 306.882533 -57.739213) (xy 306.911999 -57.785063)
			(xy 306.934641 -57.83464) (xy 306.949996 -57.886935) (xy 306.957752 -57.940883) (xy 306.958238 -57.968134)
			(xy 306.957813 -57.99445) (xy 306.950572 -58.046581) (xy 306.936246 -58.097225) (xy 306.934046 -58.102242)
			(xy 310.118234 -58.102242) (xy 310.118234 -58.042306) (xy 310.126057 -57.982884) (xy 310.14157 -57.924991)
			(xy 310.164506 -57.869618) (xy 310.194473 -57.817712) (xy 310.23096 -57.770162) (xy 310.27334 -57.727782)
			(xy 310.32089 -57.691295) (xy 310.372796 -57.661328) (xy 310.428169 -57.638392) (xy 310.486062 -57.622879)
			(xy 310.545484 -57.615056) (xy 310.60542 -57.615056) (xy 310.664842 -57.622879) (xy 310.722735 -57.638392)
			(xy 310.778108 -57.661328) (xy 310.830014 -57.691295) (xy 310.877564 -57.727782) (xy 310.919944 -57.770162)
			(xy 310.956431 -57.817712) (xy 310.986398 -57.869618) (xy 311.009334 -57.924991) (xy 311.024847 -57.982884)
			(xy 311.03267 -58.042306) (xy 311.03316 -58.072274) (xy 311.03267 -58.102242) (xy 311.032168 -58.106052)
			(xy 315.482714 -58.106052) (xy 315.482714 -58.046116) (xy 315.490537 -57.986694) (xy 315.50605 -57.928801)
			(xy 315.528986 -57.873428) (xy 315.558953 -57.821522) (xy 315.59544 -57.773972) (xy 315.63782 -57.731592)
			(xy 315.68537 -57.695105) (xy 315.737276 -57.665138) (xy 315.792649 -57.642202) (xy 315.850542 -57.626689)
			(xy 315.909964 -57.618866) (xy 315.9699 -57.618866) (xy 316.029322 -57.626689) (xy 316.087215 -57.642202)
			(xy 316.142588 -57.665138) (xy 316.194494 -57.695105) (xy 316.242044 -57.731592) (xy 316.284424 -57.773972)
			(xy 316.320911 -57.821522) (xy 316.350878 -57.873428) (xy 316.360751 -57.897264) (xy 317.767698 -57.897264)
			(xy 317.767698 -57.837328) (xy 317.775521 -57.777906) (xy 317.791034 -57.720013) (xy 317.81397 -57.66464)
			(xy 317.843937 -57.612734) (xy 317.880424 -57.565184) (xy 317.922804 -57.522804) (xy 317.970354 -57.486317)
			(xy 318.02226 -57.45635) (xy 318.077633 -57.433414) (xy 318.135526 -57.417901) (xy 318.194948 -57.410078)
			(xy 318.254884 -57.410078) (xy 318.314306 -57.417901) (xy 318.372199 -57.433414) (xy 318.427572 -57.45635)
			(xy 318.479478 -57.486317) (xy 318.527028 -57.522804) (xy 318.569408 -57.565184) (xy 318.605895 -57.612734)
			(xy 318.635862 -57.66464) (xy 318.658798 -57.720013) (xy 318.674311 -57.777906) (xy 318.682134 -57.837328)
			(xy 318.682624 -57.867296) (xy 318.682134 -57.897264) (xy 318.674311 -57.956686) (xy 318.658798 -58.014579)
			(xy 318.635862 -58.069952) (xy 318.605895 -58.121858) (xy 318.569408 -58.169408) (xy 318.527028 -58.211788)
			(xy 318.479478 -58.248275) (xy 318.427572 -58.278242) (xy 318.372199 -58.301178) (xy 318.314306 -58.316691)
			(xy 318.254884 -58.324514) (xy 318.194948 -58.324514) (xy 318.135526 -58.316691) (xy 318.077633 -58.301178)
			(xy 318.02226 -58.278242) (xy 317.970354 -58.248275) (xy 317.922804 -58.211788) (xy 317.880424 -58.169408)
			(xy 317.843937 -58.121858) (xy 317.81397 -58.069952) (xy 317.791034 -58.014579) (xy 317.775521 -57.956686)
			(xy 317.767698 -57.897264) (xy 316.360751 -57.897264) (xy 316.373814 -57.928801) (xy 316.389327 -57.986694)
			(xy 316.39715 -58.046116) (xy 316.39764 -58.076084) (xy 316.39715 -58.106052) (xy 316.389327 -58.165474)
			(xy 316.373814 -58.223367) (xy 316.350878 -58.27874) (xy 316.320911 -58.330646) (xy 316.284424 -58.378196)
			(xy 316.242044 -58.420576) (xy 316.194494 -58.457063) (xy 316.142588 -58.48703) (xy 316.087215 -58.509966)
			(xy 316.029322 -58.525479) (xy 315.9699 -58.533302) (xy 315.909964 -58.533302) (xy 315.850542 -58.525479)
			(xy 315.792649 -58.509966) (xy 315.737276 -58.48703) (xy 315.68537 -58.457063) (xy 315.63782 -58.420576)
			(xy 315.59544 -58.378196) (xy 315.558953 -58.330646) (xy 315.528986 -58.27874) (xy 315.50605 -58.223367)
			(xy 315.490537 -58.165474) (xy 315.482714 -58.106052) (xy 311.032168 -58.106052) (xy 311.024847 -58.161664)
			(xy 311.009334 -58.219557) (xy 310.986398 -58.27493) (xy 310.956431 -58.326836) (xy 310.919944 -58.374386)
			(xy 310.877564 -58.416766) (xy 310.830014 -58.453253) (xy 310.778108 -58.48322) (xy 310.722735 -58.506156)
			(xy 310.664842 -58.521669) (xy 310.60542 -58.529492) (xy 310.545484 -58.529492) (xy 310.486062 -58.521669)
			(xy 310.428169 -58.506156) (xy 310.372796 -58.48322) (xy 310.32089 -58.453253) (xy 310.27334 -58.416766)
			(xy 310.23096 -58.374386) (xy 310.194473 -58.326836) (xy 310.164506 -58.27493) (xy 310.14157 -58.219557)
			(xy 310.126057 -58.161664) (xy 310.118234 -58.102242) (xy 306.934046 -58.102242) (xy 306.915106 -58.145424)
			(xy 306.887551 -58.190267) (xy 306.854104 -58.230904) (xy 306.835048 -58.249058) (xy 306.82767 -58.2566)
			(xy 306.819131 -58.275864) (xy 306.818538 -58.286396) (xy 306.818538 -58.361072) (xy 306.819058 -58.371623)
			(xy 306.827598 -58.390919) (xy 306.835048 -58.39841) (xy 306.854111 -58.416558) (xy 306.887565 -58.457191)
			(xy 306.915122 -58.502033) (xy 306.936259 -58.550235) (xy 306.947836 -58.591192) (xy 316.686928 -58.591192)
			(xy 316.686928 -58.531256) (xy 316.694751 -58.471834) (xy 316.710264 -58.413941) (xy 316.7332 -58.358568)
			(xy 316.763167 -58.306662) (xy 316.799654 -58.259112) (xy 316.842034 -58.216732) (xy 316.889584 -58.180245)
			(xy 316.94149 -58.150278) (xy 316.996863 -58.127342) (xy 317.054756 -58.111829) (xy 317.114178 -58.104006)
			(xy 317.174114 -58.104006) (xy 317.233536 -58.111829) (xy 317.291429 -58.127342) (xy 317.346802 -58.150278)
			(xy 317.398708 -58.180245) (xy 317.446258 -58.216732) (xy 317.488638 -58.259112) (xy 317.525125 -58.306662)
			(xy 317.555092 -58.358568) (xy 317.578028 -58.413941) (xy 317.593541 -58.471834) (xy 317.594575 -58.479686)
			(xy 318.933558 -58.479686) (xy 318.933558 -58.41975) (xy 318.941381 -58.360328) (xy 318.956894 -58.302435)
			(xy 318.97983 -58.247062) (xy 319.009797 -58.195156) (xy 319.046284 -58.147606) (xy 319.088664 -58.105226)
			(xy 319.136214 -58.068739) (xy 319.18812 -58.038772) (xy 319.243493 -58.015836) (xy 319.301386 -58.000323)
			(xy 319.360808 -57.9925) (xy 319.420744 -57.9925) (xy 319.480166 -58.000323) (xy 319.538059 -58.015836)
			(xy 319.593432 -58.038772) (xy 319.645338 -58.068739) (xy 319.692888 -58.105226) (xy 319.735268 -58.147606)
			(xy 319.771755 -58.195156) (xy 319.801722 -58.247062) (xy 319.824658 -58.302435) (xy 319.840171 -58.360328)
			(xy 319.847994 -58.41975) (xy 319.848484 -58.449718) (xy 319.847994 -58.479686) (xy 319.840171 -58.539108)
			(xy 319.824658 -58.597001) (xy 319.801722 -58.652374) (xy 319.771755 -58.70428) (xy 319.750942 -58.731404)
			(xy 323.72046 -58.731404) (xy 323.720914 -58.704033) (xy 323.728732 -58.649853) (xy 323.744223 -58.597349)
			(xy 323.767068 -58.547602) (xy 323.796797 -58.501637) (xy 323.81444 -58.480706) (xy 323.814694 -58.480452)
			(xy 323.820264 -58.473354) (xy 323.826521 -58.456446) (xy 323.826886 -58.447432) (xy 323.826886 -58.380376)
			(xy 323.826543 -58.371358) (xy 323.820286 -58.354441) (xy 323.814694 -58.347356) (xy 323.81444 -58.347356)
			(xy 323.81444 -58.347102) (xy 323.796803 -58.326166) (xy 323.767077 -58.280199) (xy 323.74423 -58.230454)
			(xy 323.728733 -58.177952) (xy 323.720904 -58.123774) (xy 323.720904 -58.069032) (xy 323.728732 -58.014854)
			(xy 323.744228 -57.962352) (xy 323.767074 -57.912606) (xy 323.796799 -57.866638) (xy 323.81444 -57.845706)
			(xy 323.814694 -57.845452) (xy 323.820264 -57.838354) (xy 323.826521 -57.821446) (xy 323.826886 -57.812432)
			(xy 323.826886 -57.745376) (xy 323.826543 -57.736358) (xy 323.820286 -57.719441) (xy 323.814694 -57.712356)
			(xy 323.81444 -57.712356) (xy 323.81444 -57.712102) (xy 323.796803 -57.691166) (xy 323.767077 -57.645199)
			(xy 323.74423 -57.595454) (xy 323.728733 -57.542952) (xy 323.720904 -57.488774) (xy 323.720904 -57.434032)
			(xy 323.728732 -57.379854) (xy 323.744228 -57.327352) (xy 323.767074 -57.277606) (xy 323.796799 -57.231638)
			(xy 323.81444 -57.210706) (xy 323.814694 -57.210452) (xy 323.820264 -57.203354) (xy 323.826521 -57.186446)
			(xy 323.826886 -57.177432) (xy 323.826886 -57.110376) (xy 323.826543 -57.101358) (xy 323.820286 -57.084441)
			(xy 323.814694 -57.077356) (xy 323.81444 -57.077356) (xy 323.81444 -57.077102) (xy 323.796795 -57.056175)
			(xy 323.767082 -57.010201) (xy 323.744247 -56.960453) (xy 323.728758 -56.907951) (xy 323.720932 -56.853774)
			(xy 323.72046 -56.826404) (xy 323.720946 -56.799153) (xy 323.728702 -56.745205) (xy 323.744057 -56.69291)
			(xy 323.766699 -56.643333) (xy 323.796165 -56.597483) (xy 323.831856 -56.556292) (xy 323.873047 -56.520601)
			(xy 323.918897 -56.491135) (xy 323.968474 -56.468493) (xy 324.020769 -56.453138) (xy 324.074717 -56.445382)
			(xy 324.129219 -56.445382) (xy 324.183167 -56.453138) (xy 324.235462 -56.468493) (xy 324.285039 -56.491135)
			(xy 324.330889 -56.520601) (xy 324.37208 -56.556292) (xy 324.407771 -56.597483) (xy 324.437237 -56.643333)
			(xy 324.459879 -56.69291) (xy 324.475234 -56.745205) (xy 324.48299 -56.799153) (xy 324.483186 -56.810148)
			(xy 326.300084 -56.810148) (xy 326.300084 -56.809894) (xy 326.300574 -56.779926) (xy 326.308397 -56.720504)
			(xy 326.32391 -56.662611) (xy 326.346846 -56.607238) (xy 326.376813 -56.555332) (xy 326.4133 -56.507782)
			(xy 326.45568 -56.465402) (xy 326.50323 -56.428915) (xy 326.555136 -56.398948) (xy 326.610509 -56.376012)
			(xy 326.668402 -56.360499) (xy 326.727824 -56.352676) (xy 326.78776 -56.352676) (xy 326.847182 -56.360499)
			(xy 326.905075 -56.376012) (xy 326.960448 -56.398948) (xy 327.012354 -56.428915) (xy 327.059904 -56.465402)
			(xy 327.102284 -56.507782) (xy 327.138771 -56.555332) (xy 327.168738 -56.607238) (xy 327.191674 -56.662611)
			(xy 327.207187 -56.720504) (xy 327.21501 -56.779926) (xy 327.2155 -56.809894) (xy 327.2155 -56.810148)
			(xy 327.214927 -56.841671) (xy 327.206258 -56.904119) (xy 327.189105 -56.964788) (xy 327.163792 -57.02253)
			(xy 327.130798 -57.076253) (xy 327.090746 -57.124944) (xy 327.067926 -57.146698) (xy 327.060814 -57.153302)
			(xy 327.052432 -57.17032) (xy 327.046082 -57.248806) (xy 327.045719 -57.258371) (xy 327.051335 -57.276654)
			(xy 327.057004 -57.284366) (xy 327.072538 -57.304652) (xy 327.098598 -57.348601) (xy 327.118562 -57.395634)
			(xy 327.132074 -57.444909) (xy 327.135055 -57.467049) (xy 327.318392 -57.467049) (xy 327.318392 -57.412551)
			(xy 327.326148 -57.358608) (xy 327.341501 -57.306318) (xy 327.364139 -57.256744) (xy 327.393601 -57.210897)
			(xy 327.429288 -57.169709) (xy 327.470473 -57.134019) (xy 327.516318 -57.104553) (xy 327.56589 -57.081911)
			(xy 327.618179 -57.066554) (xy 327.672121 -57.058794) (xy 327.69937 -57.058306) (xy 327.724918 -57.058716)
			(xy 327.775557 -57.065523) (xy 327.824834 -57.079032) (xy 327.871866 -57.099) (xy 327.915809 -57.125071)
			(xy 327.936098 -57.140602) (xy 327.943824 -57.146238) (xy 327.962099 -57.151839) (xy 327.971658 -57.151524)
			(xy 328.050144 -57.145174) (xy 328.067162 -57.136792) (xy 328.073766 -57.12968) (xy 328.095534 -57.106869)
			(xy 328.144206 -57.066788) (xy 328.197922 -57.033771) (xy 328.255663 -57.008445) (xy 328.316336 -56.991291)
			(xy 328.37879 -56.982633) (xy 328.410316 -56.982106) (xy 328.41057 -56.982106) (xy 328.440539 -56.982589)
			(xy 328.499964 -56.990409) (xy 328.557861 -57.005919) (xy 328.613237 -57.028854) (xy 328.665145 -57.058821)
			(xy 328.688639 -57.076848) (xy 329.338432 -57.076848) (xy 329.338918 -57.049478) (xy 329.34673 -56.9953)
			(xy 329.362214 -56.942797) (xy 329.385051 -56.893049) (xy 329.414772 -56.847082) (xy 329.432412 -56.82615)
			(xy 329.432666 -56.825896) (xy 329.438268 -56.81882) (xy 329.444504 -56.801895) (xy 329.444858 -56.792876)
			(xy 329.444858 -56.72582) (xy 329.4445 -56.716803) (xy 329.438254 -56.699886) (xy 329.432666 -56.6928)
			(xy 329.432412 -56.6928) (xy 329.432412 -56.692546) (xy 329.414783 -56.671606) (xy 329.385069 -56.625635)
			(xy 329.362231 -56.57589) (xy 329.346738 -56.523391) (xy 329.338907 -56.469217) (xy 329.338432 -56.441848)
			(xy 329.338918 -56.414597) (xy 329.346674 -56.360649) (xy 329.362029 -56.308354) (xy 329.384671 -56.258777)
			(xy 329.414137 -56.212927) (xy 329.449828 -56.171736) (xy 329.491019 -56.136045) (xy 329.536869 -56.106579)
			(xy 329.586446 -56.083937) (xy 329.638741 -56.068582) (xy 329.692689 -56.060826) (xy 329.747191 -56.060826)
			(xy 329.801139 -56.068582) (xy 329.853434 -56.083937) (xy 329.903011 -56.106579) (xy 329.948861 -56.136045)
			(xy 329.990052 -56.171736) (xy 330.025743 -56.212927) (xy 330.055209 -56.258777) (xy 330.077851 -56.308354)
			(xy 330.093206 -56.360649) (xy 330.100962 -56.414597) (xy 330.101448 -56.441848) (xy 330.100964 -56.469218)
			(xy 330.093153 -56.523397) (xy 330.077668 -56.5759) (xy 330.05483 -56.625647) (xy 330.025108 -56.671614)
			(xy 330.007468 -56.692546) (xy 330.007214 -56.6928) (xy 330.001623 -56.699884) (xy 329.995378 -56.716803)
			(xy 329.995022 -56.72582) (xy 329.995022 -56.792876) (xy 329.995386 -56.801892) (xy 330.001628 -56.818809)
			(xy 330.007214 -56.825896) (xy 330.007468 -56.825896) (xy 330.007468 -56.82615) (xy 330.025092 -56.847094)
			(xy 330.054807 -56.893063) (xy 330.077647 -56.942808) (xy 330.093141 -56.995306) (xy 330.094244 -57.002934)
			(xy 331.76337 -57.002934) (xy 331.763897 -56.974844) (xy 331.772119 -56.919268) (xy 331.788405 -56.8655)
			(xy 331.812403 -56.814703) (xy 331.843592 -56.767976) (xy 331.881299 -56.72633) (xy 331.924708 -56.690666)
			(xy 331.948536 -56.675782) (xy 331.957426 -56.670448) (xy 331.969618 -56.65343) (xy 331.989938 -56.560212)
			(xy 331.98562 -56.539638) (xy 331.979778 -56.531002) (xy 331.963774 -56.506941) (xy 331.938433 -56.455008)
			(xy 331.921208 -56.399849) (xy 331.912494 -56.342725) (xy 331.91196 -56.313832) (xy 331.912508 -56.286583)
			(xy 331.920259 -56.232639) (xy 331.935609 -56.180348) (xy 331.958244 -56.130773) (xy 331.987704 -56.084924)
			(xy 332.023389 -56.043734) (xy 332.064572 -56.008042) (xy 332.110416 -55.978574) (xy 332.159988 -55.955931)
			(xy 332.212277 -55.940573) (xy 332.266219 -55.932812) (xy 332.293468 -55.932324) (xy 332.320838 -55.932803)
			(xy 332.375017 -55.940617) (xy 332.42752 -55.956103) (xy 332.477267 -55.978942) (xy 332.523234 -56.008664)
			(xy 332.544166 -56.026304) (xy 332.54442 -56.026558) (xy 332.551492 -56.032166) (xy 332.56842 -56.038398)
			(xy 332.57744 -56.03875) (xy 332.644496 -56.03875) (xy 332.653514 -56.038402) (xy 332.670431 -56.032149)
			(xy 332.677516 -56.026558) (xy 332.677516 -56.026304) (xy 332.67777 -56.026304) (xy 332.698703 -56.008663)
			(xy 332.744671 -55.978939) (xy 332.794417 -55.956093) (xy 332.846919 -55.940597) (xy 332.901097 -55.932768)
			(xy 332.955839 -55.932768) (xy 333.010017 -55.940597) (xy 333.062519 -55.956093) (xy 333.112265 -55.978939)
			(xy 333.158233 -56.008663) (xy 333.179166 -56.026304) (xy 333.17942 -56.026558) (xy 333.186492 -56.032166)
			(xy 333.20342 -56.038398) (xy 333.21244 -56.03875) (xy 333.279496 -56.03875) (xy 333.288514 -56.038402)
			(xy 333.305431 -56.032149) (xy 333.312516 -56.026558) (xy 333.312516 -56.026304) (xy 333.31277 -56.026304)
			(xy 333.333703 -56.008666) (xy 333.379676 -55.978954) (xy 333.429423 -55.956118) (xy 333.481923 -55.940626)
			(xy 333.536099 -55.932798) (xy 333.563468 -55.932324) (xy 333.590725 -55.932721) (xy 333.644684 -55.940475)
			(xy 333.69699 -55.955829) (xy 333.746578 -55.978472) (xy 333.792439 -56.007941) (xy 333.833639 -56.043638)
			(xy 333.869339 -56.084835) (xy 333.898813 -56.130694) (xy 333.92146 -56.18028) (xy 333.936819 -56.232585)
			(xy 333.944577 -56.286543) (xy 333.944577 -56.297068) (xy 334.28635 -56.297068) (xy 334.290421 -56.241446)
			(xy 334.302547 -56.187009) (xy 334.32247 -56.134918) (xy 334.349766 -56.086283) (xy 334.383852 -56.04214)
			(xy 334.424001 -56.003431) (xy 334.469359 -55.97098) (xy 334.518959 -55.945479) (xy 334.571743 -55.927472)
			(xy 334.626586 -55.917342) (xy 334.68232 -55.915305) (xy 334.737757 -55.921405) (xy 334.791714 -55.935511)
			(xy 334.843043 -55.957323) (xy 334.890649 -55.986377) (xy 334.933517 -56.022052) (xy 334.970734 -56.063589)
			(xy 335.001507 -56.110102) (xy 335.025179 -56.160599) (xy 335.041247 -56.214006) (xy 335.049367 -56.269182)
			(xy 335.049876 -56.297068) (xy 335.049367 -56.324954) (xy 335.045172 -56.353456) (xy 337.141056 -56.353456)
			(xy 337.145127 -56.297834) (xy 337.157253 -56.243397) (xy 337.177176 -56.191306) (xy 337.204472 -56.142671)
			(xy 337.238558 -56.098528) (xy 337.278707 -56.059819) (xy 337.324065 -56.027368) (xy 337.373665 -56.001867)
			(xy 337.426449 -55.98386) (xy 337.481292 -55.97373) (xy 337.537026 -55.971693) (xy 337.592463 -55.977793)
			(xy 337.64642 -55.991899) (xy 337.697749 -56.013711) (xy 337.745355 -56.042765) (xy 337.788223 -56.07844)
			(xy 337.82544 -56.119977) (xy 337.856213 -56.16649) (xy 337.879885 -56.216987) (xy 337.895953 -56.270394)
			(xy 337.904073 -56.32557) (xy 337.904582 -56.353456) (xy 337.904073 -56.381342) (xy 337.895953 -56.436518)
			(xy 337.879885 -56.489925) (xy 337.856213 -56.540422) (xy 337.82544 -56.586935) (xy 337.788223 -56.628472)
			(xy 337.745355 -56.664147) (xy 337.697749 -56.693201) (xy 337.64642 -56.715013) (xy 337.592463 -56.729119)
			(xy 337.537026 -56.735219) (xy 337.481292 -56.733182) (xy 337.426449 -56.723052) (xy 337.373665 -56.705045)
			(xy 337.324065 -56.679544) (xy 337.278707 -56.647093) (xy 337.238558 -56.608384) (xy 337.204472 -56.564241)
			(xy 337.177176 -56.515606) (xy 337.157253 -56.463515) (xy 337.145127 -56.409078) (xy 337.141056 -56.353456)
			(xy 335.045172 -56.353456) (xy 335.041247 -56.38013) (xy 335.025179 -56.433537) (xy 335.001507 -56.484034)
			(xy 334.970734 -56.530547) (xy 334.933517 -56.572084) (xy 334.890649 -56.607759) (xy 334.843043 -56.636813)
			(xy 334.791714 -56.658625) (xy 334.737757 -56.672731) (xy 334.68232 -56.678831) (xy 334.626586 -56.676794)
			(xy 334.571743 -56.666664) (xy 334.518959 -56.648657) (xy 334.469359 -56.623156) (xy 334.424001 -56.590705)
			(xy 334.383852 -56.551996) (xy 334.349766 -56.507853) (xy 334.32247 -56.459218) (xy 334.302547 -56.407127)
			(xy 334.290421 -56.35269) (xy 334.28635 -56.297068) (xy 333.944577 -56.297068) (xy 333.944577 -56.341057)
			(xy 333.936819 -56.395015) (xy 333.92146 -56.44732) (xy 333.898813 -56.496906) (xy 333.869339 -56.542765)
			(xy 333.833639 -56.583962) (xy 333.792439 -56.619659) (xy 333.746578 -56.649128) (xy 333.69699 -56.671771)
			(xy 333.644684 -56.687125) (xy 333.590725 -56.694879) (xy 333.563468 -56.69534) (xy 333.536096 -56.694907)
			(xy 333.481915 -56.687084) (xy 333.429411 -56.671588) (xy 333.379665 -56.648738) (xy 333.3337 -56.619005)
			(xy 333.31277 -56.60136) (xy 333.312516 -56.601106) (xy 333.305429 -56.595521) (xy 333.288512 -56.589273)
			(xy 333.279496 -56.588914) (xy 333.21244 -56.588914) (xy 333.203425 -56.589287) (xy 333.186508 -56.595523)
			(xy 333.17942 -56.601106) (xy 333.17942 -56.60136) (xy 333.179166 -56.60136) (xy 333.158233 -56.619001)
			(xy 333.112265 -56.648725) (xy 333.062519 -56.671571) (xy 333.010017 -56.687067) (xy 332.955839 -56.694896)
			(xy 332.901097 -56.694896) (xy 332.846919 -56.687067) (xy 332.794417 -56.671571) (xy 332.744671 -56.648725)
			(xy 332.698703 -56.619001) (xy 332.67777 -56.60136) (xy 332.677516 -56.601106) (xy 332.670429 -56.595521)
			(xy 332.653512 -56.589273) (xy 332.644496 -56.588914) (xy 332.57744 -56.588914) (xy 332.568425 -56.589287)
			(xy 332.551508 -56.595523) (xy 332.54442 -56.601106) (xy 332.543912 -56.60136) (xy 332.531181 -56.612308)
			(xy 332.504087 -56.632147) (xy 332.48981 -56.640984) (xy 332.48092 -56.646318) (xy 332.468728 -56.663336)
			(xy 332.448408 -56.756554) (xy 332.452726 -56.777128) (xy 332.458568 -56.785764) (xy 332.474551 -56.809839)
			(xy 332.499899 -56.861766) (xy 332.517129 -56.916921) (xy 332.525849 -56.974042) (xy 332.526386 -57.002934)
			(xy 332.5259 -57.030185) (xy 332.518144 -57.084133) (xy 332.502789 -57.136428) (xy 332.480147 -57.186005)
			(xy 332.450681 -57.231855) (xy 332.41499 -57.273046) (xy 332.373799 -57.308737) (xy 332.327949 -57.338203)
			(xy 332.278372 -57.360845) (xy 332.226077 -57.3762) (xy 332.172129 -57.383956) (xy 332.117627 -57.383956)
			(xy 332.063679 -57.3762) (xy 332.011384 -57.360845) (xy 331.961807 -57.338203) (xy 331.915957 -57.308737)
			(xy 331.874766 -57.273046) (xy 331.839075 -57.231855) (xy 331.809609 -57.186005) (xy 331.786967 -57.136428)
			(xy 331.771612 -57.084133) (xy 331.763856 -57.030185) (xy 331.76337 -57.002934) (xy 330.094244 -57.002934)
			(xy 330.100972 -57.04948) (xy 330.101448 -57.076848) (xy 330.100962 -57.104099) (xy 330.093206 -57.158047)
			(xy 330.077851 -57.210342) (xy 330.055209 -57.259919) (xy 330.025743 -57.305769) (xy 329.990052 -57.34696)
			(xy 329.948861 -57.382651) (xy 329.903011 -57.412117) (xy 329.853434 -57.434759) (xy 329.801139 -57.450114)
			(xy 329.747191 -57.45787) (xy 329.692689 -57.45787) (xy 329.638741 -57.450114) (xy 329.586446 -57.434759)
			(xy 329.536869 -57.412117) (xy 329.491019 -57.382651) (xy 329.449828 -57.34696) (xy 329.414137 -57.305769)
			(xy 329.384671 -57.259919) (xy 329.362029 -57.210342) (xy 329.346674 -57.158047) (xy 329.338918 -57.104099)
			(xy 329.338432 -57.076848) (xy 328.688639 -57.076848) (xy 328.712698 -57.095308) (xy 328.755081 -57.13769)
			(xy 328.79157 -57.185241) (xy 328.821539 -57.237149) (xy 328.844475 -57.292524) (xy 328.859988 -57.35042)
			(xy 328.86781 -57.409845) (xy 328.868278 -57.439814) (xy 328.867837 -57.468047) (xy 328.865702 -57.48528)
			(xy 352.906074 -57.48528) (xy 352.910145 -57.429658) (xy 352.922271 -57.375221) (xy 352.942194 -57.32313)
			(xy 352.96949 -57.274495) (xy 353.003576 -57.230352) (xy 353.043725 -57.191643) (xy 353.089083 -57.159192)
			(xy 353.138683 -57.133691) (xy 353.191467 -57.115684) (xy 353.24631 -57.105554) (xy 353.302044 -57.103517)
			(xy 353.357481 -57.109617) (xy 353.411438 -57.123723) (xy 353.462767 -57.145535) (xy 353.510373 -57.174589)
			(xy 353.553241 -57.210264) (xy 353.590458 -57.251801) (xy 353.621231 -57.298314) (xy 353.644903 -57.348811)
			(xy 353.660971 -57.402218) (xy 353.669091 -57.457394) (xy 353.6696 -57.48528) (xy 353.669091 -57.513166)
			(xy 353.660971 -57.568342) (xy 353.644903 -57.621749) (xy 353.621231 -57.672246) (xy 353.590458 -57.718759)
			(xy 353.553241 -57.760296) (xy 353.510373 -57.795971) (xy 353.462767 -57.825025) (xy 353.411438 -57.846837)
			(xy 353.357481 -57.860943) (xy 353.302044 -57.867043) (xy 353.24631 -57.865006) (xy 353.191467 -57.854876)
			(xy 353.138683 -57.836869) (xy 353.089083 -57.811368) (xy 353.043725 -57.778917) (xy 353.003576 -57.740208)
			(xy 352.96949 -57.696065) (xy 352.942194 -57.64743) (xy 352.922271 -57.595339) (xy 352.910145 -57.540902)
			(xy 352.906074 -57.48528) (xy 328.865702 -57.48528) (xy 328.860896 -57.524084) (xy 328.84711 -57.57884)
			(xy 328.826688 -57.631483) (xy 328.799941 -57.681211) (xy 328.78395 -57.704482) (xy 328.776584 -57.71515)
			(xy 328.773536 -57.740804) (xy 328.815954 -57.844436) (xy 328.83602 -57.860692) (xy 328.848974 -57.862978)
			(xy 328.875088 -57.868093) (xy 328.925659 -57.884657) (xy 328.973439 -57.908084) (xy 329.017502 -57.937921)
			(xy 329.056994 -57.973589) (xy 329.091149 -58.014396) (xy 329.119304 -58.059552) (xy 329.140915 -58.10818)
			(xy 329.155562 -58.159339) (xy 329.162961 -58.212037) (xy 329.163426 -58.238644) (xy 329.162945 -58.266014)
			(xy 329.155134 -58.320193) (xy 329.139649 -58.372697) (xy 329.11681 -58.422444) (xy 329.087087 -58.468411)
			(xy 329.069446 -58.489342) (xy 329.069192 -58.489596) (xy 329.0636 -58.496679) (xy 329.057357 -58.513599)
			(xy 329.057 -58.522616) (xy 329.057 -58.589672) (xy 329.05737 -58.598688) (xy 329.063609 -58.615605)
			(xy 329.069192 -58.622692) (xy 329.069446 -58.622692) (xy 329.069446 -58.622946) (xy 329.087065 -58.643895)
			(xy 329.109976 -58.679334) (xy 332.11897 -58.679334) (xy 332.11897 -58.67908) (xy 332.119473 -58.647554)
			(xy 332.128153 -58.585102) (xy 332.145318 -58.524432) (xy 332.170644 -58.466689) (xy 332.203652 -58.412967)
			(xy 332.243718 -58.364281) (xy 332.266544 -58.34253) (xy 332.273656 -58.335926) (xy 332.282038 -58.318908)
			(xy 332.288388 -58.240422) (xy 332.288742 -58.230857) (xy 332.283133 -58.212575) (xy 332.277466 -58.204862)
			(xy 332.261941 -58.18457) (xy 332.23588 -58.140622) (xy 332.215915 -58.093591) (xy 332.202401 -58.044317)
			(xy 332.195581 -57.993681) (xy 332.19517 -57.968134) (xy 332.195656 -57.940883) (xy 332.203412 -57.886935)
			(xy 332.218767 -57.83464) (xy 332.241409 -57.785063) (xy 332.270875 -57.739213) (xy 332.306566 -57.698022)
			(xy 332.347757 -57.662331) (xy 332.393607 -57.632865) (xy 332.443184 -57.610223) (xy 332.495479 -57.594868)
			(xy 332.549427 -57.587112) (xy 332.603929 -57.587112) (xy 332.657877 -57.594868) (xy 332.710172 -57.610223)
			(xy 332.759749 -57.632865) (xy 332.805599 -57.662331) (xy 332.84679 -57.698022) (xy 332.882481 -57.739213)
			(xy 332.911947 -57.785063) (xy 332.934589 -57.83464) (xy 332.949944 -57.886935) (xy 332.9577 -57.940883)
			(xy 332.958186 -57.968134) (xy 332.957813 -57.993683) (xy 332.950998 -58.044324) (xy 332.93748 -58.093602)
			(xy 332.93381 -58.102242) (xy 336.118182 -58.102242) (xy 336.118182 -58.042306) (xy 336.126005 -57.982884)
			(xy 336.141518 -57.924991) (xy 336.164454 -57.869618) (xy 336.194421 -57.817712) (xy 336.230908 -57.770162)
			(xy 336.273288 -57.727782) (xy 336.320838 -57.691295) (xy 336.372744 -57.661328) (xy 336.428117 -57.638392)
			(xy 336.48601 -57.622879) (xy 336.545432 -57.615056) (xy 336.605368 -57.615056) (xy 336.66479 -57.622879)
			(xy 336.722683 -57.638392) (xy 336.778056 -57.661328) (xy 336.829962 -57.691295) (xy 336.877512 -57.727782)
			(xy 336.919892 -57.770162) (xy 336.956379 -57.817712) (xy 336.986346 -57.869618) (xy 337.009282 -57.924991)
			(xy 337.024795 -57.982884) (xy 337.032618 -58.042306) (xy 337.033108 -58.072274) (xy 337.032618 -58.102242)
			(xy 337.032116 -58.106052) (xy 353.582968 -58.106052) (xy 353.582968 -58.046116) (xy 353.590791 -57.986694)
			(xy 353.606304 -57.928801) (xy 353.62924 -57.873428) (xy 353.659207 -57.821522) (xy 353.695694 -57.773972)
			(xy 353.738074 -57.731592) (xy 353.785624 -57.695105) (xy 353.83753 -57.665138) (xy 353.892903 -57.642202)
			(xy 353.950796 -57.626689) (xy 354.010218 -57.618866) (xy 354.070154 -57.618866) (xy 354.129576 -57.626689)
			(xy 354.187469 -57.642202) (xy 354.242842 -57.665138) (xy 354.294748 -57.695105) (xy 354.342298 -57.731592)
			(xy 354.384678 -57.773972) (xy 354.421165 -57.821522) (xy 354.451132 -57.873428) (xy 354.461005 -57.897264)
			(xy 355.867952 -57.897264) (xy 355.867952 -57.837328) (xy 355.875775 -57.777906) (xy 355.891288 -57.720013)
			(xy 355.914224 -57.66464) (xy 355.944191 -57.612734) (xy 355.980678 -57.565184) (xy 356.023058 -57.522804)
			(xy 356.070608 -57.486317) (xy 356.122514 -57.45635) (xy 356.177887 -57.433414) (xy 356.23578 -57.417901)
			(xy 356.295202 -57.410078) (xy 356.355138 -57.410078) (xy 356.41456 -57.417901) (xy 356.472453 -57.433414)
			(xy 356.527826 -57.45635) (xy 356.579732 -57.486317) (xy 356.627282 -57.522804) (xy 356.669662 -57.565184)
			(xy 356.706149 -57.612734) (xy 356.736116 -57.66464) (xy 356.759052 -57.720013) (xy 356.774565 -57.777906)
			(xy 356.782388 -57.837328) (xy 356.782878 -57.867296) (xy 356.782388 -57.897264) (xy 356.774565 -57.956686)
			(xy 356.759052 -58.014579) (xy 356.736116 -58.069952) (xy 356.706149 -58.121858) (xy 356.669662 -58.169408)
			(xy 356.627282 -58.211788) (xy 356.579732 -58.248275) (xy 356.527826 -58.278242) (xy 356.472453 -58.301178)
			(xy 356.41456 -58.316691) (xy 356.355138 -58.324514) (xy 356.295202 -58.324514) (xy 356.23578 -58.316691)
			(xy 356.177887 -58.301178) (xy 356.122514 -58.278242) (xy 356.070608 -58.248275) (xy 356.023058 -58.211788)
			(xy 355.980678 -58.169408) (xy 355.944191 -58.121858) (xy 355.914224 -58.069952) (xy 355.891288 -58.014579)
			(xy 355.875775 -57.956686) (xy 355.867952 -57.897264) (xy 354.461005 -57.897264) (xy 354.474068 -57.928801)
			(xy 354.489581 -57.986694) (xy 354.497404 -58.046116) (xy 354.497894 -58.076084) (xy 354.497404 -58.106052)
			(xy 354.489581 -58.165474) (xy 354.474068 -58.223367) (xy 354.451132 -58.27874) (xy 354.421165 -58.330646)
			(xy 354.384678 -58.378196) (xy 354.342298 -58.420576) (xy 354.294748 -58.457063) (xy 354.242842 -58.48703)
			(xy 354.187469 -58.509966) (xy 354.129576 -58.525479) (xy 354.070154 -58.533302) (xy 354.010218 -58.533302)
			(xy 353.950796 -58.525479) (xy 353.892903 -58.509966) (xy 353.83753 -58.48703) (xy 353.785624 -58.457063)
			(xy 353.738074 -58.420576) (xy 353.695694 -58.378196) (xy 353.659207 -58.330646) (xy 353.62924 -58.27874)
			(xy 353.606304 -58.223367) (xy 353.590791 -58.165474) (xy 353.582968 -58.106052) (xy 337.032116 -58.106052)
			(xy 337.024795 -58.161664) (xy 337.009282 -58.219557) (xy 336.986346 -58.27493) (xy 336.956379 -58.326836)
			(xy 336.919892 -58.374386) (xy 336.877512 -58.416766) (xy 336.829962 -58.453253) (xy 336.778056 -58.48322)
			(xy 336.722683 -58.506156) (xy 336.66479 -58.521669) (xy 336.605368 -58.529492) (xy 336.545432 -58.529492)
			(xy 336.48601 -58.521669) (xy 336.428117 -58.506156) (xy 336.372744 -58.48322) (xy 336.320838 -58.453253)
			(xy 336.273288 -58.416766) (xy 336.230908 -58.374386) (xy 336.194421 -58.326836) (xy 336.164454 -58.27493)
			(xy 336.141518 -58.219557) (xy 336.126005 -58.161664) (xy 336.118182 -58.102242) (xy 332.93381 -58.102242)
			(xy 332.917504 -58.140633) (xy 332.891425 -58.184575) (xy 332.87589 -58.204862) (xy 332.87028 -58.212605)
			(xy 332.86466 -58.230866) (xy 332.864968 -58.240422) (xy 332.871318 -58.318908) (xy 332.8797 -58.335926)
			(xy 332.886812 -58.34253) (xy 332.909652 -58.364269) (xy 332.949732 -58.412947) (xy 332.982744 -58.466669)
			(xy 333.008065 -58.524416) (xy 333.025213 -58.585094) (xy 333.026058 -58.591192) (xy 354.787182 -58.591192)
			(xy 354.787182 -58.531256) (xy 354.795005 -58.471834) (xy 354.810518 -58.413941) (xy 354.833454 -58.358568)
			(xy 354.863421 -58.306662) (xy 354.899908 -58.259112) (xy 354.942288 -58.216732) (xy 354.989838 -58.180245)
			(xy 355.041744 -58.150278) (xy 355.097117 -58.127342) (xy 355.15501 -58.111829) (xy 355.214432 -58.104006)
			(xy 355.274368 -58.104006) (xy 355.33379 -58.111829) (xy 355.391683 -58.127342) (xy 355.447056 -58.150278)
			(xy 355.498962 -58.180245) (xy 355.546512 -58.216732) (xy 355.588892 -58.259112) (xy 355.625379 -58.306662)
			(xy 355.655346 -58.358568) (xy 355.678282 -58.413941) (xy 355.693795 -58.471834) (xy 355.694829 -58.479686)
			(xy 357.033812 -58.479686) (xy 357.033812 -58.41975) (xy 357.041635 -58.360328) (xy 357.057148 -58.302435)
			(xy 357.080084 -58.247062) (xy 357.110051 -58.195156) (xy 357.146538 -58.147606) (xy 357.188918 -58.105226)
			(xy 357.236468 -58.068739) (xy 357.288374 -58.038772) (xy 357.343747 -58.015836) (xy 357.40164 -58.000323)
			(xy 357.461062 -57.9925) (xy 357.520998 -57.9925) (xy 357.58042 -58.000323) (xy 357.638313 -58.015836)
			(xy 357.693686 -58.038772) (xy 357.745592 -58.068739) (xy 357.793142 -58.105226) (xy 357.835522 -58.147606)
			(xy 357.872009 -58.195156) (xy 357.901976 -58.247062) (xy 357.924912 -58.302435) (xy 357.940425 -58.360328)
			(xy 357.948248 -58.41975) (xy 357.948738 -58.449718) (xy 357.948248 -58.479686) (xy 357.940425 -58.539108)
			(xy 357.924912 -58.597001) (xy 357.901976 -58.652374) (xy 357.872009 -58.70428) (xy 357.851196 -58.731404)
			(xy 361.820714 -58.731404) (xy 361.821179 -58.704034) (xy 361.828997 -58.649854) (xy 361.844486 -58.597351)
			(xy 361.867328 -58.547604) (xy 361.897053 -58.501638) (xy 361.914694 -58.480706) (xy 361.914948 -58.480452)
			(xy 361.920525 -58.473359) (xy 361.926776 -58.456447) (xy 361.92714 -58.447432) (xy 361.92714 -58.380376)
			(xy 361.926807 -58.371356) (xy 361.920544 -58.354439) (xy 361.914948 -58.347356) (xy 361.914694 -58.347356)
			(xy 361.914694 -58.347102) (xy 361.897059 -58.326165) (xy 361.867336 -58.280197) (xy 361.844493 -58.230452)
			(xy 361.828997 -58.17795) (xy 361.821169 -58.123773) (xy 361.821169 -58.069033) (xy 361.828996 -58.014855)
			(xy 361.84449 -57.962354) (xy 361.867333 -57.912608) (xy 361.897055 -57.866639) (xy 361.914694 -57.845706)
			(xy 361.914948 -57.845452) (xy 361.920525 -57.838359) (xy 361.926776 -57.821447) (xy 361.92714 -57.812432)
			(xy 361.92714 -57.745376) (xy 361.926807 -57.736356) (xy 361.920544 -57.719439) (xy 361.914948 -57.712356)
			(xy 361.914694 -57.712356) (xy 361.914694 -57.712102) (xy 361.897059 -57.691165) (xy 361.867336 -57.645197)
			(xy 361.844493 -57.595452) (xy 361.828997 -57.54295) (xy 361.821169 -57.488773) (xy 361.821169 -57.434033)
			(xy 361.828996 -57.379855) (xy 361.84449 -57.327354) (xy 361.867333 -57.277608) (xy 361.897055 -57.231639)
			(xy 361.914694 -57.210706) (xy 361.914948 -57.210452) (xy 361.920525 -57.203359) (xy 361.926776 -57.186447)
			(xy 361.92714 -57.177432) (xy 361.92714 -57.110376) (xy 361.926807 -57.101356) (xy 361.920544 -57.084439)
			(xy 361.914948 -57.077356) (xy 361.914694 -57.077356) (xy 361.914694 -57.077102) (xy 361.897041 -57.056181)
			(xy 361.867332 -57.010205) (xy 361.844499 -56.960455) (xy 361.829011 -56.907952) (xy 361.821186 -56.853774)
			(xy 361.820714 -56.826404) (xy 361.8212 -56.799153) (xy 361.828956 -56.745205) (xy 361.844311 -56.69291)
			(xy 361.866953 -56.643333) (xy 361.896419 -56.597483) (xy 361.93211 -56.556292) (xy 361.973301 -56.520601)
			(xy 362.019151 -56.491135) (xy 362.068728 -56.468493) (xy 362.121023 -56.453138) (xy 362.174971 -56.445382)
			(xy 362.229473 -56.445382) (xy 362.283421 -56.453138) (xy 362.335716 -56.468493) (xy 362.385293 -56.491135)
			(xy 362.431143 -56.520601) (xy 362.472334 -56.556292) (xy 362.508025 -56.597483) (xy 362.537491 -56.643333)
			(xy 362.560133 -56.69291) (xy 362.575488 -56.745205) (xy 362.583244 -56.799153) (xy 362.58344 -56.810148)
			(xy 364.400338 -56.810148) (xy 364.400338 -56.809894) (xy 364.400828 -56.779926) (xy 364.408651 -56.720504)
			(xy 364.424164 -56.662611) (xy 364.4471 -56.607238) (xy 364.477067 -56.555332) (xy 364.513554 -56.507782)
			(xy 364.555934 -56.465402) (xy 364.603484 -56.428915) (xy 364.65539 -56.398948) (xy 364.710763 -56.376012)
			(xy 364.768656 -56.360499) (xy 364.828078 -56.352676) (xy 364.888014 -56.352676) (xy 364.947436 -56.360499)
			(xy 365.005329 -56.376012) (xy 365.060702 -56.398948) (xy 365.112608 -56.428915) (xy 365.160158 -56.465402)
			(xy 365.202538 -56.507782) (xy 365.239025 -56.555332) (xy 365.268992 -56.607238) (xy 365.291928 -56.662611)
			(xy 365.307441 -56.720504) (xy 365.315264 -56.779926) (xy 365.315754 -56.809894) (xy 365.315754 -56.810148)
			(xy 365.315195 -56.841672) (xy 365.306526 -56.904121) (xy 365.289371 -56.96479) (xy 365.264055 -57.022533)
			(xy 365.231058 -57.076256) (xy 365.191002 -57.124945) (xy 365.16818 -57.146698) (xy 365.161068 -57.153302)
			(xy 365.152686 -57.17032) (xy 365.146336 -57.248806) (xy 365.145962 -57.258372) (xy 365.151584 -57.276655)
			(xy 365.157258 -57.284366) (xy 365.172799 -57.304646) (xy 365.198857 -57.348597) (xy 365.218819 -57.395632)
			(xy 365.232329 -57.444908) (xy 365.23531 -57.467053) (xy 365.418569 -57.467053) (xy 365.418569 -57.412547)
			(xy 365.426327 -57.358596) (xy 365.441683 -57.306298) (xy 365.464327 -57.256718) (xy 365.493796 -57.210866)
			(xy 365.529491 -57.169674) (xy 365.570685 -57.133982) (xy 365.616539 -57.104515) (xy 365.666121 -57.081875)
			(xy 365.718419 -57.066522) (xy 365.772371 -57.058768) (xy 365.799624 -57.058306) (xy 365.825173 -57.058687)
			(xy 365.875814 -57.0655) (xy 365.925091 -57.079016) (xy 365.972122 -57.098991) (xy 366.016064 -57.125068)
			(xy 366.036352 -57.140602) (xy 366.044091 -57.146217) (xy 366.062356 -57.151831) (xy 366.071912 -57.151524)
			(xy 366.150398 -57.145174) (xy 366.167416 -57.136792) (xy 366.17402 -57.12968) (xy 366.195762 -57.106843)
			(xy 366.244439 -57.066764) (xy 366.298161 -57.033751) (xy 366.355907 -57.00843) (xy 366.416585 -56.991281)
			(xy 366.479043 -56.982629) (xy 366.51057 -56.982106) (xy 366.510824 -56.982106) (xy 366.540793 -56.98256)
			(xy 366.600217 -56.990386) (xy 366.658112 -57.005902) (xy 366.713486 -57.028842) (xy 366.765392 -57.058813)
			(xy 366.788893 -57.076848) (xy 367.438686 -57.076848) (xy 367.439184 -57.049479) (xy 367.446994 -56.995301)
			(xy 367.462476 -56.942799) (xy 367.485311 -56.893051) (xy 367.515028 -56.847083) (xy 367.532666 -56.82615)
			(xy 367.53292 -56.825896) (xy 367.538517 -56.818816) (xy 367.544757 -56.801894) (xy 367.545112 -56.792876)
			(xy 367.545112 -56.72582) (xy 367.544743 -56.716804) (xy 367.538503 -56.699887) (xy 367.53292 -56.6928)
			(xy 367.532666 -56.6928) (xy 367.532666 -56.692546) (xy 367.51503 -56.671612) (xy 367.485319 -56.625639)
			(xy 367.462483 -56.575892) (xy 367.446991 -56.523392) (xy 367.439161 -56.469217) (xy 367.438686 -56.441848)
			(xy 367.439172 -56.414597) (xy 367.446928 -56.360649) (xy 367.462283 -56.308354) (xy 367.484925 -56.258777)
			(xy 367.514391 -56.212927) (xy 367.550082 -56.171736) (xy 367.591273 -56.136045) (xy 367.637123 -56.106579)
			(xy 367.6867 -56.083937) (xy 367.738995 -56.068582) (xy 367.792943 -56.060826) (xy 367.847445 -56.060826)
			(xy 367.901393 -56.068582) (xy 367.953688 -56.083937) (xy 368.003265 -56.106579) (xy 368.049115 -56.136045)
			(xy 368.090306 -56.171736) (xy 368.125997 -56.212927) (xy 368.155463 -56.258777) (xy 368.178105 -56.308354)
			(xy 368.19346 -56.360649) (xy 368.201216 -56.414597) (xy 368.201702 -56.441848) (xy 368.201205 -56.469217)
			(xy 368.193395 -56.523395) (xy 368.177913 -56.575898) (xy 368.155078 -56.625645) (xy 368.12536 -56.671613)
			(xy 368.107722 -56.692546) (xy 368.107468 -56.6928) (xy 368.101872 -56.69988) (xy 368.095632 -56.716802)
			(xy 368.095276 -56.72582) (xy 368.095276 -56.792876) (xy 368.09565 -56.801891) (xy 368.101886 -56.818808)
			(xy 368.107468 -56.825896) (xy 368.107722 -56.825896) (xy 368.107722 -56.82615) (xy 368.125355 -56.847087)
			(xy 368.155067 -56.893059) (xy 368.177903 -56.942805) (xy 368.193396 -56.995305) (xy 368.194499 -57.002934)
			(xy 369.863624 -57.002934) (xy 369.864125 -56.974842) (xy 369.872349 -56.919265) (xy 369.888637 -56.865495)
			(xy 369.912638 -56.814697) (xy 369.943833 -56.76797) (xy 369.981545 -56.726325) (xy 370.024959 -56.690664)
			(xy 370.04879 -56.675782) (xy 370.05768 -56.670448) (xy 370.069872 -56.65343) (xy 370.090192 -56.560212)
			(xy 370.085874 -56.539638) (xy 370.080032 -56.531002) (xy 370.064034 -56.506937) (xy 370.03869 -56.455006)
			(xy 370.021464 -56.399848) (xy 370.012748 -56.342724) (xy 370.012214 -56.313832) (xy 370.012685 -56.286579)
			(xy 370.020438 -56.232627) (xy 370.035791 -56.180328) (xy 370.058432 -56.130747) (xy 370.087899 -56.084892)
			(xy 370.123592 -56.043699) (xy 370.164784 -56.008005) (xy 370.210638 -55.978537) (xy 370.260219 -55.955895)
			(xy 370.312517 -55.94054) (xy 370.366469 -55.932786) (xy 370.393722 -55.932324) (xy 370.421093 -55.932771)
			(xy 370.475273 -55.940593) (xy 370.527777 -55.956086) (xy 370.577523 -55.978932) (xy 370.623489 -56.008661)
			(xy 370.64442 -56.026304) (xy 370.644674 -56.026558) (xy 370.651759 -56.032147) (xy 370.668677 -56.038391)
			(xy 370.677694 -56.03875) (xy 370.74475 -56.03875) (xy 370.753766 -56.03838) (xy 370.770683 -56.032143)
			(xy 370.77777 -56.026558) (xy 370.77777 -56.026304) (xy 370.778024 -56.026304) (xy 370.798957 -56.008663)
			(xy 370.844925 -55.978939) (xy 370.894671 -55.956093) (xy 370.947173 -55.940597) (xy 371.001351 -55.932768)
			(xy 371.056093 -55.932768) (xy 371.110271 -55.940597) (xy 371.162773 -55.956093) (xy 371.212519 -55.978939)
			(xy 371.258487 -56.008663) (xy 371.27942 -56.026304) (xy 371.279674 -56.026558) (xy 371.286759 -56.032147)
			(xy 371.303677 -56.038391) (xy 371.312694 -56.03875) (xy 371.37975 -56.03875) (xy 371.388766 -56.03838)
			(xy 371.405683 -56.032143) (xy 371.41277 -56.026558) (xy 371.41277 -56.026304) (xy 371.413024 -56.026304)
			(xy 371.433974 -56.008688) (xy 371.479942 -55.978972) (xy 371.529685 -55.956132) (xy 371.582182 -55.940635)
			(xy 371.636354 -55.932801) (xy 371.663722 -55.932324) (xy 371.690975 -55.932747) (xy 371.744924 -55.940507)
			(xy 371.797221 -55.955865) (xy 371.846799 -55.97851) (xy 371.892651 -56.007979) (xy 371.933842 -56.043674)
			(xy 371.969534 -56.084867) (xy 371.999001 -56.13072) (xy 372.021642 -56.1803) (xy 372.036998 -56.232597)
			(xy 372.044754 -56.286547) (xy 372.044754 -56.297068) (xy 372.386604 -56.297068) (xy 372.390675 -56.241446)
			(xy 372.402801 -56.187009) (xy 372.422724 -56.134918) (xy 372.45002 -56.086283) (xy 372.484106 -56.04214)
			(xy 372.524255 -56.003431) (xy 372.569613 -55.97098) (xy 372.619213 -55.945479) (xy 372.671997 -55.927472)
			(xy 372.72684 -55.917342) (xy 372.782574 -55.915305) (xy 372.838011 -55.921405) (xy 372.891968 -55.935511)
			(xy 372.943297 -55.957323) (xy 372.990903 -55.986377) (xy 373.033771 -56.022052) (xy 373.070988 -56.063589)
			(xy 373.101761 -56.110102) (xy 373.125433 -56.160599) (xy 373.141501 -56.214006) (xy 373.149621 -56.269182)
			(xy 373.15013 -56.297068) (xy 373.149621 -56.324954) (xy 373.145426 -56.353456) (xy 375.24131 -56.353456)
			(xy 375.245381 -56.297834) (xy 375.257507 -56.243397) (xy 375.27743 -56.191306) (xy 375.304726 -56.142671)
			(xy 375.338812 -56.098528) (xy 375.378961 -56.059819) (xy 375.424319 -56.027368) (xy 375.473919 -56.001867)
			(xy 375.526703 -55.98386) (xy 375.581546 -55.97373) (xy 375.63728 -55.971693) (xy 375.692717 -55.977793)
			(xy 375.746674 -55.991899) (xy 375.798003 -56.013711) (xy 375.845609 -56.042765) (xy 375.888477 -56.07844)
			(xy 375.925694 -56.119977) (xy 375.956467 -56.16649) (xy 375.980139 -56.216987) (xy 375.996207 -56.270394)
			(xy 376.004327 -56.32557) (xy 376.004836 -56.353456) (xy 376.004327 -56.381342) (xy 375.996207 -56.436518)
			(xy 375.980139 -56.489925) (xy 375.956467 -56.540422) (xy 375.925694 -56.586935) (xy 375.888477 -56.628472)
			(xy 375.845609 -56.664147) (xy 375.798003 -56.693201) (xy 375.746674 -56.715013) (xy 375.692717 -56.729119)
			(xy 375.63728 -56.735219) (xy 375.581546 -56.733182) (xy 375.526703 -56.723052) (xy 375.473919 -56.705045)
			(xy 375.424319 -56.679544) (xy 375.378961 -56.647093) (xy 375.338812 -56.608384) (xy 375.304726 -56.564241)
			(xy 375.27743 -56.515606) (xy 375.257507 -56.463515) (xy 375.245381 -56.409078) (xy 375.24131 -56.353456)
			(xy 373.145426 -56.353456) (xy 373.141501 -56.38013) (xy 373.125433 -56.433537) (xy 373.101761 -56.484034)
			(xy 373.070988 -56.530547) (xy 373.033771 -56.572084) (xy 372.990903 -56.607759) (xy 372.943297 -56.636813)
			(xy 372.891968 -56.658625) (xy 372.838011 -56.672731) (xy 372.782574 -56.678831) (xy 372.72684 -56.676794)
			(xy 372.671997 -56.666664) (xy 372.619213 -56.648657) (xy 372.569613 -56.623156) (xy 372.524255 -56.590705)
			(xy 372.484106 -56.551996) (xy 372.45002 -56.507853) (xy 372.422724 -56.459218) (xy 372.402801 -56.407127)
			(xy 372.390675 -56.35269) (xy 372.386604 -56.297068) (xy 372.044754 -56.297068) (xy 372.044754 -56.341053)
			(xy 372.036998 -56.395003) (xy 372.021642 -56.4473) (xy 371.999001 -56.49688) (xy 371.969534 -56.542733)
			(xy 371.933842 -56.583926) (xy 371.892651 -56.619621) (xy 371.846799 -56.64909) (xy 371.797221 -56.671735)
			(xy 371.744924 -56.687093) (xy 371.690975 -56.694853) (xy 371.663722 -56.69534) (xy 371.636352 -56.694876)
			(xy 371.582172 -56.68706) (xy 371.529668 -56.671571) (xy 371.479921 -56.648728) (xy 371.433955 -56.619002)
			(xy 371.413024 -56.60136) (xy 371.41277 -56.601106) (xy 371.405667 -56.595543) (xy 371.388763 -56.589282)
			(xy 371.37975 -56.588914) (xy 371.312694 -56.588914) (xy 371.303676 -56.589265) (xy 371.286759 -56.595516)
			(xy 371.279674 -56.601106) (xy 371.279674 -56.60136) (xy 371.27942 -56.60136) (xy 371.258487 -56.619001)
			(xy 371.212519 -56.648725) (xy 371.162773 -56.671571) (xy 371.110271 -56.687067) (xy 371.056093 -56.694896)
			(xy 371.001351 -56.694896) (xy 370.947173 -56.687067) (xy 370.894671 -56.671571) (xy 370.844925 -56.648725)
			(xy 370.798957 -56.619001) (xy 370.778024 -56.60136) (xy 370.77777 -56.601106) (xy 370.770667 -56.595543)
			(xy 370.753763 -56.589282) (xy 370.74475 -56.588914) (xy 370.677694 -56.588914) (xy 370.668676 -56.589265)
			(xy 370.651759 -56.595516) (xy 370.644674 -56.601106) (xy 370.644166 -56.60136) (xy 370.631431 -56.612304)
			(xy 370.60434 -56.632145) (xy 370.590064 -56.640984) (xy 370.581174 -56.646318) (xy 370.568982 -56.663336)
			(xy 370.548662 -56.756554) (xy 370.55298 -56.777128) (xy 370.558822 -56.785764) (xy 370.574811 -56.809834)
			(xy 370.600156 -56.861764) (xy 370.617384 -56.91692) (xy 370.626103 -56.974042) (xy 370.62664 -57.002934)
			(xy 370.626154 -57.030185) (xy 370.618398 -57.084133) (xy 370.603043 -57.136428) (xy 370.580401 -57.186005)
			(xy 370.550935 -57.231855) (xy 370.515244 -57.273046) (xy 370.474053 -57.308737) (xy 370.428203 -57.338203)
			(xy 370.378626 -57.360845) (xy 370.326331 -57.3762) (xy 370.272383 -57.383956) (xy 370.217881 -57.383956)
			(xy 370.163933 -57.3762) (xy 370.111638 -57.360845) (xy 370.062061 -57.338203) (xy 370.016211 -57.308737)
			(xy 369.97502 -57.273046) (xy 369.939329 -57.231855) (xy 369.909863 -57.186005) (xy 369.887221 -57.136428)
			(xy 369.871866 -57.084133) (xy 369.86411 -57.030185) (xy 369.863624 -57.002934) (xy 368.194499 -57.002934)
			(xy 368.201227 -57.049479) (xy 368.201702 -57.076848) (xy 368.201216 -57.104099) (xy 368.19346 -57.158047)
			(xy 368.178105 -57.210342) (xy 368.155463 -57.259919) (xy 368.125997 -57.305769) (xy 368.090306 -57.34696)
			(xy 368.049115 -57.382651) (xy 368.003265 -57.412117) (xy 367.953688 -57.434759) (xy 367.901393 -57.450114)
			(xy 367.847445 -57.45787) (xy 367.792943 -57.45787) (xy 367.738995 -57.450114) (xy 367.6867 -57.434759)
			(xy 367.637123 -57.412117) (xy 367.591273 -57.382651) (xy 367.550082 -57.34696) (xy 367.514391 -57.305769)
			(xy 367.484925 -57.259919) (xy 367.462283 -57.210342) (xy 367.446928 -57.158047) (xy 367.439172 -57.104099)
			(xy 367.438686 -57.076848) (xy 366.788893 -57.076848) (xy 366.812942 -57.095303) (xy 366.855323 -57.137687)
			(xy 366.891808 -57.18524) (xy 366.921775 -57.237148) (xy 366.94471 -57.292524) (xy 366.960221 -57.35042)
			(xy 366.968043 -57.409845) (xy 366.968532 -57.439814) (xy 366.968099 -57.468047) (xy 366.965964 -57.48528)
			(xy 378.906022 -57.48528) (xy 378.910093 -57.429658) (xy 378.922219 -57.375221) (xy 378.942142 -57.32313)
			(xy 378.969438 -57.274495) (xy 379.003524 -57.230352) (xy 379.043673 -57.191643) (xy 379.089031 -57.159192)
			(xy 379.138631 -57.133691) (xy 379.191415 -57.115684) (xy 379.246258 -57.105554) (xy 379.301992 -57.103517)
			(xy 379.357429 -57.109617) (xy 379.411386 -57.123723) (xy 379.462715 -57.145535) (xy 379.510321 -57.174589)
			(xy 379.553189 -57.210264) (xy 379.590406 -57.251801) (xy 379.621179 -57.298314) (xy 379.644851 -57.348811)
			(xy 379.660919 -57.402218) (xy 379.669039 -57.457394) (xy 379.669548 -57.48528) (xy 379.669039 -57.513166)
			(xy 379.660919 -57.568342) (xy 379.644851 -57.621749) (xy 379.621179 -57.672246) (xy 379.590406 -57.718759)
			(xy 379.553189 -57.760296) (xy 379.510321 -57.795971) (xy 379.462715 -57.825025) (xy 379.411386 -57.846837)
			(xy 379.357429 -57.860943) (xy 379.301992 -57.867043) (xy 379.246258 -57.865006) (xy 379.191415 -57.854876)
			(xy 379.138631 -57.836869) (xy 379.089031 -57.811368) (xy 379.043673 -57.778917) (xy 379.003524 -57.740208)
			(xy 378.969438 -57.696065) (xy 378.942142 -57.64743) (xy 378.922219 -57.595339) (xy 378.910093 -57.540902)
			(xy 378.906022 -57.48528) (xy 366.965964 -57.48528) (xy 366.961158 -57.524085) (xy 366.94737 -57.578841)
			(xy 366.926946 -57.631484) (xy 366.900196 -57.681211) (xy 366.884204 -57.704482) (xy 366.876838 -57.71515)
			(xy 366.87379 -57.740804) (xy 366.916208 -57.844436) (xy 366.936274 -57.860692) (xy 366.949228 -57.862978)
			(xy 366.975335 -57.868127) (xy 367.025906 -57.884685) (xy 367.073687 -57.908107) (xy 367.117751 -57.937939)
			(xy 367.157244 -57.973603) (xy 367.191399 -58.014406) (xy 367.219556 -58.059559) (xy 367.241168 -58.108185)
			(xy 367.255815 -58.159342) (xy 367.263215 -58.212038) (xy 367.26368 -58.238644) (xy 367.263186 -58.266013)
			(xy 367.255376 -58.320191) (xy 367.239893 -58.372694) (xy 367.217058 -58.422442) (xy 367.187339 -58.46841)
			(xy 367.1697 -58.489342) (xy 367.169446 -58.489596) (xy 367.163849 -58.496675) (xy 367.15761 -58.513598)
			(xy 367.157254 -58.522616) (xy 367.157254 -58.589672) (xy 367.157613 -58.598689) (xy 367.163858 -58.615607)
			(xy 367.169446 -58.622692) (xy 367.1697 -58.622692) (xy 367.1697 -58.622946) (xy 367.187327 -58.643888)
			(xy 367.210239 -58.679334) (xy 370.295424 -58.679334) (xy 370.29584 -58.653018) (xy 370.303084 -58.600887)
			(xy 370.317413 -58.550243) (xy 370.338555 -58.502044) (xy 370.36611 -58.457202) (xy 370.399558 -58.416565)
			(xy 370.418614 -58.39841) (xy 370.426015 -58.390889) (xy 370.43454 -58.371608) (xy 370.435124 -58.361072)
			(xy 370.435124 -58.286396) (xy 370.434603 -58.275846) (xy 370.426061 -58.256551) (xy 370.418614 -58.249058)
			(xy 370.399548 -58.230913) (xy 370.366091 -58.190281) (xy 370.338533 -58.145439) (xy 370.317396 -58.097236)
			(xy 370.303082 -58.046587) (xy 370.29586 -57.994451) (xy 370.295424 -57.968134) (xy 370.29591 -57.940883)
			(xy 370.303666 -57.886935) (xy 370.319021 -57.83464) (xy 370.341663 -57.785063) (xy 370.371129 -57.739213)
			(xy 370.40682 -57.698022) (xy 370.448011 -57.662331) (xy 370.493861 -57.632865) (xy 370.543438 -57.610223)
			(xy 370.595733 -57.594868) (xy 370.649681 -57.587112) (xy 370.704183 -57.587112) (xy 370.758131 -57.594868)
			(xy 370.810426 -57.610223) (xy 370.860003 -57.632865) (xy 370.905853 -57.662331) (xy 370.947044 -57.698022)
			(xy 370.982735 -57.739213) (xy 371.012201 -57.785063) (xy 371.034843 -57.83464) (xy 371.050198 -57.886935)
			(xy 371.057954 -57.940883) (xy 371.05844 -57.968134) (xy 371.058014 -57.99445) (xy 371.050774 -58.046581)
			(xy 371.036448 -58.097225) (xy 371.034248 -58.102242) (xy 374.218436 -58.102242) (xy 374.218436 -58.042306)
			(xy 374.226259 -57.982884) (xy 374.241772 -57.924991) (xy 374.264708 -57.869618) (xy 374.294675 -57.817712)
			(xy 374.331162 -57.770162) (xy 374.373542 -57.727782) (xy 374.421092 -57.691295) (xy 374.472998 -57.661328)
			(xy 374.528371 -57.638392) (xy 374.586264 -57.622879) (xy 374.645686 -57.615056) (xy 374.705622 -57.615056)
			(xy 374.765044 -57.622879) (xy 374.822937 -57.638392) (xy 374.87831 -57.661328) (xy 374.930216 -57.691295)
			(xy 374.977766 -57.727782) (xy 375.020146 -57.770162) (xy 375.056633 -57.817712) (xy 375.0866 -57.869618)
			(xy 375.109536 -57.924991) (xy 375.125049 -57.982884) (xy 375.132872 -58.042306) (xy 375.133362 -58.072274)
			(xy 375.132872 -58.102242) (xy 375.13237 -58.106052) (xy 379.582916 -58.106052) (xy 379.582916 -58.046116)
			(xy 379.590739 -57.986694) (xy 379.606252 -57.928801) (xy 379.629188 -57.873428) (xy 379.659155 -57.821522)
			(xy 379.695642 -57.773972) (xy 379.738022 -57.731592) (xy 379.785572 -57.695105) (xy 379.837478 -57.665138)
			(xy 379.892851 -57.642202) (xy 379.950744 -57.626689) (xy 380.010166 -57.618866) (xy 380.070102 -57.618866)
			(xy 380.129524 -57.626689) (xy 380.187417 -57.642202) (xy 380.24279 -57.665138) (xy 380.294696 -57.695105)
			(xy 380.342246 -57.731592) (xy 380.384626 -57.773972) (xy 380.421113 -57.821522) (xy 380.45108 -57.873428)
			(xy 380.460953 -57.897264) (xy 381.8679 -57.897264) (xy 381.8679 -57.837328) (xy 381.875723 -57.777906)
			(xy 381.891236 -57.720013) (xy 381.914172 -57.66464) (xy 381.944139 -57.612734) (xy 381.980626 -57.565184)
			(xy 382.023006 -57.522804) (xy 382.070556 -57.486317) (xy 382.122462 -57.45635) (xy 382.177835 -57.433414)
			(xy 382.235728 -57.417901) (xy 382.29515 -57.410078) (xy 382.355086 -57.410078) (xy 382.414508 -57.417901)
			(xy 382.472401 -57.433414) (xy 382.527774 -57.45635) (xy 382.57968 -57.486317) (xy 382.62723 -57.522804)
			(xy 382.66961 -57.565184) (xy 382.706097 -57.612734) (xy 382.736064 -57.66464) (xy 382.759 -57.720013)
			(xy 382.774513 -57.777906) (xy 382.782336 -57.837328) (xy 382.782826 -57.867296) (xy 382.782336 -57.897264)
			(xy 382.774513 -57.956686) (xy 382.759 -58.014579) (xy 382.736064 -58.069952) (xy 382.706097 -58.121858)
			(xy 382.66961 -58.169408) (xy 382.62723 -58.211788) (xy 382.57968 -58.248275) (xy 382.527774 -58.278242)
			(xy 382.472401 -58.301178) (xy 382.414508 -58.316691) (xy 382.355086 -58.324514) (xy 382.29515 -58.324514)
			(xy 382.235728 -58.316691) (xy 382.177835 -58.301178) (xy 382.122462 -58.278242) (xy 382.070556 -58.248275)
			(xy 382.023006 -58.211788) (xy 381.980626 -58.169408) (xy 381.944139 -58.121858) (xy 381.914172 -58.069952)
			(xy 381.891236 -58.014579) (xy 381.875723 -57.956686) (xy 381.8679 -57.897264) (xy 380.460953 -57.897264)
			(xy 380.474016 -57.928801) (xy 380.489529 -57.986694) (xy 380.497352 -58.046116) (xy 380.497842 -58.076084)
			(xy 380.497352 -58.106052) (xy 380.489529 -58.165474) (xy 380.474016 -58.223367) (xy 380.45108 -58.27874)
			(xy 380.421113 -58.330646) (xy 380.384626 -58.378196) (xy 380.342246 -58.420576) (xy 380.294696 -58.457063)
			(xy 380.24279 -58.48703) (xy 380.187417 -58.509966) (xy 380.129524 -58.525479) (xy 380.070102 -58.533302)
			(xy 380.010166 -58.533302) (xy 379.950744 -58.525479) (xy 379.892851 -58.509966) (xy 379.837478 -58.48703)
			(xy 379.785572 -58.457063) (xy 379.738022 -58.420576) (xy 379.695642 -58.378196) (xy 379.659155 -58.330646)
			(xy 379.629188 -58.27874) (xy 379.606252 -58.223367) (xy 379.590739 -58.165474) (xy 379.582916 -58.106052)
			(xy 375.13237 -58.106052) (xy 375.125049 -58.161664) (xy 375.109536 -58.219557) (xy 375.0866 -58.27493)
			(xy 375.056633 -58.326836) (xy 375.020146 -58.374386) (xy 374.977766 -58.416766) (xy 374.930216 -58.453253)
			(xy 374.87831 -58.48322) (xy 374.822937 -58.506156) (xy 374.765044 -58.521669) (xy 374.705622 -58.529492)
			(xy 374.645686 -58.529492) (xy 374.586264 -58.521669) (xy 374.528371 -58.506156) (xy 374.472998 -58.48322)
			(xy 374.421092 -58.453253) (xy 374.373542 -58.416766) (xy 374.331162 -58.374386) (xy 374.294675 -58.326836)
			(xy 374.264708 -58.27493) (xy 374.241772 -58.219557) (xy 374.226259 -58.161664) (xy 374.218436 -58.102242)
			(xy 371.034248 -58.102242) (xy 371.015308 -58.145424) (xy 370.987753 -58.190267) (xy 370.954306 -58.230903)
			(xy 370.93525 -58.249058) (xy 370.927872 -58.2566) (xy 370.919333 -58.275864) (xy 370.91874 -58.286396)
			(xy 370.91874 -58.361072) (xy 370.919259 -58.371623) (xy 370.9278 -58.390919) (xy 370.93525 -58.39841)
			(xy 370.954313 -58.416558) (xy 370.987767 -58.45719) (xy 371.015324 -58.502033) (xy 371.036461 -58.550235)
			(xy 371.048038 -58.591192) (xy 380.78713 -58.591192) (xy 380.78713 -58.531256) (xy 380.794953 -58.471834)
			(xy 380.810466 -58.413941) (xy 380.833402 -58.358568) (xy 380.863369 -58.306662) (xy 380.899856 -58.259112)
			(xy 380.942236 -58.216732) (xy 380.989786 -58.180245) (xy 381.041692 -58.150278) (xy 381.097065 -58.127342)
			(xy 381.154958 -58.111829) (xy 381.21438 -58.104006) (xy 381.274316 -58.104006) (xy 381.333738 -58.111829)
			(xy 381.391631 -58.127342) (xy 381.447004 -58.150278) (xy 381.49891 -58.180245) (xy 381.54646 -58.216732)
			(xy 381.58884 -58.259112) (xy 381.625327 -58.306662) (xy 381.655294 -58.358568) (xy 381.67823 -58.413941)
			(xy 381.693743 -58.471834) (xy 381.694777 -58.479686) (xy 383.03376 -58.479686) (xy 383.03376 -58.41975)
			(xy 383.041583 -58.360328) (xy 383.057096 -58.302435) (xy 383.080032 -58.247062) (xy 383.109999 -58.195156)
			(xy 383.146486 -58.147606) (xy 383.188866 -58.105226) (xy 383.236416 -58.068739) (xy 383.288322 -58.038772)
			(xy 383.343695 -58.015836) (xy 383.401588 -58.000323) (xy 383.46101 -57.9925) (xy 383.520946 -57.9925)
			(xy 383.580368 -58.000323) (xy 383.638261 -58.015836) (xy 383.693634 -58.038772) (xy 383.74554 -58.068739)
			(xy 383.79309 -58.105226) (xy 383.83547 -58.147606) (xy 383.871957 -58.195156) (xy 383.901924 -58.247062)
			(xy 383.92486 -58.302435) (xy 383.940373 -58.360328) (xy 383.948196 -58.41975) (xy 383.948686 -58.449718)
			(xy 383.948196 -58.479686) (xy 383.940373 -58.539108) (xy 383.92486 -58.597001) (xy 383.901924 -58.652374)
			(xy 383.871957 -58.70428) (xy 383.851144 -58.731404) (xy 387.820662 -58.731404) (xy 387.821115 -58.704033)
			(xy 387.828934 -58.649853) (xy 387.844425 -58.597349) (xy 387.86727 -58.547602) (xy 387.896999 -58.501637)
			(xy 387.914642 -58.480706) (xy 387.914896 -58.480452) (xy 387.920467 -58.473354) (xy 387.926723 -58.456446)
			(xy 387.927088 -58.447432) (xy 387.927088 -58.380376) (xy 387.926745 -58.371358) (xy 387.920488 -58.354441)
			(xy 387.914896 -58.347356) (xy 387.914642 -58.347356) (xy 387.914642 -58.347102) (xy 387.897005 -58.326166)
			(xy 387.867279 -58.280199) (xy 387.844432 -58.230454) (xy 387.828935 -58.177952) (xy 387.821105 -58.123774)
			(xy 387.821105 -58.069032) (xy 387.828933 -58.014854) (xy 387.84443 -57.962352) (xy 387.867276 -57.912606)
			(xy 387.897001 -57.866638) (xy 387.914642 -57.845706) (xy 387.914896 -57.845452) (xy 387.920467 -57.838354)
			(xy 387.926723 -57.821446) (xy 387.927088 -57.812432) (xy 387.927088 -57.745376) (xy 387.926745 -57.736358)
			(xy 387.920488 -57.719441) (xy 387.914896 -57.712356) (xy 387.914642 -57.712356) (xy 387.914642 -57.712102)
			(xy 387.897005 -57.691166) (xy 387.867279 -57.645199) (xy 387.844432 -57.595454) (xy 387.828935 -57.542952)
			(xy 387.821105 -57.488774) (xy 387.821105 -57.434032) (xy 387.828933 -57.379854) (xy 387.84443 -57.327352)
			(xy 387.867276 -57.277606) (xy 387.897001 -57.231638) (xy 387.914642 -57.210706) (xy 387.914896 -57.210452)
			(xy 387.920467 -57.203354) (xy 387.926723 -57.186446) (xy 387.927088 -57.177432) (xy 387.927088 -57.110376)
			(xy 387.926745 -57.101358) (xy 387.920488 -57.084441) (xy 387.914896 -57.077356) (xy 387.914642 -57.077356)
			(xy 387.914642 -57.077102) (xy 387.896997 -57.056175) (xy 387.867285 -57.010201) (xy 387.844449 -56.960453)
			(xy 387.82896 -56.907951) (xy 387.821134 -56.853774) (xy 387.820662 -56.826404) (xy 387.821148 -56.799153)
			(xy 387.828904 -56.745205) (xy 387.844259 -56.69291) (xy 387.866901 -56.643333) (xy 387.896367 -56.597483)
			(xy 387.932058 -56.556292) (xy 387.973249 -56.520601) (xy 388.019099 -56.491135) (xy 388.068676 -56.468493)
			(xy 388.120971 -56.453138) (xy 388.174919 -56.445382) (xy 388.229421 -56.445382) (xy 388.283369 -56.453138)
			(xy 388.335664 -56.468493) (xy 388.385241 -56.491135) (xy 388.431091 -56.520601) (xy 388.472282 -56.556292)
			(xy 388.507973 -56.597483) (xy 388.537439 -56.643333) (xy 388.560081 -56.69291) (xy 388.575436 -56.745205)
			(xy 388.583192 -56.799153) (xy 388.583388 -56.810148) (xy 390.400286 -56.810148) (xy 390.400286 -56.809894)
			(xy 390.400776 -56.779926) (xy 390.408599 -56.720504) (xy 390.424112 -56.662611) (xy 390.447048 -56.607238)
			(xy 390.477015 -56.555332) (xy 390.513502 -56.507782) (xy 390.555882 -56.465402) (xy 390.603432 -56.428915)
			(xy 390.655338 -56.398948) (xy 390.710711 -56.376012) (xy 390.768604 -56.360499) (xy 390.828026 -56.352676)
			(xy 390.887962 -56.352676) (xy 390.947384 -56.360499) (xy 391.005277 -56.376012) (xy 391.06065 -56.398948)
			(xy 391.112556 -56.428915) (xy 391.160106 -56.465402) (xy 391.202486 -56.507782) (xy 391.238973 -56.555332)
			(xy 391.26894 -56.607238) (xy 391.291876 -56.662611) (xy 391.307389 -56.720504) (xy 391.315212 -56.779926)
			(xy 391.315702 -56.809894) (xy 391.315702 -56.810148) (xy 391.315128 -56.841671) (xy 391.306459 -56.904119)
			(xy 391.289307 -56.964787) (xy 391.263994 -57.022529) (xy 391.231 -57.076253) (xy 391.190948 -57.124943)
			(xy 391.168128 -57.146698) (xy 391.161016 -57.153302) (xy 391.152634 -57.17032) (xy 391.146284 -57.248806)
			(xy 391.145921 -57.258371) (xy 391.151536 -57.276654) (xy 391.157206 -57.284366) (xy 391.17274 -57.304652)
			(xy 391.1988 -57.348601) (xy 391.218764 -57.395633) (xy 391.232276 -57.444909) (xy 391.235257 -57.467049)
			(xy 391.418592 -57.467049) (xy 391.418592 -57.412551) (xy 391.426348 -57.358608) (xy 391.441701 -57.306317)
			(xy 391.464339 -57.256744) (xy 391.493802 -57.210896) (xy 391.529489 -57.169709) (xy 391.570674 -57.134018)
			(xy 391.616519 -57.104552) (xy 391.666091 -57.081911) (xy 391.71838 -57.066554) (xy 391.772323 -57.058794)
			(xy 391.799572 -57.058306) (xy 391.82512 -57.058715) (xy 391.875759 -57.065522) (xy 391.925037 -57.079031)
			(xy 391.972068 -57.099) (xy 392.016011 -57.125071) (xy 392.0363 -57.140602) (xy 392.044026 -57.146239)
			(xy 392.062301 -57.15184) (xy 392.07186 -57.151524) (xy 392.150346 -57.145174) (xy 392.167364 -57.136792)
			(xy 392.173968 -57.12968) (xy 392.195735 -57.106868) (xy 392.244407 -57.066787) (xy 392.298123 -57.03377)
			(xy 392.355865 -57.008445) (xy 392.416538 -56.991291) (xy 392.478992 -56.982633) (xy 392.510518 -56.982106)
			(xy 392.510772 -56.982106) (xy 392.540741 -56.982587) (xy 392.600166 -56.990408) (xy 392.658063 -57.005918)
			(xy 392.713439 -57.028853) (xy 392.765348 -57.05882) (xy 392.788843 -57.076848) (xy 393.438634 -57.076848)
			(xy 393.43912 -57.049478) (xy 393.446932 -56.9953) (xy 393.462416 -56.942797) (xy 393.485253 -56.893049)
			(xy 393.514974 -56.847082) (xy 393.532614 -56.82615) (xy 393.532868 -56.825896) (xy 393.53847 -56.818821)
			(xy 393.544706 -56.801895) (xy 393.54506 -56.792876) (xy 393.54506 -56.72582) (xy 393.544702 -56.716803)
			(xy 393.538456 -56.699886) (xy 393.532868 -56.6928) (xy 393.532614 -56.6928) (xy 393.532614 -56.692546)
			(xy 393.514985 -56.671606) (xy 393.485271 -56.625635) (xy 393.462433 -56.57589) (xy 393.44694 -56.523391)
			(xy 393.439109 -56.469217) (xy 393.438634 -56.441848) (xy 393.43912 -56.414597) (xy 393.446876 -56.360649)
			(xy 393.462231 -56.308354) (xy 393.484873 -56.258777) (xy 393.514339 -56.212927) (xy 393.55003 -56.171736)
			(xy 393.591221 -56.136045) (xy 393.637071 -56.106579) (xy 393.686648 -56.083937) (xy 393.738943 -56.068582)
			(xy 393.792891 -56.060826) (xy 393.847393 -56.060826) (xy 393.901341 -56.068582) (xy 393.953636 -56.083937)
			(xy 394.003213 -56.106579) (xy 394.049063 -56.136045) (xy 394.090254 -56.171736) (xy 394.125945 -56.212927)
			(xy 394.155411 -56.258777) (xy 394.178053 -56.308354) (xy 394.193408 -56.360649) (xy 394.201164 -56.414597)
			(xy 394.20165 -56.441848) (xy 394.201166 -56.469218) (xy 394.193354 -56.523397) (xy 394.17787 -56.5759)
			(xy 394.155032 -56.625647) (xy 394.12531 -56.671614) (xy 394.10767 -56.692546) (xy 394.107416 -56.6928)
			(xy 394.101825 -56.699884) (xy 394.095581 -56.716803) (xy 394.095224 -56.72582) (xy 394.095224 -56.792876)
			(xy 394.095588 -56.801892) (xy 394.10183 -56.81881) (xy 394.107416 -56.825896) (xy 394.10767 -56.825896)
			(xy 394.10767 -56.82615) (xy 394.125294 -56.847094) (xy 394.15501 -56.893063) (xy 394.177849 -56.942807)
			(xy 394.193343 -56.995306) (xy 394.194446 -57.002934) (xy 395.863572 -57.002934) (xy 395.864098 -56.974844)
			(xy 395.872321 -56.919268) (xy 395.888607 -56.8655) (xy 395.912604 -56.814703) (xy 395.943794 -56.767976)
			(xy 395.981501 -56.72633) (xy 396.02491 -56.690666) (xy 396.048738 -56.675782) (xy 396.057628 -56.670448)
			(xy 396.06982 -56.65343) (xy 396.09014 -56.560212) (xy 396.085822 -56.539638) (xy 396.07998 -56.531002)
			(xy 396.063976 -56.506941) (xy 396.038635 -56.455008) (xy 396.021411 -56.399849) (xy 396.012696 -56.342725)
			(xy 396.012162 -56.313832) (xy 396.012685 -56.286581) (xy 396.020437 -56.232634) (xy 396.035787 -56.180339)
			(xy 396.058424 -56.130761) (xy 396.087886 -56.084909) (xy 396.123573 -56.043717) (xy 396.16476 -56.008023)
			(xy 396.210607 -55.978554) (xy 396.260181 -55.955909) (xy 396.312473 -55.94055) (xy 396.366419 -55.932789)
			(xy 396.39367 -55.932324) (xy 396.42104 -55.932802) (xy 396.475219 -55.940616) (xy 396.527722 -55.956102)
			(xy 396.577469 -55.978941) (xy 396.623436 -56.008664) (xy 396.644368 -56.026304) (xy 396.644622 -56.026558)
			(xy 396.651693 -56.032167) (xy 396.668622 -56.038399) (xy 396.677642 -56.03875) (xy 396.744698 -56.03875)
			(xy 396.753716 -56.038403) (xy 396.770633 -56.032149) (xy 396.777718 -56.026558) (xy 396.777718 -56.026304)
			(xy 396.777972 -56.026304) (xy 396.798905 -56.008663) (xy 396.844873 -55.978939) (xy 396.894619 -55.956093)
			(xy 396.947121 -55.940597) (xy 397.001299 -55.932768) (xy 397.056041 -55.932768) (xy 397.110219 -55.940597)
			(xy 397.162721 -55.956093) (xy 397.212467 -55.978939) (xy 397.258435 -56.008663) (xy 397.279368 -56.026304)
			(xy 397.279622 -56.026558) (xy 397.286693 -56.032167) (xy 397.303622 -56.038399) (xy 397.312642 -56.03875)
			(xy 397.379698 -56.03875) (xy 397.388716 -56.038403) (xy 397.405633 -56.032149) (xy 397.412718 -56.026558)
			(xy 397.412718 -56.026304) (xy 397.412972 -56.026304) (xy 397.433904 -56.008665) (xy 397.479877 -55.978953)
			(xy 397.529624 -55.956117) (xy 397.582125 -55.940626) (xy 397.636301 -55.932798) (xy 397.66367 -55.932324)
			(xy 397.690927 -55.932721) (xy 397.744885 -55.940475) (xy 397.797191 -55.95583) (xy 397.846779 -55.978472)
			(xy 397.89264 -56.007942) (xy 397.93384 -56.043639) (xy 397.96954 -56.084836) (xy 397.999013 -56.130694)
			(xy 398.02166 -56.180281) (xy 398.037019 -56.232585) (xy 398.044777 -56.286543) (xy 398.044777 -56.297068)
			(xy 398.386552 -56.297068) (xy 398.390623 -56.241446) (xy 398.402749 -56.187009) (xy 398.422672 -56.134918)
			(xy 398.449968 -56.086283) (xy 398.484054 -56.04214) (xy 398.524203 -56.003431) (xy 398.569561 -55.97098)
			(xy 398.619161 -55.945479) (xy 398.671945 -55.927472) (xy 398.726788 -55.917342) (xy 398.782522 -55.915305)
			(xy 398.837959 -55.921405) (xy 398.891916 -55.935511) (xy 398.943245 -55.957323) (xy 398.990851 -55.986377)
			(xy 399.033719 -56.022052) (xy 399.070936 -56.063589) (xy 399.101709 -56.110102) (xy 399.125381 -56.160599)
			(xy 399.141449 -56.214006) (xy 399.149569 -56.269182) (xy 399.150078 -56.297068) (xy 399.149569 -56.324954)
			(xy 399.145374 -56.353456) (xy 401.241258 -56.353456) (xy 401.245329 -56.297834) (xy 401.257455 -56.243397)
			(xy 401.277378 -56.191306) (xy 401.304674 -56.142671) (xy 401.33876 -56.098528) (xy 401.378909 -56.059819)
			(xy 401.424267 -56.027368) (xy 401.473867 -56.001867) (xy 401.526651 -55.98386) (xy 401.581494 -55.97373)
			(xy 401.637228 -55.971693) (xy 401.692665 -55.977793) (xy 401.746622 -55.991899) (xy 401.797951 -56.013711)
			(xy 401.845557 -56.042765) (xy 401.888425 -56.07844) (xy 401.925642 -56.119977) (xy 401.956415 -56.16649)
			(xy 401.980087 -56.216987) (xy 401.996155 -56.270394) (xy 402.004275 -56.32557) (xy 402.004784 -56.353456)
			(xy 402.004275 -56.381342) (xy 401.996155 -56.436518) (xy 401.980087 -56.489925) (xy 401.956415 -56.540422)
			(xy 401.925642 -56.586935) (xy 401.888425 -56.628472) (xy 401.845557 -56.664147) (xy 401.797951 -56.693201)
			(xy 401.746622 -56.715013) (xy 401.692665 -56.729119) (xy 401.637228 -56.735219) (xy 401.581494 -56.733182)
			(xy 401.526651 -56.723052) (xy 401.473867 -56.705045) (xy 401.424267 -56.679544) (xy 401.378909 -56.647093)
			(xy 401.33876 -56.608384) (xy 401.304674 -56.564241) (xy 401.277378 -56.515606) (xy 401.257455 -56.463515)
			(xy 401.245329 -56.409078) (xy 401.241258 -56.353456) (xy 399.145374 -56.353456) (xy 399.141449 -56.38013)
			(xy 399.125381 -56.433537) (xy 399.101709 -56.484034) (xy 399.070936 -56.530547) (xy 399.033719 -56.572084)
			(xy 398.990851 -56.607759) (xy 398.943245 -56.636813) (xy 398.891916 -56.658625) (xy 398.837959 -56.672731)
			(xy 398.782522 -56.678831) (xy 398.726788 -56.676794) (xy 398.671945 -56.666664) (xy 398.619161 -56.648657)
			(xy 398.569561 -56.623156) (xy 398.524203 -56.590705) (xy 398.484054 -56.551996) (xy 398.449968 -56.507853)
			(xy 398.422672 -56.459218) (xy 398.402749 -56.407127) (xy 398.390623 -56.35269) (xy 398.386552 -56.297068)
			(xy 398.044777 -56.297068) (xy 398.044777 -56.341057) (xy 398.037019 -56.395015) (xy 398.02166 -56.447319)
			(xy 397.999013 -56.496906) (xy 397.96954 -56.542764) (xy 397.93384 -56.583961) (xy 397.89264 -56.619658)
			(xy 397.846779 -56.649128) (xy 397.797191 -56.67177) (xy 397.744885 -56.687125) (xy 397.690927 -56.694879)
			(xy 397.66367 -56.69534) (xy 397.636298 -56.694906) (xy 397.582117 -56.687083) (xy 397.529613 -56.671587)
			(xy 397.479867 -56.648738) (xy 397.433902 -56.619005) (xy 397.412972 -56.60136) (xy 397.412718 -56.601106)
			(xy 397.40563 -56.595521) (xy 397.388714 -56.589273) (xy 397.379698 -56.588914) (xy 397.312642 -56.588914)
			(xy 397.303627 -56.589288) (xy 397.28671 -56.595524) (xy 397.279622 -56.601106) (xy 397.279622 -56.60136)
			(xy 397.279368 -56.60136) (xy 397.258435 -56.619001) (xy 397.212467 -56.648725) (xy 397.162721 -56.671571)
			(xy 397.110219 -56.687067) (xy 397.056041 -56.694896) (xy 397.001299 -56.694896) (xy 396.947121 -56.687067)
			(xy 396.894619 -56.671571) (xy 396.844873 -56.648725) (xy 396.798905 -56.619001) (xy 396.777972 -56.60136)
			(xy 396.777718 -56.601106) (xy 396.77063 -56.595521) (xy 396.753714 -56.589273) (xy 396.744698 -56.588914)
			(xy 396.677642 -56.588914) (xy 396.668627 -56.589288) (xy 396.65171 -56.595524) (xy 396.644622 -56.601106)
			(xy 396.644114 -56.60136) (xy 396.631383 -56.612308) (xy 396.604289 -56.632147) (xy 396.590012 -56.640984)
			(xy 396.581122 -56.646318) (xy 396.56893 -56.663336) (xy 396.54861 -56.756554) (xy 396.552928 -56.777128)
			(xy 396.55877 -56.785764) (xy 396.574753 -56.809838) (xy 396.600101 -56.861766) (xy 396.617331 -56.916921)
			(xy 396.626051 -56.974042) (xy 396.626588 -57.002934) (xy 396.626102 -57.030185) (xy 396.618346 -57.084133)
			(xy 396.602991 -57.136428) (xy 396.580349 -57.186005) (xy 396.550883 -57.231855) (xy 396.515192 -57.273046)
			(xy 396.474001 -57.308737) (xy 396.428151 -57.338203) (xy 396.378574 -57.360845) (xy 396.326279 -57.3762)
			(xy 396.272331 -57.383956) (xy 396.217829 -57.383956) (xy 396.163881 -57.3762) (xy 396.111586 -57.360845)
			(xy 396.062009 -57.338203) (xy 396.016159 -57.308737) (xy 395.974968 -57.273046) (xy 395.939277 -57.231855)
			(xy 395.909811 -57.186005) (xy 395.887169 -57.136428) (xy 395.871814 -57.084133) (xy 395.864058 -57.030185)
			(xy 395.863572 -57.002934) (xy 394.194446 -57.002934) (xy 394.201174 -57.04948) (xy 394.20165 -57.076848)
			(xy 394.201164 -57.104099) (xy 394.193408 -57.158047) (xy 394.178053 -57.210342) (xy 394.155411 -57.259919)
			(xy 394.125945 -57.305769) (xy 394.090254 -57.34696) (xy 394.049063 -57.382651) (xy 394.003213 -57.412117)
			(xy 393.953636 -57.434759) (xy 393.901341 -57.450114) (xy 393.847393 -57.45787) (xy 393.792891 -57.45787)
			(xy 393.738943 -57.450114) (xy 393.686648 -57.434759) (xy 393.637071 -57.412117) (xy 393.591221 -57.382651)
			(xy 393.55003 -57.34696) (xy 393.514339 -57.305769) (xy 393.484873 -57.259919) (xy 393.462231 -57.210342)
			(xy 393.446876 -57.158047) (xy 393.43912 -57.104099) (xy 393.438634 -57.076848) (xy 392.788843 -57.076848)
			(xy 392.8129 -57.095307) (xy 392.855284 -57.137689) (xy 392.891772 -57.185241) (xy 392.921741 -57.237148)
			(xy 392.944677 -57.292524) (xy 392.96019 -57.35042) (xy 392.968012 -57.409845) (xy 392.96848 -57.439814)
			(xy 392.968039 -57.468047) (xy 392.965904 -57.48528) (xy 404.90597 -57.48528) (xy 404.910041 -57.429658)
			(xy 404.922167 -57.375221) (xy 404.94209 -57.32313) (xy 404.969386 -57.274495) (xy 405.003472 -57.230352)
			(xy 405.043621 -57.191643) (xy 405.088979 -57.159192) (xy 405.138579 -57.133691) (xy 405.191363 -57.115684)
			(xy 405.246206 -57.105554) (xy 405.30194 -57.103517) (xy 405.357377 -57.109617) (xy 405.411334 -57.123723)
			(xy 405.462663 -57.145535) (xy 405.510269 -57.174589) (xy 405.553137 -57.210264) (xy 405.590354 -57.251801)
			(xy 405.621127 -57.298314) (xy 405.644799 -57.348811) (xy 405.660867 -57.402218) (xy 405.668987 -57.457394)
			(xy 405.669496 -57.48528) (xy 405.668987 -57.513166) (xy 405.660867 -57.568342) (xy 405.644799 -57.621749)
			(xy 405.621127 -57.672246) (xy 405.590354 -57.718759) (xy 405.553137 -57.760296) (xy 405.510269 -57.795971)
			(xy 405.462663 -57.825025) (xy 405.411334 -57.846837) (xy 405.357377 -57.860943) (xy 405.30194 -57.867043)
			(xy 405.246206 -57.865006) (xy 405.191363 -57.854876) (xy 405.138579 -57.836869) (xy 405.088979 -57.811368)
			(xy 405.043621 -57.778917) (xy 405.003472 -57.740208) (xy 404.969386 -57.696065) (xy 404.94209 -57.64743)
			(xy 404.922167 -57.595339) (xy 404.910041 -57.540902) (xy 404.90597 -57.48528) (xy 392.965904 -57.48528)
			(xy 392.961098 -57.524084) (xy 392.947312 -57.57884) (xy 392.92689 -57.631483) (xy 392.900143 -57.681211)
			(xy 392.884152 -57.704482) (xy 392.876786 -57.71515) (xy 392.873738 -57.740804) (xy 392.916156 -57.844436)
			(xy 392.936222 -57.860692) (xy 392.949176 -57.862978) (xy 392.975291 -57.868092) (xy 393.025862 -57.884656)
			(xy 393.073642 -57.908083) (xy 393.117705 -57.93792) (xy 393.157196 -57.973588) (xy 393.191351 -58.014396)
			(xy 393.219506 -58.059551) (xy 393.241117 -58.10818) (xy 393.255764 -58.159339) (xy 393.263163 -58.212037)
			(xy 393.263628 -58.238644) (xy 393.263147 -58.266014) (xy 393.255335 -58.320193) (xy 393.239851 -58.372697)
			(xy 393.217012 -58.422444) (xy 393.187289 -58.468411) (xy 393.169648 -58.489342) (xy 393.169394 -58.489596)
			(xy 393.163802 -58.496679) (xy 393.157559 -58.513599) (xy 393.157202 -58.522616) (xy 393.157202 -58.589672)
			(xy 393.157572 -58.598688) (xy 393.16381 -58.615605) (xy 393.169394 -58.622692) (xy 393.169648 -58.622692)
			(xy 393.169648 -58.622946) (xy 393.187267 -58.643894) (xy 393.210178 -58.679334) (xy 396.295372 -58.679334)
			(xy 396.295804 -58.653019) (xy 396.303048 -58.600889) (xy 396.317374 -58.550246) (xy 396.338513 -58.502048)
			(xy 396.366065 -58.457205) (xy 396.399508 -58.416566) (xy 396.418562 -58.39841) (xy 396.425955 -58.390881)
			(xy 396.434486 -58.371607) (xy 396.435072 -58.361072) (xy 396.435072 -58.286396) (xy 396.434567 -58.275843)
			(xy 396.426016 -58.256548) (xy 396.418562 -58.249058) (xy 396.399486 -58.230923) (xy 396.366032 -58.190288)
			(xy 396.338477 -58.145443) (xy 396.317342 -58.097239) (xy 396.303029 -58.046588) (xy 396.295808 -57.994451)
			(xy 396.295372 -57.968134) (xy 396.295858 -57.940883) (xy 396.303614 -57.886935) (xy 396.318969 -57.83464)
			(xy 396.341611 -57.785063) (xy 396.371077 -57.739213) (xy 396.406768 -57.698022) (xy 396.447959 -57.662331)
			(xy 396.493809 -57.632865) (xy 396.543386 -57.610223) (xy 396.595681 -57.594868) (xy 396.649629 -57.587112)
			(xy 396.704131 -57.587112) (xy 396.758079 -57.594868) (xy 396.810374 -57.610223) (xy 396.859951 -57.632865)
			(xy 396.905801 -57.662331) (xy 396.946992 -57.698022) (xy 396.982683 -57.739213) (xy 397.012149 -57.785063)
			(xy 397.034791 -57.83464) (xy 397.050146 -57.886935) (xy 397.057902 -57.940883) (xy 397.058388 -57.968134)
			(xy 397.057947 -57.994449) (xy 397.050707 -58.046579) (xy 397.036383 -58.097222) (xy 397.034182 -58.102242)
			(xy 400.218384 -58.102242) (xy 400.218384 -58.042306) (xy 400.226207 -57.982884) (xy 400.24172 -57.924991)
			(xy 400.264656 -57.869618) (xy 400.294623 -57.817712) (xy 400.33111 -57.770162) (xy 400.37349 -57.727782)
			(xy 400.42104 -57.691295) (xy 400.472946 -57.661328) (xy 400.528319 -57.638392) (xy 400.586212 -57.622879)
			(xy 400.645634 -57.615056) (xy 400.70557 -57.615056) (xy 400.764992 -57.622879) (xy 400.822885 -57.638392)
			(xy 400.878258 -57.661328) (xy 400.930164 -57.691295) (xy 400.977714 -57.727782) (xy 401.020094 -57.770162)
			(xy 401.056581 -57.817712) (xy 401.086548 -57.869618) (xy 401.109484 -57.924991) (xy 401.124997 -57.982884)
			(xy 401.13282 -58.042306) (xy 401.13331 -58.072274) (xy 401.13282 -58.102242) (xy 401.132318 -58.106052)
			(xy 405.582864 -58.106052) (xy 405.582864 -58.046116) (xy 405.590687 -57.986694) (xy 405.6062 -57.928801)
			(xy 405.629136 -57.873428) (xy 405.659103 -57.821522) (xy 405.69559 -57.773972) (xy 405.73797 -57.731592)
			(xy 405.78552 -57.695105) (xy 405.837426 -57.665138) (xy 405.892799 -57.642202) (xy 405.950692 -57.626689)
			(xy 406.010114 -57.618866) (xy 406.07005 -57.618866) (xy 406.129472 -57.626689) (xy 406.187365 -57.642202)
			(xy 406.242738 -57.665138) (xy 406.294644 -57.695105) (xy 406.342194 -57.731592) (xy 406.384574 -57.773972)
			(xy 406.421061 -57.821522) (xy 406.451028 -57.873428) (xy 406.460901 -57.897264) (xy 407.867848 -57.897264)
			(xy 407.867848 -57.837328) (xy 407.875671 -57.777906) (xy 407.891184 -57.720013) (xy 407.91412 -57.66464)
			(xy 407.944087 -57.612734) (xy 407.980574 -57.565184) (xy 408.022954 -57.522804) (xy 408.070504 -57.486317)
			(xy 408.12241 -57.45635) (xy 408.177783 -57.433414) (xy 408.235676 -57.417901) (xy 408.295098 -57.410078)
			(xy 408.355034 -57.410078) (xy 408.414456 -57.417901) (xy 408.472349 -57.433414) (xy 408.527722 -57.45635)
			(xy 408.579628 -57.486317) (xy 408.627178 -57.522804) (xy 408.669558 -57.565184) (xy 408.706045 -57.612734)
			(xy 408.736012 -57.66464) (xy 408.758948 -57.720013) (xy 408.774461 -57.777906) (xy 408.782284 -57.837328)
			(xy 408.782774 -57.867296) (xy 408.782284 -57.897264) (xy 408.774461 -57.956686) (xy 408.758948 -58.014579)
			(xy 408.736012 -58.069952) (xy 408.706045 -58.121858) (xy 408.669558 -58.169408) (xy 408.627178 -58.211788)
			(xy 408.579628 -58.248275) (xy 408.527722 -58.278242) (xy 408.472349 -58.301178) (xy 408.414456 -58.316691)
			(xy 408.355034 -58.324514) (xy 408.295098 -58.324514) (xy 408.235676 -58.316691) (xy 408.177783 -58.301178)
			(xy 408.12241 -58.278242) (xy 408.070504 -58.248275) (xy 408.022954 -58.211788) (xy 407.980574 -58.169408)
			(xy 407.944087 -58.121858) (xy 407.91412 -58.069952) (xy 407.891184 -58.014579) (xy 407.875671 -57.956686)
			(xy 407.867848 -57.897264) (xy 406.460901 -57.897264) (xy 406.473964 -57.928801) (xy 406.489477 -57.986694)
			(xy 406.4973 -58.046116) (xy 406.49779 -58.076084) (xy 406.4973 -58.106052) (xy 406.489477 -58.165474)
			(xy 406.473964 -58.223367) (xy 406.451028 -58.27874) (xy 406.421061 -58.330646) (xy 406.384574 -58.378196)
			(xy 406.342194 -58.420576) (xy 406.294644 -58.457063) (xy 406.242738 -58.48703) (xy 406.187365 -58.509966)
			(xy 406.129472 -58.525479) (xy 406.07005 -58.533302) (xy 406.010114 -58.533302) (xy 405.950692 -58.525479)
			(xy 405.892799 -58.509966) (xy 405.837426 -58.48703) (xy 405.78552 -58.457063) (xy 405.73797 -58.420576)
			(xy 405.69559 -58.378196) (xy 405.659103 -58.330646) (xy 405.629136 -58.27874) (xy 405.6062 -58.223367)
			(xy 405.590687 -58.165474) (xy 405.582864 -58.106052) (xy 401.132318 -58.106052) (xy 401.124997 -58.161664)
			(xy 401.109484 -58.219557) (xy 401.086548 -58.27493) (xy 401.056581 -58.326836) (xy 401.020094 -58.374386)
			(xy 400.977714 -58.416766) (xy 400.930164 -58.453253) (xy 400.878258 -58.48322) (xy 400.822885 -58.506156)
			(xy 400.764992 -58.521669) (xy 400.70557 -58.529492) (xy 400.645634 -58.529492) (xy 400.586212 -58.521669)
			(xy 400.528319 -58.506156) (xy 400.472946 -58.48322) (xy 400.42104 -58.453253) (xy 400.37349 -58.416766)
			(xy 400.33111 -58.374386) (xy 400.294623 -58.326836) (xy 400.264656 -58.27493) (xy 400.24172 -58.219557)
			(xy 400.226207 -58.161664) (xy 400.218384 -58.102242) (xy 397.034182 -58.102242) (xy 397.015246 -58.145421)
			(xy 396.987695 -58.190264) (xy 396.954252 -58.230902) (xy 396.935198 -58.249058) (xy 396.927813 -58.256593)
			(xy 396.919279 -58.275863) (xy 396.918688 -58.286396) (xy 396.918688 -58.361072) (xy 396.919222 -58.371621)
			(xy 396.927754 -58.390916) (xy 396.935198 -58.39841) (xy 396.954251 -58.416568) (xy 396.987708 -58.457197)
			(xy 397.015268 -58.502037) (xy 397.036407 -58.550237) (xy 397.047984 -58.591192) (xy 406.787078 -58.591192)
			(xy 406.787078 -58.531256) (xy 406.794901 -58.471834) (xy 406.810414 -58.413941) (xy 406.83335 -58.358568)
			(xy 406.863317 -58.306662) (xy 406.899804 -58.259112) (xy 406.942184 -58.216732) (xy 406.989734 -58.180245)
			(xy 407.04164 -58.150278) (xy 407.097013 -58.127342) (xy 407.154906 -58.111829) (xy 407.214328 -58.104006)
			(xy 407.274264 -58.104006) (xy 407.333686 -58.111829) (xy 407.391579 -58.127342) (xy 407.446952 -58.150278)
			(xy 407.498858 -58.180245) (xy 407.546408 -58.216732) (xy 407.588788 -58.259112) (xy 407.625275 -58.306662)
			(xy 407.655242 -58.358568) (xy 407.678178 -58.413941) (xy 407.693691 -58.471834) (xy 407.694725 -58.479686)
			(xy 409.033708 -58.479686) (xy 409.033708 -58.41975) (xy 409.041531 -58.360328) (xy 409.057044 -58.302435)
			(xy 409.07998 -58.247062) (xy 409.109947 -58.195156) (xy 409.146434 -58.147606) (xy 409.188814 -58.105226)
			(xy 409.236364 -58.068739) (xy 409.28827 -58.038772) (xy 409.343643 -58.015836) (xy 409.401536 -58.000323)
			(xy 409.460958 -57.9925) (xy 409.520894 -57.9925) (xy 409.580316 -58.000323) (xy 409.638209 -58.015836)
			(xy 409.693582 -58.038772) (xy 409.745488 -58.068739) (xy 409.793038 -58.105226) (xy 409.835418 -58.147606)
			(xy 409.871905 -58.195156) (xy 409.901872 -58.247062) (xy 409.924808 -58.302435) (xy 409.940321 -58.360328)
			(xy 409.948144 -58.41975) (xy 409.948634 -58.449718) (xy 409.948144 -58.479686) (xy 409.940321 -58.539108)
			(xy 409.924808 -58.597001) (xy 409.901872 -58.652374) (xy 409.871905 -58.70428) (xy 409.851092 -58.731404)
			(xy 413.82061 -58.731404) (xy 413.821076 -58.704034) (xy 413.828893 -58.649855) (xy 413.844382 -58.597351)
			(xy 413.867224 -58.547604) (xy 413.896949 -58.501638) (xy 413.91459 -58.480706) (xy 413.914844 -58.480452)
			(xy 413.92042 -58.473359) (xy 413.926672 -58.456447) (xy 413.927036 -58.447432) (xy 413.927036 -58.380376)
			(xy 413.926683 -58.371359) (xy 413.920432 -58.354442) (xy 413.914844 -58.347356) (xy 413.91459 -58.347356)
			(xy 413.91459 -58.347102) (xy 413.896955 -58.326165) (xy 413.867233 -58.280197) (xy 413.844389 -58.230451)
			(xy 413.828894 -58.17795) (xy 413.821066 -58.123773) (xy 413.821066 -58.069033) (xy 413.828893 -58.014856)
			(xy 413.844387 -57.962354) (xy 413.86723 -57.912608) (xy 413.896951 -57.866639) (xy 413.91459 -57.845706)
			(xy 413.914844 -57.845452) (xy 413.92042 -57.838359) (xy 413.926672 -57.821447) (xy 413.927036 -57.812432)
			(xy 413.927036 -57.745376) (xy 413.926683 -57.736359) (xy 413.920432 -57.719442) (xy 413.914844 -57.712356)
			(xy 413.91459 -57.712356) (xy 413.91459 -57.712102) (xy 413.896955 -57.691165) (xy 413.867233 -57.645197)
			(xy 413.844389 -57.595451) (xy 413.828894 -57.54295) (xy 413.821066 -57.488773) (xy 413.821066 -57.434033)
			(xy 413.828893 -57.379856) (xy 413.844387 -57.327354) (xy 413.86723 -57.277608) (xy 413.896951 -57.231639)
			(xy 413.91459 -57.210706) (xy 413.914844 -57.210452) (xy 413.92042 -57.203359) (xy 413.926672 -57.186447)
			(xy 413.927036 -57.177432) (xy 413.927036 -57.110376) (xy 413.926683 -57.101359) (xy 413.920432 -57.084442)
			(xy 413.914844 -57.077356) (xy 413.91459 -57.077356) (xy 413.91459 -57.077102) (xy 413.896937 -57.056181)
			(xy 413.867227 -57.010205) (xy 413.844394 -56.960455) (xy 413.828907 -56.907952) (xy 413.821082 -56.853774)
			(xy 413.82061 -56.826404) (xy 413.821096 -56.799153) (xy 413.828852 -56.745205) (xy 413.844207 -56.69291)
			(xy 413.866849 -56.643333) (xy 413.896315 -56.597483) (xy 413.932006 -56.556292) (xy 413.973197 -56.520601)
			(xy 414.019047 -56.491135) (xy 414.068624 -56.468493) (xy 414.120919 -56.453138) (xy 414.174867 -56.445382)
			(xy 414.229369 -56.445382) (xy 414.283317 -56.453138) (xy 414.335612 -56.468493) (xy 414.385189 -56.491135)
			(xy 414.431039 -56.520601) (xy 414.47223 -56.556292) (xy 414.507921 -56.597483) (xy 414.537387 -56.643333)
			(xy 414.560029 -56.69291) (xy 414.575384 -56.745205) (xy 414.58314 -56.799153) (xy 414.583336 -56.810148)
			(xy 416.400234 -56.810148) (xy 416.400234 -56.809894) (xy 416.400724 -56.779926) (xy 416.408547 -56.720504)
			(xy 416.42406 -56.662611) (xy 416.446996 -56.607238) (xy 416.476963 -56.555332) (xy 416.51345 -56.507782)
			(xy 416.55583 -56.465402) (xy 416.60338 -56.428915) (xy 416.655286 -56.398948) (xy 416.710659 -56.376012)
			(xy 416.768552 -56.360499) (xy 416.827974 -56.352676) (xy 416.88791 -56.352676) (xy 416.947332 -56.360499)
			(xy 417.005225 -56.376012) (xy 417.060598 -56.398948) (xy 417.112504 -56.428915) (xy 417.160054 -56.465402)
			(xy 417.202434 -56.507782) (xy 417.238921 -56.555332) (xy 417.268888 -56.607238) (xy 417.291824 -56.662611)
			(xy 417.307337 -56.720504) (xy 417.31516 -56.779926) (xy 417.31565 -56.809894) (xy 417.31565 -56.810148)
			(xy 417.315093 -56.841672) (xy 417.306423 -56.904121) (xy 417.289268 -56.964791) (xy 417.263952 -57.022533)
			(xy 417.230954 -57.076256) (xy 417.190898 -57.124945) (xy 417.168076 -57.146698) (xy 417.160964 -57.153302)
			(xy 417.152582 -57.17032) (xy 417.146232 -57.248806) (xy 417.145859 -57.258372) (xy 417.15148 -57.276655)
			(xy 417.157154 -57.284366) (xy 417.172695 -57.304647) (xy 417.198752 -57.348598) (xy 417.218715 -57.395632)
			(xy 417.232225 -57.444908) (xy 417.235206 -57.467053) (xy 417.418469 -57.467053) (xy 417.418469 -57.412547)
			(xy 417.426227 -57.358597) (xy 417.441583 -57.306299) (xy 417.464226 -57.256719) (xy 417.493695 -57.210867)
			(xy 417.529389 -57.169675) (xy 417.570583 -57.133983) (xy 417.616437 -57.104517) (xy 417.666018 -57.081876)
			(xy 417.718316 -57.066522) (xy 417.772267 -57.058768) (xy 417.79952 -57.058306) (xy 417.825069 -57.058689)
			(xy 417.875709 -57.065502) (xy 417.924987 -57.079017) (xy 417.972018 -57.098992) (xy 418.01596 -57.125068)
			(xy 418.036248 -57.140602) (xy 418.043989 -57.146215) (xy 418.062252 -57.15183) (xy 418.071808 -57.151524)
			(xy 418.150294 -57.145174) (xy 418.167312 -57.136792) (xy 418.173916 -57.12968) (xy 418.19566 -57.106845)
			(xy 418.244337 -57.066766) (xy 418.298058 -57.033752) (xy 418.355804 -57.008431) (xy 418.416481 -56.991282)
			(xy 418.478939 -56.982629) (xy 418.510466 -56.982106) (xy 418.51072 -56.982106) (xy 418.540689 -56.982563)
			(xy 418.600113 -56.990389) (xy 418.658007 -57.005905) (xy 418.713381 -57.028844) (xy 418.765288 -57.058815)
			(xy 418.788787 -57.076848) (xy 419.438582 -57.076848) (xy 419.439056 -57.049478) (xy 419.446869 -56.995298)
			(xy 419.462355 -56.942795) (xy 419.485196 -56.893047) (xy 419.51492 -56.847081) (xy 419.532562 -56.82615)
			(xy 419.532816 -56.825896) (xy 419.538412 -56.818816) (xy 419.544653 -56.801894) (xy 419.545008 -56.792876)
			(xy 419.545008 -56.72582) (xy 419.54464 -56.716804) (xy 419.5384 -56.699887) (xy 419.532816 -56.6928)
			(xy 419.532562 -56.6928) (xy 419.532562 -56.692546) (xy 419.514925 -56.671613) (xy 419.485214 -56.62564)
			(xy 419.462378 -56.575892) (xy 419.446886 -56.523392) (xy 419.439057 -56.469217) (xy 419.438582 -56.441848)
			(xy 419.439068 -56.414597) (xy 419.446824 -56.360649) (xy 419.462179 -56.308354) (xy 419.484821 -56.258777)
			(xy 419.514287 -56.212927) (xy 419.549978 -56.171736) (xy 419.591169 -56.136045) (xy 419.637019 -56.106579)
			(xy 419.686596 -56.083937) (xy 419.738891 -56.068582) (xy 419.792839 -56.060826) (xy 419.847341 -56.060826)
			(xy 419.901289 -56.068582) (xy 419.953584 -56.083937) (xy 420.003161 -56.106579) (xy 420.049011 -56.136045)
			(xy 420.090202 -56.171736) (xy 420.125893 -56.212927) (xy 420.155359 -56.258777) (xy 420.178001 -56.308354)
			(xy 420.193356 -56.360649) (xy 420.201112 -56.414597) (xy 420.201598 -56.441848) (xy 420.201102 -56.469217)
			(xy 420.193291 -56.523395) (xy 420.177809 -56.575898) (xy 420.154974 -56.625645) (xy 420.125256 -56.671613)
			(xy 420.107618 -56.692546) (xy 420.107364 -56.6928) (xy 420.101767 -56.699879) (xy 420.095528 -56.716802)
			(xy 420.095172 -56.72582) (xy 420.095172 -56.792876) (xy 420.095547 -56.801891) (xy 420.101783 -56.818808)
			(xy 420.107364 -56.825896) (xy 420.107618 -56.825896) (xy 420.107618 -56.82615) (xy 420.12525 -56.847088)
			(xy 420.154962 -56.893059) (xy 420.177799 -56.942805) (xy 420.193292 -56.995305) (xy 420.194395 -57.002934)
			(xy 421.86352 -57.002934) (xy 421.864023 -56.974843) (xy 421.872247 -56.919265) (xy 421.888535 -56.865495)
			(xy 421.912536 -56.814697) (xy 421.94373 -56.76797) (xy 421.981442 -56.726325) (xy 422.024855 -56.690664)
			(xy 422.048686 -56.675782) (xy 422.057576 -56.670448) (xy 422.069768 -56.65343) (xy 422.090088 -56.560212)
			(xy 422.08577 -56.539638) (xy 422.079928 -56.531002) (xy 422.06393 -56.506937) (xy 422.038586 -56.455006)
			(xy 422.02136 -56.399849) (xy 422.012644 -56.342724) (xy 422.01211 -56.313832) (xy 422.012585 -56.286579)
			(xy 422.020338 -56.232628) (xy 422.035691 -56.180329) (xy 422.058331 -56.130748) (xy 422.087798 -56.084894)
			(xy 422.12349 -56.0437) (xy 422.164682 -56.008006) (xy 422.210535 -55.978538) (xy 422.260116 -55.955896)
			(xy 422.312414 -55.940541) (xy 422.366365 -55.932786) (xy 422.393618 -55.932324) (xy 422.420989 -55.932774)
			(xy 422.475169 -55.940595) (xy 422.527672 -55.956087) (xy 422.577419 -55.978933) (xy 422.623385 -56.008661)
			(xy 422.644316 -56.026304) (xy 422.64457 -56.026558) (xy 422.651656 -56.032145) (xy 422.668573 -56.03839)
			(xy 422.67759 -56.03875) (xy 422.744646 -56.03875) (xy 422.753662 -56.038378) (xy 422.770579 -56.032142)
			(xy 422.777666 -56.026558) (xy 422.777666 -56.026304) (xy 422.77792 -56.026304) (xy 422.798853 -56.008663)
			(xy 422.844821 -55.978939) (xy 422.894567 -55.956093) (xy 422.947069 -55.940597) (xy 423.001247 -55.932768)
			(xy 423.055989 -55.932768) (xy 423.110167 -55.940597) (xy 423.162669 -55.956093) (xy 423.212415 -55.978939)
			(xy 423.258383 -56.008663) (xy 423.279316 -56.026304) (xy 423.27957 -56.026558) (xy 423.286656 -56.032145)
			(xy 423.303573 -56.03839) (xy 423.31259 -56.03875) (xy 423.379646 -56.03875) (xy 423.388662 -56.038378)
			(xy 423.405579 -56.032142) (xy 423.412666 -56.026558) (xy 423.412666 -56.026304) (xy 423.41292 -56.026304)
			(xy 423.433872 -56.00869) (xy 423.479839 -55.978974) (xy 423.529582 -55.956133) (xy 423.582078 -55.940636)
			(xy 423.63625 -55.932802) (xy 423.663618 -55.932324) (xy 423.690871 -55.932747) (xy 423.744821 -55.940506)
			(xy 423.797118 -55.955864) (xy 423.846697 -55.978508) (xy 423.892549 -56.007978) (xy 423.933741 -56.043672)
			(xy 423.969433 -56.084865) (xy 423.9989 -56.130719) (xy 424.021542 -56.180299) (xy 424.036897 -56.232597)
			(xy 424.044654 -56.286547) (xy 424.044654 -56.297068) (xy 424.3865 -56.297068) (xy 424.390571 -56.241446)
			(xy 424.402697 -56.187009) (xy 424.42262 -56.134918) (xy 424.449916 -56.086283) (xy 424.484002 -56.04214)
			(xy 424.524151 -56.003431) (xy 424.569509 -55.97098) (xy 424.619109 -55.945479) (xy 424.671893 -55.927472)
			(xy 424.726736 -55.917342) (xy 424.78247 -55.915305) (xy 424.837907 -55.921405) (xy 424.891864 -55.935511)
			(xy 424.943193 -55.957323) (xy 424.990799 -55.986377) (xy 425.033667 -56.022052) (xy 425.070884 -56.063589)
			(xy 425.101657 -56.110102) (xy 425.125329 -56.160599) (xy 425.141397 -56.214006) (xy 425.149517 -56.269182)
			(xy 425.150026 -56.297068) (xy 425.149517 -56.324954) (xy 425.145322 -56.353456) (xy 427.241206 -56.353456)
			(xy 427.245277 -56.297834) (xy 427.257403 -56.243397) (xy 427.277326 -56.191306) (xy 427.304622 -56.142671)
			(xy 427.338708 -56.098528) (xy 427.378857 -56.059819) (xy 427.424215 -56.027368) (xy 427.473815 -56.001867)
			(xy 427.526599 -55.98386) (xy 427.581442 -55.97373) (xy 427.637176 -55.971693) (xy 427.692613 -55.977793)
			(xy 427.74657 -55.991899) (xy 427.797899 -56.013711) (xy 427.845505 -56.042765) (xy 427.888373 -56.07844)
			(xy 427.92559 -56.119977) (xy 427.956363 -56.16649) (xy 427.980035 -56.216987) (xy 427.996103 -56.270394)
			(xy 428.004223 -56.32557) (xy 428.004732 -56.353456) (xy 428.004223 -56.381342) (xy 427.996103 -56.436518)
			(xy 427.980035 -56.489925) (xy 427.956363 -56.540422) (xy 427.92559 -56.586935) (xy 427.888373 -56.628472)
			(xy 427.845505 -56.664147) (xy 427.797899 -56.693201) (xy 427.74657 -56.715013) (xy 427.692613 -56.729119)
			(xy 427.637176 -56.735219) (xy 427.581442 -56.733182) (xy 427.526599 -56.723052) (xy 427.473815 -56.705045)
			(xy 427.424215 -56.679544) (xy 427.378857 -56.647093) (xy 427.338708 -56.608384) (xy 427.304622 -56.564241)
			(xy 427.277326 -56.515606) (xy 427.257403 -56.463515) (xy 427.245277 -56.409078) (xy 427.241206 -56.353456)
			(xy 425.145322 -56.353456) (xy 425.141397 -56.38013) (xy 425.125329 -56.433537) (xy 425.101657 -56.484034)
			(xy 425.070884 -56.530547) (xy 425.033667 -56.572084) (xy 424.990799 -56.607759) (xy 424.943193 -56.636813)
			(xy 424.891864 -56.658625) (xy 424.837907 -56.672731) (xy 424.78247 -56.678831) (xy 424.726736 -56.676794)
			(xy 424.671893 -56.666664) (xy 424.619109 -56.648657) (xy 424.569509 -56.623156) (xy 424.524151 -56.590705)
			(xy 424.484002 -56.551996) (xy 424.449916 -56.507853) (xy 424.42262 -56.459218) (xy 424.402697 -56.407127)
			(xy 424.390571 -56.35269) (xy 424.3865 -56.297068) (xy 424.044654 -56.297068) (xy 424.044654 -56.341053)
			(xy 424.036897 -56.395003) (xy 424.021542 -56.447301) (xy 423.9989 -56.496881) (xy 423.969433 -56.542735)
			(xy 423.933741 -56.583928) (xy 423.892549 -56.619622) (xy 423.846697 -56.649092) (xy 423.797118 -56.671736)
			(xy 423.744821 -56.687094) (xy 423.690871 -56.694853) (xy 423.663618 -56.69534) (xy 423.636247 -56.694878)
			(xy 423.582068 -56.687061) (xy 423.529564 -56.671572) (xy 423.479817 -56.648729) (xy 423.433851 -56.619003)
			(xy 423.41292 -56.60136) (xy 423.412666 -56.601106) (xy 423.405564 -56.595542) (xy 423.388659 -56.589281)
			(xy 423.379646 -56.588914) (xy 423.31259 -56.588914) (xy 423.303572 -56.589263) (xy 423.286655 -56.595516)
			(xy 423.27957 -56.601106) (xy 423.27957 -56.60136) (xy 423.279316 -56.60136) (xy 423.258383 -56.619001)
			(xy 423.212415 -56.648725) (xy 423.162669 -56.671571) (xy 423.110167 -56.687067) (xy 423.055989 -56.694896)
			(xy 423.001247 -56.694896) (xy 422.947069 -56.687067) (xy 422.894567 -56.671571) (xy 422.844821 -56.648725)
			(xy 422.798853 -56.619001) (xy 422.77792 -56.60136) (xy 422.777666 -56.601106) (xy 422.770564 -56.595542)
			(xy 422.753659 -56.589281) (xy 422.744646 -56.588914) (xy 422.67759 -56.588914) (xy 422.668572 -56.589263)
			(xy 422.651655 -56.595516) (xy 422.64457 -56.601106) (xy 422.644062 -56.60136) (xy 422.631328 -56.612304)
			(xy 422.604236 -56.632145) (xy 422.58996 -56.640984) (xy 422.58107 -56.646318) (xy 422.568878 -56.663336)
			(xy 422.548558 -56.756554) (xy 422.552876 -56.777128) (xy 422.558718 -56.785764) (xy 422.574707 -56.809835)
			(xy 422.600052 -56.861764) (xy 422.61728 -56.91692) (xy 422.625999 -56.974042) (xy 422.626536 -57.002934)
			(xy 422.62605 -57.030185) (xy 422.618294 -57.084133) (xy 422.602939 -57.136428) (xy 422.580297 -57.186005)
			(xy 422.550831 -57.231855) (xy 422.51514 -57.273046) (xy 422.473949 -57.308737) (xy 422.428099 -57.338203)
			(xy 422.378522 -57.360845) (xy 422.326227 -57.3762) (xy 422.272279 -57.383956) (xy 422.217777 -57.383956)
			(xy 422.163829 -57.3762) (xy 422.111534 -57.360845) (xy 422.061957 -57.338203) (xy 422.016107 -57.308737)
			(xy 421.974916 -57.273046) (xy 421.939225 -57.231855) (xy 421.909759 -57.186005) (xy 421.887117 -57.136428)
			(xy 421.871762 -57.084133) (xy 421.864006 -57.030185) (xy 421.86352 -57.002934) (xy 420.194395 -57.002934)
			(xy 420.201123 -57.049479) (xy 420.201598 -57.076848) (xy 420.201112 -57.104099) (xy 420.193356 -57.158047)
			(xy 420.178001 -57.210342) (xy 420.155359 -57.259919) (xy 420.125893 -57.305769) (xy 420.090202 -57.34696)
			(xy 420.049011 -57.382651) (xy 420.003161 -57.412117) (xy 419.953584 -57.434759) (xy 419.901289 -57.450114)
			(xy 419.847341 -57.45787) (xy 419.792839 -57.45787) (xy 419.738891 -57.450114) (xy 419.686596 -57.434759)
			(xy 419.637019 -57.412117) (xy 419.591169 -57.382651) (xy 419.549978 -57.34696) (xy 419.514287 -57.305769)
			(xy 419.484821 -57.259919) (xy 419.462179 -57.210342) (xy 419.446824 -57.158047) (xy 419.439068 -57.104099)
			(xy 419.438582 -57.076848) (xy 418.788787 -57.076848) (xy 418.812838 -57.095304) (xy 418.855218 -57.137688)
			(xy 418.891704 -57.185241) (xy 418.921671 -57.237149) (xy 418.944606 -57.292525) (xy 418.960117 -57.35042)
			(xy 418.967939 -57.409845) (xy 418.968428 -57.439814) (xy 418.967996 -57.468047) (xy 418.965861 -57.48528)
			(xy 430.905918 -57.48528) (xy 430.909989 -57.429658) (xy 430.922115 -57.375221) (xy 430.942038 -57.32313)
			(xy 430.969334 -57.274495) (xy 431.00342 -57.230352) (xy 431.043569 -57.191643) (xy 431.088927 -57.159192)
			(xy 431.138527 -57.133691) (xy 431.191311 -57.115684) (xy 431.246154 -57.105554) (xy 431.301888 -57.103517)
			(xy 431.357325 -57.109617) (xy 431.411282 -57.123723) (xy 431.462611 -57.145535) (xy 431.510217 -57.174589)
			(xy 431.553085 -57.210264) (xy 431.590302 -57.251801) (xy 431.621075 -57.298314) (xy 431.644747 -57.348811)
			(xy 431.660815 -57.402218) (xy 431.668935 -57.457394) (xy 431.669444 -57.48528) (xy 431.668935 -57.513166)
			(xy 431.660815 -57.568342) (xy 431.644747 -57.621749) (xy 431.621075 -57.672246) (xy 431.590302 -57.718759)
			(xy 431.553085 -57.760296) (xy 431.510217 -57.795971) (xy 431.462611 -57.825025) (xy 431.411282 -57.846837)
			(xy 431.357325 -57.860943) (xy 431.301888 -57.867043) (xy 431.246154 -57.865006) (xy 431.191311 -57.854876)
			(xy 431.138527 -57.836869) (xy 431.088927 -57.811368) (xy 431.043569 -57.778917) (xy 431.00342 -57.740208)
			(xy 430.969334 -57.696065) (xy 430.942038 -57.64743) (xy 430.922115 -57.595339) (xy 430.909989 -57.540902)
			(xy 430.905918 -57.48528) (xy 418.965861 -57.48528) (xy 418.961055 -57.524085) (xy 418.947267 -57.578841)
			(xy 418.926843 -57.631484) (xy 418.900092 -57.681211) (xy 418.8841 -57.704482) (xy 418.876734 -57.71515)
			(xy 418.873686 -57.740804) (xy 418.916104 -57.844436) (xy 418.93617 -57.860692) (xy 418.949124 -57.862978)
			(xy 418.975231 -57.86813) (xy 419.025802 -57.884688) (xy 419.073582 -57.908109) (xy 419.117646 -57.937941)
			(xy 419.157139 -57.973604) (xy 419.191295 -58.014407) (xy 419.219452 -58.05956) (xy 419.241064 -58.108186)
			(xy 419.255711 -58.159343) (xy 419.263111 -58.212038) (xy 419.263576 -58.238644) (xy 419.263083 -58.266013)
			(xy 419.255273 -58.320191) (xy 419.23979 -58.372695) (xy 419.216954 -58.422442) (xy 419.187235 -58.46841)
			(xy 419.169596 -58.489342) (xy 419.169342 -58.489596) (xy 419.163744 -58.496675) (xy 419.157506 -58.513598)
			(xy 419.15715 -58.522616) (xy 419.15715 -58.589672) (xy 419.15751 -58.598689) (xy 419.163754 -58.615606)
			(xy 419.169342 -58.622692) (xy 419.169596 -58.622692) (xy 419.169596 -58.622946) (xy 419.187223 -58.643888)
			(xy 419.210134 -58.679334) (xy 422.21912 -58.679334) (xy 422.21912 -58.67908) (xy 422.219639 -58.647555)
			(xy 422.228318 -58.585104) (xy 422.245481 -58.524435) (xy 422.270804 -58.466693) (xy 422.303808 -58.41297)
			(xy 422.34387 -58.364283) (xy 422.366694 -58.34253) (xy 422.373806 -58.335926) (xy 422.382188 -58.318908)
			(xy 422.388538 -58.240422) (xy 422.388882 -58.230858) (xy 422.383279 -58.212576) (xy 422.377616 -58.204862)
			(xy 422.362084 -58.184575) (xy 422.336026 -58.140625) (xy 422.316062 -58.093593) (xy 422.30255 -58.044318)
			(xy 422.295731 -57.993681) (xy 422.29532 -57.968134) (xy 422.295806 -57.940883) (xy 422.303562 -57.886935)
			(xy 422.318917 -57.83464) (xy 422.341559 -57.785063) (xy 422.371025 -57.739213) (xy 422.406716 -57.698022)
			(xy 422.447907 -57.662331) (xy 422.493757 -57.632865) (xy 422.543334 -57.610223) (xy 422.595629 -57.594868)
			(xy 422.649577 -57.587112) (xy 422.704079 -57.587112) (xy 422.758027 -57.594868) (xy 422.810322 -57.610223)
			(xy 422.859899 -57.632865) (xy 422.905749 -57.662331) (xy 422.94694 -57.698022) (xy 422.982631 -57.739213)
			(xy 423.012097 -57.785063) (xy 423.034739 -57.83464) (xy 423.050094 -57.886935) (xy 423.05785 -57.940883)
			(xy 423.058336 -57.968134) (xy 423.057952 -57.993682) (xy 423.051138 -58.044323) (xy 423.037623 -58.0936)
			(xy 423.033953 -58.102242) (xy 426.218332 -58.102242) (xy 426.218332 -58.042306) (xy 426.226155 -57.982884)
			(xy 426.241668 -57.924991) (xy 426.264604 -57.869618) (xy 426.294571 -57.817712) (xy 426.331058 -57.770162)
			(xy 426.373438 -57.727782) (xy 426.420988 -57.691295) (xy 426.472894 -57.661328) (xy 426.528267 -57.638392)
			(xy 426.58616 -57.622879) (xy 426.645582 -57.615056) (xy 426.705518 -57.615056) (xy 426.76494 -57.622879)
			(xy 426.822833 -57.638392) (xy 426.878206 -57.661328) (xy 426.930112 -57.691295) (xy 426.977662 -57.727782)
			(xy 427.020042 -57.770162) (xy 427.056529 -57.817712) (xy 427.086496 -57.869618) (xy 427.109432 -57.924991)
			(xy 427.124945 -57.982884) (xy 427.132768 -58.042306) (xy 427.133258 -58.072274) (xy 427.132768 -58.102242)
			(xy 427.132266 -58.106052) (xy 431.582812 -58.106052) (xy 431.582812 -58.046116) (xy 431.590635 -57.986694)
			(xy 431.606148 -57.928801) (xy 431.629084 -57.873428) (xy 431.659051 -57.821522) (xy 431.695538 -57.773972)
			(xy 431.737918 -57.731592) (xy 431.785468 -57.695105) (xy 431.837374 -57.665138) (xy 431.892747 -57.642202)
			(xy 431.95064 -57.626689) (xy 432.010062 -57.618866) (xy 432.069998 -57.618866) (xy 432.12942 -57.626689)
			(xy 432.187313 -57.642202) (xy 432.242686 -57.665138) (xy 432.294592 -57.695105) (xy 432.342142 -57.731592)
			(xy 432.384522 -57.773972) (xy 432.421009 -57.821522) (xy 432.450976 -57.873428) (xy 432.473912 -57.928801)
			(xy 432.489425 -57.986694) (xy 432.497248 -58.046116) (xy 432.497738 -58.076084) (xy 432.497248 -58.106052)
			(xy 432.489425 -58.165474) (xy 432.473912 -58.223367) (xy 432.450976 -58.27874) (xy 432.421009 -58.330646)
			(xy 432.384522 -58.378196) (xy 432.342142 -58.420576) (xy 432.294592 -58.457063) (xy 432.242686 -58.48703)
			(xy 432.187313 -58.509966) (xy 432.12942 -58.525479) (xy 432.069998 -58.533302) (xy 432.010062 -58.533302)
			(xy 431.95064 -58.525479) (xy 431.892747 -58.509966) (xy 431.837374 -58.48703) (xy 431.785468 -58.457063)
			(xy 431.737918 -58.420576) (xy 431.695538 -58.378196) (xy 431.659051 -58.330646) (xy 431.629084 -58.27874)
			(xy 431.606148 -58.223367) (xy 431.590635 -58.165474) (xy 431.582812 -58.106052) (xy 427.132266 -58.106052)
			(xy 427.124945 -58.161664) (xy 427.109432 -58.219557) (xy 427.086496 -58.27493) (xy 427.056529 -58.326836)
			(xy 427.020042 -58.374386) (xy 426.977662 -58.416766) (xy 426.930112 -58.453253) (xy 426.878206 -58.48322)
			(xy 426.822833 -58.506156) (xy 426.76494 -58.521669) (xy 426.705518 -58.529492) (xy 426.645582 -58.529492)
			(xy 426.58616 -58.521669) (xy 426.528267 -58.506156) (xy 426.472894 -58.48322) (xy 426.420988 -58.453253)
			(xy 426.373438 -58.416766) (xy 426.331058 -58.374386) (xy 426.294571 -58.326836) (xy 426.264604 -58.27493)
			(xy 426.241668 -58.219557) (xy 426.226155 -58.161664) (xy 426.218332 -58.102242) (xy 423.033953 -58.102242)
			(xy 423.017648 -58.140631) (xy 422.991573 -58.184574) (xy 422.97604 -58.204862) (xy 422.970425 -58.212602)
			(xy 422.96481 -58.230865) (xy 422.965118 -58.240422) (xy 422.971468 -58.318908) (xy 422.97985 -58.335926)
			(xy 422.986962 -58.34253) (xy 423.009812 -58.364259) (xy 423.049888 -58.41294) (xy 423.082899 -58.466664)
			(xy 423.108217 -58.524414) (xy 423.125364 -58.585093) (xy 423.126209 -58.591192) (xy 432.787026 -58.591192)
			(xy 432.787026 -58.531256) (xy 432.794849 -58.471834) (xy 432.810362 -58.413941) (xy 432.833298 -58.358568)
			(xy 432.863265 -58.306662) (xy 432.899752 -58.259112) (xy 432.942132 -58.216732) (xy 432.989682 -58.180245)
			(xy 433.041588 -58.150278) (xy 433.096961 -58.127342) (xy 433.154854 -58.111829) (xy 433.214276 -58.104006)
			(xy 433.274212 -58.104006) (xy 433.333634 -58.111829) (xy 433.391527 -58.127342) (xy 433.402063 -58.131706)
			(xy 433.867796 -58.131706) (xy 433.867796 -58.07177) (xy 433.875619 -58.012348) (xy 433.891132 -57.954455)
			(xy 433.914068 -57.899082) (xy 433.944035 -57.847176) (xy 433.980522 -57.799626) (xy 434.022902 -57.757246)
			(xy 434.070452 -57.720759) (xy 434.122358 -57.690792) (xy 434.177731 -57.667856) (xy 434.235624 -57.652343)
			(xy 434.295046 -57.64452) (xy 434.354982 -57.64452) (xy 434.414404 -57.652343) (xy 434.472297 -57.667856)
			(xy 434.52767 -57.690792) (xy 434.579576 -57.720759) (xy 434.627126 -57.757246) (xy 434.669506 -57.799626)
			(xy 434.705993 -57.847176) (xy 434.73596 -57.899082) (xy 434.758896 -57.954455) (xy 434.774409 -58.012348)
			(xy 434.782232 -58.07177) (xy 434.782722 -58.101738) (xy 434.782232 -58.131706) (xy 434.774409 -58.191128)
			(xy 434.758896 -58.249021) (xy 434.73596 -58.304394) (xy 434.705993 -58.3563) (xy 434.669506 -58.40385)
			(xy 434.627126 -58.44623) (xy 434.583526 -58.479686) (xy 435.033656 -58.479686) (xy 435.033656 -58.41975)
			(xy 435.041479 -58.360328) (xy 435.056992 -58.302435) (xy 435.079928 -58.247062) (xy 435.109895 -58.195156)
			(xy 435.146382 -58.147606) (xy 435.188762 -58.105226) (xy 435.236312 -58.068739) (xy 435.288218 -58.038772)
			(xy 435.343591 -58.015836) (xy 435.401484 -58.000323) (xy 435.460906 -57.9925) (xy 435.520842 -57.9925)
			(xy 435.580264 -58.000323) (xy 435.638157 -58.015836) (xy 435.69353 -58.038772) (xy 435.745436 -58.068739)
			(xy 435.792986 -58.105226) (xy 435.835366 -58.147606) (xy 435.871853 -58.195156) (xy 435.90182 -58.247062)
			(xy 435.924756 -58.302435) (xy 435.940269 -58.360328) (xy 435.948092 -58.41975) (xy 435.948582 -58.449718)
			(xy 435.948092 -58.479686) (xy 435.940269 -58.539108) (xy 435.924756 -58.597001) (xy 435.90182 -58.652374)
			(xy 435.871853 -58.70428) (xy 435.85104 -58.731404) (xy 439.820558 -58.731404) (xy 439.821012 -58.704033)
			(xy 439.828831 -58.649853) (xy 439.844322 -58.597349) (xy 439.867167 -58.547603) (xy 439.896895 -58.501637)
			(xy 439.914538 -58.480706) (xy 439.914792 -58.480452) (xy 439.920362 -58.473354) (xy 439.926619 -58.456446)
			(xy 439.926984 -58.447432) (xy 439.926984 -58.380376) (xy 439.926642 -58.371358) (xy 439.920384 -58.354441)
			(xy 439.914792 -58.347356) (xy 439.914538 -58.347356) (xy 439.914538 -58.347102) (xy 439.896901 -58.326166)
			(xy 439.867175 -58.280199) (xy 439.844329 -58.230454) (xy 439.828832 -58.177952) (xy 439.821002 -58.123774)
			(xy 439.821002 -58.069032) (xy 439.82883 -58.014854) (xy 439.844327 -57.962352) (xy 439.867172 -57.912606)
			(xy 439.896897 -57.866639) (xy 439.914538 -57.845706) (xy 439.914792 -57.845452) (xy 439.920362 -57.838354)
			(xy 439.926619 -57.821446) (xy 439.926984 -57.812432) (xy 439.926984 -57.745376) (xy 439.926642 -57.736358)
			(xy 439.920384 -57.719441) (xy 439.914792 -57.712356) (xy 439.914538 -57.712356) (xy 439.914538 -57.712102)
			(xy 439.896901 -57.691166) (xy 439.867175 -57.645199) (xy 439.844329 -57.595454) (xy 439.828832 -57.542952)
			(xy 439.821002 -57.488774) (xy 439.821002 -57.434032) (xy 439.82883 -57.379854) (xy 439.844327 -57.327352)
			(xy 439.867172 -57.277606) (xy 439.896897 -57.231639) (xy 439.914538 -57.210706) (xy 439.914792 -57.210452)
			(xy 439.920362 -57.203354) (xy 439.926619 -57.186446) (xy 439.926984 -57.177432) (xy 439.926984 -57.110376)
			(xy 439.926642 -57.101358) (xy 439.920384 -57.084441) (xy 439.914792 -57.077356) (xy 439.914538 -57.077356)
			(xy 439.914538 -57.077102) (xy 439.896892 -57.056175) (xy 439.86718 -57.010201) (xy 439.844345 -56.960453)
			(xy 439.828855 -56.907951) (xy 439.82103 -56.853774) (xy 439.820558 -56.826404) (xy 439.821044 -56.799153)
			(xy 439.8288 -56.745205) (xy 439.844155 -56.69291) (xy 439.866797 -56.643333) (xy 439.896263 -56.597483)
			(xy 439.931954 -56.556292) (xy 439.973145 -56.520601) (xy 440.018995 -56.491135) (xy 440.068572 -56.468493)
			(xy 440.120867 -56.453138) (xy 440.174815 -56.445382) (xy 440.229317 -56.445382) (xy 440.283265 -56.453138)
			(xy 440.33556 -56.468493) (xy 440.385137 -56.491135) (xy 440.430987 -56.520601) (xy 440.472178 -56.556292)
			(xy 440.507869 -56.597483) (xy 440.537335 -56.643333) (xy 440.559977 -56.69291) (xy 440.575332 -56.745205)
			(xy 440.583088 -56.799153) (xy 440.583284 -56.810148) (xy 442.400182 -56.810148) (xy 442.400182 -56.809894)
			(xy 442.400672 -56.779926) (xy 442.408495 -56.720504) (xy 442.424008 -56.662611) (xy 442.446944 -56.607238)
			(xy 442.476911 -56.555332) (xy 442.513398 -56.507782) (xy 442.555778 -56.465402) (xy 442.603328 -56.428915)
			(xy 442.655234 -56.398948) (xy 442.710607 -56.376012) (xy 442.7685 -56.360499) (xy 442.827922 -56.352676)
			(xy 442.887858 -56.352676) (xy 442.94728 -56.360499) (xy 443.005173 -56.376012) (xy 443.060546 -56.398948)
			(xy 443.112452 -56.428915) (xy 443.160002 -56.465402) (xy 443.202382 -56.507782) (xy 443.238869 -56.555332)
			(xy 443.268836 -56.607238) (xy 443.291772 -56.662611) (xy 443.307285 -56.720504) (xy 443.315108 -56.779926)
			(xy 443.315598 -56.809894) (xy 443.315598 -56.810148) (xy 443.315025 -56.841671) (xy 443.306357 -56.904119)
			(xy 443.289204 -56.964788) (xy 443.263891 -57.02253) (xy 443.230896 -57.076254) (xy 443.190844 -57.124944)
			(xy 443.168024 -57.146698) (xy 443.160912 -57.153302) (xy 443.15253 -57.17032) (xy 443.14618 -57.248806)
			(xy 443.145817 -57.258371) (xy 443.151433 -57.276654) (xy 443.157102 -57.284366) (xy 443.172636 -57.304652)
			(xy 443.198696 -57.348601) (xy 443.21866 -57.395634) (xy 443.232172 -57.444909) (xy 443.235153 -57.467049)
			(xy 443.418492 -57.467049) (xy 443.418492 -57.412551) (xy 443.426248 -57.358608) (xy 443.4416 -57.306318)
			(xy 443.464238 -57.256745) (xy 443.493701 -57.210898) (xy 443.529387 -57.16971) (xy 443.570572 -57.13402)
			(xy 443.616417 -57.104554) (xy 443.665988 -57.081912) (xy 443.718277 -57.066554) (xy 443.772219 -57.058794)
			(xy 443.799468 -57.058306) (xy 443.825016 -57.058718) (xy 443.875655 -57.065524) (xy 443.924932 -57.079032)
			(xy 443.971964 -57.099) (xy 444.015907 -57.125071) (xy 444.036196 -57.140602) (xy 444.043923 -57.146237)
			(xy 444.062197 -57.151839) (xy 444.071756 -57.151524) (xy 444.150242 -57.145174) (xy 444.16726 -57.136792)
			(xy 444.173864 -57.12968) (xy 444.195585 -57.106822) (xy 444.244267 -57.066744) (xy 444.297992 -57.033734)
			(xy 444.355743 -57.008417) (xy 444.416425 -56.991272) (xy 444.478886 -56.982626) (xy 444.510414 -56.982106)
			(xy 444.510668 -56.982106) (xy 444.540637 -56.982591) (xy 444.600062 -56.990411) (xy 444.657958 -57.005921)
			(xy 444.713335 -57.028855) (xy 444.765243 -57.058822) (xy 444.788736 -57.076848) (xy 445.43853 -57.076848)
			(xy 445.439017 -57.049478) (xy 445.446829 -56.9953) (xy 445.462312 -56.942797) (xy 445.48515 -56.89305)
			(xy 445.51487 -56.847082) (xy 445.53251 -56.82615) (xy 445.532764 -56.825896) (xy 445.538366 -56.81882)
			(xy 445.544602 -56.801895) (xy 445.544956 -56.792876) (xy 445.544956 -56.72582) (xy 445.544599 -56.716803)
			(xy 445.538352 -56.699886) (xy 445.532764 -56.6928) (xy 445.53251 -56.6928) (xy 445.53251 -56.692546)
			(xy 445.514881 -56.671606) (xy 445.485167 -56.625636) (xy 445.462329 -56.57589) (xy 445.446836 -56.523391)
			(xy 445.439005 -56.469217) (xy 445.43853 -56.441848) (xy 445.439016 -56.414597) (xy 445.446772 -56.360649)
			(xy 445.462127 -56.308354) (xy 445.484769 -56.258777) (xy 445.514235 -56.212927) (xy 445.549926 -56.171736)
			(xy 445.591117 -56.136045) (xy 445.636967 -56.106579) (xy 445.686544 -56.083937) (xy 445.738839 -56.068582)
			(xy 445.792787 -56.060826) (xy 445.847289 -56.060826) (xy 445.901237 -56.068582) (xy 445.953532 -56.083937)
			(xy 446.003109 -56.106579) (xy 446.048959 -56.136045) (xy 446.09015 -56.171736) (xy 446.125841 -56.212927)
			(xy 446.155307 -56.258777) (xy 446.177949 -56.308354) (xy 446.193304 -56.360649) (xy 446.20106 -56.414597)
			(xy 446.201546 -56.441848) (xy 446.201063 -56.469218) (xy 446.193251 -56.523397) (xy 446.177767 -56.5759)
			(xy 446.154928 -56.625647) (xy 446.125206 -56.671614) (xy 446.107566 -56.692546) (xy 446.107312 -56.6928)
			(xy 446.101721 -56.699883) (xy 446.095476 -56.716803) (xy 446.09512 -56.72582) (xy 446.09512 -56.792876)
			(xy 446.095484 -56.801892) (xy 446.101727 -56.818809) (xy 446.107312 -56.825896) (xy 446.107566 -56.825896)
			(xy 446.107566 -56.82615) (xy 446.12519 -56.847094) (xy 446.154905 -56.893063) (xy 446.177745 -56.942808)
			(xy 446.193239 -56.995306) (xy 446.194342 -57.002934) (xy 447.863468 -57.002934) (xy 447.863996 -56.974844)
			(xy 447.872218 -56.919268) (xy 447.888504 -56.865501) (xy 447.912501 -56.814703) (xy 447.943691 -56.767976)
			(xy 447.981398 -56.72633) (xy 448.024806 -56.690666) (xy 448.048634 -56.675782) (xy 448.057524 -56.670448)
			(xy 448.069716 -56.65343) (xy 448.090036 -56.560212) (xy 448.085718 -56.539638) (xy 448.079876 -56.531002)
			(xy 448.063872 -56.506941) (xy 448.038531 -56.455008) (xy 448.021306 -56.399849) (xy 448.012592 -56.342725)
			(xy 448.012058 -56.313832) (xy 448.012608 -56.286583) (xy 448.020359 -56.232639) (xy 448.035709 -56.180348)
			(xy 448.058343 -56.130773) (xy 448.087803 -56.084924) (xy 448.123488 -56.043735) (xy 448.164672 -56.008043)
			(xy 448.210515 -55.978575) (xy 448.260086 -55.955932) (xy 448.312375 -55.940573) (xy 448.366317 -55.932813)
			(xy 448.393566 -55.932324) (xy 448.420936 -55.932804) (xy 448.475115 -55.940618) (xy 448.527618 -55.956103)
			(xy 448.577365 -55.978942) (xy 448.623332 -56.008664) (xy 448.644264 -56.026304) (xy 448.644518 -56.026558)
			(xy 448.65159 -56.032165) (xy 448.668518 -56.038398) (xy 448.677538 -56.03875) (xy 448.744594 -56.03875)
			(xy 448.753612 -56.038401) (xy 448.770529 -56.032149) (xy 448.777614 -56.026558) (xy 448.777614 -56.026304)
			(xy 448.777868 -56.026304) (xy 448.798801 -56.008663) (xy 448.844769 -55.978939) (xy 448.894515 -55.956093)
			(xy 448.947017 -55.940597) (xy 449.001195 -55.932768) (xy 449.055937 -55.932768) (xy 449.110115 -55.940597)
			(xy 449.162617 -55.956093) (xy 449.212363 -55.978939) (xy 449.258331 -56.008663) (xy 449.279264 -56.026304)
			(xy 449.279518 -56.026558) (xy 449.28659 -56.032165) (xy 449.303518 -56.038398) (xy 449.312538 -56.03875)
			(xy 449.379594 -56.03875) (xy 449.388612 -56.038401) (xy 449.405529 -56.032149) (xy 449.412614 -56.026558)
			(xy 449.412614 -56.026304) (xy 449.412868 -56.026304) (xy 449.433802 -56.008667) (xy 449.479774 -55.978955)
			(xy 449.529521 -55.956118) (xy 449.582021 -55.940627) (xy 449.636197 -55.932798) (xy 449.663566 -55.932324)
			(xy 449.690823 -55.932721) (xy 449.744782 -55.940474) (xy 449.797088 -55.955829) (xy 449.846677 -55.978471)
			(xy 449.892538 -56.007941) (xy 449.933738 -56.043637) (xy 449.969439 -56.084835) (xy 449.998913 -56.130693)
			(xy 450.021559 -56.18028) (xy 450.036918 -56.232585) (xy 450.044677 -56.286543) (xy 450.044677 -56.297068)
			(xy 450.386448 -56.297068) (xy 450.390519 -56.241446) (xy 450.402645 -56.187009) (xy 450.422568 -56.134918)
			(xy 450.449864 -56.086283) (xy 450.48395 -56.04214) (xy 450.524099 -56.003431) (xy 450.569457 -55.97098)
			(xy 450.619057 -55.945479) (xy 450.671841 -55.927472) (xy 450.726684 -55.917342) (xy 450.782418 -55.915305)
			(xy 450.837855 -55.921405) (xy 450.891812 -55.935511) (xy 450.943141 -55.957323) (xy 450.990747 -55.986377)
			(xy 451.033615 -56.022052) (xy 451.070832 -56.063589) (xy 451.101605 -56.110102) (xy 451.125277 -56.160599)
			(xy 451.141345 -56.214006) (xy 451.149465 -56.269182) (xy 451.149974 -56.297068) (xy 451.149465 -56.324954)
			(xy 451.14527 -56.353456) (xy 453.241154 -56.353456) (xy 453.245225 -56.297834) (xy 453.257351 -56.243397)
			(xy 453.277274 -56.191306) (xy 453.30457 -56.142671) (xy 453.338656 -56.098528) (xy 453.378805 -56.059819)
			(xy 453.424163 -56.027368) (xy 453.473763 -56.001867) (xy 453.526547 -55.98386) (xy 453.58139 -55.97373)
			(xy 453.637124 -55.971693) (xy 453.692561 -55.977793) (xy 453.746518 -55.991899) (xy 453.797847 -56.013711)
			(xy 453.845453 -56.042765) (xy 453.888321 -56.07844) (xy 453.925538 -56.119977) (xy 453.956311 -56.16649)
			(xy 453.979983 -56.216987) (xy 453.996051 -56.270394) (xy 454.004171 -56.32557) (xy 454.00468 -56.353456)
			(xy 454.004171 -56.381342) (xy 453.996051 -56.436518) (xy 453.979983 -56.489925) (xy 453.956311 -56.540422)
			(xy 453.925538 -56.586935) (xy 453.888321 -56.628472) (xy 453.845453 -56.664147) (xy 453.797847 -56.693201)
			(xy 453.746518 -56.715013) (xy 453.692561 -56.729119) (xy 453.637124 -56.735219) (xy 453.58139 -56.733182)
			(xy 453.526547 -56.723052) (xy 453.473763 -56.705045) (xy 453.424163 -56.679544) (xy 453.378805 -56.647093)
			(xy 453.338656 -56.608384) (xy 453.30457 -56.564241) (xy 453.277274 -56.515606) (xy 453.257351 -56.463515)
			(xy 453.245225 -56.409078) (xy 453.241154 -56.353456) (xy 451.14527 -56.353456) (xy 451.141345 -56.38013)
			(xy 451.125277 -56.433537) (xy 451.101605 -56.484034) (xy 451.070832 -56.530547) (xy 451.033615 -56.572084)
			(xy 450.990747 -56.607759) (xy 450.943141 -56.636813) (xy 450.891812 -56.658625) (xy 450.837855 -56.672731)
			(xy 450.782418 -56.678831) (xy 450.726684 -56.676794) (xy 450.671841 -56.666664) (xy 450.619057 -56.648657)
			(xy 450.569457 -56.623156) (xy 450.524099 -56.590705) (xy 450.48395 -56.551996) (xy 450.449864 -56.507853)
			(xy 450.422568 -56.459218) (xy 450.402645 -56.407127) (xy 450.390519 -56.35269) (xy 450.386448 -56.297068)
			(xy 450.044677 -56.297068) (xy 450.044677 -56.341057) (xy 450.036918 -56.395015) (xy 450.021559 -56.44732)
			(xy 449.998913 -56.496907) (xy 449.969439 -56.542765) (xy 449.933738 -56.583963) (xy 449.892538 -56.619659)
			(xy 449.846677 -56.649129) (xy 449.797088 -56.671771) (xy 449.744782 -56.687126) (xy 449.690823 -56.694879)
			(xy 449.663566 -56.69534) (xy 449.636194 -56.694908) (xy 449.582013 -56.687085) (xy 449.529509 -56.671588)
			(xy 449.479763 -56.648738) (xy 449.433798 -56.619005) (xy 449.412868 -56.60136) (xy 449.412614 -56.601106)
			(xy 449.405527 -56.59552) (xy 449.388611 -56.589273) (xy 449.379594 -56.588914) (xy 449.312538 -56.588914)
			(xy 449.303523 -56.589286) (xy 449.286605 -56.595523) (xy 449.279518 -56.601106) (xy 449.279518 -56.60136)
			(xy 449.279264 -56.60136) (xy 449.258331 -56.619001) (xy 449.212363 -56.648725) (xy 449.162617 -56.671571)
			(xy 449.110115 -56.687067) (xy 449.055937 -56.694896) (xy 449.001195 -56.694896) (xy 448.947017 -56.687067)
			(xy 448.894515 -56.671571) (xy 448.844769 -56.648725) (xy 448.798801 -56.619001) (xy 448.777868 -56.60136)
			(xy 448.777614 -56.601106) (xy 448.770527 -56.59552) (xy 448.753611 -56.589273) (xy 448.744594 -56.588914)
			(xy 448.677538 -56.588914) (xy 448.668523 -56.589286) (xy 448.651605 -56.595523) (xy 448.644518 -56.601106)
			(xy 448.64401 -56.60136) (xy 448.631279 -56.612308) (xy 448.604185 -56.632147) (xy 448.589908 -56.640984)
			(xy 448.581018 -56.646318) (xy 448.568826 -56.663336) (xy 448.548506 -56.756554) (xy 448.552824 -56.777128)
			(xy 448.558666 -56.785764) (xy 448.574649 -56.809839) (xy 448.599997 -56.861766) (xy 448.617227 -56.916921)
			(xy 448.625947 -56.974042) (xy 448.626484 -57.002934) (xy 448.625998 -57.030185) (xy 448.618242 -57.084133)
			(xy 448.602887 -57.136428) (xy 448.580245 -57.186005) (xy 448.550779 -57.231855) (xy 448.515088 -57.273046)
			(xy 448.473897 -57.308737) (xy 448.428047 -57.338203) (xy 448.37847 -57.360845) (xy 448.326175 -57.3762)
			(xy 448.272227 -57.383956) (xy 448.217725 -57.383956) (xy 448.163777 -57.3762) (xy 448.111482 -57.360845)
			(xy 448.061905 -57.338203) (xy 448.016055 -57.308737) (xy 447.974864 -57.273046) (xy 447.939173 -57.231855)
			(xy 447.909707 -57.186005) (xy 447.887065 -57.136428) (xy 447.87171 -57.084133) (xy 447.863954 -57.030185)
			(xy 447.863468 -57.002934) (xy 446.194342 -57.002934) (xy 446.20107 -57.04948) (xy 446.201546 -57.076848)
			(xy 446.20106 -57.104099) (xy 446.193304 -57.158047) (xy 446.177949 -57.210342) (xy 446.155307 -57.259919)
			(xy 446.125841 -57.305769) (xy 446.09015 -57.34696) (xy 446.048959 -57.382651) (xy 446.003109 -57.412117)
			(xy 445.953532 -57.434759) (xy 445.901237 -57.450114) (xy 445.847289 -57.45787) (xy 445.792787 -57.45787)
			(xy 445.738839 -57.450114) (xy 445.686544 -57.434759) (xy 445.636967 -57.412117) (xy 445.591117 -57.382651)
			(xy 445.549926 -57.34696) (xy 445.514235 -57.305769) (xy 445.484769 -57.259919) (xy 445.462127 -57.210342)
			(xy 445.446772 -57.158047) (xy 445.439016 -57.104099) (xy 445.43853 -57.076848) (xy 444.788736 -57.076848)
			(xy 444.812796 -57.095309) (xy 444.855179 -57.13769) (xy 444.891668 -57.185242) (xy 444.921637 -57.237149)
			(xy 444.944573 -57.292524) (xy 444.960086 -57.35042) (xy 444.967908 -57.409845) (xy 444.968376 -57.439814)
			(xy 444.967935 -57.468047) (xy 444.960995 -57.524084) (xy 444.947208 -57.57884) (xy 444.926786 -57.631483)
			(xy 444.900039 -57.681211) (xy 444.884048 -57.704482) (xy 444.876682 -57.71515) (xy 444.873634 -57.740804)
			(xy 444.916052 -57.844436) (xy 444.936118 -57.860692) (xy 444.949072 -57.862978) (xy 444.975186 -57.868095)
			(xy 445.025757 -57.884658) (xy 445.073537 -57.908085) (xy 445.1176 -57.937922) (xy 445.157092 -57.973589)
			(xy 445.191246 -58.014396) (xy 445.219402 -58.059552) (xy 445.241013 -58.108181) (xy 445.25566 -58.159339)
			(xy 445.263059 -58.212037) (xy 445.263524 -58.238644) (xy 445.263044 -58.266014) (xy 445.255232 -58.320193)
			(xy 445.239747 -58.372697) (xy 445.216908 -58.422444) (xy 445.187185 -58.468411) (xy 445.169544 -58.489342)
			(xy 445.16929 -58.489596) (xy 445.163698 -58.496679) (xy 445.157455 -58.513598) (xy 445.157098 -58.522616)
			(xy 445.157098 -58.589672) (xy 445.157469 -58.598687) (xy 445.163707 -58.615605) (xy 445.16929 -58.622692)
			(xy 445.169544 -58.622692) (xy 445.169544 -58.622946) (xy 445.187178 -58.643882) (xy 445.210091 -58.679334)
			(xy 448.295268 -58.679334) (xy 448.295702 -58.653019) (xy 448.302945 -58.600889) (xy 448.317271 -58.550246)
			(xy 448.33841 -58.502048) (xy 448.365962 -58.457205) (xy 448.399405 -58.416566) (xy 448.418458 -58.39841)
			(xy 448.425851 -58.390881) (xy 448.434382 -58.371607) (xy 448.434968 -58.361072) (xy 448.434968 -58.286396)
			(xy 448.434464 -58.275843) (xy 448.425912 -58.256548) (xy 448.418458 -58.249058) (xy 448.399381 -58.230924)
			(xy 448.365927 -58.190289) (xy 448.338372 -58.145444) (xy 448.317238 -58.097239) (xy 448.302925 -58.046588)
			(xy 448.295704 -57.994451) (xy 448.295268 -57.968134) (xy 448.295754 -57.940883) (xy 448.30351 -57.886935)
			(xy 448.318865 -57.83464) (xy 448.341507 -57.785063) (xy 448.370973 -57.739213) (xy 448.406664 -57.698022)
			(xy 448.447855 -57.662331) (xy 448.493705 -57.632865) (xy 448.543282 -57.610223) (xy 448.595577 -57.594868)
			(xy 448.649525 -57.587112) (xy 448.704027 -57.587112) (xy 448.757975 -57.594868) (xy 448.81027 -57.610223)
			(xy 448.859847 -57.632865) (xy 448.905697 -57.662331) (xy 448.946888 -57.698022) (xy 448.982579 -57.739213)
			(xy 449.012045 -57.785063) (xy 449.034687 -57.83464) (xy 449.050042 -57.886935) (xy 449.057798 -57.940883)
			(xy 449.058284 -57.968134) (xy 449.057844 -57.994449) (xy 449.050605 -58.046579) (xy 449.03628 -58.097222)
			(xy 449.034079 -58.102242) (xy 452.21828 -58.102242) (xy 452.21828 -58.042306) (xy 452.226103 -57.982884)
			(xy 452.241616 -57.924991) (xy 452.264552 -57.869618) (xy 452.294519 -57.817712) (xy 452.331006 -57.770162)
			(xy 452.373386 -57.727782) (xy 452.420936 -57.691295) (xy 452.472842 -57.661328) (xy 452.528215 -57.638392)
			(xy 452.586108 -57.622879) (xy 452.64553 -57.615056) (xy 452.705466 -57.615056) (xy 452.764888 -57.622879)
			(xy 452.822781 -57.638392) (xy 452.878154 -57.661328) (xy 452.93006 -57.691295) (xy 452.97761 -57.727782)
			(xy 453.01999 -57.770162) (xy 453.056477 -57.817712) (xy 453.086444 -57.869618) (xy 453.10938 -57.924991)
			(xy 453.124893 -57.982884) (xy 453.132716 -58.042306) (xy 453.133206 -58.072274) (xy 453.132716 -58.102242)
			(xy 453.124893 -58.161664) (xy 453.10938 -58.219557) (xy 453.086444 -58.27493) (xy 453.056477 -58.326836)
			(xy 453.01999 -58.374386) (xy 452.97761 -58.416766) (xy 452.93006 -58.453253) (xy 452.878154 -58.48322)
			(xy 452.822781 -58.506156) (xy 452.764888 -58.521669) (xy 452.705466 -58.529492) (xy 452.64553 -58.529492)
			(xy 452.586108 -58.521669) (xy 452.528215 -58.506156) (xy 452.472842 -58.48322) (xy 452.420936 -58.453253)
			(xy 452.373386 -58.416766) (xy 452.331006 -58.374386) (xy 452.294519 -58.326836) (xy 452.264552 -58.27493)
			(xy 452.241616 -58.219557) (xy 452.226103 -58.161664) (xy 452.21828 -58.102242) (xy 449.034079 -58.102242)
			(xy 449.015143 -58.145421) (xy 448.987592 -58.190264) (xy 448.954148 -58.230902) (xy 448.935094 -58.249058)
			(xy 448.927708 -58.256593) (xy 448.919175 -58.275863) (xy 448.918584 -58.286396) (xy 448.918584 -58.361072)
			(xy 448.91912 -58.371621) (xy 448.927651 -58.390916) (xy 448.935094 -58.39841) (xy 448.954146 -58.416569)
			(xy 448.987604 -58.457198) (xy 449.015164 -58.502037) (xy 449.036303 -58.550237) (xy 449.05062 -58.600884)
			(xy 449.057845 -58.653018) (xy 449.058284 -58.679334) (xy 449.057798 -58.706585) (xy 449.050042 -58.760533)
			(xy 449.034687 -58.812828) (xy 449.012045 -58.862405) (xy 448.982579 -58.908255) (xy 448.946888 -58.949446)
			(xy 448.905697 -58.985137) (xy 448.859847 -59.014603) (xy 448.81027 -59.037245) (xy 448.757975 -59.0526)
			(xy 448.704027 -59.060356) (xy 448.649525 -59.060356) (xy 448.595577 -59.0526) (xy 448.543282 -59.037245)
			(xy 448.493705 -59.014603) (xy 448.447855 -58.985137) (xy 448.406664 -58.949446) (xy 448.370973 -58.908255)
			(xy 448.341507 -58.862405) (xy 448.318865 -58.812828) (xy 448.30351 -58.760533) (xy 448.295754 -58.706585)
			(xy 448.295268 -58.679334) (xy 445.210091 -58.679334) (xy 445.21689 -58.689854) (xy 445.239726 -58.739601)
			(xy 445.255218 -58.7921) (xy 445.263049 -58.846275) (xy 445.263524 -58.873644) (xy 445.263038 -58.900895)
			(xy 445.255282 -58.954843) (xy 445.239927 -59.007138) (xy 445.217285 -59.056715) (xy 445.187819 -59.102565)
			(xy 445.152128 -59.143756) (xy 445.110937 -59.179447) (xy 445.065087 -59.208913) (xy 445.01551 -59.231555)
			(xy 444.963215 -59.24691) (xy 444.909267 -59.254666) (xy 444.854765 -59.254666) (xy 444.800817 -59.24691)
			(xy 444.748522 -59.231555) (xy 444.698945 -59.208913) (xy 444.653095 -59.179447) (xy 444.611904 -59.143756)
			(xy 444.576213 -59.102565) (xy 444.546747 -59.056715) (xy 444.524105 -59.007138) (xy 444.50875 -58.954843)
			(xy 444.500994 -58.900895) (xy 444.500508 -58.873644) (xy 444.500998 -58.846275) (xy 444.50881 -58.792096)
			(xy 444.524293 -58.739594) (xy 444.54713 -58.689846) (xy 444.576849 -58.643878) (xy 444.594488 -58.622946)
			(xy 444.594742 -58.622692) (xy 444.600343 -58.615616) (xy 444.60658 -58.598691) (xy 444.606934 -58.589672)
			(xy 444.606934 -58.522616) (xy 444.606562 -58.513601) (xy 444.600324 -58.496684) (xy 444.594742 -58.489596)
			(xy 444.594488 -58.489596) (xy 444.594488 -58.489342) (xy 444.576853 -58.468406) (xy 444.547141 -58.422434)
			(xy 444.524305 -58.372688) (xy 444.508812 -58.320188) (xy 444.500983 -58.266013) (xy 444.500508 -58.238644)
			(xy 444.500508 -58.23839) (xy 444.500875 -58.213442) (xy 444.507393 -58.163974) (xy 444.520315 -58.11578)
			(xy 444.53942 -58.069687) (xy 444.551562 -58.04789) (xy 444.558166 -58.03646) (xy 444.558674 -58.010806)
			(xy 444.512954 -57.923176) (xy 444.508694 -57.915734) (xy 444.496229 -57.903979) (xy 444.480572 -57.89702)
			(xy 444.47206 -57.895998) (xy 444.443872 -57.893174) (xy 444.388441 -57.881483) (xy 444.334876 -57.863039)
			(xy 444.283999 -57.838124) (xy 444.236585 -57.807119) (xy 444.193362 -57.770499) (xy 444.173864 -57.749948)
			(xy 444.16726 -57.742836) (xy 444.150242 -57.734454) (xy 444.071756 -57.728104) (xy 444.06219 -57.727716)
			(xy 444.043906 -57.733348) (xy 444.036196 -57.739026) (xy 444.015892 -57.754535) (xy 443.971948 -57.780598)
			(xy 443.92492 -57.800567) (xy 443.875648 -57.814084) (xy 443.825014 -57.820909) (xy 443.799468 -57.821322)
			(xy 443.772219 -57.820806) (xy 443.718277 -57.813046) (xy 443.665988 -57.797688) (xy 443.616417 -57.775046)
			(xy 443.570572 -57.74558) (xy 443.529387 -57.70989) (xy 443.493701 -57.668702) (xy 443.464238 -57.622855)
			(xy 443.4416 -57.573282) (xy 443.426248 -57.520992) (xy 443.418492 -57.467049) (xy 443.235153 -57.467049)
			(xy 443.238989 -57.495547) (xy 443.239398 -57.521094) (xy 443.238929 -57.548464) (xy 443.231112 -57.602643)
			(xy 443.215624 -57.655146) (xy 443.192782 -57.704893) (xy 443.163059 -57.75086) (xy 443.145418 -57.771792)
			(xy 443.145164 -57.772046) (xy 443.13959 -57.779141) (xy 443.133337 -57.796051) (xy 443.132972 -57.805066)
			(xy 443.132972 -57.872122) (xy 443.133324 -57.881139) (xy 443.139576 -57.898056) (xy 443.145164 -57.905142)
			(xy 443.145418 -57.905142) (xy 443.145418 -57.905396) (xy 443.163051 -57.926334) (xy 443.192773 -57.972302)
			(xy 443.215616 -58.022048) (xy 443.23111 -58.074549) (xy 443.238938 -58.128726) (xy 443.238939 -58.183465)
			(xy 443.231112 -58.237642) (xy 443.215619 -58.290144) (xy 443.192777 -58.33989) (xy 443.163056 -58.385858)
			(xy 443.145418 -58.406792) (xy 443.145164 -58.407046) (xy 443.13959 -58.414141) (xy 443.133337 -58.431051)
			(xy 443.132972 -58.440066) (xy 443.132972 -58.507122) (xy 443.133324 -58.516139) (xy 443.139576 -58.533056)
			(xy 443.145164 -58.540142) (xy 443.145418 -58.540142) (xy 443.145418 -58.540396) (xy 443.163071 -58.561316)
			(xy 443.192781 -58.607293) (xy 443.215613 -58.657043) (xy 443.231101 -58.709546) (xy 443.238926 -58.763724)
			(xy 443.239398 -58.791094) (xy 443.238912 -58.818345) (xy 443.231156 -58.872293) (xy 443.215801 -58.924588)
			(xy 443.193159 -58.974165) (xy 443.163693 -59.020015) (xy 443.128002 -59.061206) (xy 443.086811 -59.096897)
			(xy 443.040961 -59.126363) (xy 442.991384 -59.149005) (xy 442.939089 -59.16436) (xy 442.885141 -59.172116)
			(xy 442.830639 -59.172116) (xy 442.776691 -59.16436) (xy 442.724396 -59.149005) (xy 442.674819 -59.126363)
			(xy 442.628969 -59.096897) (xy 442.587778 -59.061206) (xy 442.552087 -59.020015) (xy 442.522621 -58.974165)
			(xy 442.499979 -58.924588) (xy 442.484624 -58.872293) (xy 442.476868 -58.818345) (xy 442.476382 -58.791094)
			(xy 442.476825 -58.763723) (xy 442.484645 -58.709542) (xy 442.500138 -58.657038) (xy 442.522986 -58.607291)
			(xy 442.552717 -58.561326) (xy 442.570362 -58.540396) (xy 442.570616 -58.540142) (xy 442.576193 -58.533049)
			(xy 442.582445 -58.516137) (xy 442.582808 -58.507122) (xy 442.582808 -58.440066) (xy 442.582465 -58.431048)
			(xy 442.576207 -58.414131) (xy 442.570616 -58.407046) (xy 442.570362 -58.407046) (xy 442.570362 -58.406792)
			(xy 442.552714 -58.385865) (xy 442.522987 -58.339897) (xy 442.50014 -58.29015) (xy 442.484642 -58.237647)
			(xy 442.476813 -58.183467) (xy 442.476814 -58.128724) (xy 442.484644 -58.074544) (xy 442.500143 -58.022042)
			(xy 442.522991 -57.972295) (xy 442.552719 -57.926328) (xy 442.570362 -57.905396) (xy 442.570616 -57.905142)
			(xy 442.576193 -57.898049) (xy 442.582445 -57.881137) (xy 442.582808 -57.872122) (xy 442.582808 -57.805066)
			(xy 442.582465 -57.796048) (xy 442.576207 -57.779131) (xy 442.570616 -57.772046) (xy 442.570362 -57.772046)
			(xy 442.570362 -57.771792) (xy 442.552699 -57.750879) (xy 442.522992 -57.7049) (xy 442.500161 -57.655148)
			(xy 442.484676 -57.602643) (xy 442.476853 -57.548464) (xy 442.476382 -57.521094) (xy 442.476778 -57.495546)
			(xy 442.483588 -57.444906) (xy 442.497101 -57.395629) (xy 442.517072 -57.348597) (xy 442.543146 -57.304654)
			(xy 442.558678 -57.284366) (xy 442.564283 -57.27662) (xy 442.569904 -57.258361) (xy 442.5696 -57.248806)
			(xy 442.56325 -57.17032) (xy 442.554868 -57.153302) (xy 442.547756 -57.146698) (xy 442.524923 -57.124952)
			(xy 442.484845 -57.076275) (xy 442.451831 -57.022554) (xy 442.42651 -56.964808) (xy 442.40936 -56.904132)
			(xy 442.400706 -56.841675) (xy 442.400182 -56.810148) (xy 440.583284 -56.810148) (xy 440.583574 -56.826404)
			(xy 440.583117 -56.853775) (xy 440.575298 -56.907954) (xy 440.559807 -56.960458) (xy 440.536963 -57.010205)
			(xy 440.507236 -57.056171) (xy 440.489594 -57.077102) (xy 440.48934 -57.077356) (xy 440.483759 -57.084446)
			(xy 440.47751 -57.10136) (xy 440.477148 -57.110376) (xy 440.477148 -57.177432) (xy 440.477479 -57.186452)
			(xy 440.483743 -57.203369) (xy 440.48934 -57.210452) (xy 440.489594 -57.210452) (xy 440.489594 -57.210706)
			(xy 440.507238 -57.231636) (xy 440.536961 -57.277605) (xy 440.559805 -57.327352) (xy 440.5753 -57.379854)
			(xy 440.583127 -57.434032) (xy 440.583127 -57.488774) (xy 440.575298 -57.542952) (xy 440.559802 -57.595454)
			(xy 440.536958 -57.645201) (xy 440.507234 -57.691169) (xy 440.489594 -57.712102) (xy 440.48934 -57.712356)
			(xy 440.483759 -57.719446) (xy 440.47751 -57.73636) (xy 440.477148 -57.745376) (xy 440.477148 -57.812432)
			(xy 440.477479 -57.821452) (xy 440.483743 -57.838369) (xy 440.48934 -57.845452) (xy 440.489594 -57.845452)
			(xy 440.489594 -57.845706) (xy 440.507238 -57.866636) (xy 440.536961 -57.912605) (xy 440.559805 -57.962352)
			(xy 440.5753 -58.014854) (xy 440.583127 -58.069032) (xy 440.583127 -58.123774) (xy 440.575298 -58.177952)
			(xy 440.559802 -58.230454) (xy 440.536958 -58.280201) (xy 440.507234 -58.326169) (xy 440.489594 -58.347102)
			(xy 440.48934 -58.347356) (xy 440.483759 -58.354446) (xy 440.47751 -58.37136) (xy 440.477148 -58.380376)
			(xy 440.477148 -58.447432) (xy 440.477479 -58.456452) (xy 440.483743 -58.473369) (xy 440.48934 -58.480452)
			(xy 440.489594 -58.480452) (xy 440.489594 -58.480706) (xy 440.507248 -58.501626) (xy 440.536958 -58.547602)
			(xy 440.559791 -58.597352) (xy 440.575279 -58.649856) (xy 440.583102 -58.704034) (xy 440.583574 -58.731404)
			(xy 440.583088 -58.758655) (xy 440.575332 -58.812603) (xy 440.559977 -58.864898) (xy 440.537335 -58.914475)
			(xy 440.507869 -58.960325) (xy 440.472178 -59.001516) (xy 440.430987 -59.037207) (xy 440.385137 -59.066673)
			(xy 440.33556 -59.089315) (xy 440.283265 -59.10467) (xy 440.229317 -59.112426) (xy 440.174815 -59.112426)
			(xy 440.120867 -59.10467) (xy 440.068572 -59.089315) (xy 440.018995 -59.066673) (xy 439.973145 -59.037207)
			(xy 439.931954 -59.001516) (xy 439.896263 -58.960325) (xy 439.866797 -58.914475) (xy 439.844155 -58.864898)
			(xy 439.8288 -58.812603) (xy 439.821044 -58.758655) (xy 439.820558 -58.731404) (xy 435.85104 -58.731404)
			(xy 435.835366 -58.75183) (xy 435.792986 -58.79421) (xy 435.745436 -58.830697) (xy 435.69353 -58.860664)
			(xy 435.638157 -58.8836) (xy 435.580264 -58.899113) (xy 435.520842 -58.906936) (xy 435.460906 -58.906936)
			(xy 435.401484 -58.899113) (xy 435.343591 -58.8836) (xy 435.288218 -58.860664) (xy 435.236312 -58.830697)
			(xy 435.188762 -58.79421) (xy 435.146382 -58.75183) (xy 435.109895 -58.70428) (xy 435.079928 -58.652374)
			(xy 435.056992 -58.597001) (xy 435.041479 -58.539108) (xy 435.033656 -58.479686) (xy 434.583526 -58.479686)
			(xy 434.579576 -58.482717) (xy 434.52767 -58.512684) (xy 434.472297 -58.53562) (xy 434.414404 -58.551133)
			(xy 434.354982 -58.558956) (xy 434.295046 -58.558956) (xy 434.235624 -58.551133) (xy 434.177731 -58.53562)
			(xy 434.122358 -58.512684) (xy 434.070452 -58.482717) (xy 434.022902 -58.44623) (xy 433.980522 -58.40385)
			(xy 433.944035 -58.3563) (xy 433.914068 -58.304394) (xy 433.891132 -58.249021) (xy 433.875619 -58.191128)
			(xy 433.867796 -58.131706) (xy 433.402063 -58.131706) (xy 433.4469 -58.150278) (xy 433.498806 -58.180245)
			(xy 433.546356 -58.216732) (xy 433.588736 -58.259112) (xy 433.625223 -58.306662) (xy 433.65519 -58.358568)
			(xy 433.678126 -58.413941) (xy 433.693639 -58.471834) (xy 433.701462 -58.531256) (xy 433.701952 -58.561224)
			(xy 433.701462 -58.591192) (xy 433.693639 -58.650614) (xy 433.678126 -58.708507) (xy 433.65519 -58.76388)
			(xy 433.625223 -58.815786) (xy 433.588736 -58.863336) (xy 433.546356 -58.905716) (xy 433.498806 -58.942203)
			(xy 433.4469 -58.97217) (xy 433.391527 -58.995106) (xy 433.333634 -59.010619) (xy 433.274212 -59.018442)
			(xy 433.214276 -59.018442) (xy 433.154854 -59.010619) (xy 433.096961 -58.995106) (xy 433.041588 -58.97217)
			(xy 432.989682 -58.942203) (xy 432.942132 -58.905716) (xy 432.899752 -58.863336) (xy 432.863265 -58.815786)
			(xy 432.833298 -58.76388) (xy 432.810362 -58.708507) (xy 432.794849 -58.650614) (xy 432.787026 -58.591192)
			(xy 423.126209 -58.591192) (xy 423.134014 -58.647552) (xy 423.134536 -58.67908) (xy 423.134536 -58.679334)
			(xy 423.134046 -58.709302) (xy 423.126223 -58.768724) (xy 423.11071 -58.826617) (xy 423.087774 -58.88199)
			(xy 423.057807 -58.933896) (xy 423.02132 -58.981446) (xy 422.97894 -59.023826) (xy 422.93139 -59.060313)
			(xy 422.879484 -59.09028) (xy 422.824111 -59.113216) (xy 422.766218 -59.128729) (xy 422.706796 -59.136552)
			(xy 422.64686 -59.136552) (xy 422.587438 -59.128729) (xy 422.529545 -59.113216) (xy 422.474172 -59.09028)
			(xy 422.422266 -59.060313) (xy 422.374716 -59.023826) (xy 422.332336 -58.981446) (xy 422.295849 -58.933896)
			(xy 422.265882 -58.88199) (xy 422.242946 -58.826617) (xy 422.227433 -58.768724) (xy 422.21961 -58.709302)
			(xy 422.21912 -58.679334) (xy 419.210134 -58.679334) (xy 419.216936 -58.689858) (xy 419.239775 -58.739603)
			(xy 419.255269 -58.792102) (xy 419.2631 -58.846276) (xy 419.263576 -58.873644) (xy 419.26309 -58.900895)
			(xy 419.255334 -58.954843) (xy 419.239979 -59.007138) (xy 419.217337 -59.056715) (xy 419.187871 -59.102565)
			(xy 419.15218 -59.143756) (xy 419.110989 -59.179447) (xy 419.065139 -59.208913) (xy 419.015562 -59.231555)
			(xy 418.963267 -59.24691) (xy 418.909319 -59.254666) (xy 418.854817 -59.254666) (xy 418.800869 -59.24691)
			(xy 418.748574 -59.231555) (xy 418.698997 -59.208913) (xy 418.653147 -59.179447) (xy 418.611956 -59.143756)
			(xy 418.576265 -59.102565) (xy 418.546799 -59.056715) (xy 418.524157 -59.007138) (xy 418.508802 -58.954843)
			(xy 418.501046 -58.900895) (xy 418.50056 -58.873644) (xy 418.501037 -58.846274) (xy 418.50885 -58.792095)
			(xy 418.524336 -58.739591) (xy 418.547175 -58.689844) (xy 418.576899 -58.643877) (xy 418.59454 -58.622946)
			(xy 418.594794 -58.622692) (xy 418.600389 -58.615611) (xy 418.606631 -58.59869) (xy 418.606986 -58.589672)
			(xy 418.606986 -58.522616) (xy 418.606625 -58.5136) (xy 418.60038 -58.496682) (xy 418.594794 -58.489596)
			(xy 418.59454 -58.489596) (xy 418.59454 -58.489342) (xy 418.576913 -58.4684) (xy 418.547198 -58.42243)
			(xy 418.524359 -58.372686) (xy 418.508865 -58.320187) (xy 418.501035 -58.266013) (xy 418.50056 -58.238644)
			(xy 418.50056 -58.23839) (xy 418.500934 -58.213442) (xy 418.50745 -58.163975) (xy 418.520371 -58.115781)
			(xy 418.539474 -58.069688) (xy 418.551614 -58.04789) (xy 418.558218 -58.03646) (xy 418.558726 -58.010806)
			(xy 418.513006 -57.923176) (xy 418.508775 -57.915715) (xy 418.496298 -57.903963) (xy 418.480629 -57.897013)
			(xy 418.472112 -57.895998) (xy 418.443921 -57.893202) (xy 418.388489 -57.881506) (xy 418.334925 -57.863056)
			(xy 418.284047 -57.838136) (xy 418.236635 -57.807126) (xy 418.193413 -57.770501) (xy 418.173916 -57.749948)
			(xy 418.167312 -57.742836) (xy 418.150294 -57.734454) (xy 418.071808 -57.728104) (xy 418.062243 -57.727744)
			(xy 418.04396 -57.733357) (xy 418.036248 -57.739026) (xy 418.01596 -57.754556) (xy 417.972011 -57.780617)
			(xy 417.924979 -57.800581) (xy 417.875704 -57.814093) (xy 417.825067 -57.820912) (xy 417.79952 -57.821322)
			(xy 417.772267 -57.820832) (xy 417.718316 -57.813078) (xy 417.666018 -57.797724) (xy 417.616437 -57.775083)
			(xy 417.570583 -57.745617) (xy 417.529389 -57.709925) (xy 417.493695 -57.668733) (xy 417.464226 -57.622881)
			(xy 417.441583 -57.573301) (xy 417.426227 -57.521003) (xy 417.418469 -57.467053) (xy 417.235206 -57.467053)
			(xy 417.239041 -57.495547) (xy 417.23945 -57.521094) (xy 417.238993 -57.548465) (xy 417.231175 -57.602645)
			(xy 417.215684 -57.655148) (xy 417.19284 -57.704895) (xy 417.163113 -57.750861) (xy 417.14547 -57.771792)
			(xy 417.145216 -57.772046) (xy 417.139648 -57.779145) (xy 417.13339 -57.796052) (xy 417.133024 -57.805066)
			(xy 417.133024 -57.872122) (xy 417.133365 -57.881141) (xy 417.139623 -57.898058) (xy 417.145216 -57.905142)
			(xy 417.14547 -57.905142) (xy 417.14547 -57.905396) (xy 417.163105 -57.926333) (xy 417.19283 -57.9723)
			(xy 417.215676 -58.022046) (xy 417.231173 -58.074547) (xy 417.239002 -58.128725) (xy 417.239003 -58.183466)
			(xy 417.231175 -58.237644) (xy 417.215679 -58.290146) (xy 417.192835 -58.339892) (xy 417.16311 -58.385859)
			(xy 417.14547 -58.406792) (xy 417.145216 -58.407046) (xy 417.139648 -58.414145) (xy 417.13339 -58.431052)
			(xy 417.133024 -58.440066) (xy 417.133024 -58.507122) (xy 417.133365 -58.516141) (xy 417.139623 -58.533058)
			(xy 417.145216 -58.540142) (xy 417.14547 -58.540142) (xy 417.14547 -58.540396) (xy 417.163116 -58.561323)
			(xy 417.192828 -58.607296) (xy 417.215663 -58.657045) (xy 417.231152 -58.709547) (xy 417.238978 -58.763724)
			(xy 417.23945 -58.791094) (xy 417.238964 -58.818345) (xy 417.231208 -58.872293) (xy 417.215853 -58.924588)
			(xy 417.193211 -58.974165) (xy 417.163745 -59.020015) (xy 417.128054 -59.061206) (xy 417.086863 -59.096897)
			(xy 417.041013 -59.126363) (xy 416.991436 -59.149005) (xy 416.939141 -59.16436) (xy 416.885193 -59.172116)
			(xy 416.830691 -59.172116) (xy 416.776743 -59.16436) (xy 416.724448 -59.149005) (xy 416.674871 -59.126363)
			(xy 416.629021 -59.096897) (xy 416.58783 -59.061206) (xy 416.552139 -59.020015) (xy 416.522673 -58.974165)
			(xy 416.500031 -58.924588) (xy 416.484676 -58.872293) (xy 416.47692 -58.818345) (xy 416.476434 -58.791094)
			(xy 416.476888 -58.763723) (xy 416.484708 -58.709543) (xy 416.500199 -58.65704) (xy 416.523044 -58.607293)
			(xy 416.552771 -58.561327) (xy 416.570414 -58.540396) (xy 416.570668 -58.540142) (xy 416.576251 -58.533053)
			(xy 416.582498 -58.516138) (xy 416.58286 -58.507122) (xy 416.58286 -58.440066) (xy 416.582528 -58.431046)
			(xy 416.576264 -58.414129) (xy 416.570668 -58.407046) (xy 416.570414 -58.407046) (xy 416.570414 -58.406792)
			(xy 416.552768 -58.385864) (xy 416.523044 -58.339895) (xy 416.5002 -58.290148) (xy 416.484705 -58.237645)
			(xy 416.476877 -58.183466) (xy 416.476878 -58.128725) (xy 416.484707 -58.074546) (xy 416.500203 -58.022044)
			(xy 416.523049 -57.972297) (xy 416.552773 -57.926329) (xy 416.570414 -57.905396) (xy 416.570668 -57.905142)
			(xy 416.576251 -57.898053) (xy 416.582498 -57.881138) (xy 416.58286 -57.872122) (xy 416.58286 -57.805066)
			(xy 416.582528 -57.796046) (xy 416.576264 -57.779129) (xy 416.570668 -57.772046) (xy 416.570414 -57.772046)
			(xy 416.570414 -57.771792) (xy 416.55276 -57.750872) (xy 416.52305 -57.704896) (xy 416.500217 -57.655146)
			(xy 416.484729 -57.602642) (xy 416.476905 -57.548464) (xy 416.476434 -57.521094) (xy 416.476819 -57.495545)
			(xy 416.48363 -57.444904) (xy 416.497145 -57.395627) (xy 416.517119 -57.348596) (xy 416.543196 -57.304654)
			(xy 416.55873 -57.284366) (xy 416.56433 -57.276617) (xy 416.569955 -57.258361) (xy 416.569652 -57.248806)
			(xy 416.563302 -57.17032) (xy 416.55492 -57.153302) (xy 416.547808 -57.146698) (xy 416.524985 -57.124942)
			(xy 416.484904 -57.076268) (xy 416.451888 -57.02255) (xy 416.426564 -56.964806) (xy 416.409413 -56.904131)
			(xy 416.400758 -56.841674) (xy 416.400234 -56.810148) (xy 414.583336 -56.810148) (xy 414.583626 -56.826404)
			(xy 414.58318 -56.853775) (xy 414.57536 -56.907956) (xy 414.559867 -56.96046) (xy 414.537021 -57.010206)
			(xy 414.50729 -57.056172) (xy 414.489646 -57.077102) (xy 414.489392 -57.077356) (xy 414.483817 -57.08445)
			(xy 414.477564 -57.101361) (xy 414.4772 -57.110376) (xy 414.4772 -57.177432) (xy 414.477542 -57.18645)
			(xy 414.4838 -57.203367) (xy 414.489392 -57.210452) (xy 414.489646 -57.210452) (xy 414.489646 -57.210706)
			(xy 414.507292 -57.231635) (xy 414.537018 -57.277603) (xy 414.559865 -57.32735) (xy 414.575362 -57.379852)
			(xy 414.583191 -57.434032) (xy 414.583191 -57.488774) (xy 414.575361 -57.542954) (xy 414.559863 -57.595456)
			(xy 414.537016 -57.645203) (xy 414.507288 -57.69117) (xy 414.489646 -57.712102) (xy 414.489392 -57.712356)
			(xy 414.483817 -57.71945) (xy 414.477564 -57.736361) (xy 414.4772 -57.745376) (xy 414.4772 -57.812432)
			(xy 414.477542 -57.82145) (xy 414.4838 -57.838367) (xy 414.489392 -57.845452) (xy 414.489646 -57.845452)
			(xy 414.489646 -57.845706) (xy 414.507292 -57.866635) (xy 414.537018 -57.912603) (xy 414.559865 -57.96235)
			(xy 414.575362 -58.014852) (xy 414.583191 -58.069032) (xy 414.583191 -58.123774) (xy 414.575361 -58.177954)
			(xy 414.559863 -58.230456) (xy 414.537016 -58.280203) (xy 414.507288 -58.32617) (xy 414.489646 -58.347102)
			(xy 414.489392 -58.347356) (xy 414.483817 -58.35445) (xy 414.477564 -58.371361) (xy 414.4772 -58.380376)
			(xy 414.4772 -58.447432) (xy 414.477542 -58.45645) (xy 414.4838 -58.473367) (xy 414.489392 -58.480452)
			(xy 414.489646 -58.480452) (xy 414.489646 -58.480706) (xy 414.507293 -58.501632) (xy 414.537005 -58.547606)
			(xy 414.559841 -58.597355) (xy 414.57533 -58.649857) (xy 414.583154 -58.704034) (xy 414.583626 -58.731404)
			(xy 414.58314 -58.758655) (xy 414.575384 -58.812603) (xy 414.560029 -58.864898) (xy 414.537387 -58.914475)
			(xy 414.507921 -58.960325) (xy 414.47223 -59.001516) (xy 414.431039 -59.037207) (xy 414.385189 -59.066673)
			(xy 414.335612 -59.089315) (xy 414.283317 -59.10467) (xy 414.229369 -59.112426) (xy 414.174867 -59.112426)
			(xy 414.120919 -59.10467) (xy 414.068624 -59.089315) (xy 414.019047 -59.066673) (xy 413.973197 -59.037207)
			(xy 413.932006 -59.001516) (xy 413.896315 -58.960325) (xy 413.866849 -58.914475) (xy 413.844207 -58.864898)
			(xy 413.828852 -58.812603) (xy 413.821096 -58.758655) (xy 413.82061 -58.731404) (xy 409.851092 -58.731404)
			(xy 409.835418 -58.75183) (xy 409.793038 -58.79421) (xy 409.745488 -58.830697) (xy 409.693582 -58.860664)
			(xy 409.638209 -58.8836) (xy 409.580316 -58.899113) (xy 409.520894 -58.906936) (xy 409.460958 -58.906936)
			(xy 409.401536 -58.899113) (xy 409.343643 -58.8836) (xy 409.28827 -58.860664) (xy 409.236364 -58.830697)
			(xy 409.188814 -58.79421) (xy 409.146434 -58.75183) (xy 409.109947 -58.70428) (xy 409.07998 -58.652374)
			(xy 409.057044 -58.597001) (xy 409.041531 -58.539108) (xy 409.033708 -58.479686) (xy 407.694725 -58.479686)
			(xy 407.701514 -58.531256) (xy 407.702004 -58.561224) (xy 407.701514 -58.591192) (xy 407.693691 -58.650614)
			(xy 407.678178 -58.708507) (xy 407.655242 -58.76388) (xy 407.625275 -58.815786) (xy 407.588788 -58.863336)
			(xy 407.546408 -58.905716) (xy 407.498858 -58.942203) (xy 407.446952 -58.97217) (xy 407.391579 -58.995106)
			(xy 407.333686 -59.010619) (xy 407.274264 -59.018442) (xy 407.214328 -59.018442) (xy 407.154906 -59.010619)
			(xy 407.097013 -58.995106) (xy 407.04164 -58.97217) (xy 406.989734 -58.942203) (xy 406.942184 -58.905716)
			(xy 406.899804 -58.863336) (xy 406.863317 -58.815786) (xy 406.83335 -58.76388) (xy 406.810414 -58.708507)
			(xy 406.794901 -58.650614) (xy 406.787078 -58.591192) (xy 397.047984 -58.591192) (xy 397.050724 -58.600884)
			(xy 397.057949 -58.653018) (xy 397.058388 -58.679334) (xy 397.057902 -58.706585) (xy 397.050146 -58.760533)
			(xy 397.034791 -58.812828) (xy 397.012149 -58.862405) (xy 396.982683 -58.908255) (xy 396.946992 -58.949446)
			(xy 396.905801 -58.985137) (xy 396.859951 -59.014603) (xy 396.810374 -59.037245) (xy 396.758079 -59.0526)
			(xy 396.704131 -59.060356) (xy 396.649629 -59.060356) (xy 396.595681 -59.0526) (xy 396.543386 -59.037245)
			(xy 396.493809 -59.014603) (xy 396.447959 -58.985137) (xy 396.406768 -58.949446) (xy 396.371077 -58.908255)
			(xy 396.341611 -58.862405) (xy 396.318969 -58.812828) (xy 396.303614 -58.760533) (xy 396.295858 -58.706585)
			(xy 396.295372 -58.679334) (xy 393.210178 -58.679334) (xy 393.216984 -58.689862) (xy 393.239824 -58.739605)
			(xy 393.25532 -58.792103) (xy 393.263152 -58.846276) (xy 393.263628 -58.873644) (xy 393.263142 -58.900895)
			(xy 393.255386 -58.954843) (xy 393.240031 -59.007138) (xy 393.217389 -59.056715) (xy 393.187923 -59.102565)
			(xy 393.152232 -59.143756) (xy 393.111041 -59.179447) (xy 393.065191 -59.208913) (xy 393.015614 -59.231555)
			(xy 392.963319 -59.24691) (xy 392.909371 -59.254666) (xy 392.854869 -59.254666) (xy 392.800921 -59.24691)
			(xy 392.748626 -59.231555) (xy 392.699049 -59.208913) (xy 392.653199 -59.179447) (xy 392.612008 -59.143756)
			(xy 392.576317 -59.102565) (xy 392.546851 -59.056715) (xy 392.524209 -59.007138) (xy 392.508854 -58.954843)
			(xy 392.501098 -58.900895) (xy 392.500612 -58.873644) (xy 392.501101 -58.846275) (xy 392.508913 -58.792096)
			(xy 392.524396 -58.739593) (xy 392.547233 -58.689846) (xy 392.576953 -58.643878) (xy 392.594592 -58.622946)
			(xy 392.594846 -58.622692) (xy 392.600448 -58.615616) (xy 392.606684 -58.598691) (xy 392.607038 -58.589672)
			(xy 392.607038 -58.522616) (xy 392.606665 -58.513601) (xy 392.600428 -58.496684) (xy 392.594846 -58.489596)
			(xy 392.594592 -58.489596) (xy 392.594592 -58.489342) (xy 392.576958 -58.468406) (xy 392.547246 -58.422434)
			(xy 392.524409 -58.372688) (xy 392.508917 -58.320188) (xy 392.501087 -58.266013) (xy 392.500612 -58.238644)
			(xy 392.500612 -58.23839) (xy 392.500979 -58.213442) (xy 392.507496 -58.163974) (xy 392.520419 -58.11578)
			(xy 392.539524 -58.069687) (xy 392.551666 -58.04789) (xy 392.55827 -58.03646) (xy 392.558778 -58.010806)
			(xy 392.513058 -57.923176) (xy 392.508856 -57.915696) (xy 392.496366 -57.903946) (xy 392.480685 -57.897006)
			(xy 392.472164 -57.895998) (xy 392.443976 -57.893172) (xy 392.388545 -57.881481) (xy 392.334981 -57.863038)
			(xy 392.284103 -57.838123) (xy 392.23669 -57.807119) (xy 392.193466 -57.770499) (xy 392.173968 -57.749948)
			(xy 392.167364 -57.742836) (xy 392.150346 -57.734454) (xy 392.07186 -57.728104) (xy 392.062294 -57.727719)
			(xy 392.04401 -57.733349) (xy 392.0363 -57.739026) (xy 392.015994 -57.754533) (xy 391.972051 -57.780597)
			(xy 391.925023 -57.800566) (xy 391.875752 -57.814084) (xy 391.825118 -57.820908) (xy 391.799572 -57.821322)
			(xy 391.772323 -57.820806) (xy 391.71838 -57.813046) (xy 391.666091 -57.797689) (xy 391.616519 -57.775048)
			(xy 391.570674 -57.745582) (xy 391.529489 -57.709891) (xy 391.493802 -57.668704) (xy 391.464339 -57.622856)
			(xy 391.441701 -57.573283) (xy 391.426348 -57.520992) (xy 391.418592 -57.467049) (xy 391.235257 -57.467049)
			(xy 391.239093 -57.495547) (xy 391.239502 -57.521094) (xy 391.239032 -57.548464) (xy 391.231215 -57.602643)
			(xy 391.215727 -57.655146) (xy 391.192886 -57.704893) (xy 391.163163 -57.75086) (xy 391.145522 -57.771792)
			(xy 391.145268 -57.772046) (xy 391.139694 -57.779141) (xy 391.133441 -57.796051) (xy 391.133076 -57.805066)
			(xy 391.133076 -57.872122) (xy 391.133427 -57.881139) (xy 391.139679 -57.898056) (xy 391.145268 -57.905142)
			(xy 391.145522 -57.905142) (xy 391.145522 -57.905396) (xy 391.163155 -57.926334) (xy 391.192876 -57.972302)
			(xy 391.215719 -58.022048) (xy 391.231213 -58.074549) (xy 391.239042 -58.128726) (xy 391.239042 -58.183465)
			(xy 391.231215 -58.237642) (xy 391.215722 -58.290143) (xy 391.19288 -58.33989) (xy 391.16316 -58.385858)
			(xy 391.145522 -58.406792) (xy 391.145268 -58.407046) (xy 391.139694 -58.414141) (xy 391.133441 -58.431051)
			(xy 391.133076 -58.440066) (xy 391.133076 -58.507122) (xy 391.133427 -58.516139) (xy 391.139679 -58.533056)
			(xy 391.145268 -58.540142) (xy 391.145522 -58.540142) (xy 391.145522 -58.540396) (xy 391.163176 -58.561316)
			(xy 391.192885 -58.607292) (xy 391.215718 -58.657043) (xy 391.231205 -58.709546) (xy 391.23903 -58.763724)
			(xy 391.239502 -58.791094) (xy 391.239016 -58.818345) (xy 391.23126 -58.872293) (xy 391.215905 -58.924588)
			(xy 391.193263 -58.974165) (xy 391.163797 -59.020015) (xy 391.128106 -59.061206) (xy 391.086915 -59.096897)
			(xy 391.041065 -59.126363) (xy 390.991488 -59.149005) (xy 390.939193 -59.16436) (xy 390.885245 -59.172116)
			(xy 390.830743 -59.172116) (xy 390.776795 -59.16436) (xy 390.7245 -59.149005) (xy 390.674923 -59.126363)
			(xy 390.629073 -59.096897) (xy 390.587882 -59.061206) (xy 390.552191 -59.020015) (xy 390.522725 -58.974165)
			(xy 390.500083 -58.924588) (xy 390.484728 -58.872293) (xy 390.476972 -58.818345) (xy 390.476486 -58.791094)
			(xy 390.476952 -58.763724) (xy 390.48477 -58.709545) (xy 390.50026 -58.657042) (xy 390.523101 -58.607295)
			(xy 390.552825 -58.561328) (xy 390.570466 -58.540396) (xy 390.57072 -58.540142) (xy 390.576297 -58.533049)
			(xy 390.582549 -58.516137) (xy 390.582912 -58.507122) (xy 390.582912 -58.440066) (xy 390.582569 -58.431048)
			(xy 390.576312 -58.414131) (xy 390.57072 -58.407046) (xy 390.570466 -58.407046) (xy 390.570466 -58.406792)
			(xy 390.552818 -58.385865) (xy 390.52309 -58.339897) (xy 390.500243 -58.29015) (xy 390.484745 -58.237647)
			(xy 390.476917 -58.183467) (xy 390.476917 -58.128724) (xy 390.484747 -58.074544) (xy 390.500246 -58.022041)
			(xy 390.523095 -57.972295) (xy 390.552823 -57.926328) (xy 390.570466 -57.905396) (xy 390.57072 -57.905142)
			(xy 390.576297 -57.898049) (xy 390.582549 -57.881137) (xy 390.582912 -57.872122) (xy 390.582912 -57.805066)
			(xy 390.582569 -57.796048) (xy 390.576312 -57.779131) (xy 390.57072 -57.772046) (xy 390.570466 -57.772046)
			(xy 390.570466 -57.771792) (xy 390.552804 -57.750878) (xy 390.523097 -57.7049) (xy 390.500266 -57.655148)
			(xy 390.48478 -57.602643) (xy 390.476957 -57.548464) (xy 390.476486 -57.521094) (xy 390.476881 -57.495546)
			(xy 390.483692 -57.444906) (xy 390.497204 -57.395629) (xy 390.517176 -57.348597) (xy 390.54325 -57.304654)
			(xy 390.558782 -57.284366) (xy 390.564387 -57.27662) (xy 390.570008 -57.258361) (xy 390.569704 -57.248806)
			(xy 390.563354 -57.17032) (xy 390.554972 -57.153302) (xy 390.54786 -57.146698) (xy 390.525028 -57.124951)
			(xy 390.484949 -57.076274) (xy 390.451936 -57.022554) (xy 390.426614 -56.964808) (xy 390.409464 -56.904132)
			(xy 390.40081 -56.841675) (xy 390.400286 -56.810148) (xy 388.583388 -56.810148) (xy 388.583678 -56.826404)
			(xy 388.58322 -56.853775) (xy 388.575401 -56.907954) (xy 388.55991 -56.960458) (xy 388.537067 -57.010204)
			(xy 388.50734 -57.056171) (xy 388.489698 -57.077102) (xy 388.489444 -57.077356) (xy 388.483863 -57.084446)
			(xy 388.477614 -57.10136) (xy 388.477252 -57.110376) (xy 388.477252 -57.177432) (xy 388.477582 -57.186452)
			(xy 388.483847 -57.203369) (xy 388.489444 -57.210452) (xy 388.489698 -57.210452) (xy 388.489698 -57.210706)
			(xy 388.507342 -57.231636) (xy 388.537064 -57.277605) (xy 388.559908 -57.327352) (xy 388.575403 -57.379854)
			(xy 388.58323 -57.434033) (xy 388.58323 -57.488774) (xy 388.575401 -57.542952) (xy 388.559906 -57.595454)
			(xy 388.537061 -57.6452) (xy 388.507338 -57.691169) (xy 388.489698 -57.712102) (xy 388.489444 -57.712356)
			(xy 388.483863 -57.719446) (xy 388.477614 -57.73636) (xy 388.477252 -57.745376) (xy 388.477252 -57.812432)
			(xy 388.477582 -57.821452) (xy 388.483847 -57.838369) (xy 388.489444 -57.845452) (xy 388.489698 -57.845452)
			(xy 388.489698 -57.845706) (xy 388.507342 -57.866636) (xy 388.537064 -57.912605) (xy 388.559908 -57.962352)
			(xy 388.575403 -58.014854) (xy 388.58323 -58.069033) (xy 388.58323 -58.123774) (xy 388.575401 -58.177952)
			(xy 388.559906 -58.230454) (xy 388.537061 -58.2802) (xy 388.507338 -58.326169) (xy 388.489698 -58.347102)
			(xy 388.489444 -58.347356) (xy 388.483863 -58.354446) (xy 388.477614 -58.37136) (xy 388.477252 -58.380376)
			(xy 388.477252 -58.447432) (xy 388.477582 -58.456452) (xy 388.483847 -58.473369) (xy 388.489444 -58.480452)
			(xy 388.489698 -58.480452) (xy 388.489698 -58.480706) (xy 388.507353 -58.501625) (xy 388.537063 -58.547602)
			(xy 388.559895 -58.597352) (xy 388.575383 -58.649856) (xy 388.583206 -58.704034) (xy 388.583678 -58.731404)
			(xy 388.583192 -58.758655) (xy 388.575436 -58.812603) (xy 388.560081 -58.864898) (xy 388.537439 -58.914475)
			(xy 388.507973 -58.960325) (xy 388.472282 -59.001516) (xy 388.431091 -59.037207) (xy 388.385241 -59.066673)
			(xy 388.335664 -59.089315) (xy 388.283369 -59.10467) (xy 388.229421 -59.112426) (xy 388.174919 -59.112426)
			(xy 388.120971 -59.10467) (xy 388.068676 -59.089315) (xy 388.019099 -59.066673) (xy 387.973249 -59.037207)
			(xy 387.932058 -59.001516) (xy 387.896367 -58.960325) (xy 387.866901 -58.914475) (xy 387.844259 -58.864898)
			(xy 387.828904 -58.812603) (xy 387.821148 -58.758655) (xy 387.820662 -58.731404) (xy 383.851144 -58.731404)
			(xy 383.83547 -58.75183) (xy 383.79309 -58.79421) (xy 383.74554 -58.830697) (xy 383.693634 -58.860664)
			(xy 383.638261 -58.8836) (xy 383.580368 -58.899113) (xy 383.520946 -58.906936) (xy 383.46101 -58.906936)
			(xy 383.401588 -58.899113) (xy 383.343695 -58.8836) (xy 383.288322 -58.860664) (xy 383.236416 -58.830697)
			(xy 383.188866 -58.79421) (xy 383.146486 -58.75183) (xy 383.109999 -58.70428) (xy 383.080032 -58.652374)
			(xy 383.057096 -58.597001) (xy 383.041583 -58.539108) (xy 383.03376 -58.479686) (xy 381.694777 -58.479686)
			(xy 381.701566 -58.531256) (xy 381.702056 -58.561224) (xy 381.701566 -58.591192) (xy 381.693743 -58.650614)
			(xy 381.67823 -58.708507) (xy 381.655294 -58.76388) (xy 381.625327 -58.815786) (xy 381.58884 -58.863336)
			(xy 381.54646 -58.905716) (xy 381.49891 -58.942203) (xy 381.447004 -58.97217) (xy 381.391631 -58.995106)
			(xy 381.333738 -59.010619) (xy 381.274316 -59.018442) (xy 381.21438 -59.018442) (xy 381.154958 -59.010619)
			(xy 381.097065 -58.995106) (xy 381.041692 -58.97217) (xy 380.989786 -58.942203) (xy 380.942236 -58.905716)
			(xy 380.899856 -58.863336) (xy 380.863369 -58.815786) (xy 380.833402 -58.76388) (xy 380.810466 -58.708507)
			(xy 380.794953 -58.650614) (xy 380.78713 -58.591192) (xy 371.048038 -58.591192) (xy 371.050777 -58.600883)
			(xy 371.058002 -58.653018) (xy 371.05844 -58.679334) (xy 371.057954 -58.706585) (xy 371.050198 -58.760533)
			(xy 371.034843 -58.812828) (xy 371.012201 -58.862405) (xy 370.982735 -58.908255) (xy 370.947044 -58.949446)
			(xy 370.905853 -58.985137) (xy 370.860003 -59.014603) (xy 370.810426 -59.037245) (xy 370.758131 -59.0526)
			(xy 370.704183 -59.060356) (xy 370.649681 -59.060356) (xy 370.595733 -59.0526) (xy 370.543438 -59.037245)
			(xy 370.493861 -59.014603) (xy 370.448011 -58.985137) (xy 370.40682 -58.949446) (xy 370.371129 -58.908255)
			(xy 370.341663 -58.862405) (xy 370.319021 -58.812828) (xy 370.303666 -58.760533) (xy 370.29591 -58.706585)
			(xy 370.295424 -58.679334) (xy 367.210239 -58.679334) (xy 367.217041 -58.689858) (xy 367.239879 -58.739603)
			(xy 367.255373 -58.792101) (xy 367.263204 -58.846275) (xy 367.26368 -58.873644) (xy 367.263194 -58.900895)
			(xy 367.255438 -58.954843) (xy 367.240083 -59.007138) (xy 367.217441 -59.056715) (xy 367.187975 -59.102565)
			(xy 367.152284 -59.143756) (xy 367.111093 -59.179447) (xy 367.065243 -59.208913) (xy 367.015666 -59.231555)
			(xy 366.963371 -59.24691) (xy 366.909423 -59.254666) (xy 366.854921 -59.254666) (xy 366.800973 -59.24691)
			(xy 366.748678 -59.231555) (xy 366.699101 -59.208913) (xy 366.653251 -59.179447) (xy 366.61206 -59.143756)
			(xy 366.576369 -59.102565) (xy 366.546903 -59.056715) (xy 366.524261 -59.007138) (xy 366.508906 -58.954843)
			(xy 366.50115 -58.900895) (xy 366.500664 -58.873644) (xy 366.50114 -58.846274) (xy 366.508953 -58.792095)
			(xy 366.524439 -58.739591) (xy 366.547279 -58.689844) (xy 366.577003 -58.643877) (xy 366.594644 -58.622946)
			(xy 366.594898 -58.622692) (xy 366.600494 -58.615612) (xy 366.606735 -58.59869) (xy 366.60709 -58.589672)
			(xy 366.60709 -58.522616) (xy 366.606728 -58.5136) (xy 366.600484 -58.496682) (xy 366.594898 -58.489596)
			(xy 366.594644 -58.489596) (xy 366.594644 -58.489342) (xy 366.577018 -58.468399) (xy 366.547303 -58.42243)
			(xy 366.524464 -58.372685) (xy 366.50897 -58.320187) (xy 366.501139 -58.266013) (xy 366.500664 -58.238644)
			(xy 366.500664 -58.23839) (xy 366.501037 -58.213442) (xy 366.507554 -58.163975) (xy 366.520474 -58.115781)
			(xy 366.539577 -58.069688) (xy 366.551718 -58.04789) (xy 366.558322 -58.03646) (xy 366.55883 -58.010806)
			(xy 366.51311 -57.923176) (xy 366.508877 -57.915717) (xy 366.4964 -57.903964) (xy 366.480732 -57.897014)
			(xy 366.472216 -57.895998) (xy 366.444025 -57.8932) (xy 366.388593 -57.881504) (xy 366.335029 -57.863055)
			(xy 366.284151 -57.838135) (xy 366.236739 -57.807125) (xy 366.193517 -57.770501) (xy 366.17402 -57.749948)
			(xy 366.167416 -57.742836) (xy 366.150398 -57.734454) (xy 366.071912 -57.728104) (xy 366.062347 -57.727746)
			(xy 366.044064 -57.733357) (xy 366.036352 -57.739026) (xy 366.016062 -57.754555) (xy 365.972114 -57.780615)
			(xy 365.925082 -57.80058) (xy 365.875808 -57.814093) (xy 365.825171 -57.820912) (xy 365.799624 -57.821322)
			(xy 365.772371 -57.820832) (xy 365.718419 -57.813078) (xy 365.666121 -57.797725) (xy 365.616539 -57.775085)
			(xy 365.570685 -57.745618) (xy 365.529491 -57.709926) (xy 365.493796 -57.668734) (xy 365.464327 -57.622882)
			(xy 365.441683 -57.573302) (xy 365.426327 -57.521004) (xy 365.418569 -57.467053) (xy 365.23531 -57.467053)
			(xy 365.239145 -57.495547) (xy 365.239554 -57.521094) (xy 365.239096 -57.548465) (xy 365.231278 -57.602645)
			(xy 365.215787 -57.655148) (xy 365.192944 -57.704895) (xy 365.163217 -57.750861) (xy 365.145574 -57.771792)
			(xy 365.14532 -57.772046) (xy 365.139741 -57.779137) (xy 365.133492 -57.796051) (xy 365.133128 -57.805066)
			(xy 365.133128 -57.872122) (xy 365.133468 -57.881141) (xy 365.139727 -57.898058) (xy 365.14532 -57.905142)
			(xy 365.145574 -57.905142) (xy 365.145574 -57.905396) (xy 365.163209 -57.926334) (xy 365.192934 -57.9723)
			(xy 365.215779 -58.022046) (xy 365.231276 -58.074547) (xy 365.239105 -58.128725) (xy 365.239106 -58.183466)
			(xy 365.231278 -58.237644) (xy 365.215783 -58.290146) (xy 365.192938 -58.339892) (xy 365.163214 -58.385859)
			(xy 365.145574 -58.406792) (xy 365.14532 -58.407046) (xy 365.139741 -58.414137) (xy 365.133492 -58.431051)
			(xy 365.133128 -58.440066) (xy 365.133128 -58.507122) (xy 365.133468 -58.516141) (xy 365.139727 -58.533058)
			(xy 365.14532 -58.540142) (xy 365.145574 -58.540142) (xy 365.145574 -58.540396) (xy 365.163221 -58.561322)
			(xy 365.192932 -58.607296) (xy 365.215767 -58.657045) (xy 365.231256 -58.709547) (xy 365.239082 -58.763724)
			(xy 365.239554 -58.791094) (xy 365.239068 -58.818345) (xy 365.231312 -58.872293) (xy 365.215957 -58.924588)
			(xy 365.193315 -58.974165) (xy 365.163849 -59.020015) (xy 365.128158 -59.061206) (xy 365.086967 -59.096897)
			(xy 365.041117 -59.126363) (xy 364.99154 -59.149005) (xy 364.939245 -59.16436) (xy 364.885297 -59.172116)
			(xy 364.830795 -59.172116) (xy 364.776847 -59.16436) (xy 364.724552 -59.149005) (xy 364.674975 -59.126363)
			(xy 364.629125 -59.096897) (xy 364.587934 -59.061206) (xy 364.552243 -59.020015) (xy 364.522777 -58.974165)
			(xy 364.500135 -58.924588) (xy 364.48478 -58.872293) (xy 364.477024 -58.818345) (xy 364.476538 -58.791094)
			(xy 364.476991 -58.763723) (xy 364.484811 -58.709543) (xy 364.500302 -58.65704) (xy 364.523147 -58.607293)
			(xy 364.552875 -58.561327) (xy 364.570518 -58.540396) (xy 364.570772 -58.540142) (xy 364.576356 -58.533054)
			(xy 364.582602 -58.516138) (xy 364.582964 -58.507122) (xy 364.582964 -58.440066) (xy 364.582631 -58.431047)
			(xy 364.576368 -58.414129) (xy 364.570772 -58.407046) (xy 364.570518 -58.407046) (xy 364.570518 -58.406792)
			(xy 364.552872 -58.385864) (xy 364.523148 -58.339895) (xy 364.500303 -58.290148) (xy 364.484808 -58.237645)
			(xy 364.47698 -58.183466) (xy 364.476981 -58.128725) (xy 364.48481 -58.074546) (xy 364.500307 -58.022044)
			(xy 364.523152 -57.972297) (xy 364.552877 -57.926329) (xy 364.570518 -57.905396) (xy 364.570772 -57.905142)
			(xy 364.576356 -57.898054) (xy 364.582602 -57.881138) (xy 364.582964 -57.872122) (xy 364.582964 -57.805066)
			(xy 364.582631 -57.796047) (xy 364.576368 -57.779129) (xy 364.570772 -57.772046) (xy 364.570518 -57.772046)
			(xy 364.570518 -57.771792) (xy 364.552864 -57.750871) (xy 364.523154 -57.704896) (xy 364.500321 -57.655145)
			(xy 364.484833 -57.602642) (xy 364.477009 -57.548464) (xy 364.476538 -57.521094) (xy 364.476922 -57.495545)
			(xy 364.483734 -57.444904) (xy 364.497248 -57.395627) (xy 364.517223 -57.348596) (xy 364.5433 -57.304654)
			(xy 364.558834 -57.284366) (xy 364.564434 -57.276617) (xy 364.570059 -57.258361) (xy 364.569756 -57.248806)
			(xy 364.563406 -57.17032) (xy 364.555024 -57.153302) (xy 364.547912 -57.146698) (xy 364.52509 -57.124941)
			(xy 364.485008 -57.076268) (xy 364.451992 -57.02255) (xy 364.426668 -56.964806) (xy 364.409517 -56.904131)
			(xy 364.400862 -56.841674) (xy 364.400338 -56.810148) (xy 362.58344 -56.810148) (xy 362.58373 -56.826404)
			(xy 362.583283 -56.853775) (xy 362.575463 -56.907956) (xy 362.559971 -56.96046) (xy 362.537124 -57.010206)
			(xy 362.507394 -57.056172) (xy 362.48975 -57.077102) (xy 362.489496 -57.077356) (xy 362.483921 -57.084451)
			(xy 362.477668 -57.101361) (xy 362.477304 -57.110376) (xy 362.477304 -57.177432) (xy 362.477645 -57.186451)
			(xy 362.483904 -57.203367) (xy 362.489496 -57.210452) (xy 362.48975 -57.210452) (xy 362.48975 -57.210706)
			(xy 362.507396 -57.231635) (xy 362.537122 -57.277603) (xy 362.559968 -57.32735) (xy 362.575465 -57.379853)
			(xy 362.583294 -57.434032) (xy 362.583294 -57.488774) (xy 362.575464 -57.542953) (xy 362.559966 -57.595456)
			(xy 362.537119 -57.645202) (xy 362.507392 -57.69117) (xy 362.48975 -57.712102) (xy 362.489496 -57.712356)
			(xy 362.483921 -57.719451) (xy 362.477668 -57.736361) (xy 362.477304 -57.745376) (xy 362.477304 -57.812432)
			(xy 362.477645 -57.821451) (xy 362.483904 -57.838367) (xy 362.489496 -57.845452) (xy 362.48975 -57.845452)
			(xy 362.48975 -57.845706) (xy 362.507396 -57.866635) (xy 362.537122 -57.912603) (xy 362.559968 -57.96235)
			(xy 362.575465 -58.014853) (xy 362.583294 -58.069032) (xy 362.583294 -58.123774) (xy 362.575464 -58.177953)
			(xy 362.559966 -58.230456) (xy 362.537119 -58.280202) (xy 362.507392 -58.32617) (xy 362.48975 -58.347102)
			(xy 362.489496 -58.347356) (xy 362.483921 -58.354451) (xy 362.477668 -58.371361) (xy 362.477304 -58.380376)
			(xy 362.477304 -58.447432) (xy 362.477645 -58.456451) (xy 362.483904 -58.473367) (xy 362.489496 -58.480452)
			(xy 362.48975 -58.480452) (xy 362.48975 -58.480706) (xy 362.507398 -58.501631) (xy 362.53711 -58.547605)
			(xy 362.559945 -58.597354) (xy 362.575434 -58.649857) (xy 362.583258 -58.704034) (xy 362.58373 -58.731404)
			(xy 362.583244 -58.758655) (xy 362.575488 -58.812603) (xy 362.560133 -58.864898) (xy 362.537491 -58.914475)
			(xy 362.508025 -58.960325) (xy 362.472334 -59.001516) (xy 362.431143 -59.037207) (xy 362.385293 -59.066673)
			(xy 362.335716 -59.089315) (xy 362.283421 -59.10467) (xy 362.229473 -59.112426) (xy 362.174971 -59.112426)
			(xy 362.121023 -59.10467) (xy 362.068728 -59.089315) (xy 362.019151 -59.066673) (xy 361.973301 -59.037207)
			(xy 361.93211 -59.001516) (xy 361.896419 -58.960325) (xy 361.866953 -58.914475) (xy 361.844311 -58.864898)
			(xy 361.828956 -58.812603) (xy 361.8212 -58.758655) (xy 361.820714 -58.731404) (xy 357.851196 -58.731404)
			(xy 357.835522 -58.75183) (xy 357.793142 -58.79421) (xy 357.745592 -58.830697) (xy 357.693686 -58.860664)
			(xy 357.638313 -58.8836) (xy 357.58042 -58.899113) (xy 357.520998 -58.906936) (xy 357.461062 -58.906936)
			(xy 357.40164 -58.899113) (xy 357.343747 -58.8836) (xy 357.288374 -58.860664) (xy 357.236468 -58.830697)
			(xy 357.188918 -58.79421) (xy 357.146538 -58.75183) (xy 357.110051 -58.70428) (xy 357.080084 -58.652374)
			(xy 357.057148 -58.597001) (xy 357.041635 -58.539108) (xy 357.033812 -58.479686) (xy 355.694829 -58.479686)
			(xy 355.701618 -58.531256) (xy 355.702108 -58.561224) (xy 355.701618 -58.591192) (xy 355.693795 -58.650614)
			(xy 355.678282 -58.708507) (xy 355.655346 -58.76388) (xy 355.625379 -58.815786) (xy 355.588892 -58.863336)
			(xy 355.546512 -58.905716) (xy 355.498962 -58.942203) (xy 355.447056 -58.97217) (xy 355.391683 -58.995106)
			(xy 355.33379 -59.010619) (xy 355.274368 -59.018442) (xy 355.214432 -59.018442) (xy 355.15501 -59.010619)
			(xy 355.097117 -58.995106) (xy 355.041744 -58.97217) (xy 354.989838 -58.942203) (xy 354.942288 -58.905716)
			(xy 354.899908 -58.863336) (xy 354.863421 -58.815786) (xy 354.833454 -58.76388) (xy 354.810518 -58.708507)
			(xy 354.795005 -58.650614) (xy 354.787182 -58.591192) (xy 333.026058 -58.591192) (xy 333.033863 -58.647553)
			(xy 333.034386 -58.67908) (xy 333.034386 -58.679334) (xy 333.033896 -58.709302) (xy 333.026073 -58.768724)
			(xy 333.01056 -58.826617) (xy 332.987624 -58.88199) (xy 332.957657 -58.933896) (xy 332.92117 -58.981446)
			(xy 332.87879 -59.023826) (xy 332.83124 -59.060313) (xy 332.779334 -59.09028) (xy 332.723961 -59.113216)
			(xy 332.666068 -59.128729) (xy 332.606646 -59.136552) (xy 332.54671 -59.136552) (xy 332.487288 -59.128729)
			(xy 332.429395 -59.113216) (xy 332.374022 -59.09028) (xy 332.322116 -59.060313) (xy 332.274566 -59.023826)
			(xy 332.232186 -58.981446) (xy 332.195699 -58.933896) (xy 332.165732 -58.88199) (xy 332.142796 -58.826617)
			(xy 332.127283 -58.768724) (xy 332.11946 -58.709302) (xy 332.11897 -58.679334) (xy 329.109976 -58.679334)
			(xy 329.116782 -58.689862) (xy 329.139622 -58.739605) (xy 329.155118 -58.792103) (xy 329.16295 -58.846276)
			(xy 329.163426 -58.873644) (xy 329.16294 -58.900895) (xy 329.155184 -58.954843) (xy 329.139829 -59.007138)
			(xy 329.117187 -59.056715) (xy 329.087721 -59.102565) (xy 329.05203 -59.143756) (xy 329.010839 -59.179447)
			(xy 328.964989 -59.208913) (xy 328.915412 -59.231555) (xy 328.863117 -59.24691) (xy 328.809169 -59.254666)
			(xy 328.754667 -59.254666) (xy 328.700719 -59.24691) (xy 328.648424 -59.231555) (xy 328.598847 -59.208913)
			(xy 328.552997 -59.179447) (xy 328.511806 -59.143756) (xy 328.476115 -59.102565) (xy 328.446649 -59.056715)
			(xy 328.424007 -59.007138) (xy 328.408652 -58.954843) (xy 328.400896 -58.900895) (xy 328.40041 -58.873644)
			(xy 328.400899 -58.846275) (xy 328.408711 -58.792096) (xy 328.424195 -58.739593) (xy 328.447031 -58.689846)
			(xy 328.476751 -58.643878) (xy 328.49439 -58.622946) (xy 328.494644 -58.622692) (xy 328.500245 -58.615616)
			(xy 328.506482 -58.598691) (xy 328.506836 -58.589672) (xy 328.506836 -58.522616) (xy 328.506463 -58.513601)
			(xy 328.500226 -58.496684) (xy 328.494644 -58.489596) (xy 328.49439 -58.489596) (xy 328.49439 -58.489342)
			(xy 328.476756 -58.468406) (xy 328.447043 -58.422434) (xy 328.424207 -58.372688) (xy 328.408715 -58.320188)
			(xy 328.400885 -58.266013) (xy 328.40041 -58.238644) (xy 328.40041 -58.23839) (xy 328.400777 -58.213442)
			(xy 328.407295 -58.163974) (xy 328.420217 -58.11578) (xy 328.439322 -58.069687) (xy 328.451464 -58.04789)
			(xy 328.458068 -58.03646) (xy 328.458576 -58.010806) (xy 328.412856 -57.923176) (xy 328.408656 -57.915695)
			(xy 328.396165 -57.903946) (xy 328.380484 -57.897006) (xy 328.371962 -57.895998) (xy 328.343774 -57.893173)
			(xy 328.288343 -57.881482) (xy 328.234779 -57.863039) (xy 328.183901 -57.838124) (xy 328.136487 -57.807119)
			(xy 328.093264 -57.770499) (xy 328.073766 -57.749948) (xy 328.067162 -57.742836) (xy 328.050144 -57.734454)
			(xy 327.971658 -57.728104) (xy 327.962092 -57.727717) (xy 327.943808 -57.733349) (xy 327.936098 -57.739026)
			(xy 327.915793 -57.754534) (xy 327.871849 -57.780597) (xy 327.824821 -57.800566) (xy 327.77555 -57.814084)
			(xy 327.724916 -57.820909) (xy 327.69937 -57.821322) (xy 327.672121 -57.820806) (xy 327.618179 -57.813046)
			(xy 327.56589 -57.797689) (xy 327.516318 -57.775047) (xy 327.470473 -57.745581) (xy 327.429288 -57.709891)
			(xy 327.393601 -57.668703) (xy 327.364139 -57.622856) (xy 327.341501 -57.573282) (xy 327.326148 -57.520992)
			(xy 327.318392 -57.467049) (xy 327.135055 -57.467049) (xy 327.138891 -57.495547) (xy 327.1393 -57.521094)
			(xy 327.13883 -57.548464) (xy 327.131013 -57.602643) (xy 327.115525 -57.655146) (xy 327.092684 -57.704893)
			(xy 327.062961 -57.75086) (xy 327.04532 -57.771792) (xy 327.045066 -57.772046) (xy 327.039492 -57.779141)
			(xy 327.033239 -57.796051) (xy 327.032874 -57.805066) (xy 327.032874 -57.872122) (xy 327.033226 -57.881139)
			(xy 327.039478 -57.898056) (xy 327.045066 -57.905142) (xy 327.04532 -57.905142) (xy 327.04532 -57.905396)
			(xy 327.062953 -57.926334) (xy 327.092674 -57.972302) (xy 327.115517 -58.022048) (xy 327.131012 -58.074549)
			(xy 327.13884 -58.128726) (xy 327.138841 -58.183465) (xy 327.131014 -58.237642) (xy 327.11552 -58.290144)
			(xy 327.092679 -58.33989) (xy 327.062958 -58.385858) (xy 327.04532 -58.406792) (xy 327.045066 -58.407046)
			(xy 327.039492 -58.414141) (xy 327.033239 -58.431051) (xy 327.032874 -58.440066) (xy 327.032874 -58.507122)
			(xy 327.033226 -58.516139) (xy 327.039478 -58.533056) (xy 327.045066 -58.540142) (xy 327.04532 -58.540142)
			(xy 327.04532 -58.540396) (xy 327.062974 -58.561316) (xy 327.092683 -58.607293) (xy 327.115516 -58.657043)
			(xy 327.131003 -58.709546) (xy 327.138828 -58.763724) (xy 327.1393 -58.791094) (xy 327.138814 -58.818345)
			(xy 327.131058 -58.872293) (xy 327.115703 -58.924588) (xy 327.093061 -58.974165) (xy 327.063595 -59.020015)
			(xy 327.027904 -59.061206) (xy 326.986713 -59.096897) (xy 326.940863 -59.126363) (xy 326.891286 -59.149005)
			(xy 326.838991 -59.16436) (xy 326.785043 -59.172116) (xy 326.730541 -59.172116) (xy 326.676593 -59.16436)
			(xy 326.624298 -59.149005) (xy 326.574721 -59.126363) (xy 326.528871 -59.096897) (xy 326.48768 -59.061206)
			(xy 326.451989 -59.020015) (xy 326.422523 -58.974165) (xy 326.399881 -58.924588) (xy 326.384526 -58.872293)
			(xy 326.37677 -58.818345) (xy 326.376284 -58.791094) (xy 326.376726 -58.763723) (xy 326.384547 -58.709542)
			(xy 326.40004 -58.657038) (xy 326.422888 -58.607291) (xy 326.452619 -58.561326) (xy 326.470264 -58.540396)
			(xy 326.470518 -58.540142) (xy 326.476095 -58.533049) (xy 326.482347 -58.516137) (xy 326.48271 -58.507122)
			(xy 326.48271 -58.440066) (xy 326.482367 -58.431048) (xy 326.47611 -58.414131) (xy 326.470518 -58.407046)
			(xy 326.470264 -58.407046) (xy 326.470264 -58.406792) (xy 326.452616 -58.385865) (xy 326.422889 -58.339897)
			(xy 326.400041 -58.29015) (xy 326.384544 -58.237647) (xy 326.376715 -58.183467) (xy 326.376716 -58.128724)
			(xy 326.384546 -58.074544) (xy 326.400044 -58.022042) (xy 326.422893 -57.972295) (xy 326.452621 -57.926328)
			(xy 326.470264 -57.905396) (xy 326.470518 -57.905142) (xy 326.476095 -57.898049) (xy 326.482347 -57.881137)
			(xy 326.48271 -57.872122) (xy 326.48271 -57.805066) (xy 326.482367 -57.796048) (xy 326.47611 -57.779131)
			(xy 326.470518 -57.772046) (xy 326.470264 -57.772046) (xy 326.470264 -57.771792) (xy 326.452602 -57.750878)
			(xy 326.422895 -57.7049) (xy 326.400064 -57.655148) (xy 326.384578 -57.602643) (xy 326.376755 -57.548464)
			(xy 326.376284 -57.521094) (xy 326.376679 -57.495546) (xy 326.38349 -57.444906) (xy 326.397002 -57.395629)
			(xy 326.416974 -57.348597) (xy 326.443048 -57.304654) (xy 326.45858 -57.284366) (xy 326.464185 -57.27662)
			(xy 326.469806 -57.258361) (xy 326.469502 -57.248806) (xy 326.463152 -57.17032) (xy 326.45477 -57.153302)
			(xy 326.447658 -57.146698) (xy 326.424826 -57.124951) (xy 326.384747 -57.076275) (xy 326.351734 -57.022554)
			(xy 326.326412 -56.964808) (xy 326.309262 -56.904132) (xy 326.300608 -56.841675) (xy 326.300084 -56.810148)
			(xy 324.483186 -56.810148) (xy 324.483476 -56.826404) (xy 324.483018 -56.853775) (xy 324.475199 -56.907954)
			(xy 324.459709 -56.960458) (xy 324.436865 -57.010204) (xy 324.407138 -57.056171) (xy 324.389496 -57.077102)
			(xy 324.389242 -57.077356) (xy 324.383661 -57.084446) (xy 324.377412 -57.10136) (xy 324.37705 -57.110376)
			(xy 324.37705 -57.177432) (xy 324.377381 -57.186452) (xy 324.383645 -57.203369) (xy 324.389242 -57.210452)
			(xy 324.389496 -57.210452) (xy 324.389496 -57.210706) (xy 324.40714 -57.231636) (xy 324.436863 -57.277605)
			(xy 324.459706 -57.327352) (xy 324.475201 -57.379854) (xy 324.483029 -57.434032) (xy 324.483029 -57.488774)
			(xy 324.4752 -57.542952) (xy 324.459704 -57.595454) (xy 324.43686 -57.6452) (xy 324.407136 -57.691169)
			(xy 324.389496 -57.712102) (xy 324.389242 -57.712356) (xy 324.383661 -57.719446) (xy 324.377412 -57.73636)
			(xy 324.37705 -57.745376) (xy 324.37705 -57.812432) (xy 324.377381 -57.821452) (xy 324.383645 -57.838369)
			(xy 324.389242 -57.845452) (xy 324.389496 -57.845452) (xy 324.389496 -57.845706) (xy 324.40714 -57.866636)
			(xy 324.436863 -57.912605) (xy 324.459706 -57.962352) (xy 324.475201 -58.014854) (xy 324.483029 -58.069032)
			(xy 324.483029 -58.123774) (xy 324.4752 -58.177952) (xy 324.459704 -58.230454) (xy 324.43686 -58.2802)
			(xy 324.407136 -58.326169) (xy 324.389496 -58.347102) (xy 324.389242 -58.347356) (xy 324.383661 -58.354446)
			(xy 324.377412 -58.37136) (xy 324.37705 -58.380376) (xy 324.37705 -58.447432) (xy 324.377381 -58.456452)
			(xy 324.383645 -58.473369) (xy 324.389242 -58.480452) (xy 324.389496 -58.480452) (xy 324.389496 -58.480706)
			(xy 324.407151 -58.501625) (xy 324.43686 -58.547602) (xy 324.459693 -58.597352) (xy 324.475181 -58.649856)
			(xy 324.483004 -58.704034) (xy 324.483476 -58.731404) (xy 324.48299 -58.758655) (xy 324.475234 -58.812603)
			(xy 324.459879 -58.864898) (xy 324.437237 -58.914475) (xy 324.407771 -58.960325) (xy 324.37208 -59.001516)
			(xy 324.330889 -59.037207) (xy 324.285039 -59.066673) (xy 324.235462 -59.089315) (xy 324.183167 -59.10467)
			(xy 324.129219 -59.112426) (xy 324.074717 -59.112426) (xy 324.020769 -59.10467) (xy 323.968474 -59.089315)
			(xy 323.918897 -59.066673) (xy 323.873047 -59.037207) (xy 323.831856 -59.001516) (xy 323.796165 -58.960325)
			(xy 323.766699 -58.914475) (xy 323.744057 -58.864898) (xy 323.728702 -58.812603) (xy 323.720946 -58.758655)
			(xy 323.72046 -58.731404) (xy 319.750942 -58.731404) (xy 319.735268 -58.75183) (xy 319.692888 -58.79421)
			(xy 319.645338 -58.830697) (xy 319.593432 -58.860664) (xy 319.538059 -58.8836) (xy 319.480166 -58.899113)
			(xy 319.420744 -58.906936) (xy 319.360808 -58.906936) (xy 319.301386 -58.899113) (xy 319.243493 -58.8836)
			(xy 319.18812 -58.860664) (xy 319.136214 -58.830697) (xy 319.088664 -58.79421) (xy 319.046284 -58.75183)
			(xy 319.009797 -58.70428) (xy 318.97983 -58.652374) (xy 318.956894 -58.597001) (xy 318.941381 -58.539108)
			(xy 318.933558 -58.479686) (xy 317.594575 -58.479686) (xy 317.601364 -58.531256) (xy 317.601854 -58.561224)
			(xy 317.601364 -58.591192) (xy 317.593541 -58.650614) (xy 317.578028 -58.708507) (xy 317.555092 -58.76388)
			(xy 317.525125 -58.815786) (xy 317.488638 -58.863336) (xy 317.446258 -58.905716) (xy 317.398708 -58.942203)
			(xy 317.346802 -58.97217) (xy 317.291429 -58.995106) (xy 317.233536 -59.010619) (xy 317.174114 -59.018442)
			(xy 317.114178 -59.018442) (xy 317.054756 -59.010619) (xy 316.996863 -58.995106) (xy 316.94149 -58.97217)
			(xy 316.889584 -58.942203) (xy 316.842034 -58.905716) (xy 316.799654 -58.863336) (xy 316.763167 -58.815786)
			(xy 316.7332 -58.76388) (xy 316.710264 -58.708507) (xy 316.694751 -58.650614) (xy 316.686928 -58.591192)
			(xy 306.947836 -58.591192) (xy 306.950575 -58.600883) (xy 306.9578 -58.653018) (xy 306.958238 -58.679334)
			(xy 306.957752 -58.706585) (xy 306.949996 -58.760533) (xy 306.934641 -58.812828) (xy 306.911999 -58.862405)
			(xy 306.882533 -58.908255) (xy 306.846842 -58.949446) (xy 306.805651 -58.985137) (xy 306.759801 -59.014603)
			(xy 306.710224 -59.037245) (xy 306.657929 -59.0526) (xy 306.603981 -59.060356) (xy 306.549479 -59.060356)
			(xy 306.495531 -59.0526) (xy 306.443236 -59.037245) (xy 306.393659 -59.014603) (xy 306.347809 -58.985137)
			(xy 306.306618 -58.949446) (xy 306.270927 -58.908255) (xy 306.241461 -58.862405) (xy 306.218819 -58.812828)
			(xy 306.203464 -58.760533) (xy 306.195708 -58.706585) (xy 306.195222 -58.679334) (xy 303.110037 -58.679334)
			(xy 303.116839 -58.689858) (xy 303.139677 -58.739603) (xy 303.155171 -58.792101) (xy 303.163002 -58.846275)
			(xy 303.163478 -58.873644) (xy 303.162992 -58.900895) (xy 303.155236 -58.954843) (xy 303.139881 -59.007138)
			(xy 303.117239 -59.056715) (xy 303.087773 -59.102565) (xy 303.052082 -59.143756) (xy 303.010891 -59.179447)
			(xy 302.965041 -59.208913) (xy 302.915464 -59.231555) (xy 302.863169 -59.24691) (xy 302.809221 -59.254666)
			(xy 302.754719 -59.254666) (xy 302.700771 -59.24691) (xy 302.648476 -59.231555) (xy 302.598899 -59.208913)
			(xy 302.553049 -59.179447) (xy 302.511858 -59.143756) (xy 302.476167 -59.102565) (xy 302.446701 -59.056715)
			(xy 302.424059 -59.007138) (xy 302.408704 -58.954843) (xy 302.400948 -58.900895) (xy 302.400462 -58.873644)
			(xy 302.400939 -58.846274) (xy 302.408752 -58.792095) (xy 302.424237 -58.739591) (xy 302.447077 -58.689844)
			(xy 302.476801 -58.643877) (xy 302.494442 -58.622946) (xy 302.494696 -58.622692) (xy 302.500292 -58.615612)
			(xy 302.506533 -58.59869) (xy 302.506888 -58.589672) (xy 302.506888 -58.522616) (xy 302.506526 -58.5136)
			(xy 302.500282 -58.496682) (xy 302.494696 -58.489596) (xy 302.494442 -58.489596) (xy 302.494442 -58.489342)
			(xy 302.476816 -58.4684) (xy 302.4471 -58.42243) (xy 302.424261 -58.372685) (xy 302.408767 -58.320187)
			(xy 302.400937 -58.266013) (xy 302.400462 -58.238644) (xy 302.400462 -58.23839) (xy 302.400835 -58.213442)
			(xy 302.407352 -58.163975) (xy 302.420272 -58.115781) (xy 302.439375 -58.069688) (xy 302.451516 -58.04789)
			(xy 302.45812 -58.03646) (xy 302.458628 -58.010806) (xy 302.412908 -57.923176) (xy 302.408676 -57.915716)
			(xy 302.396199 -57.903963) (xy 302.380531 -57.897013) (xy 302.372014 -57.895998) (xy 302.343823 -57.893201)
			(xy 302.288391 -57.881505) (xy 302.234827 -57.863055) (xy 302.183949 -57.838135) (xy 302.136537 -57.807126)
			(xy 302.093315 -57.770501) (xy 302.073818 -57.749948) (xy 302.067214 -57.742836) (xy 302.050196 -57.734454)
			(xy 301.97171 -57.728104) (xy 301.962145 -57.727745) (xy 301.943862 -57.733357) (xy 301.93615 -57.739026)
			(xy 301.915861 -57.754556) (xy 301.871913 -57.780616) (xy 301.824881 -57.800581) (xy 301.775606 -57.814093)
			(xy 301.724969 -57.820912) (xy 301.699422 -57.821322) (xy 301.672169 -57.820832) (xy 301.618218 -57.813078)
			(xy 301.565919 -57.797724) (xy 301.516338 -57.775084) (xy 301.470484 -57.745618) (xy 301.42929 -57.709925)
			(xy 301.393595 -57.668734) (xy 301.364126 -57.622881) (xy 301.341483 -57.573301) (xy 301.326127 -57.521004)
			(xy 301.318369 -57.467053) (xy 301.135108 -57.467053) (xy 301.138943 -57.495547) (xy 301.139352 -57.521094)
			(xy 301.138894 -57.548465) (xy 301.131076 -57.602645) (xy 301.115586 -57.655148) (xy 301.092742 -57.704895)
			(xy 301.063015 -57.750861) (xy 301.045372 -57.771792) (xy 301.045118 -57.772046) (xy 301.03955 -57.779146)
			(xy 301.033292 -57.796052) (xy 301.032926 -57.805066) (xy 301.032926 -57.872122) (xy 301.033267 -57.881141)
			(xy 301.039525 -57.898058) (xy 301.045118 -57.905142) (xy 301.045372 -57.905142) (xy 301.045372 -57.905396)
			(xy 301.063007 -57.926333) (xy 301.092732 -57.9723) (xy 301.115578 -58.022046) (xy 301.131075 -58.074547)
			(xy 301.138904 -58.128725) (xy 301.138904 -58.183466) (xy 301.131076 -58.237644) (xy 301.115581 -58.290146)
			(xy 301.092736 -58.339892) (xy 301.063012 -58.385859) (xy 301.045372 -58.406792) (xy 301.045118 -58.407046)
			(xy 301.03955 -58.414146) (xy 301.033292 -58.431052) (xy 301.032926 -58.440066) (xy 301.032926 -58.507122)
			(xy 301.033267 -58.516141) (xy 301.039525 -58.533058) (xy 301.045118 -58.540142) (xy 301.045372 -58.540142)
			(xy 301.045372 -58.540396) (xy 301.063018 -58.561322) (xy 301.09273 -58.607296) (xy 301.115565 -58.657045)
			(xy 301.131054 -58.709547) (xy 301.13888 -58.763724) (xy 301.139352 -58.791094) (xy 301.138866 -58.818345)
			(xy 301.13111 -58.872293) (xy 301.115755 -58.924588) (xy 301.093113 -58.974165) (xy 301.063647 -59.020015)
			(xy 301.027956 -59.061206) (xy 300.986765 -59.096897) (xy 300.940915 -59.126363) (xy 300.891338 -59.149005)
			(xy 300.839043 -59.16436) (xy 300.785095 -59.172116) (xy 300.730593 -59.172116) (xy 300.676645 -59.16436)
			(xy 300.62435 -59.149005) (xy 300.574773 -59.126363) (xy 300.528923 -59.096897) (xy 300.487732 -59.061206)
			(xy 300.452041 -59.020015) (xy 300.422575 -58.974165) (xy 300.399933 -58.924588) (xy 300.384578 -58.872293)
			(xy 300.376822 -58.818345) (xy 300.376336 -58.791094) (xy 300.37679 -58.763723) (xy 300.384609 -58.709543)
			(xy 300.400101 -58.65704) (xy 300.422945 -58.607293) (xy 300.452673 -58.561327) (xy 300.470316 -58.540396)
			(xy 300.47057 -58.540142) (xy 300.476153 -58.533054) (xy 300.4824 -58.516138) (xy 300.482762 -58.507122)
			(xy 300.482762 -58.440066) (xy 300.48243 -58.431046) (xy 300.476166 -58.414129) (xy 300.47057 -58.407046)
			(xy 300.470316 -58.407046) (xy 300.470316 -58.406792) (xy 300.45267 -58.385864) (xy 300.422946 -58.339895)
			(xy 300.400102 -58.290148) (xy 300.384607 -58.237645) (xy 300.376779 -58.183466) (xy 300.376779 -58.128725)
			(xy 300.384608 -58.074546) (xy 300.400105 -58.022044) (xy 300.422951 -57.972297) (xy 300.452675 -57.926329)
			(xy 300.470316 -57.905396) (xy 300.47057 -57.905142) (xy 300.476153 -57.898054) (xy 300.4824 -57.881138)
			(xy 300.482762 -57.872122) (xy 300.482762 -57.805066) (xy 300.48243 -57.796046) (xy 300.476166 -57.779129)
			(xy 300.47057 -57.772046) (xy 300.470316 -57.772046) (xy 300.470316 -57.771792) (xy 300.452662 -57.750872)
			(xy 300.422952 -57.704896) (xy 300.400119 -57.655145) (xy 300.384631 -57.602642) (xy 300.376807 -57.548464)
			(xy 300.376336 -57.521094) (xy 300.37672 -57.495545) (xy 300.383532 -57.444904) (xy 300.397046 -57.395627)
			(xy 300.417021 -57.348596) (xy 300.443098 -57.304654) (xy 300.458632 -57.284366) (xy 300.464232 -57.276617)
			(xy 300.469857 -57.258361) (xy 300.469554 -57.248806) (xy 300.463204 -57.17032) (xy 300.454822 -57.153302)
			(xy 300.44771 -57.146698) (xy 300.424888 -57.124941) (xy 300.384806 -57.076268) (xy 300.35179 -57.02255)
			(xy 300.326466 -56.964806) (xy 300.309315 -56.904131) (xy 300.30066 -56.841674) (xy 300.300136 -56.810148)
			(xy 298.483238 -56.810148) (xy 298.483528 -56.826404) (xy 298.483082 -56.853775) (xy 298.475262 -56.907956)
			(xy 298.459769 -56.96046) (xy 298.436923 -57.010206) (xy 298.407192 -57.056172) (xy 298.389548 -57.077102)
			(xy 298.389294 -57.077356) (xy 298.383719 -57.084451) (xy 298.377466 -57.101361) (xy 298.377102 -57.110376)
			(xy 298.377102 -57.177432) (xy 298.377443 -57.18645) (xy 298.383702 -57.203367) (xy 298.389294 -57.210452)
			(xy 298.389548 -57.210452) (xy 298.389548 -57.210706) (xy 298.407194 -57.231635) (xy 298.43692 -57.277603)
			(xy 298.459767 -57.32735) (xy 298.475264 -57.379852) (xy 298.483093 -57.434032) (xy 298.483092 -57.488774)
			(xy 298.475263 -57.542953) (xy 298.459765 -57.595456) (xy 298.436917 -57.645202) (xy 298.40719 -57.69117)
			(xy 298.389548 -57.712102) (xy 298.389294 -57.712356) (xy 298.383719 -57.719451) (xy 298.377466 -57.736361)
			(xy 298.377102 -57.745376) (xy 298.377102 -57.812432) (xy 298.377443 -57.82145) (xy 298.383702 -57.838367)
			(xy 298.389294 -57.845452) (xy 298.389548 -57.845452) (xy 298.389548 -57.845706) (xy 298.407194 -57.866635)
			(xy 298.43692 -57.912603) (xy 298.459767 -57.96235) (xy 298.475264 -58.014852) (xy 298.483093 -58.069032)
			(xy 298.483092 -58.123774) (xy 298.475263 -58.177953) (xy 298.459765 -58.230456) (xy 298.436917 -58.280202)
			(xy 298.40719 -58.32617) (xy 298.389548 -58.347102) (xy 298.389294 -58.347356) (xy 298.383719 -58.354451)
			(xy 298.377466 -58.371361) (xy 298.377102 -58.380376) (xy 298.377102 -58.447432) (xy 298.377443 -58.45645)
			(xy 298.383702 -58.473367) (xy 298.389294 -58.480452) (xy 298.389548 -58.480452) (xy 298.389548 -58.480706)
			(xy 298.407195 -58.501632) (xy 298.436908 -58.547605) (xy 298.459743 -58.597354) (xy 298.475232 -58.649857)
			(xy 298.483056 -58.704034) (xy 298.483528 -58.731404) (xy 298.483042 -58.758655) (xy 298.475286 -58.812603)
			(xy 298.459931 -58.864898) (xy 298.437289 -58.914475) (xy 298.407823 -58.960325) (xy 298.372132 -59.001516)
			(xy 298.330941 -59.037207) (xy 298.285091 -59.066673) (xy 298.235514 -59.089315) (xy 298.183219 -59.10467)
			(xy 298.129271 -59.112426) (xy 298.074769 -59.112426) (xy 298.020821 -59.10467) (xy 297.968526 -59.089315)
			(xy 297.918949 -59.066673) (xy 297.873099 -59.037207) (xy 297.831908 -59.001516) (xy 297.796217 -58.960325)
			(xy 297.766751 -58.914475) (xy 297.744109 -58.864898) (xy 297.728754 -58.812603) (xy 297.720998 -58.758655)
			(xy 297.720512 -58.731404) (xy 293.750994 -58.731404) (xy 293.73532 -58.75183) (xy 293.69294 -58.79421)
			(xy 293.64539 -58.830697) (xy 293.593484 -58.860664) (xy 293.538111 -58.8836) (xy 293.480218 -58.899113)
			(xy 293.420796 -58.906936) (xy 293.36086 -58.906936) (xy 293.301438 -58.899113) (xy 293.243545 -58.8836)
			(xy 293.188172 -58.860664) (xy 293.136266 -58.830697) (xy 293.088716 -58.79421) (xy 293.046336 -58.75183)
			(xy 293.009849 -58.70428) (xy 292.979882 -58.652374) (xy 292.956946 -58.597001) (xy 292.941433 -58.539108)
			(xy 292.93361 -58.479686) (xy 291.594627 -58.479686) (xy 291.601416 -58.531256) (xy 291.601906 -58.561224)
			(xy 291.601416 -58.591192) (xy 291.593593 -58.650614) (xy 291.57808 -58.708507) (xy 291.555144 -58.76388)
			(xy 291.525177 -58.815786) (xy 291.48869 -58.863336) (xy 291.44631 -58.905716) (xy 291.39876 -58.942203)
			(xy 291.346854 -58.97217) (xy 291.291481 -58.995106) (xy 291.233588 -59.010619) (xy 291.174166 -59.018442)
			(xy 291.11423 -59.018442) (xy 291.054808 -59.010619) (xy 290.996915 -58.995106) (xy 290.941542 -58.97217)
			(xy 290.889636 -58.942203) (xy 290.842086 -58.905716) (xy 290.799706 -58.863336) (xy 290.763219 -58.815786)
			(xy 290.733252 -58.76388) (xy 290.710316 -58.708507) (xy 290.694803 -58.650614) (xy 290.68698 -58.591192)
			(xy 280.947886 -58.591192) (xy 280.950626 -58.600884) (xy 280.957851 -58.653018) (xy 280.95829 -58.679334)
			(xy 280.957804 -58.706585) (xy 280.950048 -58.760533) (xy 280.934693 -58.812828) (xy 280.912051 -58.862405)
			(xy 280.882585 -58.908255) (xy 280.846894 -58.949446) (xy 280.805703 -58.985137) (xy 280.759853 -59.014603)
			(xy 280.710276 -59.037245) (xy 280.657981 -59.0526) (xy 280.604033 -59.060356) (xy 280.549531 -59.060356)
			(xy 280.495583 -59.0526) (xy 280.443288 -59.037245) (xy 280.393711 -59.014603) (xy 280.347861 -58.985137)
			(xy 280.30667 -58.949446) (xy 280.270979 -58.908255) (xy 280.241513 -58.862405) (xy 280.218871 -58.812828)
			(xy 280.203516 -58.760533) (xy 280.19576 -58.706585) (xy 280.195274 -58.679334) (xy 277.11008 -58.679334)
			(xy 277.116886 -58.689862) (xy 277.139726 -58.739605) (xy 277.155222 -58.792102) (xy 277.163054 -58.846276)
			(xy 277.16353 -58.873644) (xy 277.163044 -58.900895) (xy 277.155288 -58.954843) (xy 277.139933 -59.007138)
			(xy 277.117291 -59.056715) (xy 277.087825 -59.102565) (xy 277.052134 -59.143756) (xy 277.010943 -59.179447)
			(xy 276.965093 -59.208913) (xy 276.915516 -59.231555) (xy 276.863221 -59.24691) (xy 276.809273 -59.254666)
			(xy 276.754771 -59.254666) (xy 276.700823 -59.24691) (xy 276.648528 -59.231555) (xy 276.598951 -59.208913)
			(xy 276.553101 -59.179447) (xy 276.51191 -59.143756) (xy 276.476219 -59.102565) (xy 276.446753 -59.056715)
			(xy 276.424111 -59.007138) (xy 276.408756 -58.954843) (xy 276.401 -58.900895) (xy 276.400514 -58.873644)
			(xy 276.401002 -58.846275) (xy 276.408814 -58.792096) (xy 276.424298 -58.739593) (xy 276.447135 -58.689846)
			(xy 276.476855 -58.643878) (xy 276.494494 -58.622946) (xy 276.494748 -58.622692) (xy 276.50035 -58.615616)
			(xy 276.506586 -58.598691) (xy 276.50694 -58.589672) (xy 276.50694 -58.522616) (xy 276.506588 -58.513598)
			(xy 276.500338 -58.496681) (xy 276.494748 -58.489596) (xy 276.494494 -58.489596) (xy 276.494494 -58.489342)
			(xy 276.47686 -58.468406) (xy 276.447148 -58.422434) (xy 276.424311 -58.372688) (xy 276.408819 -58.320188)
			(xy 276.400989 -58.266013) (xy 276.400514 -58.238644) (xy 276.400514 -58.23839) (xy 276.400881 -58.213442)
			(xy 276.407398 -58.163974) (xy 276.42032 -58.11578) (xy 276.439426 -58.069687) (xy 276.451568 -58.04789)
			(xy 276.458172 -58.03646) (xy 276.45868 -58.010806) (xy 276.41296 -57.923176) (xy 276.408757 -57.915697)
			(xy 276.396268 -57.903947) (xy 276.380587 -57.897006) (xy 276.372066 -57.895998) (xy 276.343879 -57.89317)
			(xy 276.288447 -57.88148) (xy 276.234883 -57.863037) (xy 276.184005 -57.838123) (xy 276.136592 -57.807119)
			(xy 276.093368 -57.770499) (xy 276.07387 -57.749948) (xy 276.067266 -57.742836) (xy 276.050248 -57.734454)
			(xy 275.971762 -57.728104) (xy 275.962196 -57.72772) (xy 275.943912 -57.733349) (xy 275.936202 -57.739026)
			(xy 275.915896 -57.754532) (xy 275.871952 -57.780596) (xy 275.824925 -57.800565) (xy 275.775654 -57.814083)
			(xy 275.72502 -57.820908) (xy 275.699474 -57.821322) (xy 275.672225 -57.820806) (xy 275.618282 -57.813047)
			(xy 275.565992 -57.79769) (xy 275.51642 -57.775048) (xy 275.470575 -57.745582) (xy 275.429389 -57.709892)
			(xy 275.393702 -57.668704) (xy 275.364239 -57.622857) (xy 275.341601 -57.573283) (xy 275.326248 -57.520992)
			(xy 275.318492 -57.467049) (xy 275.135159 -57.467049) (xy 275.138995 -57.495547) (xy 275.139404 -57.521094)
			(xy 275.138933 -57.548464) (xy 275.131117 -57.602643) (xy 275.115628 -57.655146) (xy 275.092788 -57.704893)
			(xy 275.063065 -57.75086) (xy 275.045424 -57.771792) (xy 275.04517 -57.772046) (xy 275.039597 -57.779141)
			(xy 275.033343 -57.796052) (xy 275.032978 -57.805066) (xy 275.032978 -57.872122) (xy 275.033329 -57.881139)
			(xy 275.039581 -57.898056) (xy 275.04517 -57.905142) (xy 275.045424 -57.905142) (xy 275.045424 -57.905396)
			(xy 275.063061 -57.926333) (xy 275.09279 -57.972298) (xy 275.115638 -58.022044) (xy 275.131137 -58.074546)
			(xy 275.138967 -58.128725) (xy 275.138968 -58.183466) (xy 275.131139 -58.237645) (xy 275.115642 -58.290148)
			(xy 275.092794 -58.339894) (xy 275.063066 -58.38586) (xy 275.045424 -58.406792) (xy 275.04517 -58.407046)
			(xy 275.039597 -58.414141) (xy 275.033343 -58.431052) (xy 275.032978 -58.440066) (xy 275.032978 -58.507122)
			(xy 275.033329 -58.516139) (xy 275.039581 -58.533056) (xy 275.04517 -58.540142) (xy 275.045424 -58.540142)
			(xy 275.045424 -58.540396) (xy 275.063078 -58.561316) (xy 275.092787 -58.607292) (xy 275.11562 -58.657043)
			(xy 275.131107 -58.709546) (xy 275.138932 -58.763724) (xy 275.139404 -58.791094) (xy 275.138918 -58.818345)
			(xy 275.131162 -58.872293) (xy 275.115807 -58.924588) (xy 275.093165 -58.974165) (xy 275.063699 -59.020015)
			(xy 275.028008 -59.061206) (xy 274.986817 -59.096897) (xy 274.940967 -59.126363) (xy 274.89139 -59.149005)
			(xy 274.839095 -59.16436) (xy 274.785147 -59.172116) (xy 274.730645 -59.172116) (xy 274.676697 -59.16436)
			(xy 274.624402 -59.149005) (xy 274.574825 -59.126363) (xy 274.528975 -59.096897) (xy 274.487784 -59.061206)
			(xy 274.452093 -59.020015) (xy 274.422627 -58.974165) (xy 274.399985 -58.924588) (xy 274.38463 -58.872293)
			(xy 274.376874 -58.818345) (xy 274.376388 -58.791094) (xy 274.376853 -58.763724) (xy 274.384672 -58.709545)
			(xy 274.400161 -58.657042) (xy 274.423003 -58.607295) (xy 274.452727 -58.561328) (xy 274.470368 -58.540396)
			(xy 274.470622 -58.540142) (xy 274.4762 -58.533049) (xy 274.482451 -58.516137) (xy 274.482814 -58.507122)
			(xy 274.482814 -58.440066) (xy 274.48247 -58.431048) (xy 274.476213 -58.414131) (xy 274.470622 -58.407046)
			(xy 274.470368 -58.407046) (xy 274.470368 -58.406792) (xy 274.45272 -58.385865) (xy 274.422992 -58.339897)
			(xy 274.400145 -58.29015) (xy 274.384647 -58.237647) (xy 274.376818 -58.183467) (xy 274.376819 -58.128724)
			(xy 274.384649 -58.074544) (xy 274.400148 -58.022041) (xy 274.422996 -57.972295) (xy 274.452725 -57.926328)
			(xy 274.470368 -57.905396) (xy 274.470622 -57.905142) (xy 274.4762 -57.898049) (xy 274.482451 -57.881137)
			(xy 274.482814 -57.872122) (xy 274.482814 -57.805066) (xy 274.48247 -57.796048) (xy 274.476213 -57.779131)
			(xy 274.470622 -57.772046) (xy 274.470368 -57.772046) (xy 274.470368 -57.771792) (xy 274.452707 -57.750878)
			(xy 274.422999 -57.7049) (xy 274.400168 -57.655148) (xy 274.384682 -57.602643) (xy 274.376859 -57.548464)
			(xy 274.376388 -57.521094) (xy 274.376782 -57.495546) (xy 274.383593 -57.444906) (xy 274.397106 -57.395629)
			(xy 274.417078 -57.348597) (xy 274.443152 -57.304654) (xy 274.458684 -57.284366) (xy 274.464289 -57.27662)
			(xy 274.46991 -57.258361) (xy 274.469606 -57.248806) (xy 274.463256 -57.17032) (xy 274.454874 -57.153302)
			(xy 274.447762 -57.146698) (xy 274.424931 -57.124951) (xy 274.384851 -57.076274) (xy 274.351838 -57.022554)
			(xy 274.326516 -56.964808) (xy 274.309366 -56.904132) (xy 274.300712 -56.841675) (xy 274.300188 -56.810148)
			(xy 272.48329 -56.810148) (xy 272.48358 -56.826404) (xy 272.483121 -56.853775) (xy 272.475302 -56.907954)
			(xy 272.459812 -56.960458) (xy 272.436968 -57.010204) (xy 272.407242 -57.056171) (xy 272.3896 -57.077102)
			(xy 272.389346 -57.077356) (xy 272.383765 -57.084446) (xy 272.377516 -57.10136) (xy 272.377154 -57.110376)
			(xy 272.377154 -57.177432) (xy 272.377484 -57.186452) (xy 272.383749 -57.203369) (xy 272.389346 -57.210452)
			(xy 272.3896 -57.210452) (xy 272.3896 -57.210706) (xy 272.407243 -57.231636) (xy 272.436966 -57.277605)
			(xy 272.45981 -57.327352) (xy 272.475304 -57.379854) (xy 272.483132 -57.434033) (xy 272.483132 -57.488773)
			(xy 272.475303 -57.542952) (xy 272.459807 -57.595454) (xy 272.436963 -57.6452) (xy 272.40724 -57.691169)
			(xy 272.3896 -57.712102) (xy 272.389346 -57.712356) (xy 272.383765 -57.719446) (xy 272.377516 -57.73636)
			(xy 272.377154 -57.745376) (xy 272.377154 -57.812432) (xy 272.377484 -57.821452) (xy 272.383749 -57.838369)
			(xy 272.389346 -57.845452) (xy 272.3896 -57.845452) (xy 272.3896 -57.845706) (xy 272.407243 -57.866636)
			(xy 272.436966 -57.912605) (xy 272.45981 -57.962352) (xy 272.475304 -58.014854) (xy 272.483132 -58.069033)
			(xy 272.483132 -58.123773) (xy 272.475303 -58.177952) (xy 272.459807 -58.230454) (xy 272.436963 -58.2802)
			(xy 272.40724 -58.326169) (xy 272.3896 -58.347102) (xy 272.389346 -58.347356) (xy 272.383765 -58.354446)
			(xy 272.377516 -58.37136) (xy 272.377154 -58.380376) (xy 272.377154 -58.447432) (xy 272.377484 -58.456452)
			(xy 272.383749 -58.473369) (xy 272.389346 -58.480452) (xy 272.3896 -58.480452) (xy 272.3896 -58.480706)
			(xy 272.407255 -58.501625) (xy 272.436965 -58.547601) (xy 272.459798 -58.597352) (xy 272.475285 -58.649856)
			(xy 272.483108 -58.704034) (xy 272.48358 -58.731404) (xy 272.483094 -58.758655) (xy 272.475338 -58.812603)
			(xy 272.459983 -58.864898) (xy 272.437341 -58.914475) (xy 272.407875 -58.960325) (xy 272.372184 -59.001516)
			(xy 272.330993 -59.037207) (xy 272.285143 -59.066673) (xy 272.235566 -59.089315) (xy 272.183271 -59.10467)
			(xy 272.129323 -59.112426) (xy 272.074821 -59.112426) (xy 272.020873 -59.10467) (xy 271.968578 -59.089315)
			(xy 271.919001 -59.066673) (xy 271.873151 -59.037207) (xy 271.83196 -59.001516) (xy 271.796269 -58.960325)
			(xy 271.766803 -58.914475) (xy 271.744161 -58.864898) (xy 271.728806 -58.812603) (xy 271.72105 -58.758655)
			(xy 271.720564 -58.731404) (xy 267.751046 -58.731404) (xy 267.735372 -58.75183) (xy 267.692992 -58.79421)
			(xy 267.645442 -58.830697) (xy 267.593536 -58.860664) (xy 267.538163 -58.8836) (xy 267.48027 -58.899113)
			(xy 267.420848 -58.906936) (xy 267.360912 -58.906936) (xy 267.30149 -58.899113) (xy 267.243597 -58.8836)
			(xy 267.188224 -58.860664) (xy 267.136318 -58.830697) (xy 267.088768 -58.79421) (xy 267.046388 -58.75183)
			(xy 267.009901 -58.70428) (xy 266.979934 -58.652374) (xy 266.956998 -58.597001) (xy 266.941485 -58.539108)
			(xy 266.933662 -58.479686) (xy 265.594679 -58.479686) (xy 265.601468 -58.531256) (xy 265.601958 -58.561224)
			(xy 265.601468 -58.591192) (xy 265.593645 -58.650614) (xy 265.578132 -58.708507) (xy 265.555196 -58.76388)
			(xy 265.525229 -58.815786) (xy 265.488742 -58.863336) (xy 265.446362 -58.905716) (xy 265.398812 -58.942203)
			(xy 265.346906 -58.97217) (xy 265.291533 -58.995106) (xy 265.23364 -59.010619) (xy 265.174218 -59.018442)
			(xy 265.114282 -59.018442) (xy 265.05486 -59.010619) (xy 264.996967 -58.995106) (xy 264.941594 -58.97217)
			(xy 264.889688 -58.942203) (xy 264.842138 -58.905716) (xy 264.799758 -58.863336) (xy 264.763271 -58.815786)
			(xy 264.733304 -58.76388) (xy 264.710368 -58.708507) (xy 264.694855 -58.650614) (xy 264.687032 -58.591192)
			(xy 254.94794 -58.591192) (xy 254.950679 -58.600883) (xy 254.957904 -58.653018) (xy 254.958342 -58.679334)
			(xy 254.957856 -58.706585) (xy 254.9501 -58.760533) (xy 254.934745 -58.812828) (xy 254.912103 -58.862405)
			(xy 254.882637 -58.908255) (xy 254.846946 -58.949446) (xy 254.805755 -58.985137) (xy 254.759905 -59.014603)
			(xy 254.710328 -59.037245) (xy 254.658033 -59.0526) (xy 254.604085 -59.060356) (xy 254.549583 -59.060356)
			(xy 254.495635 -59.0526) (xy 254.44334 -59.037245) (xy 254.393763 -59.014603) (xy 254.347913 -58.985137)
			(xy 254.306722 -58.949446) (xy 254.271031 -58.908255) (xy 254.241565 -58.862405) (xy 254.218923 -58.812828)
			(xy 254.203568 -58.760533) (xy 254.195812 -58.706585) (xy 254.195326 -58.679334) (xy 251.110141 -58.679334)
			(xy 251.116943 -58.689858) (xy 251.139781 -58.739603) (xy 251.155275 -58.792101) (xy 251.163106 -58.846275)
			(xy 251.163582 -58.873644) (xy 251.163096 -58.900895) (xy 251.15534 -58.954843) (xy 251.139985 -59.007138)
			(xy 251.117343 -59.056715) (xy 251.087877 -59.102565) (xy 251.052186 -59.143756) (xy 251.010995 -59.179447)
			(xy 250.965145 -59.208913) (xy 250.915568 -59.231555) (xy 250.863273 -59.24691) (xy 250.809325 -59.254666)
			(xy 250.754823 -59.254666) (xy 250.700875 -59.24691) (xy 250.64858 -59.231555) (xy 250.599003 -59.208913)
			(xy 250.553153 -59.179447) (xy 250.511962 -59.143756) (xy 250.476271 -59.102565) (xy 250.446805 -59.056715)
			(xy 250.424163 -59.007138) (xy 250.408808 -58.954843) (xy 250.401052 -58.900895) (xy 250.400566 -58.873644)
			(xy 250.401042 -58.846274) (xy 250.408855 -58.792095) (xy 250.424341 -58.739591) (xy 250.447181 -58.689844)
			(xy 250.476905 -58.643877) (xy 250.494546 -58.622946) (xy 250.4948 -58.622692) (xy 250.500396 -58.615612)
			(xy 250.506637 -58.59869) (xy 250.506992 -58.589672) (xy 250.506992 -58.522616) (xy 250.506629 -58.5136)
			(xy 250.500386 -58.496683) (xy 250.4948 -58.489596) (xy 250.494546 -58.489596) (xy 250.494546 -58.489342)
			(xy 250.47692 -58.468399) (xy 250.447205 -58.42243) (xy 250.424366 -58.372685) (xy 250.408872 -58.320187)
			(xy 250.401041 -58.266013) (xy 250.400566 -58.238644) (xy 250.400566 -58.23839) (xy 250.400939 -58.213442)
			(xy 250.407456 -58.163975) (xy 250.420376 -58.115781) (xy 250.439479 -58.069688) (xy 250.45162 -58.04789)
			(xy 250.458224 -58.03646) (xy 250.458732 -58.010806) (xy 250.413012 -57.923176) (xy 250.408778 -57.915718)
			(xy 250.396302 -57.903965) (xy 250.380634 -57.897014) (xy 250.372118 -57.895998) (xy 250.343927 -57.893199)
			(xy 250.288495 -57.881503) (xy 250.234931 -57.863054) (xy 250.184054 -57.838134) (xy 250.136641 -57.807125)
			(xy 250.093419 -57.770501) (xy 250.073922 -57.749948) (xy 250.067318 -57.742836) (xy 250.0503 -57.734454)
			(xy 249.971814 -57.728104) (xy 249.962249 -57.727747) (xy 249.943966 -57.733358) (xy 249.936254 -57.739026)
			(xy 249.915964 -57.754554) (xy 249.872016 -57.780614) (xy 249.824984 -57.800579) (xy 249.77571 -57.814092)
			(xy 249.725073 -57.820911) (xy 249.699526 -57.821322) (xy 249.672273 -57.820832) (xy 249.618321 -57.813079)
			(xy 249.566022 -57.797726) (xy 249.516441 -57.775085) (xy 249.470586 -57.745619) (xy 249.429392 -57.709927)
			(xy 249.393696 -57.668735) (xy 249.364227 -57.622882) (xy 249.341584 -57.573302) (xy 249.326227 -57.521004)
			(xy 249.318469 -57.467053) (xy 249.135212 -57.467053) (xy 249.139047 -57.495547) (xy 249.139456 -57.521094)
			(xy 249.138997 -57.548465) (xy 249.131179 -57.602644) (xy 249.115689 -57.655148) (xy 249.092845 -57.704895)
			(xy 249.063119 -57.750861) (xy 249.045476 -57.771792) (xy 249.045222 -57.772046) (xy 249.039643 -57.779137)
			(xy 249.033394 -57.796051) (xy 249.03303 -57.805066) (xy 249.03303 -57.872122) (xy 249.03337 -57.881141)
			(xy 249.039629 -57.898058) (xy 249.045222 -57.905142) (xy 249.045476 -57.905142) (xy 249.045476 -57.905396)
			(xy 249.063111 -57.926334) (xy 249.092835 -57.972301) (xy 249.115681 -58.022046) (xy 249.131178 -58.074547)
			(xy 249.139007 -58.128725) (xy 249.139007 -58.183466) (xy 249.13118 -58.237644) (xy 249.115684 -58.290145)
			(xy 249.09284 -58.339891) (xy 249.063116 -58.385859) (xy 249.045476 -58.406792) (xy 249.045222 -58.407046)
			(xy 249.039643 -58.414137) (xy 249.033394 -58.431051) (xy 249.03303 -58.440066) (xy 249.03303 -58.507122)
			(xy 249.03337 -58.516141) (xy 249.039629 -58.533058) (xy 249.045222 -58.540142) (xy 249.045476 -58.540142)
			(xy 249.045476 -58.540396) (xy 249.063123 -58.561322) (xy 249.092834 -58.607296) (xy 249.115669 -58.657045)
			(xy 249.131158 -58.709547) (xy 249.138984 -58.763724) (xy 249.139456 -58.791094) (xy 249.13897 -58.818345)
			(xy 249.131214 -58.872293) (xy 249.115859 -58.924588) (xy 249.093217 -58.974165) (xy 249.063751 -59.020015)
			(xy 249.02806 -59.061206) (xy 248.986869 -59.096897) (xy 248.941019 -59.126363) (xy 248.891442 -59.149005)
			(xy 248.839147 -59.16436) (xy 248.785199 -59.172116) (xy 248.730697 -59.172116) (xy 248.676749 -59.16436)
			(xy 248.624454 -59.149005) (xy 248.574877 -59.126363) (xy 248.529027 -59.096897) (xy 248.487836 -59.061206)
			(xy 248.452145 -59.020015) (xy 248.422679 -58.974165) (xy 248.400037 -58.924588) (xy 248.384682 -58.872293)
			(xy 248.376926 -58.818345) (xy 248.37644 -58.791094) (xy 248.376893 -58.763723) (xy 248.384712 -58.709543)
			(xy 248.400204 -58.657039) (xy 248.423049 -58.607293) (xy 248.452777 -58.561327) (xy 248.47042 -58.540396)
			(xy 248.470674 -58.540142) (xy 248.476258 -58.533054) (xy 248.482504 -58.516138) (xy 248.482866 -58.507122)
			(xy 248.482866 -58.440066) (xy 248.482533 -58.431047) (xy 248.476269 -58.414129) (xy 248.470674 -58.407046)
			(xy 248.47042 -58.407046) (xy 248.47042 -58.406792) (xy 248.452774 -58.385864) (xy 248.42305 -58.339895)
			(xy 248.400205 -58.290148) (xy 248.38471 -58.237645) (xy 248.376882 -58.183466) (xy 248.376882 -58.128725)
			(xy 248.384712 -58.074546) (xy 248.400208 -58.022043) (xy 248.423054 -57.972297) (xy 248.452779 -57.926329)
			(xy 248.47042 -57.905396) (xy 248.470674 -57.905142) (xy 248.476258 -57.898054) (xy 248.482504 -57.881138)
			(xy 248.482866 -57.872122) (xy 248.482866 -57.805066) (xy 248.482533 -57.796047) (xy 248.476269 -57.779129)
			(xy 248.470674 -57.772046) (xy 248.47042 -57.772046) (xy 248.47042 -57.771792) (xy 248.452767 -57.750871)
			(xy 248.423056 -57.704896) (xy 248.400223 -57.655145) (xy 248.384735 -57.602642) (xy 248.376911 -57.548464)
			(xy 248.37644 -57.521094) (xy 248.376823 -57.495545) (xy 248.383635 -57.444904) (xy 248.39715 -57.395627)
			(xy 248.417124 -57.348595) (xy 248.443202 -57.304653) (xy 248.458736 -57.284366) (xy 248.464336 -57.276617)
			(xy 248.469961 -57.258361) (xy 248.469658 -57.248806) (xy 248.463308 -57.17032) (xy 248.454926 -57.153302)
			(xy 248.447814 -57.146698) (xy 248.424992 -57.12494) (xy 248.38491 -57.076267) (xy 248.351894 -57.022549)
			(xy 248.32657 -56.964806) (xy 248.309419 -56.90413) (xy 248.300764 -56.841674) (xy 248.30024 -56.810148)
			(xy 246.483342 -56.810148) (xy 246.483632 -56.826404) (xy 246.483185 -56.853775) (xy 246.475365 -56.907956)
			(xy 246.459872 -56.96046) (xy 246.437026 -57.010206) (xy 246.407296 -57.056172) (xy 246.389652 -57.077102)
			(xy 246.389398 -57.077356) (xy 246.383823 -57.084451) (xy 246.37757 -57.101361) (xy 246.377206 -57.110376)
			(xy 246.377206 -57.177432) (xy 246.377547 -57.186451) (xy 246.383805 -57.203367) (xy 246.389398 -57.210452)
			(xy 246.389652 -57.210452) (xy 246.389652 -57.210706) (xy 246.407297 -57.231635) (xy 246.437024 -57.277603)
			(xy 246.45987 -57.32735) (xy 246.475367 -57.379853) (xy 246.483196 -57.434032) (xy 246.483195 -57.488774)
			(xy 246.475366 -57.542953) (xy 246.459868 -57.595456) (xy 246.437021 -57.645202) (xy 246.407294 -57.69117)
			(xy 246.389652 -57.712102) (xy 246.389398 -57.712356) (xy 246.383823 -57.719451) (xy 246.37757 -57.736361)
			(xy 246.377206 -57.745376) (xy 246.377206 -57.812432) (xy 246.377547 -57.821451) (xy 246.383805 -57.838367)
			(xy 246.389398 -57.845452) (xy 246.389652 -57.845452) (xy 246.389652 -57.845706) (xy 246.407297 -57.866635)
			(xy 246.437024 -57.912603) (xy 246.45987 -57.96235) (xy 246.475367 -58.014853) (xy 246.483196 -58.069032)
			(xy 246.483195 -58.123774) (xy 246.475366 -58.177953) (xy 246.459868 -58.230456) (xy 246.437021 -58.280202)
			(xy 246.407294 -58.32617) (xy 246.389652 -58.347102) (xy 246.389398 -58.347356) (xy 246.383823 -58.354451)
			(xy 246.37757 -58.371361) (xy 246.377206 -58.380376) (xy 246.377206 -58.447432) (xy 246.377547 -58.456451)
			(xy 246.383805 -58.473367) (xy 246.389398 -58.480452) (xy 246.389652 -58.480452) (xy 246.389652 -58.480706)
			(xy 246.4073 -58.501631) (xy 246.437012 -58.547605) (xy 246.459847 -58.597354) (xy 246.475336 -58.649857)
			(xy 246.48316 -58.704034) (xy 246.483632 -58.731404) (xy 246.483146 -58.758655) (xy 246.47539 -58.812603)
			(xy 246.460035 -58.864898) (xy 246.437393 -58.914475) (xy 246.407927 -58.960325) (xy 246.372236 -59.001516)
			(xy 246.331045 -59.037207) (xy 246.285195 -59.066673) (xy 246.235618 -59.089315) (xy 246.183323 -59.10467)
			(xy 246.129375 -59.112426) (xy 246.074873 -59.112426) (xy 246.020925 -59.10467) (xy 245.96863 -59.089315)
			(xy 245.919053 -59.066673) (xy 245.873203 -59.037207) (xy 245.832012 -59.001516) (xy 245.796321 -58.960325)
			(xy 245.766855 -58.914475) (xy 245.744213 -58.864898) (xy 245.728858 -58.812603) (xy 245.721102 -58.758655)
			(xy 245.720616 -58.731404) (xy 241.080288 -58.731404) (xy 241.069604 -58.734267) (xy 241.010182 -58.74209)
			(xy 240.950246 -58.74209) (xy 240.890824 -58.734267) (xy 240.832931 -58.718754) (xy 240.777558 -58.695818)
			(xy 240.725652 -58.665851) (xy 240.678102 -58.629364) (xy 240.635722 -58.586984) (xy 240.599235 -58.539434)
			(xy 240.569268 -58.487528) (xy 240.546332 -58.432155) (xy 240.530819 -58.374262) (xy 240.522996 -58.31484)
			(xy 238.471977 -58.31484) (xy 238.506031 -58.335623) (xy 238.548899 -58.371298) (xy 238.586116 -58.412835)
			(xy 238.616889 -58.459348) (xy 238.640561 -58.509845) (xy 238.656629 -58.563252) (xy 238.664749 -58.618428)
			(xy 238.665258 -58.646314) (xy 238.664749 -58.6742) (xy 238.656629 -58.729376) (xy 238.640561 -58.782783)
			(xy 238.616889 -58.83328) (xy 238.586116 -58.879793) (xy 238.548899 -58.92133) (xy 238.506031 -58.957005)
			(xy 238.458425 -58.986059) (xy 238.407096 -59.007871) (xy 238.353139 -59.021977) (xy 238.297702 -59.028077)
			(xy 238.241968 -59.02604) (xy 238.187125 -59.01591) (xy 238.134341 -58.997903) (xy 238.084741 -58.972402)
			(xy 238.039383 -58.939951) (xy 237.999234 -58.901242) (xy 237.965148 -58.857099) (xy 237.937852 -58.808464)
			(xy 237.917929 -58.756373) (xy 237.905803 -58.701936) (xy 237.901732 -58.646314) (xy 233.960883 -58.646314)
			(xy 233.960946 -58.646749) (xy 233.961432 -58.674) (xy 233.961432 -58.674254) (xy 233.960943 -58.701601)
			(xy 233.953116 -58.755732) (xy 233.937642 -58.808191) (xy 233.91484 -58.857905) (xy 233.885176 -58.903855)
			(xy 233.849257 -58.945102) (xy 233.828844 -58.963306) (xy 233.820462 -58.970418) (xy 233.811318 -58.99023)
			(xy 233.810302 -59.077352) (xy 233.810683 -59.088195) (xy 233.81937 -59.108057) (xy 233.827066 -59.115706)
			(xy 233.82732 -59.11596) (xy 233.84691 -59.134114) (xy 233.881302 -59.174976) (xy 233.909659 -59.220235)
			(xy 233.931425 -59.269008) (xy 233.946175 -59.32034) (xy 233.953621 -59.373227) (xy 233.954066 -59.399932)
			(xy 233.953574 -59.428638) (xy 233.94496 -59.485401) (xy 233.927947 -59.540235) (xy 233.902917 -59.591905)
			(xy 233.870434 -59.639246) (xy 233.831231 -59.681191) (xy 233.809032 -59.699398) (xy 233.799999 -59.707327)
			(xy 233.78978 -59.729041) (xy 233.789474 -59.741054) (xy 233.792776 -59.835034) (xy 233.80446 -59.856116)
			(xy 233.81462 -59.862974) (xy 233.836203 -59.878309) (xy 233.87535 -59.913955) (xy 233.909191 -59.954672)
			(xy 233.937078 -59.999676) (xy 233.958475 -60.048104) (xy 233.97297 -60.099025) (xy 233.976797 -60.126455)
			(xy 249.38015 -60.126455) (xy 249.38015 -60.071945) (xy 249.387908 -60.017989) (xy 249.403267 -59.965686)
			(xy 249.425913 -59.916102) (xy 249.455386 -59.870246) (xy 249.491085 -59.829051) (xy 249.532284 -59.793357)
			(xy 249.578144 -59.76389) (xy 249.627731 -59.74125) (xy 249.680036 -59.725898) (xy 249.733992 -59.718146)
			(xy 249.761248 -59.717686) (xy 249.788617 -59.718186) (xy 249.842794 -59.725996) (xy 249.895297 -59.741477)
			(xy 249.945044 -59.764312) (xy 249.991013 -59.794028) (xy 250.011946 -59.811666) (xy 250.0122 -59.81192)
			(xy 250.019281 -59.817515) (xy 250.036202 -59.823756) (xy 250.04522 -59.824112) (xy 250.112276 -59.824112)
			(xy 250.121291 -59.823741) (xy 250.138208 -59.817503) (xy 250.145296 -59.81192) (xy 250.145296 -59.811666)
			(xy 250.14555 -59.811666) (xy 250.166483 -59.794025) (xy 250.212451 -59.764301) (xy 250.262197 -59.741455)
			(xy 250.314699 -59.725959) (xy 250.368877 -59.71813) (xy 250.423619 -59.71813) (xy 250.477797 -59.725959)
			(xy 250.530299 -59.741455) (xy 250.580045 -59.764301) (xy 250.626013 -59.794025) (xy 250.646946 -59.811666)
			(xy 250.6472 -59.81192) (xy 250.654281 -59.817515) (xy 250.671202 -59.823756) (xy 250.68022 -59.824112)
			(xy 250.747276 -59.824112) (xy 250.756291 -59.823741) (xy 250.773208 -59.817503) (xy 250.780296 -59.81192)
			(xy 250.780296 -59.811666) (xy 250.78055 -59.811666) (xy 250.801486 -59.794032) (xy 250.847458 -59.76432)
			(xy 250.897205 -59.741484) (xy 250.949704 -59.725992) (xy 251.003879 -59.718161) (xy 251.031248 -59.717686)
			(xy 251.058497 -59.718187) (xy 251.112438 -59.725949) (xy 251.164726 -59.741308) (xy 251.214297 -59.763952)
			(xy 251.260141 -59.793419) (xy 251.301324 -59.82911) (xy 251.33701 -59.870298) (xy 251.366471 -59.916145)
			(xy 251.389109 -59.965719) (xy 251.404461 -60.018009) (xy 251.404639 -60.01925) (xy 254.335784 -60.01925)
			(xy 254.335784 -59.96475) (xy 254.34354 -59.910804) (xy 254.358894 -59.858511) (xy 254.381534 -59.808935)
			(xy 254.410999 -59.763086) (xy 254.446688 -59.721897) (xy 254.487877 -59.686206) (xy 254.533725 -59.65674)
			(xy 254.5833 -59.634098) (xy 254.635592 -59.618742) (xy 254.689538 -59.610985) (xy 254.716788 -59.610498)
			(xy 254.744158 -59.610972) (xy 254.798337 -59.618788) (xy 254.85084 -59.634275) (xy 254.900587 -59.657115)
			(xy 254.946554 -59.686838) (xy 254.967486 -59.704478) (xy 254.96774 -59.704732) (xy 254.974837 -59.710303)
			(xy 254.991746 -59.716558) (xy 255.00076 -59.716924) (xy 255.067816 -59.716924) (xy 255.076833 -59.716569)
			(xy 255.09375 -59.710319) (xy 255.100836 -59.704732) (xy 255.100836 -59.704478) (xy 255.10109 -59.704478)
			(xy 255.122023 -59.686837) (xy 255.167991 -59.657113) (xy 255.217737 -59.634267) (xy 255.270239 -59.618771)
			(xy 255.324417 -59.610942) (xy 255.379159 -59.610942) (xy 255.433337 -59.618771) (xy 255.485839 -59.634267)
			(xy 255.535585 -59.657113) (xy 255.581553 -59.686837) (xy 255.602486 -59.704478) (xy 255.60274 -59.704732)
			(xy 255.609837 -59.710303) (xy 255.626746 -59.716558) (xy 255.63576 -59.716924) (xy 255.702816 -59.716924)
			(xy 255.711833 -59.716569) (xy 255.72875 -59.710319) (xy 255.735836 -59.704732) (xy 255.735836 -59.704478)
			(xy 255.73609 -59.704478) (xy 255.757012 -59.686827) (xy 255.802988 -59.657117) (xy 255.852738 -59.634284)
			(xy 255.905241 -59.618796) (xy 255.959418 -59.610971) (xy 255.986788 -59.610498) (xy 256.014042 -59.610949)
			(xy 256.067995 -59.618704) (xy 256.120295 -59.634059) (xy 256.169877 -59.656702) (xy 256.215733 -59.68617)
			(xy 256.256928 -59.721864) (xy 256.292623 -59.763058) (xy 256.322093 -59.808912) (xy 256.344736 -59.858494)
			(xy 256.360093 -59.910793) (xy 256.367851 -59.964746) (xy 256.367851 -59.974734) (xy 263.286492 -59.974734)
			(xy 263.290563 -59.919112) (xy 263.302689 -59.864675) (xy 263.322612 -59.812584) (xy 263.349908 -59.763949)
			(xy 263.383994 -59.719806) (xy 263.424143 -59.681097) (xy 263.469501 -59.648646) (xy 263.519101 -59.623145)
			(xy 263.571885 -59.605138) (xy 263.626728 -59.595008) (xy 263.682462 -59.592971) (xy 263.737899 -59.599071)
			(xy 263.791856 -59.613177) (xy 263.843185 -59.634989) (xy 263.890791 -59.664043) (xy 263.933659 -59.699718)
			(xy 263.970876 -59.741255) (xy 264.001649 -59.787768) (xy 264.025321 -59.838265) (xy 264.041389 -59.891672)
			(xy 264.049509 -59.946848) (xy 264.050018 -59.974734) (xy 264.049509 -60.00262) (xy 264.041389 -60.057796)
			(xy 264.025321 -60.111203) (xy 264.018173 -60.126451) (xy 275.380172 -60.126451) (xy 275.380172 -60.071949)
			(xy 275.387928 -60.018) (xy 275.403283 -59.965705) (xy 275.425925 -59.916127) (xy 275.455391 -59.870276)
			(xy 275.491083 -59.829086) (xy 275.532273 -59.793393) (xy 275.578124 -59.763927) (xy 275.627701 -59.741285)
			(xy 275.679996 -59.725929) (xy 275.733945 -59.718172) (xy 275.761196 -59.717686) (xy 275.788566 -59.718158)
			(xy 275.842745 -59.725975) (xy 275.895248 -59.741463) (xy 275.944995 -59.764303) (xy 275.990962 -59.794026)
			(xy 276.011894 -59.811666) (xy 276.012148 -59.81192) (xy 276.019244 -59.817493) (xy 276.036154 -59.823747)
			(xy 276.045168 -59.824112) (xy 276.112224 -59.824112) (xy 276.121242 -59.823764) (xy 276.138158 -59.81751)
			(xy 276.145244 -59.81192) (xy 276.145244 -59.811666) (xy 276.145498 -59.811666) (xy 276.166431 -59.794025)
			(xy 276.212399 -59.764301) (xy 276.262145 -59.741455) (xy 276.314647 -59.725959) (xy 276.368825 -59.71813)
			(xy 276.423567 -59.71813) (xy 276.477745 -59.725959) (xy 276.530247 -59.741455) (xy 276.579993 -59.764301)
			(xy 276.625961 -59.794025) (xy 276.646894 -59.811666) (xy 276.647148 -59.81192) (xy 276.654244 -59.817493)
			(xy 276.671154 -59.823747) (xy 276.680168 -59.824112) (xy 276.747224 -59.824112) (xy 276.756242 -59.823764)
			(xy 276.773158 -59.81751) (xy 276.780244 -59.81192) (xy 276.780244 -59.811666) (xy 276.780498 -59.811666)
			(xy 276.801416 -59.794009) (xy 276.847393 -59.764301) (xy 276.897144 -59.741469) (xy 276.949648 -59.725982)
			(xy 277.003826 -59.718158) (xy 277.031196 -59.717686) (xy 277.058449 -59.718161) (xy 277.112399 -59.725917)
			(xy 277.164697 -59.741273) (xy 277.214276 -59.763915) (xy 277.260129 -59.793382) (xy 277.301322 -59.829075)
			(xy 277.337015 -59.870267) (xy 277.366483 -59.91612) (xy 277.389126 -59.9657) (xy 277.404482 -60.017997)
			(xy 277.404663 -60.019254) (xy 280.335661 -60.019254) (xy 280.335661 -59.964746) (xy 280.343419 -59.910793)
			(xy 280.358777 -59.858493) (xy 280.381422 -59.808911) (xy 280.410892 -59.763057) (xy 280.446589 -59.721864)
			(xy 280.487786 -59.686171) (xy 280.533643 -59.656704) (xy 280.583227 -59.634064) (xy 280.635528 -59.618712)
			(xy 280.689482 -59.610959) (xy 280.716736 -59.610498) (xy 280.744107 -59.610943) (xy 280.798287 -59.618766)
			(xy 280.85079 -59.63426) (xy 280.900537 -59.657107) (xy 280.946503 -59.686835) (xy 280.967434 -59.704478)
			(xy 280.967688 -59.704732) (xy 280.974771 -59.710323) (xy 280.991691 -59.716566) (xy 281.000708 -59.716924)
			(xy 281.067764 -59.716924) (xy 281.076778 -59.716545) (xy 281.093695 -59.710312) (xy 281.100784 -59.704732)
			(xy 281.100784 -59.704478) (xy 281.101038 -59.704478) (xy 281.121971 -59.686837) (xy 281.167939 -59.657113)
			(xy 281.217685 -59.634267) (xy 281.270187 -59.618771) (xy 281.324365 -59.610942) (xy 281.379107 -59.610942)
			(xy 281.433285 -59.618771) (xy 281.485787 -59.634267) (xy 281.535533 -59.657113) (xy 281.581501 -59.686837)
			(xy 281.602434 -59.704478) (xy 281.602688 -59.704732) (xy 281.609771 -59.710323) (xy 281.626691 -59.716566)
			(xy 281.635708 -59.716924) (xy 281.702764 -59.716924) (xy 281.711778 -59.716545) (xy 281.728695 -59.710312)
			(xy 281.735784 -59.704732) (xy 281.735784 -59.704478) (xy 281.736038 -59.704478) (xy 281.75698 -59.686851)
			(xy 281.80295 -59.657138) (xy 281.852695 -59.6343) (xy 281.905194 -59.618806) (xy 281.959368 -59.610974)
			(xy 281.986736 -59.610498) (xy 282.013986 -59.610974) (xy 282.067931 -59.618735) (xy 282.120222 -59.634094)
			(xy 282.169795 -59.656737) (xy 282.215642 -59.686205) (xy 282.256829 -59.721897) (xy 282.292517 -59.763087)
			(xy 282.32198 -59.808936) (xy 282.344619 -59.858512) (xy 282.359973 -59.910805) (xy 282.367728 -59.96475)
			(xy 282.367728 -59.974734) (xy 289.28644 -59.974734) (xy 289.290511 -59.919112) (xy 289.302637 -59.864675)
			(xy 289.32256 -59.812584) (xy 289.349856 -59.763949) (xy 289.383942 -59.719806) (xy 289.424091 -59.681097)
			(xy 289.469449 -59.648646) (xy 289.519049 -59.623145) (xy 289.571833 -59.605138) (xy 289.626676 -59.595008)
			(xy 289.68241 -59.592971) (xy 289.737847 -59.599071) (xy 289.791804 -59.613177) (xy 289.843133 -59.634989)
			(xy 289.890739 -59.664043) (xy 289.933607 -59.699718) (xy 289.970824 -59.741255) (xy 290.001597 -59.787768)
			(xy 290.025269 -59.838265) (xy 290.041337 -59.891672) (xy 290.049457 -59.946848) (xy 290.049966 -59.974734)
			(xy 290.049457 -60.00262) (xy 290.041337 -60.057796) (xy 290.025269 -60.111203) (xy 290.018119 -60.126455)
			(xy 301.380049 -60.126455) (xy 301.380049 -60.071945) (xy 301.387808 -60.017989) (xy 301.403166 -59.965687)
			(xy 301.425812 -59.916103) (xy 301.455285 -59.870247) (xy 301.490984 -59.829053) (xy 301.532182 -59.793358)
			(xy 301.578042 -59.763891) (xy 301.627628 -59.741251) (xy 301.679932 -59.725898) (xy 301.733889 -59.718146)
			(xy 301.761144 -59.717686) (xy 301.788513 -59.718188) (xy 301.84269 -59.725998) (xy 301.895193 -59.741479)
			(xy 301.94494 -59.764312) (xy 301.990909 -59.794029) (xy 302.011842 -59.811666) (xy 302.012096 -59.81192)
			(xy 302.019178 -59.817513) (xy 302.036098 -59.823755) (xy 302.045116 -59.824112) (xy 302.112172 -59.824112)
			(xy 302.121187 -59.823739) (xy 302.138104 -59.817502) (xy 302.145192 -59.81192) (xy 302.145192 -59.811666)
			(xy 302.145446 -59.811666) (xy 302.166379 -59.794025) (xy 302.212347 -59.764301) (xy 302.262093 -59.741455)
			(xy 302.314595 -59.725959) (xy 302.368773 -59.71813) (xy 302.423515 -59.71813) (xy 302.477693 -59.725959)
			(xy 302.530195 -59.741455) (xy 302.579941 -59.764301) (xy 302.625909 -59.794025) (xy 302.646842 -59.811666)
			(xy 302.647096 -59.81192) (xy 302.654178 -59.817513) (xy 302.671098 -59.823755) (xy 302.680116 -59.824112)
			(xy 302.747172 -59.824112) (xy 302.756187 -59.823739) (xy 302.773104 -59.817502) (xy 302.780192 -59.81192)
			(xy 302.780192 -59.811666) (xy 302.780446 -59.811666) (xy 302.801383 -59.794033) (xy 302.847355 -59.764322)
			(xy 302.897101 -59.741485) (xy 302.949601 -59.725992) (xy 303.003775 -59.718162) (xy 303.031144 -59.717686)
			(xy 303.058393 -59.718187) (xy 303.112335 -59.725948) (xy 303.164624 -59.741307) (xy 303.214194 -59.76395)
			(xy 303.260039 -59.793417) (xy 303.301223 -59.829108) (xy 303.336909 -59.870297) (xy 303.366371 -59.916144)
			(xy 303.389008 -59.965718) (xy 303.404361 -60.018008) (xy 303.40454 -60.01925) (xy 306.335684 -60.01925)
			(xy 306.335684 -59.96475) (xy 306.34344 -59.910804) (xy 306.358794 -59.858512) (xy 306.381433 -59.808936)
			(xy 306.410898 -59.763087) (xy 306.446587 -59.721898) (xy 306.487775 -59.686207) (xy 306.533622 -59.656741)
			(xy 306.583197 -59.634099) (xy 306.635489 -59.618743) (xy 306.689434 -59.610985) (xy 306.716684 -59.610498)
			(xy 306.744054 -59.610974) (xy 306.798233 -59.618789) (xy 306.850736 -59.634276) (xy 306.900483 -59.657116)
			(xy 306.94645 -59.686838) (xy 306.967382 -59.704478) (xy 306.967636 -59.704732) (xy 306.974734 -59.710301)
			(xy 306.991642 -59.716557) (xy 307.000656 -59.716924) (xy 307.067712 -59.716924) (xy 307.076729 -59.716567)
			(xy 307.093645 -59.710319) (xy 307.100732 -59.704732) (xy 307.100732 -59.704478) (xy 307.100986 -59.704478)
			(xy 307.121919 -59.686837) (xy 307.167887 -59.657113) (xy 307.217633 -59.634267) (xy 307.270135 -59.618771)
			(xy 307.324313 -59.610942) (xy 307.379055 -59.610942) (xy 307.433233 -59.618771) (xy 307.485735 -59.634267)
			(xy 307.535481 -59.657113) (xy 307.581449 -59.686837) (xy 307.602382 -59.704478) (xy 307.602636 -59.704732)
			(xy 307.609734 -59.710301) (xy 307.626642 -59.716557) (xy 307.635656 -59.716924) (xy 307.702712 -59.716924)
			(xy 307.711729 -59.716567) (xy 307.728645 -59.710319) (xy 307.735732 -59.704732) (xy 307.735732 -59.704478)
			(xy 307.735986 -59.704478) (xy 307.75691 -59.686829) (xy 307.802885 -59.657119) (xy 307.852635 -59.634285)
			(xy 307.905137 -59.618797) (xy 307.959314 -59.610971) (xy 307.986684 -59.610498) (xy 308.013938 -59.610948)
			(xy 308.067892 -59.618704) (xy 308.120192 -59.634058) (xy 308.169775 -59.6567) (xy 308.215631 -59.686168)
			(xy 308.256826 -59.721863) (xy 308.292522 -59.763056) (xy 308.321992 -59.808911) (xy 308.344636 -59.858493)
			(xy 308.359993 -59.910793) (xy 308.367751 -59.964746) (xy 308.367751 -59.974734) (xy 315.286388 -59.974734)
			(xy 315.290459 -59.919112) (xy 315.302585 -59.864675) (xy 315.322508 -59.812584) (xy 315.349804 -59.763949)
			(xy 315.38389 -59.719806) (xy 315.424039 -59.681097) (xy 315.469397 -59.648646) (xy 315.518997 -59.623145)
			(xy 315.571781 -59.605138) (xy 315.626624 -59.595008) (xy 315.682358 -59.592971) (xy 315.737795 -59.599071)
			(xy 315.791752 -59.613177) (xy 315.843081 -59.634989) (xy 315.890687 -59.664043) (xy 315.933555 -59.699718)
			(xy 315.970772 -59.741255) (xy 316.001545 -59.787768) (xy 316.025217 -59.838265) (xy 316.041285 -59.891672)
			(xy 316.049405 -59.946848) (xy 316.049914 -59.974734) (xy 316.049405 -60.00262) (xy 316.041285 -60.057796)
			(xy 316.025217 -60.111203) (xy 316.018069 -60.126451) (xy 327.380072 -60.126451) (xy 327.380072 -60.071949)
			(xy 327.387828 -60.018001) (xy 327.403183 -59.965706) (xy 327.425824 -59.916128) (xy 327.45529 -59.870278)
			(xy 327.490981 -59.829087) (xy 327.532171 -59.793395) (xy 327.578021 -59.763928) (xy 327.627598 -59.741286)
			(xy 327.679893 -59.72593) (xy 327.733841 -59.718172) (xy 327.761092 -59.717686) (xy 327.788462 -59.71816)
			(xy 327.84264 -59.725977) (xy 327.895143 -59.741464) (xy 327.94489 -59.764304) (xy 327.990858 -59.794026)
			(xy 328.01179 -59.811666) (xy 328.012044 -59.81192) (xy 328.019141 -59.817492) (xy 328.03605 -59.823747)
			(xy 328.045064 -59.824112) (xy 328.11212 -59.824112) (xy 328.121137 -59.823762) (xy 328.138054 -59.817509)
			(xy 328.14514 -59.81192) (xy 328.14514 -59.811666) (xy 328.145394 -59.811666) (xy 328.166327 -59.794025)
			(xy 328.212295 -59.764301) (xy 328.262041 -59.741455) (xy 328.314543 -59.725959) (xy 328.368721 -59.71813)
			(xy 328.423463 -59.71813) (xy 328.477641 -59.725959) (xy 328.530143 -59.741455) (xy 328.579889 -59.764301)
			(xy 328.625857 -59.794025) (xy 328.64679 -59.811666) (xy 328.647044 -59.81192) (xy 328.654141 -59.817492)
			(xy 328.67105 -59.823747) (xy 328.680064 -59.824112) (xy 328.74712 -59.824112) (xy 328.756137 -59.823762)
			(xy 328.773054 -59.817509) (xy 328.78014 -59.81192) (xy 328.78014 -59.811666) (xy 328.780394 -59.811666)
			(xy 328.801313 -59.794011) (xy 328.84729 -59.764303) (xy 328.897041 -59.74147) (xy 328.949544 -59.725983)
			(xy 329.003722 -59.718158) (xy 329.031092 -59.717686) (xy 329.058345 -59.718161) (xy 329.112296 -59.725917)
			(xy 329.164594 -59.741272) (xy 329.214174 -59.763913) (xy 329.260027 -59.793381) (xy 329.30122 -59.829074)
			(xy 329.336914 -59.870266) (xy 329.366383 -59.916119) (xy 329.389025 -59.965699) (xy 329.404382 -60.017996)
			(xy 329.404563 -60.019254) (xy 332.335561 -60.019254) (xy 332.335561 -59.964746) (xy 332.343319 -59.910793)
			(xy 332.358677 -59.858494) (xy 332.381321 -59.808912) (xy 332.410791 -59.763058) (xy 332.446488 -59.721865)
			(xy 332.487684 -59.686172) (xy 332.53354 -59.656706) (xy 332.583124 -59.634065) (xy 332.635425 -59.618712)
			(xy 332.689378 -59.610959) (xy 332.716632 -59.610498) (xy 332.744003 -59.610946) (xy 332.798183 -59.618768)
			(xy 332.850686 -59.634261) (xy 332.900433 -59.657107) (xy 332.946399 -59.686835) (xy 332.96733 -59.704478)
			(xy 332.967584 -59.704732) (xy 332.974668 -59.710322) (xy 332.991587 -59.716565) (xy 333.000604 -59.716924)
			(xy 333.06766 -59.716924) (xy 333.076674 -59.716543) (xy 333.093591 -59.710311) (xy 333.10068 -59.704732)
			(xy 333.10068 -59.704478) (xy 333.100934 -59.704478) (xy 333.121867 -59.686837) (xy 333.167835 -59.657113)
			(xy 333.217581 -59.634267) (xy 333.270083 -59.618771) (xy 333.324261 -59.610942) (xy 333.379003 -59.610942)
			(xy 333.433181 -59.618771) (xy 333.485683 -59.634267) (xy 333.535429 -59.657113) (xy 333.581397 -59.686837)
			(xy 333.60233 -59.704478) (xy 333.602584 -59.704732) (xy 333.609668 -59.710322) (xy 333.626587 -59.716565)
			(xy 333.635604 -59.716924) (xy 333.70266 -59.716924) (xy 333.711674 -59.716543) (xy 333.728591 -59.710311)
			(xy 333.73568 -59.704732) (xy 333.73568 -59.704478) (xy 333.735934 -59.704478) (xy 333.756877 -59.686853)
			(xy 333.802847 -59.65714) (xy 333.852592 -59.634301) (xy 333.90509 -59.618807) (xy 333.959264 -59.610975)
			(xy 333.986632 -59.610498) (xy 334.013882 -59.610974) (xy 334.067827 -59.618734) (xy 334.120119 -59.634092)
			(xy 334.169693 -59.656736) (xy 334.21554 -59.686203) (xy 334.256727 -59.721895) (xy 334.292416 -59.763086)
			(xy 334.32188 -59.808935) (xy 334.344519 -59.858511) (xy 334.359872 -59.910804) (xy 334.367628 -59.96475)
			(xy 334.367628 -59.974734) (xy 353.386642 -59.974734) (xy 353.390713 -59.919112) (xy 353.402839 -59.864675)
			(xy 353.422762 -59.812584) (xy 353.450058 -59.763949) (xy 353.484144 -59.719806) (xy 353.524293 -59.681097)
			(xy 353.569651 -59.648646) (xy 353.619251 -59.623145) (xy 353.672035 -59.605138) (xy 353.726878 -59.595008)
			(xy 353.782612 -59.592971) (xy 353.838049 -59.599071) (xy 353.892006 -59.613177) (xy 353.943335 -59.634989)
			(xy 353.990941 -59.664043) (xy 354.033809 -59.699718) (xy 354.071026 -59.741255) (xy 354.101799 -59.787768)
			(xy 354.125471 -59.838265) (xy 354.141539 -59.891672) (xy 354.149659 -59.946848) (xy 354.150168 -59.974734)
			(xy 354.149659 -60.00262) (xy 354.141539 -60.057796) (xy 354.137282 -60.071945) (xy 365.480249 -60.071945)
			(xy 365.488008 -60.017989) (xy 365.503366 -59.965686) (xy 365.526013 -59.916103) (xy 365.555485 -59.870246)
			(xy 365.591185 -59.829052) (xy 365.632383 -59.793358) (xy 365.678243 -59.763891) (xy 365.72783 -59.74125)
			(xy 365.780134 -59.725898) (xy 365.834091 -59.718146) (xy 365.861346 -59.717686) (xy 365.888715 -59.718187)
			(xy 365.942892 -59.725997) (xy 365.995395 -59.741478) (xy 366.045142 -59.764312) (xy 366.091111 -59.794029)
			(xy 366.112044 -59.811666) (xy 366.112298 -59.81192) (xy 366.119379 -59.817514) (xy 366.1363 -59.823756)
			(xy 366.145318 -59.824112) (xy 366.212374 -59.824112) (xy 366.221389 -59.82374) (xy 366.238306 -59.817503)
			(xy 366.245394 -59.81192) (xy 366.245394 -59.811666) (xy 366.245648 -59.811666) (xy 366.266581 -59.794025)
			(xy 366.312549 -59.764301) (xy 366.362295 -59.741455) (xy 366.414797 -59.725959) (xy 366.468975 -59.71813)
			(xy 366.523717 -59.71813) (xy 366.577895 -59.725959) (xy 366.630397 -59.741455) (xy 366.680143 -59.764301)
			(xy 366.726111 -59.794025) (xy 366.747044 -59.811666) (xy 366.747298 -59.81192) (xy 366.754379 -59.817514)
			(xy 366.7713 -59.823756) (xy 366.780318 -59.824112) (xy 366.847374 -59.824112) (xy 366.856389 -59.82374)
			(xy 366.873306 -59.817503) (xy 366.880394 -59.81192) (xy 366.880394 -59.811666) (xy 366.880648 -59.811666)
			(xy 366.901584 -59.794033) (xy 366.947557 -59.764321) (xy 366.997303 -59.741485) (xy 367.049803 -59.725992)
			(xy 367.103977 -59.718162) (xy 367.131346 -59.717686) (xy 367.158595 -59.718187) (xy 367.212537 -59.725949)
			(xy 367.264825 -59.741307) (xy 367.314396 -59.763951) (xy 367.36024 -59.793418) (xy 367.401424 -59.829109)
			(xy 367.43711 -59.870297) (xy 367.466571 -59.916145) (xy 367.489209 -59.965718) (xy 367.504561 -60.018008)
			(xy 367.50474 -60.01925) (xy 370.435884 -60.01925) (xy 370.435884 -59.96475) (xy 370.44364 -59.910804)
			(xy 370.458994 -59.858511) (xy 370.481634 -59.808936) (xy 370.511098 -59.763087) (xy 370.546788 -59.721898)
			(xy 370.587976 -59.686207) (xy 370.633824 -59.65674) (xy 370.683398 -59.634099) (xy 370.73569 -59.618743)
			(xy 370.789636 -59.610985) (xy 370.816886 -59.610498) (xy 370.844256 -59.610973) (xy 370.898435 -59.618789)
			(xy 370.950938 -59.634276) (xy 371.000685 -59.657115) (xy 371.046652 -59.686838) (xy 371.067584 -59.704478)
			(xy 371.067838 -59.704732) (xy 371.074936 -59.710302) (xy 371.091844 -59.716558) (xy 371.100858 -59.716924)
			(xy 371.167914 -59.716924) (xy 371.176931 -59.716568) (xy 371.193847 -59.710319) (xy 371.200934 -59.704732)
			(xy 371.200934 -59.704478) (xy 371.201188 -59.704478) (xy 371.222121 -59.686837) (xy 371.268089 -59.657113)
			(xy 371.317835 -59.634267) (xy 371.370337 -59.618771) (xy 371.424515 -59.610942) (xy 371.479257 -59.610942)
			(xy 371.533435 -59.618771) (xy 371.585937 -59.634267) (xy 371.635683 -59.657113) (xy 371.681651 -59.686837)
			(xy 371.702584 -59.704478) (xy 371.702838 -59.704732) (xy 371.709936 -59.710302) (xy 371.726844 -59.716558)
			(xy 371.735858 -59.716924) (xy 371.802914 -59.716924) (xy 371.811931 -59.716568) (xy 371.828847 -59.710319)
			(xy 371.835934 -59.704732) (xy 371.835934 -59.704478) (xy 371.836188 -59.704478) (xy 371.857111 -59.686828)
			(xy 371.903087 -59.657118) (xy 371.952836 -59.634285) (xy 372.005339 -59.618796) (xy 372.059516 -59.610971)
			(xy 372.086886 -59.610498) (xy 372.11414 -59.610948) (xy 372.168093 -59.618704) (xy 372.220394 -59.634059)
			(xy 372.269976 -59.656701) (xy 372.315832 -59.686169) (xy 372.357027 -59.721863) (xy 372.392723 -59.763057)
			(xy 372.422192 -59.808911) (xy 372.444836 -59.858493) (xy 372.460193 -59.910793) (xy 372.467951 -59.964746)
			(xy 372.467951 -59.974734) (xy 379.38659 -59.974734) (xy 379.390661 -59.919112) (xy 379.402787 -59.864675)
			(xy 379.42271 -59.812584) (xy 379.450006 -59.763949) (xy 379.484092 -59.719806) (xy 379.524241 -59.681097)
			(xy 379.569599 -59.648646) (xy 379.619199 -59.623145) (xy 379.671983 -59.605138) (xy 379.726826 -59.595008)
			(xy 379.78256 -59.592971) (xy 379.837997 -59.599071) (xy 379.891954 -59.613177) (xy 379.943283 -59.634989)
			(xy 379.990889 -59.664043) (xy 380.033757 -59.699718) (xy 380.070974 -59.741255) (xy 380.101747 -59.787768)
			(xy 380.125419 -59.838265) (xy 380.141487 -59.891672) (xy 380.149607 -59.946848) (xy 380.150116 -59.974734)
			(xy 380.149607 -60.00262) (xy 380.141487 -60.057796) (xy 380.125419 -60.111203) (xy 380.118271 -60.126451)
			(xy 391.480272 -60.126451) (xy 391.480272 -60.071949) (xy 391.488028 -60.018001) (xy 391.503383 -59.965705)
			(xy 391.526024 -59.916128) (xy 391.555491 -59.870277) (xy 391.591182 -59.829086) (xy 391.632372 -59.793394)
			(xy 391.678223 -59.763927) (xy 391.7278 -59.741285) (xy 391.780095 -59.72593) (xy 391.834043 -59.718172)
			(xy 391.861294 -59.717686) (xy 391.888664 -59.718159) (xy 391.942843 -59.725976) (xy 391.995346 -59.741463)
			(xy 392.045092 -59.764303) (xy 392.09106 -59.794026) (xy 392.111992 -59.811666) (xy 392.112246 -59.81192)
			(xy 392.119342 -59.817492) (xy 392.136252 -59.823747) (xy 392.145266 -59.824112) (xy 392.212322 -59.824112)
			(xy 392.22134 -59.823763) (xy 392.238256 -59.817509) (xy 392.245342 -59.81192) (xy 392.245342 -59.811666)
			(xy 392.245596 -59.811666) (xy 392.266529 -59.794025) (xy 392.312497 -59.764301) (xy 392.362243 -59.741455)
			(xy 392.414745 -59.725959) (xy 392.468923 -59.71813) (xy 392.523665 -59.71813) (xy 392.577843 -59.725959)
			(xy 392.630345 -59.741455) (xy 392.680091 -59.764301) (xy 392.726059 -59.794025) (xy 392.746992 -59.811666)
			(xy 392.747246 -59.81192) (xy 392.754342 -59.817492) (xy 392.771252 -59.823747) (xy 392.780266 -59.824112)
			(xy 392.847322 -59.824112) (xy 392.85634 -59.823763) (xy 392.873256 -59.817509) (xy 392.880342 -59.81192)
			(xy 392.880342 -59.811666) (xy 392.880596 -59.811666) (xy 392.901514 -59.79401) (xy 392.947491 -59.764302)
			(xy 392.997243 -59.74147) (xy 393.049746 -59.725983) (xy 393.103924 -59.718158) (xy 393.131294 -59.717686)
			(xy 393.158547 -59.718161) (xy 393.212497 -59.725917) (xy 393.264795 -59.741272) (xy 393.314375 -59.763914)
			(xy 393.360228 -59.793382) (xy 393.401421 -59.829075) (xy 393.437115 -59.870267) (xy 393.466583 -59.916119)
			(xy 393.489226 -59.965699) (xy 393.504582 -60.017997) (xy 393.504763 -60.019254) (xy 396.435761 -60.019254)
			(xy 396.435761 -59.964746) (xy 396.443519 -59.910793) (xy 396.458877 -59.858493) (xy 396.481521 -59.808912)
			(xy 396.510992 -59.763058) (xy 396.546689 -59.721865) (xy 396.587885 -59.686172) (xy 396.633742 -59.656705)
			(xy 396.683325 -59.634065) (xy 396.735626 -59.618712) (xy 396.78958 -59.610959) (xy 396.816834 -59.610498)
			(xy 396.844205 -59.610945) (xy 396.898385 -59.618767) (xy 396.950888 -59.634261) (xy 397.000635 -59.657107)
			(xy 397.046601 -59.686835) (xy 397.067532 -59.704478) (xy 397.067786 -59.704732) (xy 397.07487 -59.710322)
			(xy 397.091789 -59.716566) (xy 397.100806 -59.716924) (xy 397.167862 -59.716924) (xy 397.176876 -59.716544)
			(xy 397.193793 -59.710312) (xy 397.200882 -59.704732) (xy 397.200882 -59.704478) (xy 397.201136 -59.704478)
			(xy 397.222069 -59.686837) (xy 397.268037 -59.657113) (xy 397.317783 -59.634267) (xy 397.370285 -59.618771)
			(xy 397.424463 -59.610942) (xy 397.479205 -59.610942) (xy 397.533383 -59.618771) (xy 397.585885 -59.634267)
			(xy 397.635631 -59.657113) (xy 397.681599 -59.686837) (xy 397.702532 -59.704478) (xy 397.702786 -59.704732)
			(xy 397.70987 -59.710322) (xy 397.726789 -59.716566) (xy 397.735806 -59.716924) (xy 397.802862 -59.716924)
			(xy 397.811876 -59.716544) (xy 397.828793 -59.710312) (xy 397.835882 -59.704732) (xy 397.835882 -59.704478)
			(xy 397.836136 -59.704478) (xy 397.857079 -59.686852) (xy 397.903049 -59.657139) (xy 397.952794 -59.634301)
			(xy 398.005292 -59.618807) (xy 398.059466 -59.610974) (xy 398.086834 -59.610498) (xy 398.114084 -59.610974)
			(xy 398.168029 -59.618735) (xy 398.22032 -59.634093) (xy 398.269894 -59.656736) (xy 398.315741 -59.686204)
			(xy 398.356928 -59.721896) (xy 398.392616 -59.763086) (xy 398.42208 -59.808936) (xy 398.444719 -59.858511)
			(xy 398.460073 -59.910804) (xy 398.467828 -59.96475) (xy 398.467828 -59.974734) (xy 405.386538 -59.974734)
			(xy 405.390609 -59.919112) (xy 405.402735 -59.864675) (xy 405.422658 -59.812584) (xy 405.449954 -59.763949)
			(xy 405.48404 -59.719806) (xy 405.524189 -59.681097) (xy 405.569547 -59.648646) (xy 405.619147 -59.623145)
			(xy 405.671931 -59.605138) (xy 405.726774 -59.595008) (xy 405.782508 -59.592971) (xy 405.837945 -59.599071)
			(xy 405.891902 -59.613177) (xy 405.943231 -59.634989) (xy 405.990837 -59.664043) (xy 406.033705 -59.699718)
			(xy 406.070922 -59.741255) (xy 406.101695 -59.787768) (xy 406.125367 -59.838265) (xy 406.141435 -59.891672)
			(xy 406.149555 -59.946848) (xy 406.150064 -59.974734) (xy 406.149555 -60.00262) (xy 406.141435 -60.057796)
			(xy 406.125367 -60.111203) (xy 406.118217 -60.126455) (xy 417.480149 -60.126455) (xy 417.480149 -60.071945)
			(xy 417.487908 -60.017989) (xy 417.503266 -59.965687) (xy 417.525912 -59.916104) (xy 417.555384 -59.870248)
			(xy 417.591083 -59.829053) (xy 417.632281 -59.793359) (xy 417.678141 -59.763892) (xy 417.727727 -59.741251)
			(xy 417.78003 -59.725899) (xy 417.833987 -59.718146) (xy 417.861242 -59.717686) (xy 417.888611 -59.718189)
			(xy 417.942788 -59.725999) (xy 417.995291 -59.741479) (xy 418.045038 -59.764313) (xy 418.091007 -59.794029)
			(xy 418.11194 -59.811666) (xy 418.112194 -59.81192) (xy 418.119276 -59.817512) (xy 418.136196 -59.823755)
			(xy 418.145214 -59.824112) (xy 418.21227 -59.824112) (xy 418.221285 -59.823738) (xy 418.238202 -59.817502)
			(xy 418.24529 -59.81192) (xy 418.24529 -59.811666) (xy 418.245544 -59.811666) (xy 418.266477 -59.794025)
			(xy 418.312445 -59.764301) (xy 418.362191 -59.741455) (xy 418.414693 -59.725959) (xy 418.468871 -59.71813)
			(xy 418.523613 -59.71813) (xy 418.577791 -59.725959) (xy 418.630293 -59.741455) (xy 418.680039 -59.764301)
			(xy 418.726007 -59.794025) (xy 418.74694 -59.811666) (xy 418.747194 -59.81192) (xy 418.754276 -59.817512)
			(xy 418.771196 -59.823755) (xy 418.780214 -59.824112) (xy 418.84727 -59.824112) (xy 418.856285 -59.823738)
			(xy 418.873202 -59.817502) (xy 418.88029 -59.81192) (xy 418.88029 -59.811666) (xy 418.880544 -59.811666)
			(xy 418.901482 -59.794034) (xy 418.947454 -59.764323) (xy 418.9972 -59.741486) (xy 419.049699 -59.725993)
			(xy 419.103873 -59.718162) (xy 419.131242 -59.717686) (xy 419.158491 -59.718187) (xy 419.212433 -59.725948)
			(xy 419.264722 -59.741306) (xy 419.314293 -59.76395) (xy 419.360138 -59.793417) (xy 419.401322 -59.829108)
			(xy 419.437009 -59.870296) (xy 419.466471 -59.916144) (xy 419.489108 -59.965717) (xy 419.504461 -60.018008)
			(xy 419.50464 -60.01925) (xy 422.435784 -60.01925) (xy 422.435784 -59.96475) (xy 422.44354 -59.910805)
			(xy 422.458894 -59.858512) (xy 422.481533 -59.808937) (xy 422.510997 -59.763088) (xy 422.546686 -59.721899)
			(xy 422.587874 -59.686208) (xy 422.633721 -59.656742) (xy 422.683295 -59.6341) (xy 422.735587 -59.618743)
			(xy 422.789532 -59.610985) (xy 422.816782 -59.610498) (xy 422.844152 -59.610975) (xy 422.89833 -59.61879)
			(xy 422.950833 -59.634277) (xy 423.00058 -59.657116) (xy 423.046548 -59.686838) (xy 423.06748 -59.704478)
			(xy 423.067734 -59.704732) (xy 423.074833 -59.710301) (xy 423.09174 -59.716557) (xy 423.100754 -59.716924)
			(xy 423.16781 -59.716924) (xy 423.176827 -59.716566) (xy 423.193743 -59.710319) (xy 423.20083 -59.704732)
			(xy 423.20083 -59.704478) (xy 423.201084 -59.704478) (xy 423.222017 -59.686837) (xy 423.267985 -59.657113)
			(xy 423.317731 -59.634267) (xy 423.370233 -59.618771) (xy 423.424411 -59.610942) (xy 423.479153 -59.610942)
			(xy 423.533331 -59.618771) (xy 423.585833 -59.634267) (xy 423.635579 -59.657113) (xy 423.681547 -59.686837)
			(xy 423.70248 -59.704478) (xy 423.702734 -59.704732) (xy 423.709833 -59.710301) (xy 423.72674 -59.716557)
			(xy 423.735754 -59.716924) (xy 423.80281 -59.716924) (xy 423.811827 -59.716566) (xy 423.828743 -59.710319)
			(xy 423.83583 -59.704732) (xy 423.83583 -59.704478) (xy 423.836084 -59.704478) (xy 423.857008 -59.68683)
			(xy 423.902984 -59.65712) (xy 423.952733 -59.634286) (xy 424.005235 -59.618797) (xy 424.059412 -59.610971)
			(xy 424.086782 -59.610498) (xy 424.114036 -59.610948) (xy 424.16799 -59.618703) (xy 424.220291 -59.634058)
			(xy 424.269874 -59.6567) (xy 424.31573 -59.686168) (xy 424.356925 -59.721862) (xy 424.392622 -59.763056)
			(xy 424.422092 -59.80891) (xy 424.444736 -59.858492) (xy 424.460093 -59.910793) (xy 424.467851 -59.964746)
			(xy 424.467851 -59.974734) (xy 431.386486 -59.974734) (xy 431.390557 -59.919112) (xy 431.402683 -59.864675)
			(xy 431.422606 -59.812584) (xy 431.449902 -59.763949) (xy 431.483988 -59.719806) (xy 431.524137 -59.681097)
			(xy 431.569495 -59.648646) (xy 431.619095 -59.623145) (xy 431.671879 -59.605138) (xy 431.726722 -59.595008)
			(xy 431.782456 -59.592971) (xy 431.837893 -59.599071) (xy 431.89185 -59.613177) (xy 431.943179 -59.634989)
			(xy 431.990785 -59.664043) (xy 432.033653 -59.699718) (xy 432.07087 -59.741255) (xy 432.101643 -59.787768)
			(xy 432.125315 -59.838265) (xy 432.141383 -59.891672) (xy 432.149503 -59.946848) (xy 432.150012 -59.974734)
			(xy 432.149503 -60.00262) (xy 432.141383 -60.057796) (xy 432.125315 -60.111203) (xy 432.118167 -60.126451)
			(xy 443.480172 -60.126451) (xy 443.480172 -60.071949) (xy 443.487928 -60.018001) (xy 443.503283 -59.965706)
			(xy 443.525924 -59.916129) (xy 443.55539 -59.870278) (xy 443.591081 -59.829088) (xy 443.63227 -59.793396)
			(xy 443.67812 -59.763929) (xy 443.727697 -59.741287) (xy 443.779991 -59.72593) (xy 443.833939 -59.718172)
			(xy 443.86119 -59.717686) (xy 443.88856 -59.718161) (xy 443.942738 -59.725977) (xy 443.995241 -59.741465)
			(xy 444.044988 -59.764304) (xy 444.090956 -59.794026) (xy 444.111888 -59.811666) (xy 444.112142 -59.81192)
			(xy 444.119239 -59.817491) (xy 444.136148 -59.823746) (xy 444.145162 -59.824112) (xy 444.212218 -59.824112)
			(xy 444.221235 -59.823761) (xy 444.238152 -59.817509) (xy 444.245238 -59.81192) (xy 444.245238 -59.811666)
			(xy 444.245492 -59.811666) (xy 444.266425 -59.794025) (xy 444.312393 -59.764301) (xy 444.362139 -59.741455)
			(xy 444.414641 -59.725959) (xy 444.468819 -59.71813) (xy 444.523561 -59.71813) (xy 444.577739 -59.725959)
			(xy 444.630241 -59.741455) (xy 444.679987 -59.764301) (xy 444.725955 -59.794025) (xy 444.746888 -59.811666)
			(xy 444.747142 -59.81192) (xy 444.754239 -59.817491) (xy 444.771148 -59.823746) (xy 444.780162 -59.824112)
			(xy 444.847218 -59.824112) (xy 444.856235 -59.823761) (xy 444.873152 -59.817509) (xy 444.880238 -59.81192)
			(xy 444.880238 -59.811666) (xy 444.880492 -59.811666) (xy 444.901412 -59.794012) (xy 444.947389 -59.764303)
			(xy 444.997139 -59.741471) (xy 445.049642 -59.725983) (xy 445.10382 -59.718158) (xy 445.13119 -59.717686)
			(xy 445.158443 -59.718161) (xy 445.212394 -59.725916) (xy 445.264692 -59.741271) (xy 445.314273 -59.763913)
			(xy 445.360127 -59.79338) (xy 445.40132 -59.829073) (xy 445.437014 -59.870265) (xy 445.466482 -59.916118)
			(xy 445.489125 -59.965698) (xy 445.504482 -60.017996) (xy 445.504663 -60.019254) (xy 448.435661 -60.019254)
			(xy 448.435661 -59.964746) (xy 448.443419 -59.910794) (xy 448.458776 -59.858494) (xy 448.481421 -59.808913)
			(xy 448.510891 -59.763059) (xy 448.546587 -59.721866) (xy 448.587783 -59.686173) (xy 448.633639 -59.656706)
			(xy 448.683222 -59.634066) (xy 448.735523 -59.618713) (xy 448.789476 -59.610959) (xy 448.81673 -59.610498)
			(xy 448.844101 -59.610947) (xy 448.898281 -59.618769) (xy 448.950784 -59.634262) (xy 449.00053 -59.657108)
			(xy 449.046497 -59.686835) (xy 449.067428 -59.704478) (xy 449.067682 -59.704732) (xy 449.074767 -59.710321)
			(xy 449.091685 -59.716565) (xy 449.100702 -59.716924) (xy 449.167758 -59.716924) (xy 449.176772 -59.716542)
			(xy 449.193689 -59.710311) (xy 449.200778 -59.704732) (xy 449.200778 -59.704478) (xy 449.201032 -59.704478)
			(xy 449.221965 -59.686837) (xy 449.267933 -59.657113) (xy 449.317679 -59.634267) (xy 449.370181 -59.618771)
			(xy 449.424359 -59.610942) (xy 449.479101 -59.610942) (xy 449.533279 -59.618771) (xy 449.585781 -59.634267)
			(xy 449.635527 -59.657113) (xy 449.681495 -59.686837) (xy 449.702428 -59.704478) (xy 449.702682 -59.704732)
			(xy 449.709767 -59.710321) (xy 449.726685 -59.716565) (xy 449.735702 -59.716924) (xy 449.802758 -59.716924)
			(xy 449.811772 -59.716542) (xy 449.828689 -59.710311) (xy 449.835778 -59.704732) (xy 449.835778 -59.704478)
			(xy 449.836032 -59.704478) (xy 449.856976 -59.686854) (xy 449.902946 -59.657141) (xy 449.95269 -59.634302)
			(xy 450.005188 -59.618807) (xy 450.059362 -59.610975) (xy 450.08673 -59.610498) (xy 450.11398 -59.610974)
			(xy 450.167926 -59.618734) (xy 450.220218 -59.634092) (xy 450.269792 -59.656735) (xy 450.315639 -59.686203)
			(xy 450.356826 -59.721895) (xy 450.392515 -59.763085) (xy 450.421979 -59.808935) (xy 450.444619 -59.858511)
			(xy 450.459972 -59.910804) (xy 450.467728 -59.96475) (xy 450.467728 -60.01925) (xy 450.459972 -60.073196)
			(xy 450.444619 -60.125489) (xy 450.421979 -60.175065) (xy 450.392515 -60.220915) (xy 450.356826 -60.262105)
			(xy 450.315639 -60.297797) (xy 450.269792 -60.327265) (xy 450.220218 -60.349908) (xy 450.167926 -60.365266)
			(xy 450.11398 -60.373026) (xy 450.08673 -60.373514) (xy 450.059361 -60.373027) (xy 450.005183 -60.365214)
			(xy 449.95268 -60.349729) (xy 449.902933 -60.326892) (xy 449.856965 -60.297173) (xy 449.836032 -60.279534)
			(xy 449.835778 -60.27928) (xy 449.828704 -60.273676) (xy 449.811777 -60.26744) (xy 449.802758 -60.267088)
			(xy 449.735702 -60.267088) (xy 449.726686 -60.267449) (xy 449.709769 -60.273694) (xy 449.702682 -60.27928)
			(xy 449.702428 -60.279534) (xy 449.681495 -60.297175) (xy 449.635527 -60.326899) (xy 449.585781 -60.349745)
			(xy 449.533279 -60.365241) (xy 449.479101 -60.37307) (xy 449.424359 -60.37307) (xy 449.370181 -60.365241)
			(xy 449.317679 -60.349745) (xy 449.267933 -60.326899) (xy 449.221965 -60.297175) (xy 449.201032 -60.279534)
			(xy 449.200778 -60.27928) (xy 449.193704 -60.273676) (xy 449.176777 -60.26744) (xy 449.167758 -60.267088)
			(xy 449.100702 -60.267088) (xy 449.091686 -60.267449) (xy 449.074769 -60.273694) (xy 449.067682 -60.27928)
			(xy 449.067682 -60.279534) (xy 449.067428 -60.279534) (xy 449.046501 -60.297179) (xy 449.000526 -60.326889)
			(xy 448.950777 -60.349723) (xy 448.898276 -60.365213) (xy 448.844099 -60.37304) (xy 448.81673 -60.373514)
			(xy 448.789476 -60.373041) (xy 448.735523 -60.365287) (xy 448.683222 -60.349934) (xy 448.633639 -60.327294)
			(xy 448.587783 -60.297827) (xy 448.546587 -60.262134) (xy 448.510891 -60.220941) (xy 448.481421 -60.175087)
			(xy 448.458776 -60.125506) (xy 448.443419 -60.073206) (xy 448.435661 -60.019254) (xy 445.504663 -60.019254)
			(xy 445.512239 -60.071947) (xy 445.512239 -60.126453) (xy 445.504482 -60.180404) (xy 445.489125 -60.232702)
			(xy 445.466482 -60.282282) (xy 445.437014 -60.328135) (xy 445.40132 -60.369327) (xy 445.360127 -60.40502)
			(xy 445.314273 -60.434487) (xy 445.264692 -60.457129) (xy 445.212394 -60.472484) (xy 445.158443 -60.480239)
			(xy 445.13119 -60.480702) (xy 445.10382 -60.480241) (xy 445.04964 -60.472422) (xy 444.997137 -60.456932)
			(xy 444.94739 -60.434089) (xy 444.901424 -60.404364) (xy 444.880492 -60.386722) (xy 444.880238 -60.386468)
			(xy 444.873147 -60.380888) (xy 444.856234 -60.374638) (xy 444.847218 -60.374276) (xy 444.780162 -60.374276)
			(xy 444.771144 -60.37462) (xy 444.754227 -60.380877) (xy 444.747142 -60.386468) (xy 444.746888 -60.386722)
			(xy 444.725955 -60.404363) (xy 444.679987 -60.434087) (xy 444.630241 -60.456933) (xy 444.577739 -60.472429)
			(xy 444.523561 -60.480258) (xy 444.468819 -60.480258) (xy 444.414641 -60.472429) (xy 444.362139 -60.456933)
			(xy 444.312393 -60.434087) (xy 444.266425 -60.404363) (xy 444.245492 -60.386722) (xy 444.245238 -60.386468)
			(xy 444.238147 -60.380888) (xy 444.221234 -60.374638) (xy 444.212218 -60.374276) (xy 444.145162 -60.374276)
			(xy 444.136144 -60.37462) (xy 444.119227 -60.380877) (xy 444.112142 -60.386468) (xy 444.112142 -60.386722)
			(xy 444.111888 -60.386722) (xy 444.090936 -60.404337) (xy 444.044969 -60.434051) (xy 443.995226 -60.456892)
			(xy 443.94273 -60.472389) (xy 443.888558 -60.480224) (xy 443.86119 -60.480702) (xy 443.833939 -60.480228)
			(xy 443.779991 -60.47247) (xy 443.727697 -60.457113) (xy 443.67812 -60.434471) (xy 443.63227 -60.405004)
			(xy 443.591081 -60.369312) (xy 443.55539 -60.328122) (xy 443.525924 -60.282271) (xy 443.503283 -60.232694)
			(xy 443.487928 -60.180399) (xy 443.480172 -60.126451) (xy 432.118167 -60.126451) (xy 432.101643 -60.1617)
			(xy 432.07087 -60.208213) (xy 432.033653 -60.24975) (xy 431.990785 -60.285425) (xy 431.943179 -60.314479)
			(xy 431.89185 -60.336291) (xy 431.837893 -60.350397) (xy 431.782456 -60.356497) (xy 431.726722 -60.35446)
			(xy 431.671879 -60.34433) (xy 431.619095 -60.326323) (xy 431.569495 -60.300822) (xy 431.524137 -60.268371)
			(xy 431.483988 -60.229662) (xy 431.449902 -60.185519) (xy 431.422606 -60.136884) (xy 431.402683 -60.084793)
			(xy 431.390557 -60.030356) (xy 431.386486 -59.974734) (xy 424.467851 -59.974734) (xy 424.467851 -60.019254)
			(xy 424.460093 -60.073207) (xy 424.444736 -60.125508) (xy 424.422092 -60.17509) (xy 424.392622 -60.220944)
			(xy 424.356925 -60.262138) (xy 424.31573 -60.297832) (xy 424.269874 -60.3273) (xy 424.220291 -60.349942)
			(xy 424.16799 -60.365297) (xy 424.114036 -60.373052) (xy 424.086782 -60.373514) (xy 424.059412 -60.373055)
			(xy 424.005232 -60.365235) (xy 423.952729 -60.349744) (xy 423.902983 -60.326901) (xy 423.857016 -60.297175)
			(xy 423.836084 -60.279534) (xy 423.83583 -60.27928) (xy 423.828741 -60.273698) (xy 423.811826 -60.267449)
			(xy 423.80281 -60.267088) (xy 423.735754 -60.267088) (xy 423.72674 -60.267473) (xy 423.709823 -60.273701)
			(xy 423.702734 -60.27928) (xy 423.70248 -60.279534) (xy 423.681547 -60.297175) (xy 423.635579 -60.326899)
			(xy 423.585833 -60.349745) (xy 423.533331 -60.365241) (xy 423.479153 -60.37307) (xy 423.424411 -60.37307)
			(xy 423.370233 -60.365241) (xy 423.317731 -60.349745) (xy 423.267985 -60.326899) (xy 423.222017 -60.297175)
			(xy 423.201084 -60.279534) (xy 423.20083 -60.27928) (xy 423.193741 -60.273698) (xy 423.176826 -60.267449)
			(xy 423.16781 -60.267088) (xy 423.100754 -60.267088) (xy 423.09174 -60.267473) (xy 423.074823 -60.273701)
			(xy 423.067734 -60.27928) (xy 423.067734 -60.279534) (xy 423.06748 -60.279534) (xy 423.046533 -60.297154)
			(xy 423.000564 -60.326868) (xy 422.95082 -60.349707) (xy 422.898323 -60.365202) (xy 422.84415 -60.373037)
			(xy 422.816782 -60.373514) (xy 422.789532 -60.373015) (xy 422.735587 -60.365257) (xy 422.683295 -60.3499)
			(xy 422.633721 -60.327258) (xy 422.587874 -60.297792) (xy 422.546686 -60.262101) (xy 422.510997 -60.220912)
			(xy 422.481533 -60.175063) (xy 422.458894 -60.125488) (xy 422.44354 -60.073195) (xy 422.435784 -60.01925)
			(xy 419.50464 -60.01925) (xy 419.512216 -60.071951) (xy 419.512216 -60.126449) (xy 419.504461 -60.180392)
			(xy 419.489108 -60.232683) (xy 419.466471 -60.282256) (xy 419.437009 -60.328104) (xy 419.401322 -60.369292)
			(xy 419.360138 -60.404983) (xy 419.314293 -60.43445) (xy 419.264722 -60.457094) (xy 419.212433 -60.472452)
			(xy 419.158491 -60.480213) (xy 419.131242 -60.480702) (xy 419.103873 -60.480211) (xy 419.049695 -60.472399)
			(xy 418.997192 -60.456916) (xy 418.947445 -60.43408) (xy 418.901477 -60.404361) (xy 418.880544 -60.386722)
			(xy 418.88029 -60.386468) (xy 418.873213 -60.380868) (xy 418.856289 -60.37463) (xy 418.84727 -60.374276)
			(xy 418.780214 -60.374276) (xy 418.771198 -60.374645) (xy 418.754282 -60.380885) (xy 418.747194 -60.386468)
			(xy 418.74694 -60.386722) (xy 418.726007 -60.404363) (xy 418.680039 -60.434087) (xy 418.630293 -60.456933)
			(xy 418.577791 -60.472429) (xy 418.523613 -60.480258) (xy 418.468871 -60.480258) (xy 418.414693 -60.472429)
			(xy 418.362191 -60.456933) (xy 418.312445 -60.434087) (xy 418.266477 -60.404363) (xy 418.245544 -60.386722)
			(xy 418.24529 -60.386468) (xy 418.238213 -60.380868) (xy 418.221289 -60.37463) (xy 418.21227 -60.374276)
			(xy 418.145214 -60.374276) (xy 418.136198 -60.374645) (xy 418.119282 -60.380885) (xy 418.112194 -60.386468)
			(xy 418.112194 -60.386722) (xy 418.11194 -60.386722) (xy 418.091006 -60.404359) (xy 418.045034 -60.434071)
			(xy 417.995287 -60.456907) (xy 417.942786 -60.472398) (xy 417.888611 -60.480227) (xy 417.861242 -60.480702)
			(xy 417.833987 -60.480254) (xy 417.78003 -60.472501) (xy 417.727727 -60.457149) (xy 417.678141 -60.434508)
			(xy 417.632281 -60.405041) (xy 417.591083 -60.369347) (xy 417.555384 -60.328152) (xy 417.525912 -60.282296)
			(xy 417.503266 -60.232713) (xy 417.487908 -60.180411) (xy 417.480149 -60.126455) (xy 406.118217 -60.126455)
			(xy 406.101695 -60.1617) (xy 406.070922 -60.208213) (xy 406.033705 -60.24975) (xy 405.990837 -60.285425)
			(xy 405.943231 -60.314479) (xy 405.891902 -60.336291) (xy 405.837945 -60.350397) (xy 405.782508 -60.356497)
			(xy 405.726774 -60.35446) (xy 405.671931 -60.34433) (xy 405.619147 -60.326323) (xy 405.569547 -60.300822)
			(xy 405.524189 -60.268371) (xy 405.48404 -60.229662) (xy 405.449954 -60.185519) (xy 405.422658 -60.136884)
			(xy 405.402735 -60.084793) (xy 405.390609 -60.030356) (xy 405.386538 -59.974734) (xy 398.467828 -59.974734)
			(xy 398.467828 -60.01925) (xy 398.460073 -60.073196) (xy 398.444719 -60.125489) (xy 398.42208 -60.175064)
			(xy 398.392616 -60.220914) (xy 398.356928 -60.262104) (xy 398.315741 -60.297796) (xy 398.269894 -60.327264)
			(xy 398.22032 -60.349907) (xy 398.168029 -60.365265) (xy 398.114084 -60.373026) (xy 398.086834 -60.373514)
			(xy 398.059465 -60.373025) (xy 398.005287 -60.365212) (xy 397.952784 -60.349728) (xy 397.903037 -60.326892)
			(xy 397.857069 -60.297173) (xy 397.836136 -60.279534) (xy 397.835882 -60.27928) (xy 397.828806 -60.273678)
			(xy 397.811881 -60.267441) (xy 397.802862 -60.267088) (xy 397.735806 -60.267088) (xy 397.72679 -60.267451)
			(xy 397.709873 -60.273695) (xy 397.702786 -60.27928) (xy 397.702532 -60.279534) (xy 397.681599 -60.297175)
			(xy 397.635631 -60.326899) (xy 397.585885 -60.349745) (xy 397.533383 -60.365241) (xy 397.479205 -60.37307)
			(xy 397.424463 -60.37307) (xy 397.370285 -60.365241) (xy 397.317783 -60.349745) (xy 397.268037 -60.326899)
			(xy 397.222069 -60.297175) (xy 397.201136 -60.279534) (xy 397.200882 -60.27928) (xy 397.193806 -60.273678)
			(xy 397.176881 -60.267441) (xy 397.167862 -60.267088) (xy 397.100806 -60.267088) (xy 397.09179 -60.267451)
			(xy 397.074873 -60.273695) (xy 397.067786 -60.27928) (xy 397.067786 -60.279534) (xy 397.067532 -60.279534)
			(xy 397.046603 -60.297177) (xy 397.000629 -60.326887) (xy 396.95088 -60.349722) (xy 396.898379 -60.365212)
			(xy 396.844203 -60.37304) (xy 396.816834 -60.373514) (xy 396.78958 -60.373041) (xy 396.735626 -60.365288)
			(xy 396.683325 -60.349935) (xy 396.633742 -60.327295) (xy 396.587885 -60.297828) (xy 396.546689 -60.262135)
			(xy 396.510992 -60.220942) (xy 396.481521 -60.175088) (xy 396.458877 -60.125507) (xy 396.443519 -60.073207)
			(xy 396.435761 -60.019254) (xy 393.504763 -60.019254) (xy 393.512339 -60.071947) (xy 393.512339 -60.126453)
			(xy 393.504582 -60.180403) (xy 393.489226 -60.232701) (xy 393.466583 -60.282281) (xy 393.437115 -60.328133)
			(xy 393.401421 -60.369325) (xy 393.360228 -60.405018) (xy 393.314375 -60.434486) (xy 393.264795 -60.457128)
			(xy 393.212497 -60.472483) (xy 393.158547 -60.480239) (xy 393.131294 -60.480702) (xy 393.103924 -60.480239)
			(xy 393.049744 -60.47242) (xy 392.997241 -60.456931) (xy 392.947495 -60.434088) (xy 392.901528 -60.404363)
			(xy 392.880596 -60.386722) (xy 392.880342 -60.386468) (xy 392.87325 -60.380889) (xy 392.856337 -60.374639)
			(xy 392.847322 -60.374276) (xy 392.780266 -60.374276) (xy 392.771248 -60.374622) (xy 392.754331 -60.380878)
			(xy 392.747246 -60.386468) (xy 392.746992 -60.386722) (xy 392.726059 -60.404363) (xy 392.680091 -60.434087)
			(xy 392.630345 -60.456933) (xy 392.577843 -60.472429) (xy 392.523665 -60.480258) (xy 392.468923 -60.480258)
			(xy 392.414745 -60.472429) (xy 392.362243 -60.456933) (xy 392.312497 -60.434087) (xy 392.266529 -60.404363)
			(xy 392.245596 -60.386722) (xy 392.245342 -60.386468) (xy 392.23825 -60.380889) (xy 392.221337 -60.374639)
			(xy 392.212322 -60.374276) (xy 392.145266 -60.374276) (xy 392.136248 -60.374622) (xy 392.119331 -60.380878)
			(xy 392.112246 -60.386468) (xy 392.112246 -60.386722) (xy 392.111992 -60.386722) (xy 392.091077 -60.404382)
			(xy 392.045099 -60.43409) (xy 391.995347 -60.456921) (xy 391.942843 -60.472408) (xy 391.888664 -60.480231)
			(xy 391.861294 -60.480702) (xy 391.834043 -60.480228) (xy 391.780095 -60.47247) (xy 391.7278 -60.457115)
			(xy 391.678223 -60.434473) (xy 391.632372 -60.405006) (xy 391.591182 -60.369314) (xy 391.555491 -60.328123)
			(xy 391.526024 -60.282272) (xy 391.503383 -60.232695) (xy 391.488028 -60.180399) (xy 391.480272 -60.126451)
			(xy 380.118271 -60.126451) (xy 380.101747 -60.1617) (xy 380.070974 -60.208213) (xy 380.033757 -60.24975)
			(xy 379.990889 -60.285425) (xy 379.943283 -60.314479) (xy 379.891954 -60.336291) (xy 379.837997 -60.350397)
			(xy 379.78256 -60.356497) (xy 379.726826 -60.35446) (xy 379.671983 -60.34433) (xy 379.619199 -60.326323)
			(xy 379.569599 -60.300822) (xy 379.524241 -60.268371) (xy 379.484092 -60.229662) (xy 379.450006 -60.185519)
			(xy 379.42271 -60.136884) (xy 379.402787 -60.084793) (xy 379.390661 -60.030356) (xy 379.38659 -59.974734)
			(xy 372.467951 -59.974734) (xy 372.467951 -60.019254) (xy 372.460193 -60.073207) (xy 372.444836 -60.125507)
			(xy 372.422192 -60.175089) (xy 372.392723 -60.220943) (xy 372.357027 -60.262137) (xy 372.315832 -60.297831)
			(xy 372.269976 -60.327299) (xy 372.220394 -60.349941) (xy 372.168093 -60.365296) (xy 372.11414 -60.373052)
			(xy 372.086886 -60.373514) (xy 372.059516 -60.373053) (xy 372.005336 -60.365233) (xy 371.952833 -60.349743)
			(xy 371.903087 -60.3269) (xy 371.85712 -60.297175) (xy 371.836188 -60.279534) (xy 371.835934 -60.27928)
			(xy 371.828844 -60.273699) (xy 371.81193 -60.26745) (xy 371.802914 -60.267088) (xy 371.735858 -60.267088)
			(xy 371.726844 -60.267476) (xy 371.709927 -60.273702) (xy 371.702838 -60.27928) (xy 371.702584 -60.279534)
			(xy 371.681651 -60.297175) (xy 371.635683 -60.326899) (xy 371.585937 -60.349745) (xy 371.533435 -60.365241)
			(xy 371.479257 -60.37307) (xy 371.424515 -60.37307) (xy 371.370337 -60.365241) (xy 371.317835 -60.349745)
			(xy 371.268089 -60.326899) (xy 371.222121 -60.297175) (xy 371.201188 -60.279534) (xy 371.200934 -60.27928)
			(xy 371.193844 -60.273699) (xy 371.17693 -60.26745) (xy 371.167914 -60.267088) (xy 371.100858 -60.267088)
			(xy 371.091844 -60.267476) (xy 371.074927 -60.273702) (xy 371.067838 -60.27928) (xy 371.067838 -60.279534)
			(xy 371.067584 -60.279534) (xy 371.046635 -60.297152) (xy 371.000667 -60.326866) (xy 370.950923 -60.349706)
			(xy 370.898426 -60.365202) (xy 370.844254 -60.373036) (xy 370.816886 -60.373514) (xy 370.789636 -60.373015)
			(xy 370.73569 -60.365257) (xy 370.683398 -60.349901) (xy 370.633824 -60.32726) (xy 370.587976 -60.297793)
			(xy 370.546788 -60.262102) (xy 370.511098 -60.220913) (xy 370.481634 -60.175064) (xy 370.458994 -60.125489)
			(xy 370.44364 -60.073196) (xy 370.435884 -60.01925) (xy 367.50474 -60.01925) (xy 367.512316 -60.071951)
			(xy 367.512316 -60.126449) (xy 367.504561 -60.180392) (xy 367.489209 -60.232682) (xy 367.466571 -60.282255)
			(xy 367.43711 -60.328103) (xy 367.401424 -60.369291) (xy 367.36024 -60.404982) (xy 367.314396 -60.434449)
			(xy 367.264825 -60.457093) (xy 367.212537 -60.472451) (xy 367.158595 -60.480213) (xy 367.131346 -60.480702)
			(xy 367.103977 -60.480208) (xy 367.049799 -60.472397) (xy 366.997296 -60.456915) (xy 366.947549 -60.434079)
			(xy 366.901581 -60.40436) (xy 366.880648 -60.386722) (xy 366.880394 -60.386468) (xy 366.873316 -60.380869)
			(xy 366.856392 -60.374631) (xy 366.847374 -60.374276) (xy 366.780318 -60.374276) (xy 366.771303 -60.374647)
			(xy 366.754386 -60.380885) (xy 366.747298 -60.386468) (xy 366.747044 -60.386722) (xy 366.726111 -60.404363)
			(xy 366.680143 -60.434087) (xy 366.630397 -60.456933) (xy 366.577895 -60.472429) (xy 366.523717 -60.480258)
			(xy 366.468975 -60.480258) (xy 366.414797 -60.472429) (xy 366.362295 -60.456933) (xy 366.312549 -60.434087)
			(xy 366.266581 -60.404363) (xy 366.245648 -60.386722) (xy 366.245394 -60.386468) (xy 366.238316 -60.380869)
			(xy 366.221392 -60.374631) (xy 366.212374 -60.374276) (xy 366.145318 -60.374276) (xy 366.136303 -60.374647)
			(xy 366.119386 -60.380885) (xy 366.112298 -60.386468) (xy 366.112298 -60.386722) (xy 366.112044 -60.386722)
			(xy 366.091109 -60.404357) (xy 366.045137 -60.434069) (xy 365.99539 -60.456905) (xy 365.94289 -60.472397)
			(xy 365.888715 -60.480227) (xy 365.861346 -60.480702) (xy 365.834091 -60.480254) (xy 365.780134 -60.472502)
			(xy 365.72783 -60.45715) (xy 365.678243 -60.434509) (xy 365.632383 -60.405042) (xy 365.591185 -60.369348)
			(xy 365.555485 -60.328154) (xy 365.526013 -60.282297) (xy 365.503366 -60.232714) (xy 365.488008 -60.180411)
			(xy 365.48025 -60.126455) (xy 365.480249 -60.071945) (xy 354.137282 -60.071945) (xy 354.125471 -60.111203)
			(xy 354.101799 -60.1617) (xy 354.071026 -60.208213) (xy 354.033809 -60.24975) (xy 353.990941 -60.285425)
			(xy 353.943335 -60.314479) (xy 353.892006 -60.336291) (xy 353.838049 -60.350397) (xy 353.782612 -60.356497)
			(xy 353.726878 -60.35446) (xy 353.672035 -60.34433) (xy 353.619251 -60.326323) (xy 353.569651 -60.300822)
			(xy 353.524293 -60.268371) (xy 353.484144 -60.229662) (xy 353.450058 -60.185519) (xy 353.422762 -60.136884)
			(xy 353.402839 -60.084793) (xy 353.390713 -60.030356) (xy 353.386642 -59.974734) (xy 334.367628 -59.974734)
			(xy 334.367628 -60.01925) (xy 334.359872 -60.073196) (xy 334.344519 -60.125489) (xy 334.32188 -60.175065)
			(xy 334.292416 -60.220914) (xy 334.256727 -60.262105) (xy 334.21554 -60.297797) (xy 334.169693 -60.327264)
			(xy 334.120119 -60.349908) (xy 334.067827 -60.365266) (xy 334.013882 -60.373026) (xy 333.986632 -60.373514)
			(xy 333.959263 -60.373026) (xy 333.905085 -60.365213) (xy 333.852582 -60.349729) (xy 333.802835 -60.326892)
			(xy 333.756867 -60.297173) (xy 333.735934 -60.279534) (xy 333.73568 -60.27928) (xy 333.728605 -60.273677)
			(xy 333.711679 -60.267441) (xy 333.70266 -60.267088) (xy 333.635604 -60.267088) (xy 333.626588 -60.26745)
			(xy 333.609671 -60.273694) (xy 333.602584 -60.27928) (xy 333.60233 -60.279534) (xy 333.581397 -60.297175)
			(xy 333.535429 -60.326899) (xy 333.485683 -60.349745) (xy 333.433181 -60.365241) (xy 333.379003 -60.37307)
			(xy 333.324261 -60.37307) (xy 333.270083 -60.365241) (xy 333.217581 -60.349745) (xy 333.167835 -60.326899)
			(xy 333.121867 -60.297175) (xy 333.100934 -60.279534) (xy 333.10068 -60.27928) (xy 333.093605 -60.273677)
			(xy 333.076679 -60.267441) (xy 333.06766 -60.267088) (xy 333.000604 -60.267088) (xy 332.991588 -60.26745)
			(xy 332.974671 -60.273694) (xy 332.967584 -60.27928) (xy 332.967584 -60.279534) (xy 332.96733 -60.279534)
			(xy 332.946402 -60.297178) (xy 332.900427 -60.326888) (xy 332.850679 -60.349722) (xy 332.798178 -60.365212)
			(xy 332.744001 -60.37304) (xy 332.716632 -60.373514) (xy 332.689378 -60.373041) (xy 332.635425 -60.365288)
			(xy 332.583124 -60.349935) (xy 332.53354 -60.327294) (xy 332.487684 -60.297828) (xy 332.446488 -60.262135)
			(xy 332.410791 -60.220942) (xy 332.381321 -60.175088) (xy 332.358677 -60.125506) (xy 332.343319 -60.073207)
			(xy 332.335561 -60.019254) (xy 329.404563 -60.019254) (xy 329.412139 -60.071947) (xy 329.412139 -60.126453)
			(xy 329.404382 -60.180404) (xy 329.389025 -60.232701) (xy 329.366383 -60.282281) (xy 329.336914 -60.328134)
			(xy 329.30122 -60.369326) (xy 329.260027 -60.405019) (xy 329.214174 -60.434487) (xy 329.164594 -60.457128)
			(xy 329.112296 -60.472483) (xy 329.058345 -60.480239) (xy 329.031092 -60.480702) (xy 329.003722 -60.48024)
			(xy 328.949542 -60.472421) (xy 328.897039 -60.456931) (xy 328.847292 -60.434089) (xy 328.801326 -60.404363)
			(xy 328.780394 -60.386722) (xy 328.78014 -60.386468) (xy 328.773049 -60.380888) (xy 328.756135 -60.374639)
			(xy 328.74712 -60.374276) (xy 328.680064 -60.374276) (xy 328.671046 -60.374621) (xy 328.654129 -60.380877)
			(xy 328.647044 -60.386468) (xy 328.64679 -60.386722) (xy 328.625857 -60.404363) (xy 328.579889 -60.434087)
			(xy 328.530143 -60.456933) (xy 328.477641 -60.472429) (xy 328.423463 -60.480258) (xy 328.368721 -60.480258)
			(xy 328.314543 -60.472429) (xy 328.262041 -60.456933) (xy 328.212295 -60.434087) (xy 328.166327 -60.404363)
			(xy 328.145394 -60.386722) (xy 328.14514 -60.386468) (xy 328.138049 -60.380888) (xy 328.121135 -60.374639)
			(xy 328.11212 -60.374276) (xy 328.045064 -60.374276) (xy 328.036046 -60.374621) (xy 328.019129 -60.380877)
			(xy 328.012044 -60.386468) (xy 328.012044 -60.386722) (xy 328.01179 -60.386722) (xy 327.990875 -60.404383)
			(xy 327.944897 -60.434091) (xy 327.895145 -60.456922) (xy 327.842641 -60.472408) (xy 327.788462 -60.480231)
			(xy 327.761092 -60.480702) (xy 327.733841 -60.480228) (xy 327.679893 -60.47247) (xy 327.627598 -60.457114)
			(xy 327.578021 -60.434472) (xy 327.532171 -60.405005) (xy 327.490981 -60.369313) (xy 327.45529 -60.328122)
			(xy 327.425824 -60.282272) (xy 327.403183 -60.232694) (xy 327.387828 -60.180399) (xy 327.380072 -60.126451)
			(xy 316.018069 -60.126451) (xy 316.001545 -60.1617) (xy 315.970772 -60.208213) (xy 315.933555 -60.24975)
			(xy 315.890687 -60.285425) (xy 315.843081 -60.314479) (xy 315.791752 -60.336291) (xy 315.737795 -60.350397)
			(xy 315.682358 -60.356497) (xy 315.626624 -60.35446) (xy 315.571781 -60.34433) (xy 315.518997 -60.326323)
			(xy 315.469397 -60.300822) (xy 315.424039 -60.268371) (xy 315.38389 -60.229662) (xy 315.349804 -60.185519)
			(xy 315.322508 -60.136884) (xy 315.302585 -60.084793) (xy 315.290459 -60.030356) (xy 315.286388 -59.974734)
			(xy 308.367751 -59.974734) (xy 308.367751 -60.019254) (xy 308.359993 -60.073207) (xy 308.344636 -60.125507)
			(xy 308.321992 -60.175089) (xy 308.292522 -60.220944) (xy 308.256826 -60.262137) (xy 308.215631 -60.297832)
			(xy 308.169775 -60.3273) (xy 308.120192 -60.349942) (xy 308.067892 -60.365296) (xy 308.013938 -60.373052)
			(xy 307.986684 -60.373514) (xy 307.959314 -60.373054) (xy 307.905134 -60.365234) (xy 307.852631 -60.349743)
			(xy 307.802885 -60.326901) (xy 307.756918 -60.297175) (xy 307.735986 -60.279534) (xy 307.735732 -60.27928)
			(xy 307.728642 -60.273698) (xy 307.711728 -60.267449) (xy 307.702712 -60.267088) (xy 307.635656 -60.267088)
			(xy 307.626642 -60.267474) (xy 307.609725 -60.273702) (xy 307.602636 -60.27928) (xy 307.602382 -60.279534)
			(xy 307.581449 -60.297175) (xy 307.535481 -60.326899) (xy 307.485735 -60.349745) (xy 307.433233 -60.365241)
			(xy 307.379055 -60.37307) (xy 307.324313 -60.37307) (xy 307.270135 -60.365241) (xy 307.217633 -60.349745)
			(xy 307.167887 -60.326899) (xy 307.121919 -60.297175) (xy 307.100986 -60.279534) (xy 307.100732 -60.27928)
			(xy 307.093642 -60.273698) (xy 307.076728 -60.267449) (xy 307.067712 -60.267088) (xy 307.000656 -60.267088)
			(xy 306.991642 -60.267474) (xy 306.974725 -60.273702) (xy 306.967636 -60.27928) (xy 306.967636 -60.279534)
			(xy 306.967382 -60.279534) (xy 306.946434 -60.297153) (xy 306.900465 -60.326867) (xy 306.850722 -60.349706)
			(xy 306.798225 -60.365202) (xy 306.744052 -60.373036) (xy 306.716684 -60.373514) (xy 306.689434 -60.373015)
			(xy 306.635489 -60.365257) (xy 306.583197 -60.349901) (xy 306.533622 -60.327259) (xy 306.487775 -60.297793)
			(xy 306.446587 -60.262102) (xy 306.410898 -60.220913) (xy 306.381433 -60.175064) (xy 306.358794 -60.125488)
			(xy 306.34344 -60.073196) (xy 306.335684 -60.01925) (xy 303.40454 -60.01925) (xy 303.412116 -60.071951)
			(xy 303.412116 -60.126449) (xy 303.404361 -60.180392) (xy 303.389008 -60.232682) (xy 303.366371 -60.282256)
			(xy 303.336909 -60.328103) (xy 303.301223 -60.369292) (xy 303.260039 -60.404983) (xy 303.214194 -60.43445)
			(xy 303.164624 -60.457093) (xy 303.112335 -60.472452) (xy 303.058393 -60.480213) (xy 303.031144 -60.480702)
			(xy 303.003775 -60.48021) (xy 302.949597 -60.472398) (xy 302.897094 -60.456915) (xy 302.847347 -60.434079)
			(xy 302.801379 -60.40436) (xy 302.780446 -60.386722) (xy 302.780192 -60.386468) (xy 302.773115 -60.380868)
			(xy 302.756191 -60.374631) (xy 302.747172 -60.374276) (xy 302.680116 -60.374276) (xy 302.671101 -60.374646)
			(xy 302.654184 -60.380885) (xy 302.647096 -60.386468) (xy 302.646842 -60.386722) (xy 302.625909 -60.404363)
			(xy 302.579941 -60.434087) (xy 302.530195 -60.456933) (xy 302.477693 -60.472429) (xy 302.423515 -60.480258)
			(xy 302.368773 -60.480258) (xy 302.314595 -60.472429) (xy 302.262093 -60.456933) (xy 302.212347 -60.434087)
			(xy 302.166379 -60.404363) (xy 302.145446 -60.386722) (xy 302.145192 -60.386468) (xy 302.138115 -60.380868)
			(xy 302.121191 -60.374631) (xy 302.112172 -60.374276) (xy 302.045116 -60.374276) (xy 302.036101 -60.374646)
			(xy 302.019184 -60.380885) (xy 302.012096 -60.386468) (xy 302.012096 -60.386722) (xy 302.011842 -60.386722)
			(xy 301.990908 -60.404358) (xy 301.944935 -60.43407) (xy 301.895188 -60.456906) (xy 301.842688 -60.472398)
			(xy 301.788513 -60.480227) (xy 301.761144 -60.480702) (xy 301.733889 -60.480254) (xy 301.679932 -60.472502)
			(xy 301.627628 -60.457149) (xy 301.578042 -60.434509) (xy 301.532182 -60.405042) (xy 301.490984 -60.369347)
			(xy 301.455285 -60.328153) (xy 301.425812 -60.282297) (xy 301.403166 -60.232713) (xy 301.387808 -60.180411)
			(xy 301.380049 -60.126455) (xy 290.018119 -60.126455) (xy 290.001597 -60.1617) (xy 289.970824 -60.208213)
			(xy 289.933607 -60.24975) (xy 289.890739 -60.285425) (xy 289.843133 -60.314479) (xy 289.791804 -60.336291)
			(xy 289.737847 -60.350397) (xy 289.68241 -60.356497) (xy 289.626676 -60.35446) (xy 289.571833 -60.34433)
			(xy 289.519049 -60.326323) (xy 289.469449 -60.300822) (xy 289.424091 -60.268371) (xy 289.383942 -60.229662)
			(xy 289.349856 -60.185519) (xy 289.32256 -60.136884) (xy 289.302637 -60.084793) (xy 289.290511 -60.030356)
			(xy 289.28644 -59.974734) (xy 282.367728 -59.974734) (xy 282.367728 -60.01925) (xy 282.359973 -60.073195)
			(xy 282.344619 -60.125488) (xy 282.32198 -60.175064) (xy 282.292517 -60.220913) (xy 282.256829 -60.262103)
			(xy 282.215642 -60.297795) (xy 282.169795 -60.327263) (xy 282.120222 -60.349906) (xy 282.067931 -60.365265)
			(xy 282.013986 -60.373026) (xy 281.986736 -60.373514) (xy 281.959367 -60.373023) (xy 281.905189 -60.365211)
			(xy 281.852686 -60.349727) (xy 281.802939 -60.326891) (xy 281.756971 -60.297172) (xy 281.736038 -60.279534)
			(xy 281.735784 -60.27928) (xy 281.728708 -60.273678) (xy 281.711783 -60.267441) (xy 281.702764 -60.267088)
			(xy 281.635708 -60.267088) (xy 281.626692 -60.267451) (xy 281.609775 -60.273695) (xy 281.602688 -60.27928)
			(xy 281.602434 -60.279534) (xy 281.581501 -60.297175) (xy 281.535533 -60.326899) (xy 281.485787 -60.349745)
			(xy 281.433285 -60.365241) (xy 281.379107 -60.37307) (xy 281.324365 -60.37307) (xy 281.270187 -60.365241)
			(xy 281.217685 -60.349745) (xy 281.167939 -60.326899) (xy 281.121971 -60.297175) (xy 281.101038 -60.279534)
			(xy 281.100784 -60.27928) (xy 281.093708 -60.273678) (xy 281.076783 -60.267441) (xy 281.067764 -60.267088)
			(xy 281.000708 -60.267088) (xy 280.991692 -60.267451) (xy 280.974775 -60.273695) (xy 280.967688 -60.27928)
			(xy 280.967688 -60.279534) (xy 280.967434 -60.279534) (xy 280.946504 -60.297176) (xy 280.90053 -60.326886)
			(xy 280.850782 -60.349721) (xy 280.798281 -60.365212) (xy 280.744105 -60.37304) (xy 280.716736 -60.373514)
			(xy 280.689482 -60.373041) (xy 280.635528 -60.365288) (xy 280.583227 -60.349936) (xy 280.533643 -60.327296)
			(xy 280.487786 -60.297829) (xy 280.446589 -60.262136) (xy 280.410892 -60.220943) (xy 280.381422 -60.175089)
			(xy 280.358777 -60.125507) (xy 280.343419 -60.073207) (xy 280.335661 -60.019254) (xy 277.404663 -60.019254)
			(xy 277.412239 -60.071947) (xy 277.412239 -60.126453) (xy 277.404482 -60.180403) (xy 277.389126 -60.2327)
			(xy 277.366483 -60.28228) (xy 277.337015 -60.328133) (xy 277.301322 -60.369325) (xy 277.260129 -60.405018)
			(xy 277.214276 -60.434485) (xy 277.164697 -60.457127) (xy 277.112399 -60.472483) (xy 277.058449 -60.480239)
			(xy 277.031196 -60.480702) (xy 277.003826 -60.480238) (xy 276.949647 -60.472419) (xy 276.897143 -60.45693)
			(xy 276.847397 -60.434088) (xy 276.80143 -60.404363) (xy 276.780498 -60.386722) (xy 276.780244 -60.386468)
			(xy 276.773152 -60.38089) (xy 276.756239 -60.374639) (xy 276.747224 -60.374276) (xy 276.680168 -60.374276)
			(xy 276.67115 -60.374623) (xy 276.654234 -60.380878) (xy 276.647148 -60.386468) (xy 276.646894 -60.386722)
			(xy 276.625961 -60.404363) (xy 276.579993 -60.434087) (xy 276.530247 -60.456933) (xy 276.477745 -60.472429)
			(xy 276.423567 -60.480258) (xy 276.368825 -60.480258) (xy 276.314647 -60.472429) (xy 276.262145 -60.456933)
			(xy 276.212399 -60.434087) (xy 276.166431 -60.404363) (xy 276.145498 -60.386722) (xy 276.145244 -60.386468)
			(xy 276.138152 -60.38089) (xy 276.121239 -60.374639) (xy 276.112224 -60.374276) (xy 276.045168 -60.374276)
			(xy 276.03615 -60.374623) (xy 276.019234 -60.380878) (xy 276.012148 -60.386468) (xy 276.012148 -60.386722)
			(xy 276.011894 -60.386722) (xy 275.990978 -60.404381) (xy 275.945 -60.434089) (xy 275.895249 -60.456921)
			(xy 275.842745 -60.472407) (xy 275.788566 -60.480231) (xy 275.761196 -60.480702) (xy 275.733945 -60.480228)
			(xy 275.679996 -60.472471) (xy 275.627701 -60.457115) (xy 275.578124 -60.434473) (xy 275.532273 -60.405007)
			(xy 275.491083 -60.369314) (xy 275.455391 -60.328124) (xy 275.425925 -60.282273) (xy 275.403283 -60.232695)
			(xy 275.387928 -60.1804) (xy 275.380172 -60.126451) (xy 264.018173 -60.126451) (xy 264.001649 -60.1617)
			(xy 263.970876 -60.208213) (xy 263.933659 -60.24975) (xy 263.890791 -60.285425) (xy 263.843185 -60.314479)
			(xy 263.791856 -60.336291) (xy 263.737899 -60.350397) (xy 263.682462 -60.356497) (xy 263.626728 -60.35446)
			(xy 263.571885 -60.34433) (xy 263.519101 -60.326323) (xy 263.469501 -60.300822) (xy 263.424143 -60.268371)
			(xy 263.383994 -60.229662) (xy 263.349908 -60.185519) (xy 263.322612 -60.136884) (xy 263.302689 -60.084793)
			(xy 263.290563 -60.030356) (xy 263.286492 -59.974734) (xy 256.367851 -59.974734) (xy 256.367851 -60.019254)
			(xy 256.360093 -60.073207) (xy 256.344736 -60.125506) (xy 256.322093 -60.175088) (xy 256.292623 -60.220942)
			(xy 256.256928 -60.262136) (xy 256.215733 -60.29783) (xy 256.169877 -60.327298) (xy 256.120295 -60.349941)
			(xy 256.067995 -60.365296) (xy 256.014042 -60.373051) (xy 255.986788 -60.373514) (xy 255.959418 -60.373052)
			(xy 255.905239 -60.365232) (xy 255.852736 -60.349742) (xy 255.802989 -60.3269) (xy 255.757022 -60.297175)
			(xy 255.73609 -60.279534) (xy 255.735836 -60.27928) (xy 255.728745 -60.2737) (xy 255.711832 -60.26745)
			(xy 255.702816 -60.267088) (xy 255.63576 -60.267088) (xy 255.626741 -60.267428) (xy 255.609825 -60.273688)
			(xy 255.60274 -60.27928) (xy 255.602486 -60.279534) (xy 255.581553 -60.297175) (xy 255.535585 -60.326899)
			(xy 255.485839 -60.349745) (xy 255.433337 -60.365241) (xy 255.379159 -60.37307) (xy 255.324417 -60.37307)
			(xy 255.270239 -60.365241) (xy 255.217737 -60.349745) (xy 255.167991 -60.326899) (xy 255.122023 -60.297175)
			(xy 255.10109 -60.279534) (xy 255.100836 -60.27928) (xy 255.093745 -60.2737) (xy 255.076832 -60.26745)
			(xy 255.067816 -60.267088) (xy 255.00076 -60.267088) (xy 254.991741 -60.267428) (xy 254.974825 -60.273688)
			(xy 254.96774 -60.27928) (xy 254.96774 -60.279534) (xy 254.967486 -60.279534) (xy 254.946537 -60.297152)
			(xy 254.900568 -60.326865) (xy 254.850825 -60.349705) (xy 254.798328 -60.365201) (xy 254.744156 -60.373036)
			(xy 254.716788 -60.373514) (xy 254.689538 -60.373015) (xy 254.635592 -60.365258) (xy 254.5833 -60.349902)
			(xy 254.533725 -60.32726) (xy 254.487877 -60.297794) (xy 254.446688 -60.262103) (xy 254.410999 -60.220914)
			(xy 254.381534 -60.175065) (xy 254.358894 -60.125489) (xy 254.34354 -60.073196) (xy 254.335784 -60.01925)
			(xy 251.404639 -60.01925) (xy 251.412216 -60.071951) (xy 251.412216 -60.126449) (xy 251.404461 -60.180391)
			(xy 251.389109 -60.232681) (xy 251.366471 -60.282255) (xy 251.33701 -60.328102) (xy 251.301324 -60.36929)
			(xy 251.260141 -60.404981) (xy 251.214297 -60.434448) (xy 251.164726 -60.457092) (xy 251.112438 -60.472451)
			(xy 251.058497 -60.480213) (xy 251.031248 -60.480702) (xy 251.003879 -60.480207) (xy 250.949701 -60.472396)
			(xy 250.897198 -60.456914) (xy 250.847451 -60.434079) (xy 250.801483 -60.40436) (xy 250.78055 -60.386722)
			(xy 250.780296 -60.386468) (xy 250.773217 -60.38087) (xy 250.756294 -60.374631) (xy 250.747276 -60.374276)
			(xy 250.68022 -60.374276) (xy 250.671205 -60.374648) (xy 250.654288 -60.380886) (xy 250.6472 -60.386468)
			(xy 250.646946 -60.386722) (xy 250.626013 -60.404363) (xy 250.580045 -60.434087) (xy 250.530299 -60.456933)
			(xy 250.477797 -60.472429) (xy 250.423619 -60.480258) (xy 250.368877 -60.480258) (xy 250.314699 -60.472429)
			(xy 250.262197 -60.456933) (xy 250.212451 -60.434087) (xy 250.166483 -60.404363) (xy 250.14555 -60.386722)
			(xy 250.145296 -60.386468) (xy 250.138217 -60.38087) (xy 250.121294 -60.374631) (xy 250.112276 -60.374276)
			(xy 250.04522 -60.374276) (xy 250.036205 -60.374648) (xy 250.019288 -60.380886) (xy 250.0122 -60.386468)
			(xy 250.0122 -60.386722) (xy 250.011946 -60.386722) (xy 249.99101 -60.404356) (xy 249.945038 -60.434068)
			(xy 249.895291 -60.456905) (xy 249.842792 -60.472397) (xy 249.788617 -60.480227) (xy 249.761248 -60.480702)
			(xy 249.733992 -60.480254) (xy 249.680036 -60.472502) (xy 249.627731 -60.45715) (xy 249.578144 -60.43451)
			(xy 249.532284 -60.405043) (xy 249.491085 -60.369349) (xy 249.455386 -60.328154) (xy 249.425913 -60.282298)
			(xy 249.403267 -60.232714) (xy 249.387908 -60.180411) (xy 249.38015 -60.126455) (xy 233.976797 -60.126455)
			(xy 233.980286 -60.151462) (xy 233.980736 -60.177934) (xy 233.98025 -60.205185) (xy 233.972494 -60.259133)
			(xy 233.957139 -60.311428) (xy 233.934497 -60.361005) (xy 233.905031 -60.406855) (xy 233.86934 -60.448046)
			(xy 233.828149 -60.483737) (xy 233.782299 -60.513203) (xy 233.732722 -60.535845) (xy 233.680427 -60.5512)
			(xy 233.626479 -60.558956) (xy 233.571977 -60.558956) (xy 233.518029 -60.5512) (xy 233.465734 -60.535845)
			(xy 233.416157 -60.513203) (xy 233.370307 -60.483737) (xy 233.329116 -60.448046) (xy 233.293425 -60.406855)
			(xy 233.263959 -60.361005) (xy 233.241317 -60.311428) (xy 233.225962 -60.259133) (xy 233.218206 -60.205185)
			(xy 233.21772 -60.177934) (xy 233.218264 -60.14923) (xy 233.226868 -60.092469) (xy 233.243871 -60.037636)
			(xy 233.268891 -59.985967) (xy 233.301364 -59.938625) (xy 233.340559 -59.896677) (xy 233.362754 -59.878468)
			(xy 233.371817 -59.870569) (xy 233.382015 -59.848831) (xy 233.382312 -59.836812) (xy 233.37901 -59.742832)
			(xy 233.367326 -59.72175) (xy 233.357166 -59.714892) (xy 233.335564 -59.699583) (xy 233.296418 -59.663932)
			(xy 233.262579 -59.623211) (xy 233.234694 -59.578202) (xy 233.213301 -59.52977) (xy 233.198809 -59.478845)
			(xy 233.191498 -59.426405) (xy 233.19105 -59.399932) (xy 231.875094 -59.399932) (xy 231.870184 -59.40624)
			(xy 231.804696 -59.47738) (xy 231.733556 -59.542868) (xy 231.657251 -59.602259) (xy 231.576303 -59.655145)
			(xy 231.491263 -59.701166) (xy 231.402714 -59.740007) (xy 231.311259 -59.771404) (xy 231.217525 -59.79514)
			(xy 231.12215 -59.811056) (xy 231.025787 -59.819041) (xy 230.929093 -59.819041) (xy 230.83273 -59.811056)
			(xy 230.737355 -59.79514) (xy 230.643621 -59.771404) (xy 230.552166 -59.740007) (xy 230.463617 -59.701166)
			(xy 230.378577 -59.655145) (xy 230.297629 -59.602259) (xy 230.221324 -59.542868) (xy 230.150184 -59.47738)
			(xy 230.084696 -59.40624) (xy 230.025305 -59.329935) (xy 229.972419 -59.248987) (xy 229.926398 -59.163947)
			(xy 229.887557 -59.075398) (xy 229.85616 -58.983943) (xy 229.832424 -58.890209) (xy 229.816508 -58.794834)
			(xy 229.808523 -58.698471) (xy 228.750613 -58.698471) (xy 228.75658 -58.718789) (xy 228.764337 -58.772734)
			(xy 228.764846 -58.799984) (xy 228.764846 -58.800238) (xy 228.764846 -58.802016) (xy 228.765082 -58.810844)
			(xy 228.770939 -58.827492) (xy 228.776276 -58.834528) (xy 228.79558 -58.857642) (xy 228.801593 -58.864441)
			(xy 228.817206 -58.873676) (xy 228.82606 -58.875676) (xy 228.861437 -58.882246) (xy 228.930721 -58.901677)
			(xy 228.997655 -58.928092) (xy 229.061537 -58.961214) (xy 229.121695 -59.000696) (xy 229.1775 -59.046124)
			(xy 229.20325 -59.071256) (xy 229.854252 -59.722258) (xy 229.881731 -59.750534) (xy 229.930877 -59.812193)
			(xy 229.972816 -59.878964) (xy 230.00702 -59.950008) (xy 230.033059 -60.024433) (xy 230.050607 -60.101305)
			(xy 230.059443 -60.179657) (xy 230.059992 -60.219082) (xy 230.059992 -60.600082) (xy 231.00614 -60.600082)
			(xy 231.010211 -60.54446) (xy 231.022337 -60.490023) (xy 231.04226 -60.437932) (xy 231.069556 -60.389297)
			(xy 231.103642 -60.345154) (xy 231.143791 -60.306445) (xy 231.189149 -60.273994) (xy 231.238749 -60.248493)
			(xy 231.291533 -60.230486) (xy 231.346376 -60.220356) (xy 231.40211 -60.218319) (xy 231.457547 -60.224419)
			(xy 231.511504 -60.238525) (xy 231.562833 -60.260337) (xy 231.610439 -60.289391) (xy 231.653307 -60.325066)
			(xy 231.690524 -60.366603) (xy 231.721297 -60.413116) (xy 231.744969 -60.463613) (xy 231.761037 -60.51702)
			(xy 231.769157 -60.572196) (xy 231.769666 -60.600082) (xy 231.769157 -60.627968) (xy 231.761037 -60.683144)
			(xy 231.744969 -60.736551) (xy 231.721297 -60.787048) (xy 231.690524 -60.833561) (xy 231.653307 -60.875098)
			(xy 231.610439 -60.910773) (xy 231.562833 -60.939827) (xy 231.538084 -60.950344) (xy 239.381774 -60.950344)
			(xy 239.381774 -60.890408) (xy 239.389597 -60.830986) (xy 239.40511 -60.773093) (xy 239.428046 -60.71772)
			(xy 239.458013 -60.665814) (xy 239.4945 -60.618264) (xy 239.53688 -60.575884) (xy 239.58443 -60.539397)
			(xy 239.636336 -60.50943) (xy 239.691709 -60.486494) (xy 239.749602 -60.470981) (xy 239.809024 -60.463158)
			(xy 239.86896 -60.463158) (xy 239.928382 -60.470981) (xy 239.986275 -60.486494) (xy 240.041648 -60.50943)
			(xy 240.093554 -60.539397) (xy 240.141104 -60.575884) (xy 240.166826 -60.601606) (xy 262.533128 -60.601606)
			(xy 262.537199 -60.545984) (xy 262.549325 -60.491547) (xy 262.569248 -60.439456) (xy 262.596544 -60.390821)
			(xy 262.63063 -60.346678) (xy 262.670779 -60.307969) (xy 262.716137 -60.275518) (xy 262.765737 -60.250017)
			(xy 262.818521 -60.23201) (xy 262.873364 -60.22188) (xy 262.929098 -60.219843) (xy 262.984535 -60.225943)
			(xy 263.038492 -60.240049) (xy 263.089821 -60.261861) (xy 263.137427 -60.290915) (xy 263.180295 -60.32659)
			(xy 263.217512 -60.368127) (xy 263.248285 -60.41464) (xy 263.271957 -60.465137) (xy 263.288025 -60.518544)
			(xy 263.296145 -60.57372) (xy 263.296654 -60.601606) (xy 263.29619 -60.627006) (xy 264.921236 -60.627006)
			(xy 264.925307 -60.571384) (xy 264.937433 -60.516947) (xy 264.957356 -60.464856) (xy 264.984652 -60.416221)
			(xy 265.018738 -60.372078) (xy 265.058887 -60.333369) (xy 265.104245 -60.300918) (xy 265.153845 -60.275417)
			(xy 265.206629 -60.25741) (xy 265.261472 -60.24728) (xy 265.317206 -60.245243) (xy 265.372643 -60.251343)
			(xy 265.4266 -60.265449) (xy 265.477929 -60.287261) (xy 265.525535 -60.316315) (xy 265.568403 -60.35199)
			(xy 265.60562 -60.393527) (xy 265.636393 -60.44004) (xy 265.660065 -60.490537) (xy 265.676133 -60.543944)
			(xy 265.684253 -60.59912) (xy 265.684762 -60.627006) (xy 265.684646 -60.633356) (xy 265.996926 -60.633356)
			(xy 266.000997 -60.577734) (xy 266.013123 -60.523297) (xy 266.033046 -60.471206) (xy 266.060342 -60.422571)
			(xy 266.094428 -60.378428) (xy 266.134577 -60.339719) (xy 266.179935 -60.307268) (xy 266.229535 -60.281767)
			(xy 266.282319 -60.26376) (xy 266.337162 -60.25363) (xy 266.392896 -60.251593) (xy 266.448333 -60.257693)
			(xy 266.50229 -60.271799) (xy 266.553619 -60.293611) (xy 266.601225 -60.322665) (xy 266.644093 -60.35834)
			(xy 266.68131 -60.399877) (xy 266.712083 -60.44639) (xy 266.735755 -60.496887) (xy 266.751823 -60.550294)
			(xy 266.759943 -60.60547) (xy 266.760452 -60.633356) (xy 267.012926 -60.633356) (xy 267.016997 -60.577734)
			(xy 267.029123 -60.523297) (xy 267.049046 -60.471206) (xy 267.076342 -60.422571) (xy 267.110428 -60.378428)
			(xy 267.150577 -60.339719) (xy 267.195935 -60.307268) (xy 267.245535 -60.281767) (xy 267.298319 -60.26376)
			(xy 267.353162 -60.25363) (xy 267.408896 -60.251593) (xy 267.464333 -60.257693) (xy 267.51829 -60.271799)
			(xy 267.569619 -60.293611) (xy 267.617225 -60.322665) (xy 267.660093 -60.35834) (xy 267.69731 -60.399877)
			(xy 267.728083 -60.44639) (xy 267.751755 -60.496887) (xy 267.767823 -60.550294) (xy 267.775374 -60.601606)
			(xy 288.533076 -60.601606) (xy 288.537147 -60.545984) (xy 288.549273 -60.491547) (xy 288.569196 -60.439456)
			(xy 288.596492 -60.390821) (xy 288.630578 -60.346678) (xy 288.670727 -60.307969) (xy 288.716085 -60.275518)
			(xy 288.765685 -60.250017) (xy 288.818469 -60.23201) (xy 288.873312 -60.22188) (xy 288.929046 -60.219843)
			(xy 288.984483 -60.225943) (xy 289.03844 -60.240049) (xy 289.089769 -60.261861) (xy 289.137375 -60.290915)
			(xy 289.180243 -60.32659) (xy 289.21746 -60.368127) (xy 289.248233 -60.41464) (xy 289.271905 -60.465137)
			(xy 289.287973 -60.518544) (xy 289.296093 -60.57372) (xy 289.296602 -60.601606) (xy 289.296138 -60.627006)
			(xy 290.921184 -60.627006) (xy 290.925255 -60.571384) (xy 290.937381 -60.516947) (xy 290.957304 -60.464856)
			(xy 290.9846 -60.416221) (xy 291.018686 -60.372078) (xy 291.058835 -60.333369) (xy 291.104193 -60.300918)
			(xy 291.153793 -60.275417) (xy 291.206577 -60.25741) (xy 291.26142 -60.24728) (xy 291.317154 -60.245243)
			(xy 291.372591 -60.251343) (xy 291.426548 -60.265449) (xy 291.477877 -60.287261) (xy 291.525483 -60.316315)
			(xy 291.568351 -60.35199) (xy 291.605568 -60.393527) (xy 291.636341 -60.44004) (xy 291.660013 -60.490537)
			(xy 291.676081 -60.543944) (xy 291.684201 -60.59912) (xy 291.68471 -60.627006) (xy 291.684594 -60.633356)
			(xy 291.996874 -60.633356) (xy 292.000945 -60.577734) (xy 292.013071 -60.523297) (xy 292.032994 -60.471206)
			(xy 292.06029 -60.422571) (xy 292.094376 -60.378428) (xy 292.134525 -60.339719) (xy 292.179883 -60.307268)
			(xy 292.229483 -60.281767) (xy 292.282267 -60.26376) (xy 292.33711 -60.25363) (xy 292.392844 -60.251593)
			(xy 292.448281 -60.257693) (xy 292.502238 -60.271799) (xy 292.553567 -60.293611) (xy 292.601173 -60.322665)
			(xy 292.644041 -60.35834) (xy 292.681258 -60.399877) (xy 292.712031 -60.44639) (xy 292.735703 -60.496887)
			(xy 292.751771 -60.550294) (xy 292.759891 -60.60547) (xy 292.7604 -60.633356) (xy 293.012874 -60.633356)
			(xy 293.016945 -60.577734) (xy 293.029071 -60.523297) (xy 293.048994 -60.471206) (xy 293.07629 -60.422571)
			(xy 293.110376 -60.378428) (xy 293.150525 -60.339719) (xy 293.195883 -60.307268) (xy 293.245483 -60.281767)
			(xy 293.298267 -60.26376) (xy 293.35311 -60.25363) (xy 293.408844 -60.251593) (xy 293.464281 -60.257693)
			(xy 293.518238 -60.271799) (xy 293.569567 -60.293611) (xy 293.617173 -60.322665) (xy 293.660041 -60.35834)
			(xy 293.697258 -60.399877) (xy 293.728031 -60.44639) (xy 293.751703 -60.496887) (xy 293.767771 -60.550294)
			(xy 293.775322 -60.601606) (xy 314.533024 -60.601606) (xy 314.537095 -60.545984) (xy 314.549221 -60.491547)
			(xy 314.569144 -60.439456) (xy 314.59644 -60.390821) (xy 314.630526 -60.346678) (xy 314.670675 -60.307969)
			(xy 314.716033 -60.275518) (xy 314.765633 -60.250017) (xy 314.818417 -60.23201) (xy 314.87326 -60.22188)
			(xy 314.928994 -60.219843) (xy 314.984431 -60.225943) (xy 315.038388 -60.240049) (xy 315.089717 -60.261861)
			(xy 315.137323 -60.290915) (xy 315.180191 -60.32659) (xy 315.217408 -60.368127) (xy 315.248181 -60.41464)
			(xy 315.271853 -60.465137) (xy 315.287921 -60.518544) (xy 315.296041 -60.57372) (xy 315.29655 -60.601606)
			(xy 315.296041 -60.629492) (xy 315.295472 -60.633356) (xy 317.996822 -60.633356) (xy 318.000893 -60.577734)
			(xy 318.013019 -60.523297) (xy 318.032942 -60.471206) (xy 318.060238 -60.422571) (xy 318.094324 -60.378428)
			(xy 318.134473 -60.339719) (xy 318.179831 -60.307268) (xy 318.229431 -60.281767) (xy 318.282215 -60.26376)
			(xy 318.337058 -60.25363) (xy 318.392792 -60.251593) (xy 318.448229 -60.257693) (xy 318.502186 -60.271799)
			(xy 318.553515 -60.293611) (xy 318.601121 -60.322665) (xy 318.643989 -60.35834) (xy 318.681206 -60.399877)
			(xy 318.711979 -60.44639) (xy 318.735651 -60.496887) (xy 318.751719 -60.550294) (xy 318.759839 -60.60547)
			(xy 318.760348 -60.633356) (xy 319.012822 -60.633356) (xy 319.016893 -60.577734) (xy 319.029019 -60.523297)
			(xy 319.048942 -60.471206) (xy 319.076238 -60.422571) (xy 319.110324 -60.378428) (xy 319.150473 -60.339719)
			(xy 319.195831 -60.307268) (xy 319.245431 -60.281767) (xy 319.298215 -60.26376) (xy 319.353058 -60.25363)
			(xy 319.408792 -60.251593) (xy 319.464229 -60.257693) (xy 319.518186 -60.271799) (xy 319.569515 -60.293611)
			(xy 319.617121 -60.322665) (xy 319.659989 -60.35834) (xy 319.697206 -60.399877) (xy 319.727979 -60.44639)
			(xy 319.751651 -60.496887) (xy 319.767719 -60.550294) (xy 319.77527 -60.601606) (xy 352.633278 -60.601606)
			(xy 352.637349 -60.545984) (xy 352.649475 -60.491547) (xy 352.669398 -60.439456) (xy 352.696694 -60.390821)
			(xy 352.73078 -60.346678) (xy 352.770929 -60.307969) (xy 352.816287 -60.275518) (xy 352.865887 -60.250017)
			(xy 352.918671 -60.23201) (xy 352.973514 -60.22188) (xy 353.029248 -60.219843) (xy 353.084685 -60.225943)
			(xy 353.138642 -60.240049) (xy 353.189971 -60.261861) (xy 353.237577 -60.290915) (xy 353.280445 -60.32659)
			(xy 353.317662 -60.368127) (xy 353.348435 -60.41464) (xy 353.372107 -60.465137) (xy 353.388175 -60.518544)
			(xy 353.396295 -60.57372) (xy 353.396804 -60.601606) (xy 353.39634 -60.627006) (xy 355.021386 -60.627006)
			(xy 355.025457 -60.571384) (xy 355.037583 -60.516947) (xy 355.057506 -60.464856) (xy 355.084802 -60.416221)
			(xy 355.118888 -60.372078) (xy 355.159037 -60.333369) (xy 355.204395 -60.300918) (xy 355.253995 -60.275417)
			(xy 355.306779 -60.25741) (xy 355.361622 -60.24728) (xy 355.417356 -60.245243) (xy 355.472793 -60.251343)
			(xy 355.52675 -60.265449) (xy 355.578079 -60.287261) (xy 355.625685 -60.316315) (xy 355.668553 -60.35199)
			(xy 355.70577 -60.393527) (xy 355.736543 -60.44004) (xy 355.760215 -60.490537) (xy 355.776283 -60.543944)
			(xy 355.784403 -60.59912) (xy 355.784912 -60.627006) (xy 355.784796 -60.633356) (xy 356.097076 -60.633356)
			(xy 356.101147 -60.577734) (xy 356.113273 -60.523297) (xy 356.133196 -60.471206) (xy 356.160492 -60.422571)
			(xy 356.194578 -60.378428) (xy 356.234727 -60.339719) (xy 356.280085 -60.307268) (xy 356.329685 -60.281767)
			(xy 356.382469 -60.26376) (xy 356.437312 -60.25363) (xy 356.493046 -60.251593) (xy 356.548483 -60.257693)
			(xy 356.60244 -60.271799) (xy 356.653769 -60.293611) (xy 356.701375 -60.322665) (xy 356.744243 -60.35834)
			(xy 356.78146 -60.399877) (xy 356.812233 -60.44639) (xy 356.835905 -60.496887) (xy 356.851973 -60.550294)
			(xy 356.860093 -60.60547) (xy 356.860602 -60.633356) (xy 357.113076 -60.633356) (xy 357.117147 -60.577734)
			(xy 357.129273 -60.523297) (xy 357.149196 -60.471206) (xy 357.176492 -60.422571) (xy 357.210578 -60.378428)
			(xy 357.250727 -60.339719) (xy 357.296085 -60.307268) (xy 357.345685 -60.281767) (xy 357.398469 -60.26376)
			(xy 357.453312 -60.25363) (xy 357.509046 -60.251593) (xy 357.564483 -60.257693) (xy 357.61844 -60.271799)
			(xy 357.669769 -60.293611) (xy 357.717375 -60.322665) (xy 357.760243 -60.35834) (xy 357.79746 -60.399877)
			(xy 357.828233 -60.44639) (xy 357.851905 -60.496887) (xy 357.867973 -60.550294) (xy 357.875524 -60.601606)
			(xy 378.633226 -60.601606) (xy 378.637297 -60.545984) (xy 378.649423 -60.491547) (xy 378.669346 -60.439456)
			(xy 378.696642 -60.390821) (xy 378.730728 -60.346678) (xy 378.770877 -60.307969) (xy 378.816235 -60.275518)
			(xy 378.865835 -60.250017) (xy 378.918619 -60.23201) (xy 378.973462 -60.22188) (xy 379.029196 -60.219843)
			(xy 379.084633 -60.225943) (xy 379.13859 -60.240049) (xy 379.189919 -60.261861) (xy 379.237525 -60.290915)
			(xy 379.280393 -60.32659) (xy 379.31761 -60.368127) (xy 379.348383 -60.41464) (xy 379.372055 -60.465137)
			(xy 379.388123 -60.518544) (xy 379.396243 -60.57372) (xy 379.396752 -60.601606) (xy 379.396288 -60.627006)
			(xy 381.021334 -60.627006) (xy 381.025405 -60.571384) (xy 381.037531 -60.516947) (xy 381.057454 -60.464856)
			(xy 381.08475 -60.416221) (xy 381.118836 -60.372078) (xy 381.158985 -60.333369) (xy 381.204343 -60.300918)
			(xy 381.253943 -60.275417) (xy 381.306727 -60.25741) (xy 381.36157 -60.24728) (xy 381.417304 -60.245243)
			(xy 381.472741 -60.251343) (xy 381.526698 -60.265449) (xy 381.578027 -60.287261) (xy 381.625633 -60.316315)
			(xy 381.668501 -60.35199) (xy 381.705718 -60.393527) (xy 381.736491 -60.44004) (xy 381.760163 -60.490537)
			(xy 381.776231 -60.543944) (xy 381.784351 -60.59912) (xy 381.78486 -60.627006) (xy 381.784744 -60.633356)
			(xy 382.097024 -60.633356) (xy 382.101095 -60.577734) (xy 382.113221 -60.523297) (xy 382.133144 -60.471206)
			(xy 382.16044 -60.422571) (xy 382.194526 -60.378428) (xy 382.234675 -60.339719) (xy 382.280033 -60.307268)
			(xy 382.329633 -60.281767) (xy 382.382417 -60.26376) (xy 382.43726 -60.25363) (xy 382.492994 -60.251593)
			(xy 382.548431 -60.257693) (xy 382.602388 -60.271799) (xy 382.653717 -60.293611) (xy 382.701323 -60.322665)
			(xy 382.744191 -60.35834) (xy 382.781408 -60.399877) (xy 382.812181 -60.44639) (xy 382.835853 -60.496887)
			(xy 382.851921 -60.550294) (xy 382.860041 -60.60547) (xy 382.86055 -60.633356) (xy 383.113024 -60.633356)
			(xy 383.117095 -60.577734) (xy 383.129221 -60.523297) (xy 383.149144 -60.471206) (xy 383.17644 -60.422571)
			(xy 383.210526 -60.378428) (xy 383.250675 -60.339719) (xy 383.296033 -60.307268) (xy 383.345633 -60.281767)
			(xy 383.398417 -60.26376) (xy 383.45326 -60.25363) (xy 383.508994 -60.251593) (xy 383.564431 -60.257693)
			(xy 383.618388 -60.271799) (xy 383.669717 -60.293611) (xy 383.717323 -60.322665) (xy 383.760191 -60.35834)
			(xy 383.797408 -60.399877) (xy 383.828181 -60.44639) (xy 383.851853 -60.496887) (xy 383.867921 -60.550294)
			(xy 383.875472 -60.601606) (xy 404.633174 -60.601606) (xy 404.637245 -60.545984) (xy 404.649371 -60.491547)
			(xy 404.669294 -60.439456) (xy 404.69659 -60.390821) (xy 404.730676 -60.346678) (xy 404.770825 -60.307969)
			(xy 404.816183 -60.275518) (xy 404.865783 -60.250017) (xy 404.918567 -60.23201) (xy 404.97341 -60.22188)
			(xy 405.029144 -60.219843) (xy 405.084581 -60.225943) (xy 405.138538 -60.240049) (xy 405.189867 -60.261861)
			(xy 405.237473 -60.290915) (xy 405.280341 -60.32659) (xy 405.317558 -60.368127) (xy 405.348331 -60.41464)
			(xy 405.372003 -60.465137) (xy 405.388071 -60.518544) (xy 405.396191 -60.57372) (xy 405.3967 -60.601606)
			(xy 405.396236 -60.627006) (xy 407.021282 -60.627006) (xy 407.025353 -60.571384) (xy 407.037479 -60.516947)
			(xy 407.057402 -60.464856) (xy 407.084698 -60.416221) (xy 407.118784 -60.372078) (xy 407.158933 -60.333369)
			(xy 407.204291 -60.300918) (xy 407.253891 -60.275417) (xy 407.306675 -60.25741) (xy 407.361518 -60.24728)
			(xy 407.417252 -60.245243) (xy 407.472689 -60.251343) (xy 407.526646 -60.265449) (xy 407.577975 -60.287261)
			(xy 407.625581 -60.316315) (xy 407.668449 -60.35199) (xy 407.705666 -60.393527) (xy 407.736439 -60.44004)
			(xy 407.760111 -60.490537) (xy 407.776179 -60.543944) (xy 407.784299 -60.59912) (xy 407.784808 -60.627006)
			(xy 407.784692 -60.633356) (xy 408.096972 -60.633356) (xy 408.101043 -60.577734) (xy 408.113169 -60.523297)
			(xy 408.133092 -60.471206) (xy 408.160388 -60.422571) (xy 408.194474 -60.378428) (xy 408.234623 -60.339719)
			(xy 408.279981 -60.307268) (xy 408.329581 -60.281767) (xy 408.382365 -60.26376) (xy 408.437208 -60.25363)
			(xy 408.492942 -60.251593) (xy 408.548379 -60.257693) (xy 408.602336 -60.271799) (xy 408.653665 -60.293611)
			(xy 408.701271 -60.322665) (xy 408.744139 -60.35834) (xy 408.781356 -60.399877) (xy 408.812129 -60.44639)
			(xy 408.835801 -60.496887) (xy 408.851869 -60.550294) (xy 408.859989 -60.60547) (xy 408.860498 -60.633356)
			(xy 409.112972 -60.633356) (xy 409.117043 -60.577734) (xy 409.129169 -60.523297) (xy 409.149092 -60.471206)
			(xy 409.176388 -60.422571) (xy 409.210474 -60.378428) (xy 409.250623 -60.339719) (xy 409.295981 -60.307268)
			(xy 409.345581 -60.281767) (xy 409.398365 -60.26376) (xy 409.453208 -60.25363) (xy 409.508942 -60.251593)
			(xy 409.564379 -60.257693) (xy 409.618336 -60.271799) (xy 409.669665 -60.293611) (xy 409.717271 -60.322665)
			(xy 409.760139 -60.35834) (xy 409.797356 -60.399877) (xy 409.828129 -60.44639) (xy 409.851801 -60.496887)
			(xy 409.867869 -60.550294) (xy 409.87542 -60.601606) (xy 430.633122 -60.601606) (xy 430.637193 -60.545984)
			(xy 430.649319 -60.491547) (xy 430.669242 -60.439456) (xy 430.696538 -60.390821) (xy 430.730624 -60.346678)
			(xy 430.770773 -60.307969) (xy 430.816131 -60.275518) (xy 430.865731 -60.250017) (xy 430.918515 -60.23201)
			(xy 430.973358 -60.22188) (xy 431.029092 -60.219843) (xy 431.084529 -60.225943) (xy 431.138486 -60.240049)
			(xy 431.189815 -60.261861) (xy 431.237421 -60.290915) (xy 431.280289 -60.32659) (xy 431.317506 -60.368127)
			(xy 431.348279 -60.41464) (xy 431.371951 -60.465137) (xy 431.388019 -60.518544) (xy 431.396139 -60.57372)
			(xy 431.396648 -60.601606) (xy 431.396184 -60.627006) (xy 433.02123 -60.627006) (xy 433.025301 -60.571384)
			(xy 433.037427 -60.516947) (xy 433.05735 -60.464856) (xy 433.084646 -60.416221) (xy 433.118732 -60.372078)
			(xy 433.158881 -60.333369) (xy 433.204239 -60.300918) (xy 433.253839 -60.275417) (xy 433.306623 -60.25741)
			(xy 433.361466 -60.24728) (xy 433.4172 -60.245243) (xy 433.472637 -60.251343) (xy 433.526594 -60.265449)
			(xy 433.577923 -60.287261) (xy 433.625529 -60.316315) (xy 433.668397 -60.35199) (xy 433.705614 -60.393527)
			(xy 433.736387 -60.44004) (xy 433.760059 -60.490537) (xy 433.776127 -60.543944) (xy 433.784247 -60.59912)
			(xy 433.784756 -60.627006) (xy 433.78464 -60.633356) (xy 434.09692 -60.633356) (xy 434.100991 -60.577734)
			(xy 434.113117 -60.523297) (xy 434.13304 -60.471206) (xy 434.160336 -60.422571) (xy 434.194422 -60.378428)
			(xy 434.234571 -60.339719) (xy 434.279929 -60.307268) (xy 434.329529 -60.281767) (xy 434.382313 -60.26376)
			(xy 434.437156 -60.25363) (xy 434.49289 -60.251593) (xy 434.548327 -60.257693) (xy 434.602284 -60.271799)
			(xy 434.653613 -60.293611) (xy 434.701219 -60.322665) (xy 434.744087 -60.35834) (xy 434.781304 -60.399877)
			(xy 434.812077 -60.44639) (xy 434.835749 -60.496887) (xy 434.851817 -60.550294) (xy 434.859937 -60.60547)
			(xy 434.860446 -60.633356) (xy 435.11292 -60.633356) (xy 435.116991 -60.577734) (xy 435.129117 -60.523297)
			(xy 435.14904 -60.471206) (xy 435.176336 -60.422571) (xy 435.210422 -60.378428) (xy 435.250571 -60.339719)
			(xy 435.295929 -60.307268) (xy 435.345529 -60.281767) (xy 435.398313 -60.26376) (xy 435.453156 -60.25363)
			(xy 435.50889 -60.251593) (xy 435.564327 -60.257693) (xy 435.618284 -60.271799) (xy 435.669613 -60.293611)
			(xy 435.717219 -60.322665) (xy 435.760087 -60.35834) (xy 435.797304 -60.399877) (xy 435.828077 -60.44639)
			(xy 435.851749 -60.496887) (xy 435.867817 -60.550294) (xy 435.875937 -60.60547) (xy 435.876446 -60.633356)
			(xy 435.875937 -60.661242) (xy 435.867817 -60.716418) (xy 435.851749 -60.769825) (xy 435.828077 -60.820322)
			(xy 435.797304 -60.866835) (xy 435.760087 -60.908372) (xy 435.717219 -60.944047) (xy 435.669613 -60.973101)
			(xy 435.618284 -60.994913) (xy 435.564327 -61.009019) (xy 435.50889 -61.015119) (xy 435.453156 -61.013082)
			(xy 435.398313 -61.002952) (xy 435.345529 -60.984945) (xy 435.295929 -60.959444) (xy 435.250571 -60.926993)
			(xy 435.210422 -60.888284) (xy 435.176336 -60.844141) (xy 435.14904 -60.795506) (xy 435.129117 -60.743415)
			(xy 435.116991 -60.688978) (xy 435.11292 -60.633356) (xy 434.860446 -60.633356) (xy 434.859937 -60.661242)
			(xy 434.851817 -60.716418) (xy 434.835749 -60.769825) (xy 434.812077 -60.820322) (xy 434.781304 -60.866835)
			(xy 434.744087 -60.908372) (xy 434.701219 -60.944047) (xy 434.653613 -60.973101) (xy 434.602284 -60.994913)
			(xy 434.548327 -61.009019) (xy 434.49289 -61.015119) (xy 434.437156 -61.013082) (xy 434.382313 -61.002952)
			(xy 434.329529 -60.984945) (xy 434.279929 -60.959444) (xy 434.234571 -60.926993) (xy 434.194422 -60.888284)
			(xy 434.160336 -60.844141) (xy 434.13304 -60.795506) (xy 434.113117 -60.743415) (xy 434.100991 -60.688978)
			(xy 434.09692 -60.633356) (xy 433.78464 -60.633356) (xy 433.784247 -60.654892) (xy 433.776127 -60.710068)
			(xy 433.760059 -60.763475) (xy 433.736387 -60.813972) (xy 433.705614 -60.860485) (xy 433.668397 -60.902022)
			(xy 433.625529 -60.937697) (xy 433.577923 -60.966751) (xy 433.526594 -60.988563) (xy 433.472637 -61.002669)
			(xy 433.4172 -61.008769) (xy 433.361466 -61.006732) (xy 433.306623 -60.996602) (xy 433.253839 -60.978595)
			(xy 433.204239 -60.953094) (xy 433.158881 -60.920643) (xy 433.118732 -60.881934) (xy 433.084646 -60.837791)
			(xy 433.05735 -60.789156) (xy 433.037427 -60.737065) (xy 433.025301 -60.682628) (xy 433.02123 -60.627006)
			(xy 431.396184 -60.627006) (xy 431.396139 -60.629492) (xy 431.388019 -60.684668) (xy 431.371951 -60.738075)
			(xy 431.348279 -60.788572) (xy 431.317506 -60.835085) (xy 431.280289 -60.876622) (xy 431.237421 -60.912297)
			(xy 431.189815 -60.941351) (xy 431.138486 -60.963163) (xy 431.084529 -60.977269) (xy 431.029092 -60.983369)
			(xy 430.973358 -60.981332) (xy 430.918515 -60.971202) (xy 430.865731 -60.953195) (xy 430.816131 -60.927694)
			(xy 430.770773 -60.895243) (xy 430.730624 -60.856534) (xy 430.696538 -60.812391) (xy 430.669242 -60.763756)
			(xy 430.649319 -60.711665) (xy 430.637193 -60.657228) (xy 430.633122 -60.601606) (xy 409.87542 -60.601606)
			(xy 409.875989 -60.60547) (xy 409.876498 -60.633356) (xy 409.875989 -60.661242) (xy 409.867869 -60.716418)
			(xy 409.851801 -60.769825) (xy 409.828129 -60.820322) (xy 409.797356 -60.866835) (xy 409.760139 -60.908372)
			(xy 409.717271 -60.944047) (xy 409.669665 -60.973101) (xy 409.618336 -60.994913) (xy 409.564379 -61.009019)
			(xy 409.508942 -61.015119) (xy 409.453208 -61.013082) (xy 409.398365 -61.002952) (xy 409.345581 -60.984945)
			(xy 409.295981 -60.959444) (xy 409.250623 -60.926993) (xy 409.210474 -60.888284) (xy 409.176388 -60.844141)
			(xy 409.149092 -60.795506) (xy 409.129169 -60.743415) (xy 409.117043 -60.688978) (xy 409.112972 -60.633356)
			(xy 408.860498 -60.633356) (xy 408.859989 -60.661242) (xy 408.851869 -60.716418) (xy 408.835801 -60.769825)
			(xy 408.812129 -60.820322) (xy 408.781356 -60.866835) (xy 408.744139 -60.908372) (xy 408.701271 -60.944047)
			(xy 408.653665 -60.973101) (xy 408.602336 -60.994913) (xy 408.548379 -61.009019) (xy 408.492942 -61.015119)
			(xy 408.437208 -61.013082) (xy 408.382365 -61.002952) (xy 408.329581 -60.984945) (xy 408.279981 -60.959444)
			(xy 408.234623 -60.926993) (xy 408.194474 -60.888284) (xy 408.160388 -60.844141) (xy 408.133092 -60.795506)
			(xy 408.113169 -60.743415) (xy 408.101043 -60.688978) (xy 408.096972 -60.633356) (xy 407.784692 -60.633356)
			(xy 407.784299 -60.654892) (xy 407.776179 -60.710068) (xy 407.760111 -60.763475) (xy 407.736439 -60.813972)
			(xy 407.705666 -60.860485) (xy 407.668449 -60.902022) (xy 407.625581 -60.937697) (xy 407.577975 -60.966751)
			(xy 407.526646 -60.988563) (xy 407.472689 -61.002669) (xy 407.417252 -61.008769) (xy 407.361518 -61.006732)
			(xy 407.306675 -60.996602) (xy 407.253891 -60.978595) (xy 407.204291 -60.953094) (xy 407.158933 -60.920643)
			(xy 407.118784 -60.881934) (xy 407.084698 -60.837791) (xy 407.057402 -60.789156) (xy 407.037479 -60.737065)
			(xy 407.025353 -60.682628) (xy 407.021282 -60.627006) (xy 405.396236 -60.627006) (xy 405.396191 -60.629492)
			(xy 405.388071 -60.684668) (xy 405.372003 -60.738075) (xy 405.348331 -60.788572) (xy 405.317558 -60.835085)
			(xy 405.280341 -60.876622) (xy 405.237473 -60.912297) (xy 405.189867 -60.941351) (xy 405.138538 -60.963163)
			(xy 405.084581 -60.977269) (xy 405.029144 -60.983369) (xy 404.97341 -60.981332) (xy 404.918567 -60.971202)
			(xy 404.865783 -60.953195) (xy 404.816183 -60.927694) (xy 404.770825 -60.895243) (xy 404.730676 -60.856534)
			(xy 404.69659 -60.812391) (xy 404.669294 -60.763756) (xy 404.649371 -60.711665) (xy 404.637245 -60.657228)
			(xy 404.633174 -60.601606) (xy 383.875472 -60.601606) (xy 383.876041 -60.60547) (xy 383.87655 -60.633356)
			(xy 383.876041 -60.661242) (xy 383.867921 -60.716418) (xy 383.851853 -60.769825) (xy 383.828181 -60.820322)
			(xy 383.797408 -60.866835) (xy 383.760191 -60.908372) (xy 383.717323 -60.944047) (xy 383.669717 -60.973101)
			(xy 383.618388 -60.994913) (xy 383.564431 -61.009019) (xy 383.508994 -61.015119) (xy 383.45326 -61.013082)
			(xy 383.398417 -61.002952) (xy 383.345633 -60.984945) (xy 383.296033 -60.959444) (xy 383.250675 -60.926993)
			(xy 383.210526 -60.888284) (xy 383.17644 -60.844141) (xy 383.149144 -60.795506) (xy 383.129221 -60.743415)
			(xy 383.117095 -60.688978) (xy 383.113024 -60.633356) (xy 382.86055 -60.633356) (xy 382.860041 -60.661242)
			(xy 382.851921 -60.716418) (xy 382.835853 -60.769825) (xy 382.812181 -60.820322) (xy 382.781408 -60.866835)
			(xy 382.744191 -60.908372) (xy 382.701323 -60.944047) (xy 382.653717 -60.973101) (xy 382.602388 -60.994913)
			(xy 382.548431 -61.009019) (xy 382.492994 -61.015119) (xy 382.43726 -61.013082) (xy 382.382417 -61.002952)
			(xy 382.329633 -60.984945) (xy 382.280033 -60.959444) (xy 382.234675 -60.926993) (xy 382.194526 -60.888284)
			(xy 382.16044 -60.844141) (xy 382.133144 -60.795506) (xy 382.113221 -60.743415) (xy 382.101095 -60.688978)
			(xy 382.097024 -60.633356) (xy 381.784744 -60.633356) (xy 381.784351 -60.654892) (xy 381.776231 -60.710068)
			(xy 381.760163 -60.763475) (xy 381.736491 -60.813972) (xy 381.705718 -60.860485) (xy 381.668501 -60.902022)
			(xy 381.625633 -60.937697) (xy 381.578027 -60.966751) (xy 381.526698 -60.988563) (xy 381.472741 -61.002669)
			(xy 381.417304 -61.008769) (xy 381.36157 -61.006732) (xy 381.306727 -60.996602) (xy 381.253943 -60.978595)
			(xy 381.204343 -60.953094) (xy 381.158985 -60.920643) (xy 381.118836 -60.881934) (xy 381.08475 -60.837791)
			(xy 381.057454 -60.789156) (xy 381.037531 -60.737065) (xy 381.025405 -60.682628) (xy 381.021334 -60.627006)
			(xy 379.396288 -60.627006) (xy 379.396243 -60.629492) (xy 379.388123 -60.684668) (xy 379.372055 -60.738075)
			(xy 379.348383 -60.788572) (xy 379.31761 -60.835085) (xy 379.280393 -60.876622) (xy 379.237525 -60.912297)
			(xy 379.189919 -60.941351) (xy 379.13859 -60.963163) (xy 379.084633 -60.977269) (xy 379.029196 -60.983369)
			(xy 378.973462 -60.981332) (xy 378.918619 -60.971202) (xy 378.865835 -60.953195) (xy 378.816235 -60.927694)
			(xy 378.770877 -60.895243) (xy 378.730728 -60.856534) (xy 378.696642 -60.812391) (xy 378.669346 -60.763756)
			(xy 378.649423 -60.711665) (xy 378.637297 -60.657228) (xy 378.633226 -60.601606) (xy 357.875524 -60.601606)
			(xy 357.876093 -60.60547) (xy 357.876602 -60.633356) (xy 357.876093 -60.661242) (xy 357.867973 -60.716418)
			(xy 357.851905 -60.769825) (xy 357.828233 -60.820322) (xy 357.79746 -60.866835) (xy 357.760243 -60.908372)
			(xy 357.717375 -60.944047) (xy 357.669769 -60.973101) (xy 357.61844 -60.994913) (xy 357.564483 -61.009019)
			(xy 357.509046 -61.015119) (xy 357.453312 -61.013082) (xy 357.398469 -61.002952) (xy 357.345685 -60.984945)
			(xy 357.296085 -60.959444) (xy 357.250727 -60.926993) (xy 357.210578 -60.888284) (xy 357.176492 -60.844141)
			(xy 357.149196 -60.795506) (xy 357.129273 -60.743415) (xy 357.117147 -60.688978) (xy 357.113076 -60.633356)
			(xy 356.860602 -60.633356) (xy 356.860093 -60.661242) (xy 356.851973 -60.716418) (xy 356.835905 -60.769825)
			(xy 356.812233 -60.820322) (xy 356.78146 -60.866835) (xy 356.744243 -60.908372) (xy 356.701375 -60.944047)
			(xy 356.653769 -60.973101) (xy 356.60244 -60.994913) (xy 356.548483 -61.009019) (xy 356.493046 -61.015119)
			(xy 356.437312 -61.013082) (xy 356.382469 -61.002952) (xy 356.329685 -60.984945) (xy 356.280085 -60.959444)
			(xy 356.234727 -60.926993) (xy 356.194578 -60.888284) (xy 356.160492 -60.844141) (xy 356.133196 -60.795506)
			(xy 356.113273 -60.743415) (xy 356.101147 -60.688978) (xy 356.097076 -60.633356) (xy 355.784796 -60.633356)
			(xy 355.784403 -60.654892) (xy 355.776283 -60.710068) (xy 355.760215 -60.763475) (xy 355.736543 -60.813972)
			(xy 355.70577 -60.860485) (xy 355.668553 -60.902022) (xy 355.625685 -60.937697) (xy 355.578079 -60.966751)
			(xy 355.52675 -60.988563) (xy 355.472793 -61.002669) (xy 355.417356 -61.008769) (xy 355.361622 -61.006732)
			(xy 355.306779 -60.996602) (xy 355.253995 -60.978595) (xy 355.204395 -60.953094) (xy 355.159037 -60.920643)
			(xy 355.118888 -60.881934) (xy 355.084802 -60.837791) (xy 355.057506 -60.789156) (xy 355.037583 -60.737065)
			(xy 355.025457 -60.682628) (xy 355.021386 -60.627006) (xy 353.39634 -60.627006) (xy 353.396295 -60.629492)
			(xy 353.388175 -60.684668) (xy 353.372107 -60.738075) (xy 353.348435 -60.788572) (xy 353.317662 -60.835085)
			(xy 353.280445 -60.876622) (xy 353.237577 -60.912297) (xy 353.189971 -60.941351) (xy 353.138642 -60.963163)
			(xy 353.084685 -60.977269) (xy 353.029248 -60.983369) (xy 352.973514 -60.981332) (xy 352.918671 -60.971202)
			(xy 352.865887 -60.953195) (xy 352.816287 -60.927694) (xy 352.770929 -60.895243) (xy 352.73078 -60.856534)
			(xy 352.696694 -60.812391) (xy 352.669398 -60.763756) (xy 352.649475 -60.711665) (xy 352.637349 -60.657228)
			(xy 352.633278 -60.601606) (xy 319.77527 -60.601606) (xy 319.775839 -60.60547) (xy 319.776348 -60.633356)
			(xy 319.775839 -60.661242) (xy 319.767719 -60.716418) (xy 319.751651 -60.769825) (xy 319.727979 -60.820322)
			(xy 319.697206 -60.866835) (xy 319.659989 -60.908372) (xy 319.617121 -60.944047) (xy 319.569515 -60.973101)
			(xy 319.518186 -60.994913) (xy 319.464229 -61.009019) (xy 319.408792 -61.015119) (xy 319.353058 -61.013082)
			(xy 319.298215 -61.002952) (xy 319.245431 -60.984945) (xy 319.195831 -60.959444) (xy 319.150473 -60.926993)
			(xy 319.110324 -60.888284) (xy 319.076238 -60.844141) (xy 319.048942 -60.795506) (xy 319.029019 -60.743415)
			(xy 319.016893 -60.688978) (xy 319.012822 -60.633356) (xy 318.760348 -60.633356) (xy 318.759839 -60.661242)
			(xy 318.751719 -60.716418) (xy 318.735651 -60.769825) (xy 318.711979 -60.820322) (xy 318.681206 -60.866835)
			(xy 318.643989 -60.908372) (xy 318.601121 -60.944047) (xy 318.553515 -60.973101) (xy 318.502186 -60.994913)
			(xy 318.448229 -61.009019) (xy 318.392792 -61.015119) (xy 318.337058 -61.013082) (xy 318.282215 -61.002952)
			(xy 318.229431 -60.984945) (xy 318.179831 -60.959444) (xy 318.134473 -60.926993) (xy 318.094324 -60.888284)
			(xy 318.060238 -60.844141) (xy 318.032942 -60.795506) (xy 318.013019 -60.743415) (xy 318.000893 -60.688978)
			(xy 317.996822 -60.633356) (xy 315.295472 -60.633356) (xy 315.287921 -60.684668) (xy 315.271853 -60.738075)
			(xy 315.248181 -60.788572) (xy 315.217408 -60.835085) (xy 315.180191 -60.876622) (xy 315.137323 -60.912297)
			(xy 315.089717 -60.941351) (xy 315.038388 -60.963163) (xy 314.984431 -60.977269) (xy 314.928994 -60.983369)
			(xy 314.87326 -60.981332) (xy 314.818417 -60.971202) (xy 314.765633 -60.953195) (xy 314.716033 -60.927694)
			(xy 314.670675 -60.895243) (xy 314.630526 -60.856534) (xy 314.59644 -60.812391) (xy 314.569144 -60.763756)
			(xy 314.549221 -60.711665) (xy 314.537095 -60.657228) (xy 314.533024 -60.601606) (xy 293.775322 -60.601606)
			(xy 293.775891 -60.60547) (xy 293.7764 -60.633356) (xy 293.775891 -60.661242) (xy 293.767771 -60.716418)
			(xy 293.751703 -60.769825) (xy 293.728031 -60.820322) (xy 293.697258 -60.866835) (xy 293.660041 -60.908372)
			(xy 293.617173 -60.944047) (xy 293.569567 -60.973101) (xy 293.518238 -60.994913) (xy 293.464281 -61.009019)
			(xy 293.408844 -61.015119) (xy 293.35311 -61.013082) (xy 293.298267 -61.002952) (xy 293.245483 -60.984945)
			(xy 293.195883 -60.959444) (xy 293.150525 -60.926993) (xy 293.110376 -60.888284) (xy 293.07629 -60.844141)
			(xy 293.048994 -60.795506) (xy 293.029071 -60.743415) (xy 293.016945 -60.688978) (xy 293.012874 -60.633356)
			(xy 292.7604 -60.633356) (xy 292.759891 -60.661242) (xy 292.751771 -60.716418) (xy 292.735703 -60.769825)
			(xy 292.712031 -60.820322) (xy 292.681258 -60.866835) (xy 292.644041 -60.908372) (xy 292.601173 -60.944047)
			(xy 292.553567 -60.973101) (xy 292.502238 -60.994913) (xy 292.448281 -61.009019) (xy 292.392844 -61.015119)
			(xy 292.33711 -61.013082) (xy 292.282267 -61.002952) (xy 292.229483 -60.984945) (xy 292.179883 -60.959444)
			(xy 292.134525 -60.926993) (xy 292.094376 -60.888284) (xy 292.06029 -60.844141) (xy 292.032994 -60.795506)
			(xy 292.013071 -60.743415) (xy 292.000945 -60.688978) (xy 291.996874 -60.633356) (xy 291.684594 -60.633356)
			(xy 291.684201 -60.654892) (xy 291.676081 -60.710068) (xy 291.660013 -60.763475) (xy 291.636341 -60.813972)
			(xy 291.605568 -60.860485) (xy 291.568351 -60.902022) (xy 291.525483 -60.937697) (xy 291.477877 -60.966751)
			(xy 291.426548 -60.988563) (xy 291.372591 -61.002669) (xy 291.317154 -61.008769) (xy 291.26142 -61.006732)
			(xy 291.206577 -60.996602) (xy 291.153793 -60.978595) (xy 291.104193 -60.953094) (xy 291.058835 -60.920643)
			(xy 291.018686 -60.881934) (xy 290.9846 -60.837791) (xy 290.957304 -60.789156) (xy 290.937381 -60.737065)
			(xy 290.925255 -60.682628) (xy 290.921184 -60.627006) (xy 289.296138 -60.627006) (xy 289.296093 -60.629492)
			(xy 289.287973 -60.684668) (xy 289.271905 -60.738075) (xy 289.248233 -60.788572) (xy 289.21746 -60.835085)
			(xy 289.180243 -60.876622) (xy 289.137375 -60.912297) (xy 289.089769 -60.941351) (xy 289.03844 -60.963163)
			(xy 288.984483 -60.977269) (xy 288.929046 -60.983369) (xy 288.873312 -60.981332) (xy 288.818469 -60.971202)
			(xy 288.765685 -60.953195) (xy 288.716085 -60.927694) (xy 288.670727 -60.895243) (xy 288.630578 -60.856534)
			(xy 288.596492 -60.812391) (xy 288.569196 -60.763756) (xy 288.549273 -60.711665) (xy 288.537147 -60.657228)
			(xy 288.533076 -60.601606) (xy 267.775374 -60.601606) (xy 267.775943 -60.60547) (xy 267.776452 -60.633356)
			(xy 267.775943 -60.661242) (xy 267.767823 -60.716418) (xy 267.751755 -60.769825) (xy 267.728083 -60.820322)
			(xy 267.69731 -60.866835) (xy 267.660093 -60.908372) (xy 267.617225 -60.944047) (xy 267.569619 -60.973101)
			(xy 267.51829 -60.994913) (xy 267.464333 -61.009019) (xy 267.408896 -61.015119) (xy 267.353162 -61.013082)
			(xy 267.298319 -61.002952) (xy 267.245535 -60.984945) (xy 267.195935 -60.959444) (xy 267.150577 -60.926993)
			(xy 267.110428 -60.888284) (xy 267.076342 -60.844141) (xy 267.049046 -60.795506) (xy 267.029123 -60.743415)
			(xy 267.016997 -60.688978) (xy 267.012926 -60.633356) (xy 266.760452 -60.633356) (xy 266.759943 -60.661242)
			(xy 266.751823 -60.716418) (xy 266.735755 -60.769825) (xy 266.712083 -60.820322) (xy 266.68131 -60.866835)
			(xy 266.644093 -60.908372) (xy 266.601225 -60.944047) (xy 266.553619 -60.973101) (xy 266.50229 -60.994913)
			(xy 266.448333 -61.009019) (xy 266.392896 -61.015119) (xy 266.337162 -61.013082) (xy 266.282319 -61.002952)
			(xy 266.229535 -60.984945) (xy 266.179935 -60.959444) (xy 266.134577 -60.926993) (xy 266.094428 -60.888284)
			(xy 266.060342 -60.844141) (xy 266.033046 -60.795506) (xy 266.013123 -60.743415) (xy 266.000997 -60.688978)
			(xy 265.996926 -60.633356) (xy 265.684646 -60.633356) (xy 265.684253 -60.654892) (xy 265.676133 -60.710068)
			(xy 265.660065 -60.763475) (xy 265.636393 -60.813972) (xy 265.60562 -60.860485) (xy 265.568403 -60.902022)
			(xy 265.525535 -60.937697) (xy 265.477929 -60.966751) (xy 265.4266 -60.988563) (xy 265.372643 -61.002669)
			(xy 265.317206 -61.008769) (xy 265.261472 -61.006732) (xy 265.206629 -60.996602) (xy 265.153845 -60.978595)
			(xy 265.104245 -60.953094) (xy 265.058887 -60.920643) (xy 265.018738 -60.881934) (xy 264.984652 -60.837791)
			(xy 264.957356 -60.789156) (xy 264.937433 -60.737065) (xy 264.925307 -60.682628) (xy 264.921236 -60.627006)
			(xy 263.29619 -60.627006) (xy 263.296145 -60.629492) (xy 263.288025 -60.684668) (xy 263.271957 -60.738075)
			(xy 263.248285 -60.788572) (xy 263.217512 -60.835085) (xy 263.180295 -60.876622) (xy 263.137427 -60.912297)
			(xy 263.089821 -60.941351) (xy 263.038492 -60.963163) (xy 262.984535 -60.977269) (xy 262.929098 -60.983369)
			(xy 262.873364 -60.981332) (xy 262.818521 -60.971202) (xy 262.765737 -60.953195) (xy 262.716137 -60.927694)
			(xy 262.670779 -60.895243) (xy 262.63063 -60.856534) (xy 262.596544 -60.812391) (xy 262.569248 -60.763756)
			(xy 262.549325 -60.711665) (xy 262.537199 -60.657228) (xy 262.533128 -60.601606) (xy 240.166826 -60.601606)
			(xy 240.183484 -60.618264) (xy 240.219971 -60.665814) (xy 240.249938 -60.71772) (xy 240.272874 -60.773093)
			(xy 240.288387 -60.830986) (xy 240.29621 -60.890408) (xy 240.2967 -60.920376) (xy 240.29621 -60.950344)
			(xy 240.288387 -61.009766) (xy 240.272874 -61.067659) (xy 240.249938 -61.123032) (xy 240.219971 -61.174938)
			(xy 240.183484 -61.222488) (xy 240.141104 -61.264868) (xy 240.093554 -61.301355) (xy 240.041648 -61.331322)
			(xy 239.986275 -61.354258) (xy 239.928382 -61.369771) (xy 239.86896 -61.377594) (xy 239.809024 -61.377594)
			(xy 239.749602 -61.369771) (xy 239.691709 -61.354258) (xy 239.636336 -61.331322) (xy 239.58443 -61.301355)
			(xy 239.53688 -61.264868) (xy 239.4945 -61.222488) (xy 239.458013 -61.174938) (xy 239.428046 -61.123032)
			(xy 239.40511 -61.067659) (xy 239.389597 -61.009766) (xy 239.381774 -60.950344) (xy 231.538084 -60.950344)
			(xy 231.511504 -60.961639) (xy 231.457547 -60.975745) (xy 231.40211 -60.981845) (xy 231.346376 -60.979808)
			(xy 231.291533 -60.969678) (xy 231.238749 -60.951671) (xy 231.189149 -60.92617) (xy 231.143791 -60.893719)
			(xy 231.103642 -60.85501) (xy 231.069556 -60.810867) (xy 231.04226 -60.762232) (xy 231.022337 -60.710141)
			(xy 231.010211 -60.655704) (xy 231.00614 -60.600082) (xy 230.059992 -60.600082) (xy 230.059992 -61.615824)
			(xy 240.534172 -61.615824) (xy 240.534172 -61.555888) (xy 240.541995 -61.496466) (xy 240.557508 -61.438573)
			(xy 240.580444 -61.3832) (xy 240.610411 -61.331294) (xy 240.646898 -61.283744) (xy 240.689278 -61.241364)
			(xy 240.736828 -61.204877) (xy 240.788734 -61.17491) (xy 240.844107 -61.151974) (xy 240.902 -61.136461)
			(xy 240.961422 -61.128638) (xy 241.021358 -61.128638) (xy 241.08078 -61.136461) (xy 241.138673 -61.151974)
			(xy 241.194046 -61.17491) (xy 241.245952 -61.204877) (xy 241.293502 -61.241364) (xy 241.335882 -61.283744)
			(xy 241.372369 -61.331294) (xy 241.402336 -61.3832) (xy 241.425272 -61.438573) (xy 241.438466 -61.487812)
			(xy 264.504422 -61.487812) (xy 264.508493 -61.43219) (xy 264.520619 -61.377753) (xy 264.540542 -61.325662)
			(xy 264.567838 -61.277027) (xy 264.601924 -61.232884) (xy 264.642073 -61.194175) (xy 264.687431 -61.161724)
			(xy 264.737031 -61.136223) (xy 264.789815 -61.118216) (xy 264.844658 -61.108086) (xy 264.900392 -61.106049)
			(xy 264.955829 -61.112149) (xy 265.009786 -61.126255) (xy 265.061115 -61.148067) (xy 265.108721 -61.177121)
			(xy 265.151589 -61.212796) (xy 265.188806 -61.254333) (xy 265.219579 -61.300846) (xy 265.243251 -61.351343)
			(xy 265.259319 -61.40475) (xy 265.267439 -61.459926) (xy 265.267948 -61.487812) (xy 290.50437 -61.487812)
			(xy 290.508441 -61.43219) (xy 290.520567 -61.377753) (xy 290.54049 -61.325662) (xy 290.567786 -61.277027)
			(xy 290.601872 -61.232884) (xy 290.642021 -61.194175) (xy 290.687379 -61.161724) (xy 290.736979 -61.136223)
			(xy 290.789763 -61.118216) (xy 290.844606 -61.108086) (xy 290.90034 -61.106049) (xy 290.955777 -61.112149)
			(xy 291.009734 -61.126255) (xy 291.061063 -61.148067) (xy 291.108669 -61.177121) (xy 291.151537 -61.212796)
			(xy 291.188754 -61.254333) (xy 291.219527 -61.300846) (xy 291.243199 -61.351343) (xy 291.259267 -61.40475)
			(xy 291.267387 -61.459926) (xy 291.267896 -61.487812) (xy 316.504318 -61.487812) (xy 316.508389 -61.43219)
			(xy 316.520515 -61.377753) (xy 316.540438 -61.325662) (xy 316.567734 -61.277027) (xy 316.60182 -61.232884)
			(xy 316.641969 -61.194175) (xy 316.687327 -61.161724) (xy 316.736927 -61.136223) (xy 316.789711 -61.118216)
			(xy 316.844554 -61.108086) (xy 316.900288 -61.106049) (xy 316.955725 -61.112149) (xy 317.009682 -61.126255)
			(xy 317.061011 -61.148067) (xy 317.108617 -61.177121) (xy 317.151485 -61.212796) (xy 317.188702 -61.254333)
			(xy 317.219475 -61.300846) (xy 317.243147 -61.351343) (xy 317.259215 -61.40475) (xy 317.267335 -61.459926)
			(xy 317.267844 -61.487812) (xy 354.604572 -61.487812) (xy 354.608643 -61.43219) (xy 354.620769 -61.377753)
			(xy 354.640692 -61.325662) (xy 354.667988 -61.277027) (xy 354.702074 -61.232884) (xy 354.742223 -61.194175)
			(xy 354.787581 -61.161724) (xy 354.837181 -61.136223) (xy 354.889965 -61.118216) (xy 354.944808 -61.108086)
			(xy 355.000542 -61.106049) (xy 355.055979 -61.112149) (xy 355.109936 -61.126255) (xy 355.161265 -61.148067)
			(xy 355.208871 -61.177121) (xy 355.251739 -61.212796) (xy 355.288956 -61.254333) (xy 355.319729 -61.300846)
			(xy 355.343401 -61.351343) (xy 355.359469 -61.40475) (xy 355.367589 -61.459926) (xy 355.368098 -61.487812)
			(xy 380.60452 -61.487812) (xy 380.608591 -61.43219) (xy 380.620717 -61.377753) (xy 380.64064 -61.325662)
			(xy 380.667936 -61.277027) (xy 380.702022 -61.232884) (xy 380.742171 -61.194175) (xy 380.787529 -61.161724)
			(xy 380.837129 -61.136223) (xy 380.889913 -61.118216) (xy 380.944756 -61.108086) (xy 381.00049 -61.106049)
			(xy 381.055927 -61.112149) (xy 381.109884 -61.126255) (xy 381.161213 -61.148067) (xy 381.208819 -61.177121)
			(xy 381.251687 -61.212796) (xy 381.288904 -61.254333) (xy 381.319677 -61.300846) (xy 381.343349 -61.351343)
			(xy 381.359417 -61.40475) (xy 381.367537 -61.459926) (xy 381.368046 -61.487812) (xy 406.604468 -61.487812)
			(xy 406.608539 -61.43219) (xy 406.620665 -61.377753) (xy 406.640588 -61.325662) (xy 406.667884 -61.277027)
			(xy 406.70197 -61.232884) (xy 406.742119 -61.194175) (xy 406.787477 -61.161724) (xy 406.837077 -61.136223)
			(xy 406.889861 -61.118216) (xy 406.944704 -61.108086) (xy 407.000438 -61.106049) (xy 407.055875 -61.112149)
			(xy 407.109832 -61.126255) (xy 407.161161 -61.148067) (xy 407.208767 -61.177121) (xy 407.251635 -61.212796)
			(xy 407.288852 -61.254333) (xy 407.319625 -61.300846) (xy 407.343297 -61.351343) (xy 407.359365 -61.40475)
			(xy 407.367485 -61.459926) (xy 407.367994 -61.487812) (xy 432.604416 -61.487812) (xy 432.608487 -61.43219)
			(xy 432.620613 -61.377753) (xy 432.640536 -61.325662) (xy 432.667832 -61.277027) (xy 432.701918 -61.232884)
			(xy 432.742067 -61.194175) (xy 432.787425 -61.161724) (xy 432.837025 -61.136223) (xy 432.889809 -61.118216)
			(xy 432.944652 -61.108086) (xy 433.000386 -61.106049) (xy 433.055823 -61.112149) (xy 433.10978 -61.126255)
			(xy 433.161109 -61.148067) (xy 433.208715 -61.177121) (xy 433.251583 -61.212796) (xy 433.2888 -61.254333)
			(xy 433.319573 -61.300846) (xy 433.343245 -61.351343) (xy 433.359313 -61.40475) (xy 433.367433 -61.459926)
			(xy 433.367942 -61.487812) (xy 433.367433 -61.515698) (xy 433.359313 -61.570874) (xy 433.343245 -61.624281)
			(xy 433.319573 -61.674778) (xy 433.2888 -61.721291) (xy 433.251583 -61.762828) (xy 433.208715 -61.798503)
			(xy 433.161109 -61.827557) (xy 433.10978 -61.849369) (xy 433.055823 -61.863475) (xy 433.000386 -61.869575)
			(xy 432.944652 -61.867538) (xy 432.889809 -61.857408) (xy 432.837025 -61.839401) (xy 432.787425 -61.8139)
			(xy 432.742067 -61.781449) (xy 432.701918 -61.74274) (xy 432.667832 -61.698597) (xy 432.640536 -61.649962)
			(xy 432.620613 -61.597871) (xy 432.608487 -61.543434) (xy 432.604416 -61.487812) (xy 407.367994 -61.487812)
			(xy 407.367485 -61.515698) (xy 407.359365 -61.570874) (xy 407.343297 -61.624281) (xy 407.319625 -61.674778)
			(xy 407.288852 -61.721291) (xy 407.251635 -61.762828) (xy 407.208767 -61.798503) (xy 407.161161 -61.827557)
			(xy 407.109832 -61.849369) (xy 407.055875 -61.863475) (xy 407.000438 -61.869575) (xy 406.944704 -61.867538)
			(xy 406.889861 -61.857408) (xy 406.837077 -61.839401) (xy 406.787477 -61.8139) (xy 406.742119 -61.781449)
			(xy 406.70197 -61.74274) (xy 406.667884 -61.698597) (xy 406.640588 -61.649962) (xy 406.620665 -61.597871)
			(xy 406.608539 -61.543434) (xy 406.604468 -61.487812) (xy 381.368046 -61.487812) (xy 381.367537 -61.515698)
			(xy 381.359417 -61.570874) (xy 381.343349 -61.624281) (xy 381.319677 -61.674778) (xy 381.288904 -61.721291)
			(xy 381.251687 -61.762828) (xy 381.208819 -61.798503) (xy 381.161213 -61.827557) (xy 381.109884 -61.849369)
			(xy 381.055927 -61.863475) (xy 381.00049 -61.869575) (xy 380.944756 -61.867538) (xy 380.889913 -61.857408)
			(xy 380.837129 -61.839401) (xy 380.787529 -61.8139) (xy 380.742171 -61.781449) (xy 380.702022 -61.74274)
			(xy 380.667936 -61.698597) (xy 380.64064 -61.649962) (xy 380.620717 -61.597871) (xy 380.608591 -61.543434)
			(xy 380.60452 -61.487812) (xy 355.368098 -61.487812) (xy 355.367589 -61.515698) (xy 355.359469 -61.570874)
			(xy 355.343401 -61.624281) (xy 355.319729 -61.674778) (xy 355.288956 -61.721291) (xy 355.251739 -61.762828)
			(xy 355.208871 -61.798503) (xy 355.161265 -61.827557) (xy 355.109936 -61.849369) (xy 355.055979 -61.863475)
			(xy 355.000542 -61.869575) (xy 354.944808 -61.867538) (xy 354.889965 -61.857408) (xy 354.837181 -61.839401)
			(xy 354.787581 -61.8139) (xy 354.742223 -61.781449) (xy 354.702074 -61.74274) (xy 354.667988 -61.698597)
			(xy 354.640692 -61.649962) (xy 354.620769 -61.597871) (xy 354.608643 -61.543434) (xy 354.604572 -61.487812)
			(xy 317.267844 -61.487812) (xy 317.267335 -61.515698) (xy 317.259215 -61.570874) (xy 317.243147 -61.624281)
			(xy 317.219475 -61.674778) (xy 317.188702 -61.721291) (xy 317.151485 -61.762828) (xy 317.108617 -61.798503)
			(xy 317.061011 -61.827557) (xy 317.009682 -61.849369) (xy 316.955725 -61.863475) (xy 316.900288 -61.869575)
			(xy 316.844554 -61.867538) (xy 316.789711 -61.857408) (xy 316.736927 -61.839401) (xy 316.687327 -61.8139)
			(xy 316.641969 -61.781449) (xy 316.60182 -61.74274) (xy 316.567734 -61.698597) (xy 316.540438 -61.649962)
			(xy 316.520515 -61.597871) (xy 316.508389 -61.543434) (xy 316.504318 -61.487812) (xy 291.267896 -61.487812)
			(xy 291.267387 -61.515698) (xy 291.259267 -61.570874) (xy 291.243199 -61.624281) (xy 291.219527 -61.674778)
			(xy 291.188754 -61.721291) (xy 291.151537 -61.762828) (xy 291.108669 -61.798503) (xy 291.061063 -61.827557)
			(xy 291.009734 -61.849369) (xy 290.955777 -61.863475) (xy 290.90034 -61.869575) (xy 290.844606 -61.867538)
			(xy 290.789763 -61.857408) (xy 290.736979 -61.839401) (xy 290.687379 -61.8139) (xy 290.642021 -61.781449)
			(xy 290.601872 -61.74274) (xy 290.567786 -61.698597) (xy 290.54049 -61.649962) (xy 290.520567 -61.597871)
			(xy 290.508441 -61.543434) (xy 290.50437 -61.487812) (xy 265.267948 -61.487812) (xy 265.267439 -61.515698)
			(xy 265.259319 -61.570874) (xy 265.243251 -61.624281) (xy 265.219579 -61.674778) (xy 265.188806 -61.721291)
			(xy 265.151589 -61.762828) (xy 265.108721 -61.798503) (xy 265.061115 -61.827557) (xy 265.009786 -61.849369)
			(xy 264.955829 -61.863475) (xy 264.900392 -61.869575) (xy 264.844658 -61.867538) (xy 264.789815 -61.857408)
			(xy 264.737031 -61.839401) (xy 264.687431 -61.8139) (xy 264.642073 -61.781449) (xy 264.601924 -61.74274)
			(xy 264.567838 -61.698597) (xy 264.540542 -61.649962) (xy 264.520619 -61.597871) (xy 264.508493 -61.543434)
			(xy 264.504422 -61.487812) (xy 241.438466 -61.487812) (xy 241.440785 -61.496466) (xy 241.448608 -61.555888)
			(xy 241.449098 -61.585856) (xy 241.448608 -61.615824) (xy 241.440785 -61.675246) (xy 241.425272 -61.733139)
			(xy 241.402336 -61.788512) (xy 241.372369 -61.840418) (xy 241.335882 -61.887968) (xy 241.293502 -61.930348)
			(xy 241.245952 -61.966835) (xy 241.194046 -61.996802) (xy 241.138673 -62.019738) (xy 241.08078 -62.035251)
			(xy 241.021358 -62.043074) (xy 240.961422 -62.043074) (xy 240.902 -62.035251) (xy 240.844107 -62.019738)
			(xy 240.788734 -61.996802) (xy 240.736828 -61.966835) (xy 240.689278 -61.930348) (xy 240.646898 -61.887968)
			(xy 240.610411 -61.840418) (xy 240.580444 -61.788512) (xy 240.557508 -61.733139) (xy 240.541995 -61.675246)
			(xy 240.534172 -61.615824) (xy 230.059992 -61.615824) (xy 230.059992 -62.399926) (xy 233.19054 -62.399926)
			(xy 233.194611 -62.344304) (xy 233.206737 -62.289867) (xy 233.22666 -62.237776) (xy 233.253956 -62.189141)
			(xy 233.288042 -62.144998) (xy 233.328191 -62.106289) (xy 233.373549 -62.073838) (xy 233.423149 -62.048337)
			(xy 233.475933 -62.03033) (xy 233.530776 -62.0202) (xy 233.58651 -62.018163) (xy 233.641947 -62.024263)
			(xy 233.695904 -62.038369) (xy 233.747233 -62.060181) (xy 233.794839 -62.089235) (xy 233.837707 -62.12491)
			(xy 233.874924 -62.166447) (xy 233.905697 -62.21296) (xy 233.929369 -62.263457) (xy 233.945437 -62.316864)
			(xy 233.951605 -62.358778) (xy 236.702344 -62.358778) (xy 236.706415 -62.303156) (xy 236.718541 -62.248719)
			(xy 236.738464 -62.196628) (xy 236.76576 -62.147993) (xy 236.799846 -62.10385) (xy 236.839995 -62.065141)
			(xy 236.885353 -62.03269) (xy 236.934953 -62.007189) (xy 236.987737 -61.989182) (xy 237.04258 -61.979052)
			(xy 237.098314 -61.977015) (xy 237.153751 -61.983115) (xy 237.207708 -61.997221) (xy 237.259037 -62.019033)
			(xy 237.306643 -62.048087) (xy 237.349511 -62.083762) (xy 237.386728 -62.125299) (xy 237.417501 -62.171812)
			(xy 237.441173 -62.222309) (xy 237.457241 -62.275716) (xy 237.465361 -62.330892) (xy 237.46587 -62.358778)
			(xy 237.465361 -62.386664) (xy 237.461989 -62.409578) (xy 238.418114 -62.409578) (xy 238.422185 -62.353956)
			(xy 238.434311 -62.299519) (xy 238.454234 -62.247428) (xy 238.48153 -62.198793) (xy 238.515616 -62.15465)
			(xy 238.555765 -62.115941) (xy 238.601123 -62.08349) (xy 238.650723 -62.057989) (xy 238.703507 -62.039982)
			(xy 238.75835 -62.029852) (xy 238.814084 -62.027815) (xy 238.869521 -62.033915) (xy 238.923478 -62.048021)
			(xy 238.974807 -62.069833) (xy 239.022413 -62.098887) (xy 239.065281 -62.134562) (xy 239.080011 -62.151002)
			(xy 262.366996 -62.151002) (xy 262.366996 -62.091066) (xy 262.374819 -62.031644) (xy 262.390332 -61.973751)
			(xy 262.413268 -61.918378) (xy 262.443235 -61.866472) (xy 262.479722 -61.818922) (xy 262.522102 -61.776542)
			(xy 262.569652 -61.740055) (xy 262.621558 -61.710088) (xy 262.676931 -61.687152) (xy 262.734824 -61.671639)
			(xy 262.794246 -61.663816) (xy 262.854182 -61.663816) (xy 262.913604 -61.671639) (xy 262.971497 -61.687152)
			(xy 263.02687 -61.710088) (xy 263.078776 -61.740055) (xy 263.126326 -61.776542) (xy 263.168706 -61.818922)
			(xy 263.205193 -61.866472) (xy 263.23516 -61.918378) (xy 263.258096 -61.973751) (xy 263.273609 -62.031644)
			(xy 263.276215 -62.051438) (xy 266.42898 -62.051438) (xy 266.433051 -61.995816) (xy 266.445177 -61.941379)
			(xy 266.4651 -61.889288) (xy 266.492396 -61.840653) (xy 266.526482 -61.79651) (xy 266.566631 -61.757801)
			(xy 266.611989 -61.72535) (xy 266.661589 -61.699849) (xy 266.714373 -61.681842) (xy 266.769216 -61.671712)
			(xy 266.82495 -61.669675) (xy 266.880387 -61.675775) (xy 266.934344 -61.689881) (xy 266.985673 -61.711693)
			(xy 267.033279 -61.740747) (xy 267.076147 -61.776422) (xy 267.113364 -61.817959) (xy 267.144137 -61.864472)
			(xy 267.167809 -61.914969) (xy 267.183877 -61.968376) (xy 267.191997 -62.023552) (xy 267.192506 -62.051438)
			(xy 267.191997 -62.079324) (xy 267.183877 -62.1345) (xy 267.178912 -62.151002) (xy 288.366944 -62.151002)
			(xy 288.366944 -62.091066) (xy 288.374767 -62.031644) (xy 288.39028 -61.973751) (xy 288.413216 -61.918378)
			(xy 288.443183 -61.866472) (xy 288.47967 -61.818922) (xy 288.52205 -61.776542) (xy 288.5696 -61.740055)
			(xy 288.621506 -61.710088) (xy 288.676879 -61.687152) (xy 288.734772 -61.671639) (xy 288.794194 -61.663816)
			(xy 288.85413 -61.663816) (xy 288.913552 -61.671639) (xy 288.971445 -61.687152) (xy 289.026818 -61.710088)
			(xy 289.078724 -61.740055) (xy 289.126274 -61.776542) (xy 289.168654 -61.818922) (xy 289.205141 -61.866472)
			(xy 289.235108 -61.918378) (xy 289.258044 -61.973751) (xy 289.273557 -62.031644) (xy 289.276163 -62.051438)
			(xy 292.428928 -62.051438) (xy 292.432999 -61.995816) (xy 292.445125 -61.941379) (xy 292.465048 -61.889288)
			(xy 292.492344 -61.840653) (xy 292.52643 -61.79651) (xy 292.566579 -61.757801) (xy 292.611937 -61.72535)
			(xy 292.661537 -61.699849) (xy 292.714321 -61.681842) (xy 292.769164 -61.671712) (xy 292.824898 -61.669675)
			(xy 292.880335 -61.675775) (xy 292.934292 -61.689881) (xy 292.985621 -61.711693) (xy 293.033227 -61.740747)
			(xy 293.076095 -61.776422) (xy 293.113312 -61.817959) (xy 293.144085 -61.864472) (xy 293.167757 -61.914969)
			(xy 293.183825 -61.968376) (xy 293.191945 -62.023552) (xy 293.192454 -62.051438) (xy 293.191945 -62.079324)
			(xy 293.183825 -62.1345) (xy 293.17886 -62.151002) (xy 314.366892 -62.151002) (xy 314.366892 -62.091066)
			(xy 314.374715 -62.031644) (xy 314.390228 -61.973751) (xy 314.413164 -61.918378) (xy 314.443131 -61.866472)
			(xy 314.479618 -61.818922) (xy 314.521998 -61.776542) (xy 314.569548 -61.740055) (xy 314.621454 -61.710088)
			(xy 314.676827 -61.687152) (xy 314.73472 -61.671639) (xy 314.794142 -61.663816) (xy 314.854078 -61.663816)
			(xy 314.9135 -61.671639) (xy 314.971393 -61.687152) (xy 315.026766 -61.710088) (xy 315.078672 -61.740055)
			(xy 315.126222 -61.776542) (xy 315.168602 -61.818922) (xy 315.205089 -61.866472) (xy 315.235056 -61.918378)
			(xy 315.257992 -61.973751) (xy 315.273505 -62.031644) (xy 315.276111 -62.051438) (xy 318.428876 -62.051438)
			(xy 318.432947 -61.995816) (xy 318.445073 -61.941379) (xy 318.464996 -61.889288) (xy 318.492292 -61.840653)
			(xy 318.526378 -61.79651) (xy 318.566527 -61.757801) (xy 318.611885 -61.72535) (xy 318.661485 -61.699849)
			(xy 318.714269 -61.681842) (xy 318.769112 -61.671712) (xy 318.824846 -61.669675) (xy 318.880283 -61.675775)
			(xy 318.93424 -61.689881) (xy 318.985569 -61.711693) (xy 319.033175 -61.740747) (xy 319.076043 -61.776422)
			(xy 319.11326 -61.817959) (xy 319.144033 -61.864472) (xy 319.167705 -61.914969) (xy 319.183773 -61.968376)
			(xy 319.191893 -62.023552) (xy 319.192402 -62.051438) (xy 319.191893 -62.079324) (xy 319.183773 -62.1345)
			(xy 319.178808 -62.151002) (xy 352.467146 -62.151002) (xy 352.467146 -62.091066) (xy 352.474969 -62.031644)
			(xy 352.490482 -61.973751) (xy 352.513418 -61.918378) (xy 352.543385 -61.866472) (xy 352.579872 -61.818922)
			(xy 352.622252 -61.776542) (xy 352.669802 -61.740055) (xy 352.721708 -61.710088) (xy 352.777081 -61.687152)
			(xy 352.834974 -61.671639) (xy 352.894396 -61.663816) (xy 352.954332 -61.663816) (xy 353.013754 -61.671639)
			(xy 353.071647 -61.687152) (xy 353.12702 -61.710088) (xy 353.178926 -61.740055) (xy 353.226476 -61.776542)
			(xy 353.268856 -61.818922) (xy 353.305343 -61.866472) (xy 353.33531 -61.918378) (xy 353.358246 -61.973751)
			(xy 353.373759 -62.031644) (xy 353.376365 -62.051438) (xy 356.52913 -62.051438) (xy 356.533201 -61.995816)
			(xy 356.545327 -61.941379) (xy 356.56525 -61.889288) (xy 356.592546 -61.840653) (xy 356.626632 -61.79651)
			(xy 356.666781 -61.757801) (xy 356.712139 -61.72535) (xy 356.761739 -61.699849) (xy 356.814523 -61.681842)
			(xy 356.869366 -61.671712) (xy 356.9251 -61.669675) (xy 356.980537 -61.675775) (xy 357.034494 -61.689881)
			(xy 357.085823 -61.711693) (xy 357.133429 -61.740747) (xy 357.176297 -61.776422) (xy 357.213514 -61.817959)
			(xy 357.244287 -61.864472) (xy 357.267959 -61.914969) (xy 357.284027 -61.968376) (xy 357.292147 -62.023552)
			(xy 357.292656 -62.051438) (xy 357.292147 -62.079324) (xy 357.284027 -62.1345) (xy 357.279062 -62.151002)
			(xy 378.467094 -62.151002) (xy 378.467094 -62.091066) (xy 378.474917 -62.031644) (xy 378.49043 -61.973751)
			(xy 378.513366 -61.918378) (xy 378.543333 -61.866472) (xy 378.57982 -61.818922) (xy 378.6222 -61.776542)
			(xy 378.66975 -61.740055) (xy 378.721656 -61.710088) (xy 378.777029 -61.687152) (xy 378.834922 -61.671639)
			(xy 378.894344 -61.663816) (xy 378.95428 -61.663816) (xy 379.013702 -61.671639) (xy 379.071595 -61.687152)
			(xy 379.126968 -61.710088) (xy 379.178874 -61.740055) (xy 379.226424 -61.776542) (xy 379.268804 -61.818922)
			(xy 379.305291 -61.866472) (xy 379.335258 -61.918378) (xy 379.358194 -61.973751) (xy 379.373707 -62.031644)
			(xy 379.376313 -62.051438) (xy 382.529078 -62.051438) (xy 382.533149 -61.995816) (xy 382.545275 -61.941379)
			(xy 382.565198 -61.889288) (xy 382.592494 -61.840653) (xy 382.62658 -61.79651) (xy 382.666729 -61.757801)
			(xy 382.712087 -61.72535) (xy 382.761687 -61.699849) (xy 382.814471 -61.681842) (xy 382.869314 -61.671712)
			(xy 382.925048 -61.669675) (xy 382.980485 -61.675775) (xy 383.034442 -61.689881) (xy 383.085771 -61.711693)
			(xy 383.133377 -61.740747) (xy 383.176245 -61.776422) (xy 383.213462 -61.817959) (xy 383.244235 -61.864472)
			(xy 383.267907 -61.914969) (xy 383.283975 -61.968376) (xy 383.292095 -62.023552) (xy 383.292604 -62.051438)
			(xy 383.292095 -62.079324) (xy 383.283975 -62.1345) (xy 383.27901 -62.151002) (xy 404.467042 -62.151002)
			(xy 404.467042 -62.091066) (xy 404.474865 -62.031644) (xy 404.490378 -61.973751) (xy 404.513314 -61.918378)
			(xy 404.543281 -61.866472) (xy 404.579768 -61.818922) (xy 404.622148 -61.776542) (xy 404.669698 -61.740055)
			(xy 404.721604 -61.710088) (xy 404.776977 -61.687152) (xy 404.83487 -61.671639) (xy 404.894292 -61.663816)
			(xy 404.954228 -61.663816) (xy 405.01365 -61.671639) (xy 405.071543 -61.687152) (xy 405.126916 -61.710088)
			(xy 405.178822 -61.740055) (xy 405.226372 -61.776542) (xy 405.268752 -61.818922) (xy 405.305239 -61.866472)
			(xy 405.335206 -61.918378) (xy 405.358142 -61.973751) (xy 405.373655 -62.031644) (xy 405.376261 -62.051438)
			(xy 408.529026 -62.051438) (xy 408.533097 -61.995816) (xy 408.545223 -61.941379) (xy 408.565146 -61.889288)
			(xy 408.592442 -61.840653) (xy 408.626528 -61.79651) (xy 408.666677 -61.757801) (xy 408.712035 -61.72535)
			(xy 408.761635 -61.699849) (xy 408.814419 -61.681842) (xy 408.869262 -61.671712) (xy 408.924996 -61.669675)
			(xy 408.980433 -61.675775) (xy 409.03439 -61.689881) (xy 409.085719 -61.711693) (xy 409.133325 -61.740747)
			(xy 409.176193 -61.776422) (xy 409.21341 -61.817959) (xy 409.244183 -61.864472) (xy 409.267855 -61.914969)
			(xy 409.283923 -61.968376) (xy 409.292043 -62.023552) (xy 409.292552 -62.051438) (xy 409.292043 -62.079324)
			(xy 409.283923 -62.1345) (xy 409.278958 -62.151002) (xy 430.46699 -62.151002) (xy 430.46699 -62.091066)
			(xy 430.474813 -62.031644) (xy 430.490326 -61.973751) (xy 430.513262 -61.918378) (xy 430.543229 -61.866472)
			(xy 430.579716 -61.818922) (xy 430.622096 -61.776542) (xy 430.669646 -61.740055) (xy 430.721552 -61.710088)
			(xy 430.776925 -61.687152) (xy 430.834818 -61.671639) (xy 430.89424 -61.663816) (xy 430.954176 -61.663816)
			(xy 431.013598 -61.671639) (xy 431.071491 -61.687152) (xy 431.126864 -61.710088) (xy 431.17877 -61.740055)
			(xy 431.22632 -61.776542) (xy 431.2687 -61.818922) (xy 431.305187 -61.866472) (xy 431.335154 -61.918378)
			(xy 431.35809 -61.973751) (xy 431.373603 -62.031644) (xy 431.376209 -62.051438) (xy 434.528974 -62.051438)
			(xy 434.533045 -61.995816) (xy 434.545171 -61.941379) (xy 434.565094 -61.889288) (xy 434.59239 -61.840653)
			(xy 434.626476 -61.79651) (xy 434.666625 -61.757801) (xy 434.711983 -61.72535) (xy 434.761583 -61.699849)
			(xy 434.814367 -61.681842) (xy 434.86921 -61.671712) (xy 434.924944 -61.669675) (xy 434.980381 -61.675775)
			(xy 435.034338 -61.689881) (xy 435.085667 -61.711693) (xy 435.133273 -61.740747) (xy 435.176141 -61.776422)
			(xy 435.213358 -61.817959) (xy 435.244131 -61.864472) (xy 435.267803 -61.914969) (xy 435.283871 -61.968376)
			(xy 435.291991 -62.023552) (xy 435.2925 -62.051438) (xy 435.291991 -62.079324) (xy 435.283871 -62.1345)
			(xy 435.267803 -62.187907) (xy 435.244131 -62.238404) (xy 435.213358 -62.284917) (xy 435.176141 -62.326454)
			(xy 435.133273 -62.362129) (xy 435.085667 -62.391183) (xy 435.034338 -62.412995) (xy 434.980381 -62.427101)
			(xy 434.924944 -62.433201) (xy 434.86921 -62.431164) (xy 434.814367 -62.421034) (xy 434.761583 -62.403027)
			(xy 434.711983 -62.377526) (xy 434.666625 -62.345075) (xy 434.626476 -62.306366) (xy 434.59239 -62.262223)
			(xy 434.565094 -62.213588) (xy 434.545171 -62.161497) (xy 434.533045 -62.10706) (xy 434.528974 -62.051438)
			(xy 431.376209 -62.051438) (xy 431.381426 -62.091066) (xy 431.381916 -62.121034) (xy 431.381426 -62.151002)
			(xy 431.373603 -62.210424) (xy 431.35809 -62.268317) (xy 431.335154 -62.32369) (xy 431.305187 -62.375596)
			(xy 431.2687 -62.423146) (xy 431.22632 -62.465526) (xy 431.17877 -62.502013) (xy 431.126864 -62.53198)
			(xy 431.071491 -62.554916) (xy 431.013598 -62.570429) (xy 430.954176 -62.578252) (xy 430.89424 -62.578252)
			(xy 430.834818 -62.570429) (xy 430.776925 -62.554916) (xy 430.721552 -62.53198) (xy 430.669646 -62.502013)
			(xy 430.622096 -62.465526) (xy 430.579716 -62.423146) (xy 430.543229 -62.375596) (xy 430.513262 -62.32369)
			(xy 430.490326 -62.268317) (xy 430.474813 -62.210424) (xy 430.46699 -62.151002) (xy 409.278958 -62.151002)
			(xy 409.267855 -62.187907) (xy 409.244183 -62.238404) (xy 409.21341 -62.284917) (xy 409.176193 -62.326454)
			(xy 409.133325 -62.362129) (xy 409.085719 -62.391183) (xy 409.03439 -62.412995) (xy 408.980433 -62.427101)
			(xy 408.924996 -62.433201) (xy 408.869262 -62.431164) (xy 408.814419 -62.421034) (xy 408.761635 -62.403027)
			(xy 408.712035 -62.377526) (xy 408.666677 -62.345075) (xy 408.626528 -62.306366) (xy 408.592442 -62.262223)
			(xy 408.565146 -62.213588) (xy 408.545223 -62.161497) (xy 408.533097 -62.10706) (xy 408.529026 -62.051438)
			(xy 405.376261 -62.051438) (xy 405.381478 -62.091066) (xy 405.381968 -62.121034) (xy 405.381478 -62.151002)
			(xy 405.373655 -62.210424) (xy 405.358142 -62.268317) (xy 405.335206 -62.32369) (xy 405.305239 -62.375596)
			(xy 405.268752 -62.423146) (xy 405.226372 -62.465526) (xy 405.178822 -62.502013) (xy 405.126916 -62.53198)
			(xy 405.071543 -62.554916) (xy 405.01365 -62.570429) (xy 404.954228 -62.578252) (xy 404.894292 -62.578252)
			(xy 404.83487 -62.570429) (xy 404.776977 -62.554916) (xy 404.721604 -62.53198) (xy 404.669698 -62.502013)
			(xy 404.622148 -62.465526) (xy 404.579768 -62.423146) (xy 404.543281 -62.375596) (xy 404.513314 -62.32369)
			(xy 404.490378 -62.268317) (xy 404.474865 -62.210424) (xy 404.467042 -62.151002) (xy 383.27901 -62.151002)
			(xy 383.267907 -62.187907) (xy 383.244235 -62.238404) (xy 383.213462 -62.284917) (xy 383.176245 -62.326454)
			(xy 383.133377 -62.362129) (xy 383.085771 -62.391183) (xy 383.034442 -62.412995) (xy 382.980485 -62.427101)
			(xy 382.925048 -62.433201) (xy 382.869314 -62.431164) (xy 382.814471 -62.421034) (xy 382.761687 -62.403027)
			(xy 382.712087 -62.377526) (xy 382.666729 -62.345075) (xy 382.62658 -62.306366) (xy 382.592494 -62.262223)
			(xy 382.565198 -62.213588) (xy 382.545275 -62.161497) (xy 382.533149 -62.10706) (xy 382.529078 -62.051438)
			(xy 379.376313 -62.051438) (xy 379.38153 -62.091066) (xy 379.38202 -62.121034) (xy 379.38153 -62.151002)
			(xy 379.373707 -62.210424) (xy 379.358194 -62.268317) (xy 379.335258 -62.32369) (xy 379.305291 -62.375596)
			(xy 379.268804 -62.423146) (xy 379.226424 -62.465526) (xy 379.178874 -62.502013) (xy 379.126968 -62.53198)
			(xy 379.071595 -62.554916) (xy 379.013702 -62.570429) (xy 378.95428 -62.578252) (xy 378.894344 -62.578252)
			(xy 378.834922 -62.570429) (xy 378.777029 -62.554916) (xy 378.721656 -62.53198) (xy 378.66975 -62.502013)
			(xy 378.6222 -62.465526) (xy 378.57982 -62.423146) (xy 378.543333 -62.375596) (xy 378.513366 -62.32369)
			(xy 378.49043 -62.268317) (xy 378.474917 -62.210424) (xy 378.467094 -62.151002) (xy 357.279062 -62.151002)
			(xy 357.267959 -62.187907) (xy 357.244287 -62.238404) (xy 357.213514 -62.284917) (xy 357.176297 -62.326454)
			(xy 357.133429 -62.362129) (xy 357.085823 -62.391183) (xy 357.034494 -62.412995) (xy 356.980537 -62.427101)
			(xy 356.9251 -62.433201) (xy 356.869366 -62.431164) (xy 356.814523 -62.421034) (xy 356.761739 -62.403027)
			(xy 356.712139 -62.377526) (xy 356.666781 -62.345075) (xy 356.626632 -62.306366) (xy 356.592546 -62.262223)
			(xy 356.56525 -62.213588) (xy 356.545327 -62.161497) (xy 356.533201 -62.10706) (xy 356.52913 -62.051438)
			(xy 353.376365 -62.051438) (xy 353.381582 -62.091066) (xy 353.382072 -62.121034) (xy 353.381582 -62.151002)
			(xy 353.373759 -62.210424) (xy 353.358246 -62.268317) (xy 353.33531 -62.32369) (xy 353.305343 -62.375596)
			(xy 353.268856 -62.423146) (xy 353.226476 -62.465526) (xy 353.178926 -62.502013) (xy 353.12702 -62.53198)
			(xy 353.071647 -62.554916) (xy 353.013754 -62.570429) (xy 352.954332 -62.578252) (xy 352.894396 -62.578252)
			(xy 352.834974 -62.570429) (xy 352.777081 -62.554916) (xy 352.721708 -62.53198) (xy 352.669802 -62.502013)
			(xy 352.622252 -62.465526) (xy 352.579872 -62.423146) (xy 352.543385 -62.375596) (xy 352.513418 -62.32369)
			(xy 352.490482 -62.268317) (xy 352.474969 -62.210424) (xy 352.467146 -62.151002) (xy 319.178808 -62.151002)
			(xy 319.167705 -62.187907) (xy 319.144033 -62.238404) (xy 319.11326 -62.284917) (xy 319.076043 -62.326454)
			(xy 319.033175 -62.362129) (xy 318.985569 -62.391183) (xy 318.93424 -62.412995) (xy 318.880283 -62.427101)
			(xy 318.824846 -62.433201) (xy 318.769112 -62.431164) (xy 318.714269 -62.421034) (xy 318.661485 -62.403027)
			(xy 318.611885 -62.377526) (xy 318.566527 -62.345075) (xy 318.526378 -62.306366) (xy 318.492292 -62.262223)
			(xy 318.464996 -62.213588) (xy 318.445073 -62.161497) (xy 318.432947 -62.10706) (xy 318.428876 -62.051438)
			(xy 315.276111 -62.051438) (xy 315.281328 -62.091066) (xy 315.281818 -62.121034) (xy 315.281328 -62.151002)
			(xy 315.273505 -62.210424) (xy 315.257992 -62.268317) (xy 315.235056 -62.32369) (xy 315.205089 -62.375596)
			(xy 315.168602 -62.423146) (xy 315.126222 -62.465526) (xy 315.078672 -62.502013) (xy 315.026766 -62.53198)
			(xy 314.971393 -62.554916) (xy 314.9135 -62.570429) (xy 314.854078 -62.578252) (xy 314.794142 -62.578252)
			(xy 314.73472 -62.570429) (xy 314.676827 -62.554916) (xy 314.621454 -62.53198) (xy 314.569548 -62.502013)
			(xy 314.521998 -62.465526) (xy 314.479618 -62.423146) (xy 314.443131 -62.375596) (xy 314.413164 -62.32369)
			(xy 314.390228 -62.268317) (xy 314.374715 -62.210424) (xy 314.366892 -62.151002) (xy 293.17886 -62.151002)
			(xy 293.167757 -62.187907) (xy 293.144085 -62.238404) (xy 293.113312 -62.284917) (xy 293.076095 -62.326454)
			(xy 293.033227 -62.362129) (xy 292.985621 -62.391183) (xy 292.934292 -62.412995) (xy 292.880335 -62.427101)
			(xy 292.824898 -62.433201) (xy 292.769164 -62.431164) (xy 292.714321 -62.421034) (xy 292.661537 -62.403027)
			(xy 292.611937 -62.377526) (xy 292.566579 -62.345075) (xy 292.52643 -62.306366) (xy 292.492344 -62.262223)
			(xy 292.465048 -62.213588) (xy 292.445125 -62.161497) (xy 292.432999 -62.10706) (xy 292.428928 -62.051438)
			(xy 289.276163 -62.051438) (xy 289.28138 -62.091066) (xy 289.28187 -62.121034) (xy 289.28138 -62.151002)
			(xy 289.273557 -62.210424) (xy 289.258044 -62.268317) (xy 289.235108 -62.32369) (xy 289.205141 -62.375596)
			(xy 289.168654 -62.423146) (xy 289.126274 -62.465526) (xy 289.078724 -62.502013) (xy 289.026818 -62.53198)
			(xy 288.971445 -62.554916) (xy 288.913552 -62.570429) (xy 288.85413 -62.578252) (xy 288.794194 -62.578252)
			(xy 288.734772 -62.570429) (xy 288.676879 -62.554916) (xy 288.621506 -62.53198) (xy 288.5696 -62.502013)
			(xy 288.52205 -62.465526) (xy 288.47967 -62.423146) (xy 288.443183 -62.375596) (xy 288.413216 -62.32369)
			(xy 288.39028 -62.268317) (xy 288.374767 -62.210424) (xy 288.366944 -62.151002) (xy 267.178912 -62.151002)
			(xy 267.167809 -62.187907) (xy 267.144137 -62.238404) (xy 267.113364 -62.284917) (xy 267.076147 -62.326454)
			(xy 267.033279 -62.362129) (xy 266.985673 -62.391183) (xy 266.934344 -62.412995) (xy 266.880387 -62.427101)
			(xy 266.82495 -62.433201) (xy 266.769216 -62.431164) (xy 266.714373 -62.421034) (xy 266.661589 -62.403027)
			(xy 266.611989 -62.377526) (xy 266.566631 -62.345075) (xy 266.526482 -62.306366) (xy 266.492396 -62.262223)
			(xy 266.4651 -62.213588) (xy 266.445177 -62.161497) (xy 266.433051 -62.10706) (xy 266.42898 -62.051438)
			(xy 263.276215 -62.051438) (xy 263.281432 -62.091066) (xy 263.281922 -62.121034) (xy 263.281432 -62.151002)
			(xy 263.273609 -62.210424) (xy 263.258096 -62.268317) (xy 263.23516 -62.32369) (xy 263.205193 -62.375596)
			(xy 263.168706 -62.423146) (xy 263.126326 -62.465526) (xy 263.078776 -62.502013) (xy 263.02687 -62.53198)
			(xy 262.971497 -62.554916) (xy 262.913604 -62.570429) (xy 262.854182 -62.578252) (xy 262.794246 -62.578252)
			(xy 262.734824 -62.570429) (xy 262.676931 -62.554916) (xy 262.621558 -62.53198) (xy 262.569652 -62.502013)
			(xy 262.522102 -62.465526) (xy 262.479722 -62.423146) (xy 262.443235 -62.375596) (xy 262.413268 -62.32369)
			(xy 262.390332 -62.268317) (xy 262.374819 -62.210424) (xy 262.366996 -62.151002) (xy 239.080011 -62.151002)
			(xy 239.102498 -62.176099) (xy 239.133271 -62.222612) (xy 239.156943 -62.273109) (xy 239.173011 -62.326516)
			(xy 239.181131 -62.381692) (xy 239.18164 -62.409578) (xy 239.181131 -62.437464) (xy 239.173011 -62.49264)
			(xy 239.156943 -62.546047) (xy 239.133271 -62.596544) (xy 239.102498 -62.643057) (xy 239.065281 -62.684594)
			(xy 239.022413 -62.720269) (xy 238.974807 -62.749323) (xy 238.923478 -62.771135) (xy 238.869521 -62.785241)
			(xy 238.814084 -62.791341) (xy 238.75835 -62.789304) (xy 238.703507 -62.779174) (xy 238.650723 -62.761167)
			(xy 238.601123 -62.735666) (xy 238.555765 -62.703215) (xy 238.515616 -62.664506) (xy 238.48153 -62.620363)
			(xy 238.454234 -62.571728) (xy 238.434311 -62.519637) (xy 238.422185 -62.4652) (xy 238.418114 -62.409578)
			(xy 237.461989 -62.409578) (xy 237.457241 -62.44184) (xy 237.441173 -62.495247) (xy 237.417501 -62.545744)
			(xy 237.386728 -62.592257) (xy 237.349511 -62.633794) (xy 237.306643 -62.669469) (xy 237.259037 -62.698523)
			(xy 237.207708 -62.720335) (xy 237.153751 -62.734441) (xy 237.098314 -62.740541) (xy 237.04258 -62.738504)
			(xy 236.987737 -62.728374) (xy 236.934953 -62.710367) (xy 236.885353 -62.684866) (xy 236.839995 -62.652415)
			(xy 236.799846 -62.613706) (xy 236.76576 -62.569563) (xy 236.738464 -62.520928) (xy 236.718541 -62.468837)
			(xy 236.706415 -62.4144) (xy 236.702344 -62.358778) (xy 233.951605 -62.358778) (xy 233.953557 -62.37204)
			(xy 233.954066 -62.399926) (xy 233.953557 -62.427812) (xy 233.945437 -62.482988) (xy 233.929369 -62.536395)
			(xy 233.905697 -62.586892) (xy 233.874924 -62.633405) (xy 233.837707 -62.674942) (xy 233.794839 -62.710617)
			(xy 233.747233 -62.739671) (xy 233.695904 -62.761483) (xy 233.641947 -62.775589) (xy 233.58651 -62.781689)
			(xy 233.530776 -62.779652) (xy 233.475933 -62.769522) (xy 233.423149 -62.751515) (xy 233.373549 -62.726014)
			(xy 233.328191 -62.693563) (xy 233.288042 -62.654854) (xy 233.253956 -62.610711) (xy 233.22666 -62.562076)
			(xy 233.206737 -62.509985) (xy 233.194611 -62.455548) (xy 233.19054 -62.399926) (xy 230.059992 -62.399926)
			(xy 230.059992 -63.480946) (xy 237.53113 -63.480946) (xy 237.53113 -63.42101) (xy 237.538953 -63.361588)
			(xy 237.554466 -63.303695) (xy 237.577402 -63.248322) (xy 237.607369 -63.196416) (xy 237.643856 -63.148866)
			(xy 237.686236 -63.106486) (xy 237.733786 -63.069999) (xy 237.785692 -63.040032) (xy 237.841065 -63.017096)
			(xy 237.898958 -63.001583) (xy 237.95838 -62.99376) (xy 238.018316 -62.99376) (xy 238.077738 -63.001583)
			(xy 238.135631 -63.017096) (xy 238.191004 -63.040032) (xy 238.24291 -63.069999) (xy 238.29046 -63.106486)
			(xy 238.33284 -63.148866) (xy 238.369327 -63.196416) (xy 238.397692 -63.245548) (xy 249.304592 -63.245548)
			(xy 249.304592 -63.191052) (xy 249.312347 -63.13711) (xy 249.3277 -63.084821) (xy 249.350337 -63.035248)
			(xy 249.379798 -62.989402) (xy 249.415483 -62.948214) (xy 249.456666 -62.912524) (xy 249.50251 -62.883058)
			(xy 249.552079 -62.860415) (xy 249.604367 -62.845057) (xy 249.658308 -62.837295) (xy 249.685556 -62.836806)
			(xy 249.712925 -62.837296) (xy 249.767103 -62.845108) (xy 249.819606 -62.860591) (xy 249.869354 -62.883428)
			(xy 249.915322 -62.913147) (xy 249.936254 -62.930786) (xy 249.936508 -62.93104) (xy 249.943585 -62.936641)
			(xy 249.960509 -62.942878) (xy 249.969528 -62.943232) (xy 250.036584 -62.943232) (xy 250.045599 -62.94286)
			(xy 250.062516 -62.936622) (xy 250.069604 -62.93104) (xy 250.069604 -62.930786) (xy 250.069858 -62.930786)
			(xy 250.090791 -62.913145) (xy 250.136759 -62.883421) (xy 250.186505 -62.860575) (xy 250.239007 -62.845079)
			(xy 250.293185 -62.83725) (xy 250.347927 -62.83725) (xy 250.402105 -62.845079) (xy 250.454607 -62.860575)
			(xy 250.504353 -62.883421) (xy 250.550321 -62.913145) (xy 250.571254 -62.930786) (xy 250.571508 -62.93104)
			(xy 250.578585 -62.936641) (xy 250.595509 -62.942878) (xy 250.604528 -62.943232) (xy 250.671584 -62.943232)
			(xy 250.680599 -62.94286) (xy 250.697516 -62.936622) (xy 250.704604 -62.93104) (xy 250.704604 -62.930786)
			(xy 250.704858 -62.930786) (xy 250.725793 -62.913151) (xy 250.771765 -62.883439) (xy 250.821512 -62.860602)
			(xy 250.874012 -62.84511) (xy 250.928187 -62.837281) (xy 250.955556 -62.836806) (xy 250.982812 -62.837238)
			(xy 251.03677 -62.84499) (xy 251.089075 -62.860343) (xy 251.138662 -62.882984) (xy 251.184523 -62.912452)
			(xy 251.225722 -62.948147) (xy 251.261422 -62.989342) (xy 251.290895 -63.035199) (xy 251.313542 -63.084784)
			(xy 251.328901 -63.137087) (xy 251.336659 -63.191044) (xy 251.336659 -63.213552) (xy 254.320765 -63.213552)
			(xy 254.320765 -63.159048) (xy 254.328522 -63.105098) (xy 254.343878 -63.052801) (xy 254.36652 -63.003222)
			(xy 254.395987 -62.95737) (xy 254.43168 -62.916179) (xy 254.472872 -62.880486) (xy 254.518724 -62.851019)
			(xy 254.568303 -62.828377) (xy 254.6206 -62.813022) (xy 254.67455 -62.805265) (xy 254.701802 -62.804802)
			(xy 254.729172 -62.805266) (xy 254.783351 -62.813085) (xy 254.835855 -62.828574) (xy 254.885601 -62.851416)
			(xy 254.931568 -62.881141) (xy 254.9525 -62.898782) (xy 254.952754 -62.899036) (xy 254.959847 -62.904613)
			(xy 254.976759 -62.910865) (xy 254.985774 -62.911228) (xy 255.05283 -62.911228) (xy 255.061848 -62.910879)
			(xy 255.078764 -62.904625) (xy 255.08585 -62.899036) (xy 255.08585 -62.898782) (xy 255.086104 -62.898782)
			(xy 255.107037 -62.881141) (xy 255.153005 -62.851417) (xy 255.202751 -62.828571) (xy 255.255253 -62.813075)
			(xy 255.309431 -62.805246) (xy 255.364173 -62.805246) (xy 255.418351 -62.813075) (xy 255.470853 -62.828571)
			(xy 255.520599 -62.851417) (xy 255.566567 -62.881141) (xy 255.5875 -62.898782) (xy 255.587754 -62.899036)
			(xy 255.594847 -62.904613) (xy 255.611759 -62.910865) (xy 255.620774 -62.911228) (xy 255.68783 -62.911228)
			(xy 255.696848 -62.910879) (xy 255.713764 -62.904625) (xy 255.72085 -62.899036) (xy 255.72085 -62.898782)
			(xy 255.721104 -62.898782) (xy 255.742021 -62.881125) (xy 255.787999 -62.851416) (xy 255.83775 -62.828584)
			(xy 255.890254 -62.813097) (xy 255.944432 -62.805274) (xy 255.971802 -62.804802) (xy 255.999054 -62.805268)
			(xy 256.053003 -62.813025) (xy 256.105299 -62.828381) (xy 256.154877 -62.851022) (xy 256.200728 -62.88049)
			(xy 256.241919 -62.916182) (xy 256.277612 -62.957373) (xy 256.307079 -63.003225) (xy 256.32972 -63.052803)
			(xy 256.339537 -63.086234) (xy 259.58749 -63.086234) (xy 259.591561 -63.030612) (xy 259.603687 -62.976175)
			(xy 259.62361 -62.924084) (xy 259.650906 -62.875449) (xy 259.684992 -62.831306) (xy 259.725141 -62.792597)
			(xy 259.770499 -62.760146) (xy 259.820099 -62.734645) (xy 259.872883 -62.716638) (xy 259.927726 -62.706508)
			(xy 259.98346 -62.704471) (xy 260.038897 -62.710571) (xy 260.092854 -62.724677) (xy 260.144183 -62.746489)
			(xy 260.191789 -62.775543) (xy 260.234657 -62.811218) (xy 260.235508 -62.812168) (xy 265.117832 -62.812168)
			(xy 265.121903 -62.756546) (xy 265.134029 -62.702109) (xy 265.153952 -62.650018) (xy 265.181248 -62.601383)
			(xy 265.215334 -62.55724) (xy 265.255483 -62.518531) (xy 265.300841 -62.48608) (xy 265.350441 -62.460579)
			(xy 265.403225 -62.442572) (xy 265.458068 -62.432442) (xy 265.513802 -62.430405) (xy 265.569239 -62.436505)
			(xy 265.623196 -62.450611) (xy 265.674525 -62.472423) (xy 265.722131 -62.501477) (xy 265.764999 -62.537152)
			(xy 265.802216 -62.578689) (xy 265.832989 -62.625202) (xy 265.856661 -62.675699) (xy 265.872729 -62.729106)
			(xy 265.880849 -62.784282) (xy 265.881358 -62.812168) (xy 265.880849 -62.840054) (xy 265.872729 -62.89523)
			(xy 265.856661 -62.948637) (xy 265.832989 -62.999134) (xy 265.802216 -63.045647) (xy 265.764999 -63.087184)
			(xy 265.722131 -63.122859) (xy 265.674525 -63.151913) (xy 265.623196 -63.173725) (xy 265.569239 -63.187831)
			(xy 265.513802 -63.193931) (xy 265.458068 -63.191894) (xy 265.403225 -63.181764) (xy 265.350441 -63.163757)
			(xy 265.300841 -63.138256) (xy 265.255483 -63.105805) (xy 265.215334 -63.067096) (xy 265.181248 -63.022953)
			(xy 265.153952 -62.974318) (xy 265.134029 -62.922227) (xy 265.121903 -62.86779) (xy 265.117832 -62.812168)
			(xy 260.235508 -62.812168) (xy 260.271874 -62.852755) (xy 260.302647 -62.899268) (xy 260.326319 -62.949765)
			(xy 260.342387 -63.003172) (xy 260.350507 -63.058348) (xy 260.351016 -63.086234) (xy 260.350507 -63.11412)
			(xy 260.342387 -63.169296) (xy 260.326319 -63.222703) (xy 260.302647 -63.2732) (xy 260.282667 -63.3034)
			(xy 261.701516 -63.3034) (xy 261.701516 -63.243464) (xy 261.709339 -63.184042) (xy 261.724852 -63.126149)
			(xy 261.747788 -63.070776) (xy 261.777755 -63.01887) (xy 261.814242 -62.97132) (xy 261.856622 -62.92894)
			(xy 261.904172 -62.892453) (xy 261.956078 -62.862486) (xy 262.011451 -62.83955) (xy 262.069344 -62.824037)
			(xy 262.128766 -62.816214) (xy 262.188702 -62.816214) (xy 262.248124 -62.824037) (xy 262.306017 -62.83955)
			(xy 262.36139 -62.862486) (xy 262.413296 -62.892453) (xy 262.460846 -62.92894) (xy 262.503226 -62.97132)
			(xy 262.539713 -63.01887) (xy 262.56968 -63.070776) (xy 262.592616 -63.126149) (xy 262.608129 -63.184042)
			(xy 262.615952 -63.243464) (xy 262.615986 -63.245552) (xy 275.304469 -63.245552) (xy 275.304469 -63.191048)
			(xy 275.312226 -63.137099) (xy 275.327582 -63.084802) (xy 275.350224 -63.035224) (xy 275.379691 -62.989372)
			(xy 275.415384 -62.948181) (xy 275.456575 -62.912489) (xy 275.502427 -62.883022) (xy 275.552006 -62.86038)
			(xy 275.604303 -62.845025) (xy 275.658252 -62.837269) (xy 275.685504 -62.836806) (xy 275.712874 -62.837268)
			(xy 275.767054 -62.845087) (xy 275.819557 -62.860577) (xy 275.869304 -62.883419) (xy 275.91527 -62.913144)
			(xy 275.936202 -62.930786) (xy 275.936456 -62.93104) (xy 275.943547 -62.936619) (xy 275.960461 -62.942869)
			(xy 275.969476 -62.943232) (xy 276.036532 -62.943232) (xy 276.04555 -62.942883) (xy 276.062466 -62.936629)
			(xy 276.069552 -62.93104) (xy 276.069552 -62.930786) (xy 276.069806 -62.930786) (xy 276.090739 -62.913145)
			(xy 276.136707 -62.883421) (xy 276.186453 -62.860575) (xy 276.238955 -62.845079) (xy 276.293133 -62.83725)
			(xy 276.347875 -62.83725) (xy 276.402053 -62.845079) (xy 276.454555 -62.860575) (xy 276.504301 -62.883421)
			(xy 276.550269 -62.913145) (xy 276.571202 -62.930786) (xy 276.571456 -62.93104) (xy 276.578547 -62.936619)
			(xy 276.595461 -62.942869) (xy 276.604476 -62.943232) (xy 276.671532 -62.943232) (xy 276.68055 -62.942883)
			(xy 276.697466 -62.936629) (xy 276.704552 -62.93104) (xy 276.704552 -62.930786) (xy 276.704806 -62.930786)
			(xy 276.725723 -62.913128) (xy 276.7717 -62.88342) (xy 276.821452 -62.860588) (xy 276.873956 -62.845101)
			(xy 276.928134 -62.837277) (xy 276.955504 -62.836806) (xy 276.982756 -62.837264) (xy 277.036705 -62.845021)
			(xy 277.089002 -62.860377) (xy 277.13858 -62.88302) (xy 277.184432 -62.912487) (xy 277.225623 -62.94818)
			(xy 277.261315 -62.989372) (xy 277.290782 -63.035223) (xy 277.313424 -63.084802) (xy 277.32878 -63.137099)
			(xy 277.336536 -63.191048) (xy 277.336536 -63.213548) (xy 280.320788 -63.213548) (xy 280.320788 -63.159052)
			(xy 280.328543 -63.10511) (xy 280.343895 -63.052821) (xy 280.366532 -63.003248) (xy 280.395993 -62.957401)
			(xy 280.431678 -62.916214) (xy 280.472861 -62.880523) (xy 280.518704 -62.851056) (xy 280.568274 -62.828413)
			(xy 280.620561 -62.813054) (xy 280.674502 -62.805292) (xy 280.70175 -62.804802) (xy 280.729119 -62.805297)
			(xy 280.783297 -62.813108) (xy 280.8358 -62.82859) (xy 280.885547 -62.851425) (xy 280.931515 -62.881144)
			(xy 280.952448 -62.898782) (xy 280.952702 -62.899036) (xy 280.959781 -62.904634) (xy 280.976704 -62.910873)
			(xy 280.985722 -62.911228) (xy 281.052778 -62.911228) (xy 281.061793 -62.910854) (xy 281.07871 -62.904618)
			(xy 281.085798 -62.899036) (xy 281.085798 -62.898782) (xy 281.086052 -62.898782) (xy 281.106985 -62.881141)
			(xy 281.152953 -62.851417) (xy 281.202699 -62.828571) (xy 281.255201 -62.813075) (xy 281.309379 -62.805246)
			(xy 281.364121 -62.805246) (xy 281.418299 -62.813075) (xy 281.470801 -62.828571) (xy 281.520547 -62.851417)
			(xy 281.566515 -62.881141) (xy 281.587448 -62.898782) (xy 281.587702 -62.899036) (xy 281.594781 -62.904634)
			(xy 281.611704 -62.910873) (xy 281.620722 -62.911228) (xy 281.687778 -62.911228) (xy 281.696793 -62.910854)
			(xy 281.71371 -62.904618) (xy 281.720798 -62.899036) (xy 281.720798 -62.898782) (xy 281.721052 -62.898782)
			(xy 281.741989 -62.881149) (xy 281.787961 -62.851437) (xy 281.837707 -62.8286) (xy 281.890206 -62.813108)
			(xy 281.944381 -62.805277) (xy 281.97175 -62.804802) (xy 281.999006 -62.805241) (xy 282.052964 -62.812993)
			(xy 282.105269 -62.828345) (xy 282.154857 -62.850985) (xy 282.200717 -62.880453) (xy 282.241917 -62.916147)
			(xy 282.277617 -62.957342) (xy 282.307091 -63.003199) (xy 282.329738 -63.052784) (xy 282.339561 -63.086234)
			(xy 285.587438 -63.086234) (xy 285.591509 -63.030612) (xy 285.603635 -62.976175) (xy 285.623558 -62.924084)
			(xy 285.650854 -62.875449) (xy 285.68494 -62.831306) (xy 285.725089 -62.792597) (xy 285.770447 -62.760146)
			(xy 285.820047 -62.734645) (xy 285.872831 -62.716638) (xy 285.927674 -62.706508) (xy 285.983408 -62.704471)
			(xy 286.038845 -62.710571) (xy 286.092802 -62.724677) (xy 286.144131 -62.746489) (xy 286.191737 -62.775543)
			(xy 286.234605 -62.811218) (xy 286.235456 -62.812168) (xy 291.11778 -62.812168) (xy 291.121851 -62.756546)
			(xy 291.133977 -62.702109) (xy 291.1539 -62.650018) (xy 291.181196 -62.601383) (xy 291.215282 -62.55724)
			(xy 291.255431 -62.518531) (xy 291.300789 -62.48608) (xy 291.350389 -62.460579) (xy 291.403173 -62.442572)
			(xy 291.458016 -62.432442) (xy 291.51375 -62.430405) (xy 291.569187 -62.436505) (xy 291.623144 -62.450611)
			(xy 291.674473 -62.472423) (xy 291.722079 -62.501477) (xy 291.764947 -62.537152) (xy 291.802164 -62.578689)
			(xy 291.832937 -62.625202) (xy 291.856609 -62.675699) (xy 291.872677 -62.729106) (xy 291.880797 -62.784282)
			(xy 291.881306 -62.812168) (xy 291.880797 -62.840054) (xy 291.872677 -62.89523) (xy 291.856609 -62.948637)
			(xy 291.832937 -62.999134) (xy 291.802164 -63.045647) (xy 291.764947 -63.087184) (xy 291.722079 -63.122859)
			(xy 291.674473 -63.151913) (xy 291.623144 -63.173725) (xy 291.569187 -63.187831) (xy 291.51375 -63.193931)
			(xy 291.458016 -63.191894) (xy 291.403173 -63.181764) (xy 291.350389 -63.163757) (xy 291.300789 -63.138256)
			(xy 291.255431 -63.105805) (xy 291.215282 -63.067096) (xy 291.181196 -63.022953) (xy 291.1539 -62.974318)
			(xy 291.133977 -62.922227) (xy 291.121851 -62.86779) (xy 291.11778 -62.812168) (xy 286.235456 -62.812168)
			(xy 286.271822 -62.852755) (xy 286.302595 -62.899268) (xy 286.326267 -62.949765) (xy 286.342335 -63.003172)
			(xy 286.350455 -63.058348) (xy 286.350964 -63.086234) (xy 286.350455 -63.11412) (xy 286.342335 -63.169296)
			(xy 286.326267 -63.222703) (xy 286.302595 -63.2732) (xy 286.282615 -63.3034) (xy 287.701464 -63.3034)
			(xy 287.701464 -63.243464) (xy 287.709287 -63.184042) (xy 287.7248 -63.126149) (xy 287.747736 -63.070776)
			(xy 287.777703 -63.01887) (xy 287.81419 -62.97132) (xy 287.85657 -62.92894) (xy 287.90412 -62.892453)
			(xy 287.956026 -62.862486) (xy 288.011399 -62.83955) (xy 288.069292 -62.824037) (xy 288.128714 -62.816214)
			(xy 288.18865 -62.816214) (xy 288.248072 -62.824037) (xy 288.305965 -62.83955) (xy 288.361338 -62.862486)
			(xy 288.413244 -62.892453) (xy 288.460794 -62.92894) (xy 288.503174 -62.97132) (xy 288.539661 -63.01887)
			(xy 288.569628 -63.070776) (xy 288.592564 -63.126149) (xy 288.608077 -63.184042) (xy 288.6159 -63.243464)
			(xy 288.615934 -63.245548) (xy 301.304492 -63.245548) (xy 301.304492 -63.191052) (xy 301.312247 -63.137111)
			(xy 301.327599 -63.084822) (xy 301.350236 -63.035249) (xy 301.379697 -62.989403) (xy 301.415382 -62.948216)
			(xy 301.456565 -62.912525) (xy 301.502407 -62.883059) (xy 301.551977 -62.860416) (xy 301.604264 -62.845057)
			(xy 301.658204 -62.837296) (xy 301.685452 -62.836806) (xy 301.712821 -62.837299) (xy 301.766999 -62.84511)
			(xy 301.819502 -62.860593) (xy 301.869249 -62.883428) (xy 301.915217 -62.913147) (xy 301.93615 -62.930786)
			(xy 301.936404 -62.93104) (xy 301.943482 -62.936639) (xy 301.960405 -62.942877) (xy 301.969424 -62.943232)
			(xy 302.03648 -62.943232) (xy 302.045495 -62.942858) (xy 302.062412 -62.936622) (xy 302.0695 -62.93104)
			(xy 302.0695 -62.930786) (xy 302.069754 -62.930786) (xy 302.090687 -62.913145) (xy 302.136655 -62.883421)
			(xy 302.186401 -62.860575) (xy 302.238903 -62.845079) (xy 302.293081 -62.83725) (xy 302.347823 -62.83725)
			(xy 302.402001 -62.845079) (xy 302.454503 -62.860575) (xy 302.504249 -62.883421) (xy 302.550217 -62.913145)
			(xy 302.57115 -62.930786) (xy 302.571404 -62.93104) (xy 302.578482 -62.936639) (xy 302.595405 -62.942877)
			(xy 302.604424 -62.943232) (xy 302.67148 -62.943232) (xy 302.680495 -62.942858) (xy 302.697412 -62.936622)
			(xy 302.7045 -62.93104) (xy 302.7045 -62.930786) (xy 302.704754 -62.930786) (xy 302.725691 -62.913153)
			(xy 302.771663 -62.883441) (xy 302.821409 -62.860604) (xy 302.873908 -62.845111) (xy 302.928083 -62.837281)
			(xy 302.955452 -62.836806) (xy 302.982708 -62.837238) (xy 303.036666 -62.844989) (xy 303.088972 -62.860342)
			(xy 303.13856 -62.882982) (xy 303.184421 -62.91245) (xy 303.225621 -62.948145) (xy 303.261321 -62.989341)
			(xy 303.290795 -63.035198) (xy 303.313441 -63.084783) (xy 303.3288 -63.137087) (xy 303.336559 -63.191044)
			(xy 303.336559 -63.21355) (xy 306.320688 -63.21355) (xy 306.320688 -63.15905) (xy 306.328444 -63.105104)
			(xy 306.343799 -63.05281) (xy 306.366439 -63.003235) (xy 306.395905 -62.957386) (xy 306.431595 -62.916197)
			(xy 306.472784 -62.880506) (xy 306.518633 -62.85104) (xy 306.568208 -62.8284) (xy 306.620502 -62.813045)
			(xy 306.674448 -62.805288) (xy 306.701698 -62.804802) (xy 306.729068 -62.805269) (xy 306.783247 -62.813086)
			(xy 306.83575 -62.828575) (xy 306.885497 -62.851417) (xy 306.931464 -62.881141) (xy 306.952396 -62.898782)
			(xy 306.95265 -62.899036) (xy 306.959744 -62.904612) (xy 306.976655 -62.910864) (xy 306.98567 -62.911228)
			(xy 307.052726 -62.911228) (xy 307.061743 -62.910878) (xy 307.07866 -62.904625) (xy 307.085746 -62.899036)
			(xy 307.085746 -62.898782) (xy 307.086 -62.898782) (xy 307.106933 -62.881141) (xy 307.152901 -62.851417)
			(xy 307.202647 -62.828571) (xy 307.255149 -62.813075) (xy 307.309327 -62.805246) (xy 307.364069 -62.805246)
			(xy 307.418247 -62.813075) (xy 307.470749 -62.828571) (xy 307.520495 -62.851417) (xy 307.566463 -62.881141)
			(xy 307.587396 -62.898782) (xy 307.58765 -62.899036) (xy 307.594744 -62.904612) (xy 307.611655 -62.910864)
			(xy 307.62067 -62.911228) (xy 307.687726 -62.911228) (xy 307.696743 -62.910878) (xy 307.71366 -62.904625)
			(xy 307.720746 -62.899036) (xy 307.720746 -62.898782) (xy 307.721 -62.898782) (xy 307.741919 -62.881127)
			(xy 307.787896 -62.851418) (xy 307.837647 -62.828585) (xy 307.89015 -62.813098) (xy 307.944328 -62.805274)
			(xy 307.971698 -62.804802) (xy 307.998952 -62.805245) (xy 308.052904 -62.813002) (xy 308.105204 -62.828358)
			(xy 308.154786 -62.851001) (xy 308.20064 -62.88047) (xy 308.241834 -62.916164) (xy 308.277529 -62.957358)
			(xy 308.306998 -63.003213) (xy 308.329641 -63.052794) (xy 308.33946 -63.086234) (xy 311.587386 -63.086234)
			(xy 311.591457 -63.030612) (xy 311.603583 -62.976175) (xy 311.623506 -62.924084) (xy 311.650802 -62.875449)
			(xy 311.684888 -62.831306) (xy 311.725037 -62.792597) (xy 311.770395 -62.760146) (xy 311.819995 -62.734645)
			(xy 311.872779 -62.716638) (xy 311.927622 -62.706508) (xy 311.983356 -62.704471) (xy 312.038793 -62.710571)
			(xy 312.09275 -62.724677) (xy 312.144079 -62.746489) (xy 312.191685 -62.775543) (xy 312.234553 -62.811218)
			(xy 312.235404 -62.812168) (xy 317.117728 -62.812168) (xy 317.121799 -62.756546) (xy 317.133925 -62.702109)
			(xy 317.153848 -62.650018) (xy 317.181144 -62.601383) (xy 317.21523 -62.55724) (xy 317.255379 -62.518531)
			(xy 317.300737 -62.48608) (xy 317.350337 -62.460579) (xy 317.403121 -62.442572) (xy 317.457964 -62.432442)
			(xy 317.513698 -62.430405) (xy 317.569135 -62.436505) (xy 317.623092 -62.450611) (xy 317.674421 -62.472423)
			(xy 317.722027 -62.501477) (xy 317.764895 -62.537152) (xy 317.802112 -62.578689) (xy 317.832885 -62.625202)
			(xy 317.856557 -62.675699) (xy 317.872625 -62.729106) (xy 317.880745 -62.784282) (xy 317.881254 -62.812168)
			(xy 317.880745 -62.840054) (xy 317.872625 -62.89523) (xy 317.856557 -62.948637) (xy 317.832885 -62.999134)
			(xy 317.802112 -63.045647) (xy 317.764895 -63.087184) (xy 317.722027 -63.122859) (xy 317.674421 -63.151913)
			(xy 317.623092 -63.173725) (xy 317.569135 -63.187831) (xy 317.513698 -63.193931) (xy 317.457964 -63.191894)
			(xy 317.403121 -63.181764) (xy 317.350337 -63.163757) (xy 317.300737 -63.138256) (xy 317.255379 -63.105805)
			(xy 317.21523 -63.067096) (xy 317.181144 -63.022953) (xy 317.153848 -62.974318) (xy 317.133925 -62.922227)
			(xy 317.121799 -62.86779) (xy 317.117728 -62.812168) (xy 312.235404 -62.812168) (xy 312.27177 -62.852755)
			(xy 312.302543 -62.899268) (xy 312.326215 -62.949765) (xy 312.342283 -63.003172) (xy 312.350403 -63.058348)
			(xy 312.350912 -63.086234) (xy 312.350403 -63.11412) (xy 312.342283 -63.169296) (xy 312.326215 -63.222703)
			(xy 312.302543 -63.2732) (xy 312.282563 -63.3034) (xy 313.701412 -63.3034) (xy 313.701412 -63.243464)
			(xy 313.709235 -63.184042) (xy 313.724748 -63.126149) (xy 313.747684 -63.070776) (xy 313.777651 -63.01887)
			(xy 313.814138 -62.97132) (xy 313.856518 -62.92894) (xy 313.904068 -62.892453) (xy 313.955974 -62.862486)
			(xy 314.011347 -62.83955) (xy 314.06924 -62.824037) (xy 314.128662 -62.816214) (xy 314.188598 -62.816214)
			(xy 314.24802 -62.824037) (xy 314.305913 -62.83955) (xy 314.361286 -62.862486) (xy 314.413192 -62.892453)
			(xy 314.460742 -62.92894) (xy 314.503122 -62.97132) (xy 314.539609 -63.01887) (xy 314.569576 -63.070776)
			(xy 314.592512 -63.126149) (xy 314.608025 -63.184042) (xy 314.615848 -63.243464) (xy 314.615882 -63.24555)
			(xy 327.304392 -63.24555) (xy 327.304392 -63.19105) (xy 327.312148 -63.137104) (xy 327.327503 -63.084811)
			(xy 327.350143 -63.035236) (xy 327.379608 -62.989387) (xy 327.415299 -62.948199) (xy 327.456487 -62.912508)
			(xy 327.502336 -62.883043) (xy 327.551911 -62.860403) (xy 327.604204 -62.845048) (xy 327.65815 -62.837292)
			(xy 327.6854 -62.836806) (xy 327.71277 -62.837271) (xy 327.76695 -62.845089) (xy 327.819453 -62.860578)
			(xy 327.8692 -62.88342) (xy 327.915166 -62.913145) (xy 327.936098 -62.930786) (xy 327.936352 -62.93104)
			(xy 327.943445 -62.936618) (xy 327.960357 -62.942869) (xy 327.969372 -62.943232) (xy 328.036428 -62.943232)
			(xy 328.045445 -62.942882) (xy 328.062362 -62.936629) (xy 328.069448 -62.93104) (xy 328.069448 -62.930786)
			(xy 328.069702 -62.930786) (xy 328.090635 -62.913145) (xy 328.136603 -62.883421) (xy 328.186349 -62.860575)
			(xy 328.238851 -62.845079) (xy 328.293029 -62.83725) (xy 328.347771 -62.83725) (xy 328.401949 -62.845079)
			(xy 328.454451 -62.860575) (xy 328.504197 -62.883421) (xy 328.550165 -62.913145) (xy 328.571098 -62.930786)
			(xy 328.571352 -62.93104) (xy 328.578445 -62.936618) (xy 328.595357 -62.942869) (xy 328.604372 -62.943232)
			(xy 328.671428 -62.943232) (xy 328.680445 -62.942882) (xy 328.697362 -62.936629) (xy 328.704448 -62.93104)
			(xy 328.704448 -62.930786) (xy 328.704702 -62.930786) (xy 328.725621 -62.91313) (xy 328.771597 -62.883421)
			(xy 328.821348 -62.860589) (xy 328.873852 -62.845102) (xy 328.92803 -62.837278) (xy 328.9554 -62.836806)
			(xy 328.982652 -62.837264) (xy 329.036602 -62.845021) (xy 329.088899 -62.860376) (xy 329.138478 -62.883018)
			(xy 329.18433 -62.912486) (xy 329.225522 -62.948178) (xy 329.261214 -62.98937) (xy 329.290682 -63.035222)
			(xy 329.313324 -63.084801) (xy 329.328679 -63.137098) (xy 329.336436 -63.191048) (xy 329.336436 -63.213554)
			(xy 332.320565 -63.213554) (xy 332.320565 -63.159046) (xy 332.328323 -63.105092) (xy 332.343681 -63.052792)
			(xy 332.366327 -63.00321) (xy 332.395798 -62.957356) (xy 332.431496 -62.916163) (xy 332.472693 -62.880471)
			(xy 332.518551 -62.851005) (xy 332.568135 -62.828365) (xy 332.620437 -62.813014) (xy 332.674392 -62.805262)
			(xy 332.701646 -62.804802) (xy 332.729015 -62.805299) (xy 332.783193 -62.813109) (xy 332.835696 -62.828591)
			(xy 332.885443 -62.851426) (xy 332.931411 -62.881144) (xy 332.952344 -62.898782) (xy 332.952598 -62.899036)
			(xy 332.959678 -62.904632) (xy 332.9766 -62.910872) (xy 332.985618 -62.911228) (xy 333.052674 -62.911228)
			(xy 333.061689 -62.910852) (xy 333.078606 -62.904617) (xy 333.085694 -62.899036) (xy 333.085694 -62.898782)
			(xy 333.085948 -62.898782) (xy 333.106881 -62.881141) (xy 333.152849 -62.851417) (xy 333.202595 -62.828571)
			(xy 333.255097 -62.813075) (xy 333.309275 -62.805246) (xy 333.364017 -62.805246) (xy 333.418195 -62.813075)
			(xy 333.470697 -62.828571) (xy 333.520443 -62.851417) (xy 333.566411 -62.881141) (xy 333.587344 -62.898782)
			(xy 333.587598 -62.899036) (xy 333.594678 -62.904632) (xy 333.6116 -62.910872) (xy 333.620618 -62.911228)
			(xy 333.687674 -62.911228) (xy 333.696689 -62.910852) (xy 333.713606 -62.904617) (xy 333.720694 -62.899036)
			(xy 333.720694 -62.898782) (xy 333.720948 -62.898782) (xy 333.741887 -62.881151) (xy 333.787858 -62.851439)
			(xy 333.837604 -62.828601) (xy 333.890103 -62.813108) (xy 333.944277 -62.805278) (xy 333.971646 -62.804802)
			(xy 333.998896 -62.805271) (xy 334.05284 -62.813033) (xy 334.105131 -62.828392) (xy 334.154703 -62.851037)
			(xy 334.200549 -62.880505) (xy 334.241735 -62.916198) (xy 334.277422 -62.957388) (xy 334.306885 -63.003237)
			(xy 334.329524 -63.052813) (xy 334.339336 -63.086234) (xy 349.68764 -63.086234) (xy 349.691711 -63.030612)
			(xy 349.703837 -62.976175) (xy 349.72376 -62.924084) (xy 349.751056 -62.875449) (xy 349.785142 -62.831306)
			(xy 349.825291 -62.792597) (xy 349.870649 -62.760146) (xy 349.920249 -62.734645) (xy 349.973033 -62.716638)
			(xy 350.027876 -62.706508) (xy 350.08361 -62.704471) (xy 350.139047 -62.710571) (xy 350.193004 -62.724677)
			(xy 350.244333 -62.746489) (xy 350.291939 -62.775543) (xy 350.334807 -62.811218) (xy 350.335658 -62.812168)
			(xy 355.217982 -62.812168) (xy 355.222053 -62.756546) (xy 355.234179 -62.702109) (xy 355.254102 -62.650018)
			(xy 355.281398 -62.601383) (xy 355.315484 -62.55724) (xy 355.355633 -62.518531) (xy 355.400991 -62.48608)
			(xy 355.450591 -62.460579) (xy 355.503375 -62.442572) (xy 355.558218 -62.432442) (xy 355.613952 -62.430405)
			(xy 355.669389 -62.436505) (xy 355.723346 -62.450611) (xy 355.774675 -62.472423) (xy 355.822281 -62.501477)
			(xy 355.865149 -62.537152) (xy 355.902366 -62.578689) (xy 355.933139 -62.625202) (xy 355.956811 -62.675699)
			(xy 355.972879 -62.729106) (xy 355.980999 -62.784282) (xy 355.981508 -62.812168) (xy 355.980999 -62.840054)
			(xy 355.972879 -62.89523) (xy 355.956811 -62.948637) (xy 355.933139 -62.999134) (xy 355.902366 -63.045647)
			(xy 355.865149 -63.087184) (xy 355.822281 -63.122859) (xy 355.774675 -63.151913) (xy 355.723346 -63.173725)
			(xy 355.669389 -63.187831) (xy 355.613952 -63.193931) (xy 355.558218 -63.191894) (xy 355.503375 -63.181764)
			(xy 355.450591 -63.163757) (xy 355.400991 -63.138256) (xy 355.355633 -63.105805) (xy 355.315484 -63.067096)
			(xy 355.281398 -63.022953) (xy 355.254102 -62.974318) (xy 355.234179 -62.922227) (xy 355.222053 -62.86779)
			(xy 355.217982 -62.812168) (xy 350.335658 -62.812168) (xy 350.372024 -62.852755) (xy 350.402797 -62.899268)
			(xy 350.426469 -62.949765) (xy 350.442537 -63.003172) (xy 350.450657 -63.058348) (xy 350.451166 -63.086234)
			(xy 350.450657 -63.11412) (xy 350.442537 -63.169296) (xy 350.426469 -63.222703) (xy 350.402797 -63.2732)
			(xy 350.382817 -63.3034) (xy 351.801666 -63.3034) (xy 351.801666 -63.243464) (xy 351.809489 -63.184042)
			(xy 351.825002 -63.126149) (xy 351.847938 -63.070776) (xy 351.877905 -63.01887) (xy 351.914392 -62.97132)
			(xy 351.956772 -62.92894) (xy 352.004322 -62.892453) (xy 352.056228 -62.862486) (xy 352.111601 -62.83955)
			(xy 352.169494 -62.824037) (xy 352.228916 -62.816214) (xy 352.288852 -62.816214) (xy 352.348274 -62.824037)
			(xy 352.406167 -62.83955) (xy 352.46154 -62.862486) (xy 352.513446 -62.892453) (xy 352.560996 -62.92894)
			(xy 352.603376 -62.97132) (xy 352.639863 -63.01887) (xy 352.66983 -63.070776) (xy 352.692766 -63.126149)
			(xy 352.708279 -63.184042) (xy 352.716102 -63.243464) (xy 352.716136 -63.245548) (xy 365.404692 -63.245548)
			(xy 365.404692 -63.191052) (xy 365.412447 -63.13711) (xy 365.427799 -63.084821) (xy 365.450436 -63.035249)
			(xy 365.479897 -62.989402) (xy 365.515582 -62.948215) (xy 365.556766 -62.912525) (xy 365.602608 -62.883058)
			(xy 365.652178 -62.860415) (xy 365.704465 -62.845057) (xy 365.758406 -62.837295) (xy 365.785654 -62.836806)
			(xy 365.813023 -62.837298) (xy 365.867201 -62.845109) (xy 365.919704 -62.860592) (xy 365.969452 -62.883428)
			(xy 366.015419 -62.913147) (xy 366.036352 -62.930786) (xy 366.036606 -62.93104) (xy 366.043683 -62.93664)
			(xy 366.060607 -62.942878) (xy 366.069626 -62.943232) (xy 366.136682 -62.943232) (xy 366.145697 -62.942859)
			(xy 366.162614 -62.936622) (xy 366.169702 -62.93104) (xy 366.169702 -62.930786) (xy 366.169956 -62.930786)
			(xy 366.190889 -62.913145) (xy 366.236857 -62.883421) (xy 366.286603 -62.860575) (xy 366.339105 -62.845079)
			(xy 366.393283 -62.83725) (xy 366.448025 -62.83725) (xy 366.502203 -62.845079) (xy 366.554705 -62.860575)
			(xy 366.604451 -62.883421) (xy 366.650419 -62.913145) (xy 366.671352 -62.930786) (xy 366.671606 -62.93104)
			(xy 366.678683 -62.93664) (xy 366.695607 -62.942878) (xy 366.704626 -62.943232) (xy 366.771682 -62.943232)
			(xy 366.780697 -62.942859) (xy 366.797614 -62.936622) (xy 366.804702 -62.93104) (xy 366.804702 -62.930786)
			(xy 366.804956 -62.930786) (xy 366.825892 -62.913152) (xy 366.871864 -62.88344) (xy 366.921611 -62.860603)
			(xy 366.97411 -62.845111) (xy 367.028285 -62.837281) (xy 367.055654 -62.836806) (xy 367.08291 -62.837238)
			(xy 367.136868 -62.84499) (xy 367.189173 -62.860342) (xy 367.238761 -62.882983) (xy 367.284622 -62.912451)
			(xy 367.325821 -62.948146) (xy 367.361521 -62.989341) (xy 367.390995 -63.035198) (xy 367.413642 -63.084784)
			(xy 367.429001 -63.137087) (xy 367.436759 -63.191044) (xy 367.436759 -63.21355) (xy 370.420888 -63.21355)
			(xy 370.420888 -63.15905) (xy 370.428645 -63.105103) (xy 370.443999 -63.05281) (xy 370.46664 -63.003234)
			(xy 370.496105 -62.957385) (xy 370.531796 -62.916196) (xy 370.572985 -62.880505) (xy 370.618834 -62.85104)
			(xy 370.66841 -62.828399) (xy 370.720703 -62.813045) (xy 370.77465 -62.805288) (xy 370.8019 -62.804802)
			(xy 370.82927 -62.805268) (xy 370.883449 -62.813085) (xy 370.935953 -62.828575) (xy 370.985699 -62.851416)
			(xy 371.031666 -62.881141) (xy 371.052598 -62.898782) (xy 371.052852 -62.899036) (xy 371.059945 -62.904613)
			(xy 371.076857 -62.910864) (xy 371.085872 -62.911228) (xy 371.152928 -62.911228) (xy 371.161946 -62.910878)
			(xy 371.178862 -62.904625) (xy 371.185948 -62.899036) (xy 371.185948 -62.898782) (xy 371.186202 -62.898782)
			(xy 371.207135 -62.881141) (xy 371.253103 -62.851417) (xy 371.302849 -62.828571) (xy 371.355351 -62.813075)
			(xy 371.409529 -62.805246) (xy 371.464271 -62.805246) (xy 371.518449 -62.813075) (xy 371.570951 -62.828571)
			(xy 371.620697 -62.851417) (xy 371.666665 -62.881141) (xy 371.687598 -62.898782) (xy 371.687852 -62.899036)
			(xy 371.694945 -62.904613) (xy 371.711857 -62.910864) (xy 371.720872 -62.911228) (xy 371.787928 -62.911228)
			(xy 371.796946 -62.910878) (xy 371.813862 -62.904625) (xy 371.820948 -62.899036) (xy 371.820948 -62.898782)
			(xy 371.821202 -62.898782) (xy 371.84212 -62.881126) (xy 371.888097 -62.851417) (xy 371.937848 -62.828585)
			(xy 371.990352 -62.813098) (xy 372.04453 -62.805274) (xy 372.0719 -62.804802) (xy 372.099152 -62.805268)
			(xy 372.153101 -62.813025) (xy 372.205397 -62.82838) (xy 372.254976 -62.851022) (xy 372.300827 -62.880489)
			(xy 372.342019 -62.916181) (xy 372.377711 -62.957373) (xy 372.407178 -63.003224) (xy 372.42982 -63.052803)
			(xy 372.439636 -63.086234) (xy 375.687588 -63.086234) (xy 375.691659 -63.030612) (xy 375.703785 -62.976175)
			(xy 375.723708 -62.924084) (xy 375.751004 -62.875449) (xy 375.78509 -62.831306) (xy 375.825239 -62.792597)
			(xy 375.870597 -62.760146) (xy 375.920197 -62.734645) (xy 375.972981 -62.716638) (xy 376.027824 -62.706508)
			(xy 376.083558 -62.704471) (xy 376.138995 -62.710571) (xy 376.192952 -62.724677) (xy 376.244281 -62.746489)
			(xy 376.291887 -62.775543) (xy 376.334755 -62.811218) (xy 376.335606 -62.812168) (xy 381.21793 -62.812168)
			(xy 381.222001 -62.756546) (xy 381.234127 -62.702109) (xy 381.25405 -62.650018) (xy 381.281346 -62.601383)
			(xy 381.315432 -62.55724) (xy 381.355581 -62.518531) (xy 381.400939 -62.48608) (xy 381.450539 -62.460579)
			(xy 381.503323 -62.442572) (xy 381.558166 -62.432442) (xy 381.6139 -62.430405) (xy 381.669337 -62.436505)
			(xy 381.723294 -62.450611) (xy 381.774623 -62.472423) (xy 381.822229 -62.501477) (xy 381.865097 -62.537152)
			(xy 381.902314 -62.578689) (xy 381.933087 -62.625202) (xy 381.956759 -62.675699) (xy 381.972827 -62.729106)
			(xy 381.980947 -62.784282) (xy 381.981456 -62.812168) (xy 381.980947 -62.840054) (xy 381.972827 -62.89523)
			(xy 381.956759 -62.948637) (xy 381.933087 -62.999134) (xy 381.902314 -63.045647) (xy 381.865097 -63.087184)
			(xy 381.822229 -63.122859) (xy 381.774623 -63.151913) (xy 381.723294 -63.173725) (xy 381.669337 -63.187831)
			(xy 381.6139 -63.193931) (xy 381.558166 -63.191894) (xy 381.503323 -63.181764) (xy 381.450539 -63.163757)
			(xy 381.400939 -63.138256) (xy 381.355581 -63.105805) (xy 381.315432 -63.067096) (xy 381.281346 -63.022953)
			(xy 381.25405 -62.974318) (xy 381.234127 -62.922227) (xy 381.222001 -62.86779) (xy 381.21793 -62.812168)
			(xy 376.335606 -62.812168) (xy 376.371972 -62.852755) (xy 376.402745 -62.899268) (xy 376.426417 -62.949765)
			(xy 376.442485 -63.003172) (xy 376.450605 -63.058348) (xy 376.451114 -63.086234) (xy 376.450605 -63.11412)
			(xy 376.442485 -63.169296) (xy 376.426417 -63.222703) (xy 376.402745 -63.2732) (xy 376.382765 -63.3034)
			(xy 377.801614 -63.3034) (xy 377.801614 -63.243464) (xy 377.809437 -63.184042) (xy 377.82495 -63.126149)
			(xy 377.847886 -63.070776) (xy 377.877853 -63.01887) (xy 377.91434 -62.97132) (xy 377.95672 -62.92894)
			(xy 378.00427 -62.892453) (xy 378.056176 -62.862486) (xy 378.111549 -62.83955) (xy 378.169442 -62.824037)
			(xy 378.228864 -62.816214) (xy 378.2888 -62.816214) (xy 378.348222 -62.824037) (xy 378.406115 -62.83955)
			(xy 378.461488 -62.862486) (xy 378.513394 -62.892453) (xy 378.560944 -62.92894) (xy 378.603324 -62.97132)
			(xy 378.639811 -63.01887) (xy 378.669778 -63.070776) (xy 378.692714 -63.126149) (xy 378.708227 -63.184042)
			(xy 378.71605 -63.243464) (xy 378.716084 -63.245552) (xy 391.404569 -63.245552) (xy 391.404569 -63.191048)
			(xy 391.412326 -63.137099) (xy 391.427682 -63.084803) (xy 391.450323 -63.035224) (xy 391.479791 -62.989373)
			(xy 391.515483 -62.948182) (xy 391.556674 -62.912489) (xy 391.602526 -62.883022) (xy 391.652105 -62.860381)
			(xy 391.704401 -62.845026) (xy 391.75835 -62.837269) (xy 391.785602 -62.836806) (xy 391.812972 -62.837269)
			(xy 391.867152 -62.845088) (xy 391.919655 -62.860577) (xy 391.969402 -62.88342) (xy 392.015368 -62.913145)
			(xy 392.0363 -62.930786) (xy 392.036554 -62.93104) (xy 392.043646 -62.936618) (xy 392.060559 -62.942869)
			(xy 392.069574 -62.943232) (xy 392.13663 -62.943232) (xy 392.145648 -62.942883) (xy 392.162564 -62.936629)
			(xy 392.16965 -62.93104) (xy 392.16965 -62.930786) (xy 392.169904 -62.930786) (xy 392.190837 -62.913145)
			(xy 392.236805 -62.883421) (xy 392.286551 -62.860575) (xy 392.339053 -62.845079) (xy 392.393231 -62.83725)
			(xy 392.447973 -62.83725) (xy 392.502151 -62.845079) (xy 392.554653 -62.860575) (xy 392.604399 -62.883421)
			(xy 392.650367 -62.913145) (xy 392.6713 -62.930786) (xy 392.671554 -62.93104) (xy 392.678646 -62.936618)
			(xy 392.695559 -62.942869) (xy 392.704574 -62.943232) (xy 392.77163 -62.943232) (xy 392.780648 -62.942883)
			(xy 392.797564 -62.936629) (xy 392.80465 -62.93104) (xy 392.80465 -62.930786) (xy 392.804904 -62.930786)
			(xy 392.825822 -62.913129) (xy 392.871799 -62.883421) (xy 392.92155 -62.860588) (xy 392.974054 -62.845101)
			(xy 393.028232 -62.837278) (xy 393.055602 -62.836806) (xy 393.082854 -62.837264) (xy 393.136804 -62.845021)
			(xy 393.1891 -62.860377) (xy 393.238679 -62.883019) (xy 393.284531 -62.912486) (xy 393.325722 -62.948179)
			(xy 393.361415 -62.989371) (xy 393.390882 -63.035223) (xy 393.413524 -63.084802) (xy 393.428879 -63.137098)
			(xy 393.436636 -63.191048) (xy 393.436636 -63.213554) (xy 396.420765 -63.213554) (xy 396.420765 -63.159046)
			(xy 396.428523 -63.105092) (xy 396.443882 -63.052792) (xy 396.466527 -63.00321) (xy 396.495999 -62.957355)
			(xy 396.531697 -62.916163) (xy 396.572894 -62.88047) (xy 396.618752 -62.851004) (xy 396.668337 -62.828365)
			(xy 396.720639 -62.813013) (xy 396.774594 -62.805262) (xy 396.801848 -62.804802) (xy 396.829217 -62.805298)
			(xy 396.883395 -62.813109) (xy 396.935898 -62.828591) (xy 396.985645 -62.851426) (xy 397.031613 -62.881144)
			(xy 397.052546 -62.898782) (xy 397.0528 -62.899036) (xy 397.059879 -62.904633) (xy 397.076802 -62.910872)
			(xy 397.08582 -62.911228) (xy 397.152876 -62.911228) (xy 397.161891 -62.910853) (xy 397.178808 -62.904617)
			(xy 397.185896 -62.899036) (xy 397.185896 -62.898782) (xy 397.18615 -62.898782) (xy 397.207083 -62.881141)
			(xy 397.253051 -62.851417) (xy 397.302797 -62.828571) (xy 397.355299 -62.813075) (xy 397.409477 -62.805246)
			(xy 397.464219 -62.805246) (xy 397.518397 -62.813075) (xy 397.570899 -62.828571) (xy 397.620645 -62.851417)
			(xy 397.666613 -62.881141) (xy 397.687546 -62.898782) (xy 397.6878 -62.899036) (xy 397.694879 -62.904633)
			(xy 397.711802 -62.910872) (xy 397.72082 -62.911228) (xy 397.787876 -62.911228) (xy 397.796891 -62.910853)
			(xy 397.813808 -62.904617) (xy 397.820896 -62.899036) (xy 397.820896 -62.898782) (xy 397.82115 -62.898782)
			(xy 397.842088 -62.88115) (xy 397.888059 -62.851438) (xy 397.937805 -62.828601) (xy 397.990305 -62.813108)
			(xy 398.044479 -62.805277) (xy 398.071848 -62.804802) (xy 398.099098 -62.805271) (xy 398.153042 -62.813033)
			(xy 398.205332 -62.828393) (xy 398.254905 -62.851038) (xy 398.30075 -62.880506) (xy 398.341936 -62.916198)
			(xy 398.377623 -62.957388) (xy 398.407086 -63.003238) (xy 398.429724 -63.052813) (xy 398.439536 -63.086234)
			(xy 401.687536 -63.086234) (xy 401.691607 -63.030612) (xy 401.703733 -62.976175) (xy 401.723656 -62.924084)
			(xy 401.750952 -62.875449) (xy 401.785038 -62.831306) (xy 401.825187 -62.792597) (xy 401.870545 -62.760146)
			(xy 401.920145 -62.734645) (xy 401.972929 -62.716638) (xy 402.027772 -62.706508) (xy 402.083506 -62.704471)
			(xy 402.138943 -62.710571) (xy 402.1929 -62.724677) (xy 402.244229 -62.746489) (xy 402.291835 -62.775543)
			(xy 402.334703 -62.811218) (xy 402.335554 -62.812168) (xy 407.217878 -62.812168) (xy 407.221949 -62.756546)
			(xy 407.234075 -62.702109) (xy 407.253998 -62.650018) (xy 407.281294 -62.601383) (xy 407.31538 -62.55724)
			(xy 407.355529 -62.518531) (xy 407.400887 -62.48608) (xy 407.450487 -62.460579) (xy 407.503271 -62.442572)
			(xy 407.558114 -62.432442) (xy 407.613848 -62.430405) (xy 407.669285 -62.436505) (xy 407.723242 -62.450611)
			(xy 407.774571 -62.472423) (xy 407.822177 -62.501477) (xy 407.865045 -62.537152) (xy 407.902262 -62.578689)
			(xy 407.933035 -62.625202) (xy 407.956707 -62.675699) (xy 407.972775 -62.729106) (xy 407.980895 -62.784282)
			(xy 407.981404 -62.812168) (xy 407.980895 -62.840054) (xy 407.972775 -62.89523) (xy 407.956707 -62.948637)
			(xy 407.933035 -62.999134) (xy 407.902262 -63.045647) (xy 407.865045 -63.087184) (xy 407.822177 -63.122859)
			(xy 407.774571 -63.151913) (xy 407.723242 -63.173725) (xy 407.669285 -63.187831) (xy 407.613848 -63.193931)
			(xy 407.558114 -63.191894) (xy 407.503271 -63.181764) (xy 407.450487 -63.163757) (xy 407.400887 -63.138256)
			(xy 407.355529 -63.105805) (xy 407.31538 -63.067096) (xy 407.281294 -63.022953) (xy 407.253998 -62.974318)
			(xy 407.234075 -62.922227) (xy 407.221949 -62.86779) (xy 407.217878 -62.812168) (xy 402.335554 -62.812168)
			(xy 402.37192 -62.852755) (xy 402.402693 -62.899268) (xy 402.426365 -62.949765) (xy 402.442433 -63.003172)
			(xy 402.450553 -63.058348) (xy 402.451062 -63.086234) (xy 402.450553 -63.11412) (xy 402.442433 -63.169296)
			(xy 402.426365 -63.222703) (xy 402.402693 -63.2732) (xy 402.382713 -63.3034) (xy 403.801562 -63.3034)
			(xy 403.801562 -63.243464) (xy 403.809385 -63.184042) (xy 403.824898 -63.126149) (xy 403.847834 -63.070776)
			(xy 403.877801 -63.01887) (xy 403.914288 -62.97132) (xy 403.956668 -62.92894) (xy 404.004218 -62.892453)
			(xy 404.056124 -62.862486) (xy 404.111497 -62.83955) (xy 404.16939 -62.824037) (xy 404.228812 -62.816214)
			(xy 404.288748 -62.816214) (xy 404.34817 -62.824037) (xy 404.406063 -62.83955) (xy 404.461436 -62.862486)
			(xy 404.513342 -62.892453) (xy 404.560892 -62.92894) (xy 404.603272 -62.97132) (xy 404.639759 -63.01887)
			(xy 404.669726 -63.070776) (xy 404.692662 -63.126149) (xy 404.708175 -63.184042) (xy 404.715998 -63.243464)
			(xy 404.716032 -63.245548) (xy 417.404592 -63.245548) (xy 417.404592 -63.191052) (xy 417.412347 -63.137111)
			(xy 417.427699 -63.084822) (xy 417.450336 -63.03525) (xy 417.479796 -62.989404) (xy 417.515481 -62.948216)
			(xy 417.556664 -62.912526) (xy 417.602506 -62.88306) (xy 417.652075 -62.860417) (xy 417.704362 -62.845058)
			(xy 417.758302 -62.837296) (xy 417.78555 -62.836806) (xy 417.812919 -62.8373) (xy 417.867097 -62.845111)
			(xy 417.9196 -62.860593) (xy 417.969347 -62.883429) (xy 418.015315 -62.913148) (xy 418.036248 -62.930786)
			(xy 418.036502 -62.93104) (xy 418.04358 -62.936638) (xy 418.060504 -62.942877) (xy 418.069522 -62.943232)
			(xy 418.136578 -62.943232) (xy 418.145593 -62.942857) (xy 418.16251 -62.936621) (xy 418.169598 -62.93104)
			(xy 418.169598 -62.930786) (xy 418.169852 -62.930786) (xy 418.190785 -62.913145) (xy 418.236753 -62.883421)
			(xy 418.286499 -62.860575) (xy 418.339001 -62.845079) (xy 418.393179 -62.83725) (xy 418.447921 -62.83725)
			(xy 418.502099 -62.845079) (xy 418.554601 -62.860575) (xy 418.604347 -62.883421) (xy 418.650315 -62.913145)
			(xy 418.671248 -62.930786) (xy 418.671502 -62.93104) (xy 418.67858 -62.936638) (xy 418.695504 -62.942877)
			(xy 418.704522 -62.943232) (xy 418.771578 -62.943232) (xy 418.780593 -62.942857) (xy 418.79751 -62.936621)
			(xy 418.804598 -62.93104) (xy 418.804598 -62.930786) (xy 418.804852 -62.930786) (xy 418.82579 -62.913154)
			(xy 418.871761 -62.883441) (xy 418.921507 -62.860604) (xy 418.974007 -62.845112) (xy 419.028181 -62.837281)
			(xy 419.05555 -62.836806) (xy 419.082806 -62.837237) (xy 419.136765 -62.844989) (xy 419.18907 -62.860341)
			(xy 419.238659 -62.882982) (xy 419.28452 -62.912449) (xy 419.32572 -62.948145) (xy 419.36142 -62.98934)
			(xy 419.390894 -63.035197) (xy 419.413541 -63.084783) (xy 419.4289 -63.137086) (xy 419.436659 -63.191044)
			(xy 419.436659 -63.21355) (xy 422.420788 -63.21355) (xy 422.420788 -63.15905) (xy 422.428544 -63.105104)
			(xy 422.443899 -63.052811) (xy 422.466539 -63.003235) (xy 422.496004 -62.957386) (xy 422.531694 -62.916197)
			(xy 422.572883 -62.880507) (xy 422.618732 -62.851041) (xy 422.668307 -62.8284) (xy 422.7206 -62.813045)
			(xy 422.774546 -62.805289) (xy 422.801796 -62.804802) (xy 422.829166 -62.80527) (xy 422.883345 -62.813087)
			(xy 422.935848 -62.828576) (xy 422.985595 -62.851417) (xy 423.031562 -62.881141) (xy 423.052494 -62.898782)
			(xy 423.052748 -62.899036) (xy 423.059842 -62.904611) (xy 423.076753 -62.910864) (xy 423.085768 -62.911228)
			(xy 423.152824 -62.911228) (xy 423.161841 -62.910877) (xy 423.178758 -62.904625) (xy 423.185844 -62.899036)
			(xy 423.185844 -62.898782) (xy 423.186098 -62.898782) (xy 423.207031 -62.881141) (xy 423.252999 -62.851417)
			(xy 423.302745 -62.828571) (xy 423.355247 -62.813075) (xy 423.409425 -62.805246) (xy 423.464167 -62.805246)
			(xy 423.518345 -62.813075) (xy 423.570847 -62.828571) (xy 423.620593 -62.851417) (xy 423.666561 -62.881141)
			(xy 423.687494 -62.898782) (xy 423.687748 -62.899036) (xy 423.694842 -62.904611) (xy 423.711753 -62.910864)
			(xy 423.720768 -62.911228) (xy 423.787824 -62.911228) (xy 423.796841 -62.910877) (xy 423.813758 -62.904625)
			(xy 423.820844 -62.899036) (xy 423.820844 -62.898782) (xy 423.821098 -62.898782) (xy 423.842018 -62.881128)
			(xy 423.887994 -62.851419) (xy 423.937745 -62.828586) (xy 423.990248 -62.813098) (xy 424.044426 -62.805274)
			(xy 424.071796 -62.804802) (xy 424.09905 -62.805245) (xy 424.153003 -62.813001) (xy 424.205302 -62.828357)
			(xy 424.254884 -62.851) (xy 424.300739 -62.880469) (xy 424.341934 -62.916164) (xy 424.377629 -62.957358)
			(xy 424.407098 -63.003212) (xy 424.429741 -63.052794) (xy 424.43956 -63.086234) (xy 427.687484 -63.086234)
			(xy 427.691555 -63.030612) (xy 427.703681 -62.976175) (xy 427.723604 -62.924084) (xy 427.7509 -62.875449)
			(xy 427.784986 -62.831306) (xy 427.825135 -62.792597) (xy 427.870493 -62.760146) (xy 427.920093 -62.734645)
			(xy 427.972877 -62.716638) (xy 428.02772 -62.706508) (xy 428.083454 -62.704471) (xy 428.138891 -62.710571)
			(xy 428.192848 -62.724677) (xy 428.244177 -62.746489) (xy 428.291783 -62.775543) (xy 428.334651 -62.811218)
			(xy 428.335502 -62.812168) (xy 433.217826 -62.812168) (xy 433.221897 -62.756546) (xy 433.234023 -62.702109)
			(xy 433.253946 -62.650018) (xy 433.281242 -62.601383) (xy 433.315328 -62.55724) (xy 433.355477 -62.518531)
			(xy 433.400835 -62.48608) (xy 433.450435 -62.460579) (xy 433.503219 -62.442572) (xy 433.558062 -62.432442)
			(xy 433.613796 -62.430405) (xy 433.669233 -62.436505) (xy 433.72319 -62.450611) (xy 433.774519 -62.472423)
			(xy 433.822125 -62.501477) (xy 433.864993 -62.537152) (xy 433.90221 -62.578689) (xy 433.932983 -62.625202)
			(xy 433.956655 -62.675699) (xy 433.972723 -62.729106) (xy 433.980843 -62.784282) (xy 433.981352 -62.812168)
			(xy 433.980843 -62.840054) (xy 433.972723 -62.89523) (xy 433.956655 -62.948637) (xy 433.932983 -62.999134)
			(xy 433.90221 -63.045647) (xy 433.864993 -63.087184) (xy 433.822125 -63.122859) (xy 433.774519 -63.151913)
			(xy 433.72319 -63.173725) (xy 433.669233 -63.187831) (xy 433.613796 -63.193931) (xy 433.558062 -63.191894)
			(xy 433.503219 -63.181764) (xy 433.450435 -63.163757) (xy 433.400835 -63.138256) (xy 433.355477 -63.105805)
			(xy 433.315328 -63.067096) (xy 433.281242 -63.022953) (xy 433.253946 -62.974318) (xy 433.234023 -62.922227)
			(xy 433.221897 -62.86779) (xy 433.217826 -62.812168) (xy 428.335502 -62.812168) (xy 428.371868 -62.852755)
			(xy 428.402641 -62.899268) (xy 428.426313 -62.949765) (xy 428.442381 -63.003172) (xy 428.450501 -63.058348)
			(xy 428.45101 -63.086234) (xy 428.450501 -63.11412) (xy 428.442381 -63.169296) (xy 428.426313 -63.222703)
			(xy 428.402641 -63.2732) (xy 428.382661 -63.3034) (xy 429.80151 -63.3034) (xy 429.80151 -63.243464)
			(xy 429.809333 -63.184042) (xy 429.824846 -63.126149) (xy 429.847782 -63.070776) (xy 429.877749 -63.01887)
			(xy 429.914236 -62.97132) (xy 429.956616 -62.92894) (xy 430.004166 -62.892453) (xy 430.056072 -62.862486)
			(xy 430.111445 -62.83955) (xy 430.169338 -62.824037) (xy 430.22876 -62.816214) (xy 430.288696 -62.816214)
			(xy 430.348118 -62.824037) (xy 430.406011 -62.83955) (xy 430.461384 -62.862486) (xy 430.51329 -62.892453)
			(xy 430.56084 -62.92894) (xy 430.60322 -62.97132) (xy 430.639707 -63.01887) (xy 430.669674 -63.070776)
			(xy 430.69261 -63.126149) (xy 430.708123 -63.184042) (xy 430.715946 -63.243464) (xy 430.71598 -63.24555)
			(xy 443.404492 -63.24555) (xy 443.404492 -63.19105) (xy 443.412248 -63.137104) (xy 443.427603 -63.084812)
			(xy 443.450243 -63.035237) (xy 443.479708 -62.989388) (xy 443.515398 -62.948199) (xy 443.556586 -62.912509)
			(xy 443.602435 -62.883044) (xy 443.65201 -62.860404) (xy 443.704302 -62.845049) (xy 443.758248 -62.837292)
			(xy 443.785498 -62.836806) (xy 443.812868 -62.837272) (xy 443.867047 -62.845089) (xy 443.919551 -62.860579)
			(xy 443.969297 -62.88342) (xy 444.015264 -62.913145) (xy 444.036196 -62.930786) (xy 444.03645 -62.93104)
			(xy 444.043543 -62.936617) (xy 444.060455 -62.942868) (xy 444.06947 -62.943232) (xy 444.136526 -62.943232)
			(xy 444.145543 -62.942881) (xy 444.16246 -62.936628) (xy 444.169546 -62.93104) (xy 444.169546 -62.930786)
			(xy 444.1698 -62.930786) (xy 444.190733 -62.913145) (xy 444.236701 -62.883421) (xy 444.286447 -62.860575)
			(xy 444.338949 -62.845079) (xy 444.393127 -62.83725) (xy 444.447869 -62.83725) (xy 444.502047 -62.845079)
			(xy 444.554549 -62.860575) (xy 444.604295 -62.883421) (xy 444.650263 -62.913145) (xy 444.671196 -62.930786)
			(xy 444.67145 -62.93104) (xy 444.678543 -62.936617) (xy 444.695455 -62.942868) (xy 444.70447 -62.943232)
			(xy 444.771526 -62.943232) (xy 444.780543 -62.942881) (xy 444.79746 -62.936628) (xy 444.804546 -62.93104)
			(xy 444.804546 -62.930786) (xy 444.8048 -62.930786) (xy 444.825719 -62.913131) (xy 444.871696 -62.883422)
			(xy 444.921447 -62.86059) (xy 444.97395 -62.845102) (xy 445.028128 -62.837278) (xy 445.055498 -62.836806)
			(xy 445.082752 -62.837241) (xy 445.136705 -62.844998) (xy 445.189005 -62.860354) (xy 445.238587 -62.882997)
			(xy 445.284443 -62.912467) (xy 445.325637 -62.948162) (xy 445.361332 -62.989356) (xy 445.390802 -63.035211)
			(xy 445.413445 -63.084793) (xy 445.428802 -63.137093) (xy 445.436559 -63.191046) (xy 445.436559 -63.213554)
			(xy 448.420665 -63.213554) (xy 448.420665 -63.159046) (xy 448.428423 -63.105092) (xy 448.443781 -63.052793)
			(xy 448.466426 -63.003211) (xy 448.495898 -62.957357) (xy 448.531595 -62.916164) (xy 448.572792 -62.880471)
			(xy 448.618649 -62.851005) (xy 448.668234 -62.828366) (xy 448.720536 -62.813014) (xy 448.77449 -62.805262)
			(xy 448.801744 -62.804802) (xy 448.829113 -62.8053) (xy 448.883291 -62.81311) (xy 448.935794 -62.828592)
			(xy 448.985541 -62.851426) (xy 449.031509 -62.881144) (xy 449.052442 -62.898782) (xy 449.052696 -62.899036)
			(xy 449.059777 -62.904631) (xy 449.076698 -62.910872) (xy 449.085716 -62.911228) (xy 449.152772 -62.911228)
			(xy 449.161787 -62.910851) (xy 449.178704 -62.904617) (xy 449.185792 -62.899036) (xy 449.185792 -62.898782)
			(xy 449.186046 -62.898782) (xy 449.206979 -62.881141) (xy 449.252947 -62.851417) (xy 449.302693 -62.828571)
			(xy 449.355195 -62.813075) (xy 449.409373 -62.805246) (xy 449.464115 -62.805246) (xy 449.518293 -62.813075)
			(xy 449.570795 -62.828571) (xy 449.620541 -62.851417) (xy 449.666509 -62.881141) (xy 449.687442 -62.898782)
			(xy 449.687696 -62.899036) (xy 449.694777 -62.904631) (xy 449.711698 -62.910872) (xy 449.720716 -62.911228)
			(xy 449.787772 -62.911228) (xy 449.796787 -62.910851) (xy 449.813704 -62.904617) (xy 449.820792 -62.899036)
			(xy 449.820792 -62.898782) (xy 449.821046 -62.898782) (xy 449.841985 -62.881152) (xy 449.887956 -62.851439)
			(xy 449.937702 -62.828602) (xy 449.990201 -62.813109) (xy 450.044375 -62.805278) (xy 450.071744 -62.804802)
			(xy 450.098994 -62.805271) (xy 450.152938 -62.813033) (xy 450.205229 -62.828392) (xy 450.254802 -62.851036)
			(xy 450.300648 -62.880504) (xy 450.341834 -62.916197) (xy 450.377522 -62.957387) (xy 450.406985 -63.003237)
			(xy 450.429623 -63.052812) (xy 450.444977 -63.105105) (xy 450.452732 -63.15905) (xy 450.452732 -63.21355)
			(xy 450.444977 -63.267495) (xy 450.429623 -63.319788) (xy 450.406985 -63.369363) (xy 450.377522 -63.415213)
			(xy 450.341834 -63.456403) (xy 450.300648 -63.492096) (xy 450.254802 -63.521564) (xy 450.205229 -63.544208)
			(xy 450.152938 -63.559567) (xy 450.098994 -63.567329) (xy 450.071744 -63.567818) (xy 450.044374 -63.567346)
			(xy 449.990194 -63.559533) (xy 449.93769 -63.544046) (xy 449.887943 -63.521205) (xy 449.841977 -63.49148)
			(xy 449.821046 -63.473838) (xy 449.820792 -63.473584) (xy 449.813713 -63.467986) (xy 449.79679 -63.461747)
			(xy 449.787772 -63.461392) (xy 449.720716 -63.461392) (xy 449.7117 -63.461758) (xy 449.694783 -63.468)
			(xy 449.687696 -63.473584) (xy 449.687442 -63.473838) (xy 449.666509 -63.491479) (xy 449.620541 -63.521203)
			(xy 449.570795 -63.544049) (xy 449.518293 -63.559545) (xy 449.464115 -63.567374) (xy 449.409373 -63.567374)
			(xy 449.355195 -63.559545) (xy 449.302693 -63.544049) (xy 449.252947 -63.521203) (xy 449.206979 -63.491479)
			(xy 449.186046 -63.473838) (xy 449.185792 -63.473584) (xy 449.178713 -63.467986) (xy 449.16179 -63.461747)
			(xy 449.152772 -63.461392) (xy 449.085716 -63.461392) (xy 449.0767 -63.461758) (xy 449.059783 -63.468)
			(xy 449.052696 -63.473584) (xy 449.052696 -63.473838) (xy 449.052442 -63.473838) (xy 449.03151 -63.491477)
			(xy 448.985537 -63.521188) (xy 448.935789 -63.544023) (xy 448.883289 -63.559515) (xy 448.829113 -63.567344)
			(xy 448.801744 -63.567818) (xy 448.77449 -63.567338) (xy 448.720536 -63.559586) (xy 448.668234 -63.544234)
			(xy 448.618649 -63.521595) (xy 448.572792 -63.492129) (xy 448.531595 -63.456436) (xy 448.495898 -63.415243)
			(xy 448.466426 -63.369389) (xy 448.443781 -63.319807) (xy 448.428423 -63.267508) (xy 448.420665 -63.213554)
			(xy 445.436559 -63.213554) (xy 445.436559 -63.245554) (xy 445.428802 -63.299507) (xy 445.413445 -63.351807)
			(xy 445.390802 -63.401389) (xy 445.361332 -63.447244) (xy 445.325637 -63.488438) (xy 445.284443 -63.524133)
			(xy 445.238587 -63.553603) (xy 445.189005 -63.576246) (xy 445.136705 -63.591602) (xy 445.082752 -63.599359)
			(xy 445.055498 -63.599822) (xy 445.028127 -63.599376) (xy 444.973946 -63.591556) (xy 444.921442 -63.576064)
			(xy 444.871695 -63.553217) (xy 444.82573 -63.523486) (xy 444.8048 -63.505842) (xy 444.804546 -63.505588)
			(xy 444.797451 -63.500013) (xy 444.780541 -63.49376) (xy 444.771526 -63.493396) (xy 444.70447 -63.493396)
			(xy 444.695452 -63.49374) (xy 444.678535 -63.499997) (xy 444.67145 -63.505588) (xy 444.671196 -63.505842)
			(xy 444.650263 -63.523483) (xy 444.604295 -63.553207) (xy 444.554549 -63.576053) (xy 444.502047 -63.591549)
			(xy 444.447869 -63.599378) (xy 444.393127 -63.599378) (xy 444.338949 -63.591549) (xy 444.286447 -63.576053)
			(xy 444.236701 -63.553207) (xy 444.190733 -63.523483) (xy 444.1698 -63.505842) (xy 444.169546 -63.505588)
			(xy 444.162451 -63.500013) (xy 444.145541 -63.49376) (xy 444.136526 -63.493396) (xy 444.06947 -63.493396)
			(xy 444.060452 -63.49374) (xy 444.043535 -63.499997) (xy 444.03645 -63.505588) (xy 444.03645 -63.505842)
			(xy 444.036196 -63.505842) (xy 444.015282 -63.523503) (xy 443.969304 -63.553211) (xy 443.919551 -63.576042)
			(xy 443.867047 -63.591528) (xy 443.812868 -63.599351) (xy 443.785498 -63.599822) (xy 443.758248 -63.599308)
			(xy 443.704302 -63.591551) (xy 443.65201 -63.576196) (xy 443.602435 -63.553556) (xy 443.556586 -63.524091)
			(xy 443.515398 -63.488401) (xy 443.479708 -63.447212) (xy 443.450243 -63.401363) (xy 443.427603 -63.351788)
			(xy 443.412248 -63.299496) (xy 443.404492 -63.24555) (xy 430.71598 -63.24555) (xy 430.716436 -63.273432)
			(xy 430.715946 -63.3034) (xy 430.708123 -63.362822) (xy 430.69261 -63.420715) (xy 430.669674 -63.476088)
			(xy 430.639707 -63.527994) (xy 430.60322 -63.575544) (xy 430.56084 -63.617924) (xy 430.51329 -63.654411)
			(xy 430.461384 -63.684378) (xy 430.406011 -63.707314) (xy 430.348118 -63.722827) (xy 430.288696 -63.73065)
			(xy 430.22876 -63.73065) (xy 430.169338 -63.722827) (xy 430.111445 -63.707314) (xy 430.056072 -63.684378)
			(xy 430.004166 -63.654411) (xy 429.956616 -63.617924) (xy 429.914236 -63.575544) (xy 429.877749 -63.527994)
			(xy 429.847782 -63.476088) (xy 429.824846 -63.420715) (xy 429.809333 -63.362822) (xy 429.80151 -63.3034)
			(xy 428.382661 -63.3034) (xy 428.371868 -63.319713) (xy 428.334651 -63.36125) (xy 428.291783 -63.396925)
			(xy 428.244177 -63.425979) (xy 428.192848 -63.447791) (xy 428.138891 -63.461897) (xy 428.083454 -63.467997)
			(xy 428.02772 -63.46596) (xy 427.972877 -63.45583) (xy 427.920093 -63.437823) (xy 427.870493 -63.412322)
			(xy 427.825135 -63.379871) (xy 427.784986 -63.341162) (xy 427.7509 -63.297019) (xy 427.723604 -63.248384)
			(xy 427.703681 -63.196293) (xy 427.691555 -63.141856) (xy 427.687484 -63.086234) (xy 424.43956 -63.086234)
			(xy 424.445098 -63.105093) (xy 424.452855 -63.159046) (xy 424.452855 -63.213554) (xy 424.445098 -63.267507)
			(xy 424.429741 -63.319806) (xy 424.407098 -63.369388) (xy 424.377629 -63.415242) (xy 424.341934 -63.456436)
			(xy 424.300739 -63.492131) (xy 424.254884 -63.5216) (xy 424.205302 -63.544243) (xy 424.153003 -63.559599)
			(xy 424.09905 -63.567355) (xy 424.071796 -63.567818) (xy 424.044425 -63.567374) (xy 423.990244 -63.559554)
			(xy 423.93774 -63.544061) (xy 423.887993 -63.521214) (xy 423.842028 -63.491483) (xy 423.821098 -63.473838)
			(xy 423.820844 -63.473584) (xy 423.81375 -63.468008) (xy 423.796839 -63.461755) (xy 423.787824 -63.461392)
			(xy 423.720768 -63.461392) (xy 423.71175 -63.461736) (xy 423.694833 -63.467993) (xy 423.687748 -63.473584)
			(xy 423.687494 -63.473838) (xy 423.666561 -63.491479) (xy 423.620593 -63.521203) (xy 423.570847 -63.544049)
			(xy 423.518345 -63.559545) (xy 423.464167 -63.567374) (xy 423.409425 -63.567374) (xy 423.355247 -63.559545)
			(xy 423.302745 -63.544049) (xy 423.252999 -63.521203) (xy 423.207031 -63.491479) (xy 423.186098 -63.473838)
			(xy 423.185844 -63.473584) (xy 423.17875 -63.468008) (xy 423.161839 -63.461755) (xy 423.152824 -63.461392)
			(xy 423.085768 -63.461392) (xy 423.07675 -63.461736) (xy 423.059833 -63.467993) (xy 423.052748 -63.473584)
			(xy 423.052748 -63.473838) (xy 423.052494 -63.473838) (xy 423.03158 -63.4915) (xy 422.985602 -63.521207)
			(xy 422.93585 -63.544038) (xy 422.883345 -63.559524) (xy 422.829166 -63.567347) (xy 422.801796 -63.567818)
			(xy 422.774546 -63.567311) (xy 422.7206 -63.559555) (xy 422.668307 -63.5442) (xy 422.618732 -63.521559)
			(xy 422.572883 -63.492093) (xy 422.531694 -63.456403) (xy 422.496004 -63.415214) (xy 422.466539 -63.369365)
			(xy 422.443899 -63.319789) (xy 422.428544 -63.267496) (xy 422.420788 -63.21355) (xy 419.436659 -63.21355)
			(xy 419.436659 -63.245556) (xy 419.4289 -63.299514) (xy 419.413541 -63.351817) (xy 419.390894 -63.401403)
			(xy 419.361421 -63.44726) (xy 419.32572 -63.488455) (xy 419.28452 -63.524151) (xy 419.238659 -63.553618)
			(xy 419.18907 -63.576259) (xy 419.136765 -63.591611) (xy 419.082806 -63.599363) (xy 419.05555 -63.599822)
			(xy 419.02818 -63.599346) (xy 418.974001 -63.591533) (xy 418.921497 -63.576048) (xy 418.87175 -63.553208)
			(xy 418.825783 -63.523483) (xy 418.804852 -63.505842) (xy 418.804598 -63.505588) (xy 418.797517 -63.499993)
			(xy 418.780596 -63.493752) (xy 418.771578 -63.493396) (xy 418.704522 -63.493396) (xy 418.695506 -63.493764)
			(xy 418.678589 -63.500004) (xy 418.671502 -63.505588) (xy 418.671248 -63.505842) (xy 418.650315 -63.523483)
			(xy 418.604347 -63.553207) (xy 418.554601 -63.576053) (xy 418.502099 -63.591549) (xy 418.447921 -63.599378)
			(xy 418.393179 -63.599378) (xy 418.339001 -63.591549) (xy 418.286499 -63.576053) (xy 418.236753 -63.553207)
			(xy 418.190785 -63.523483) (xy 418.169852 -63.505842) (xy 418.169598 -63.505588) (xy 418.162517 -63.499993)
			(xy 418.145596 -63.493752) (xy 418.136578 -63.493396) (xy 418.069522 -63.493396) (xy 418.060506 -63.493764)
			(xy 418.043589 -63.500004) (xy 418.036502 -63.505588) (xy 418.036502 -63.505842) (xy 418.036248 -63.505842)
			(xy 418.015314 -63.523479) (xy 417.969341 -63.55319) (xy 417.919594 -63.576026) (xy 417.867094 -63.591517)
			(xy 417.812919 -63.599347) (xy 417.78555 -63.599822) (xy 417.758302 -63.599304) (xy 417.704362 -63.591542)
			(xy 417.652075 -63.576183) (xy 417.602506 -63.55354) (xy 417.556664 -63.524074) (xy 417.515481 -63.488384)
			(xy 417.479796 -63.447196) (xy 417.450336 -63.40135) (xy 417.427699 -63.351778) (xy 417.412347 -63.299489)
			(xy 417.404592 -63.245548) (xy 404.716032 -63.245548) (xy 404.716488 -63.273432) (xy 404.715998 -63.3034)
			(xy 404.708175 -63.362822) (xy 404.692662 -63.420715) (xy 404.669726 -63.476088) (xy 404.639759 -63.527994)
			(xy 404.603272 -63.575544) (xy 404.560892 -63.617924) (xy 404.513342 -63.654411) (xy 404.461436 -63.684378)
			(xy 404.406063 -63.707314) (xy 404.34817 -63.722827) (xy 404.288748 -63.73065) (xy 404.228812 -63.73065)
			(xy 404.16939 -63.722827) (xy 404.111497 -63.707314) (xy 404.056124 -63.684378) (xy 404.004218 -63.654411)
			(xy 403.956668 -63.617924) (xy 403.914288 -63.575544) (xy 403.877801 -63.527994) (xy 403.847834 -63.476088)
			(xy 403.824898 -63.420715) (xy 403.809385 -63.362822) (xy 403.801562 -63.3034) (xy 402.382713 -63.3034)
			(xy 402.37192 -63.319713) (xy 402.334703 -63.36125) (xy 402.291835 -63.396925) (xy 402.244229 -63.425979)
			(xy 402.1929 -63.447791) (xy 402.138943 -63.461897) (xy 402.083506 -63.467997) (xy 402.027772 -63.46596)
			(xy 401.972929 -63.45583) (xy 401.920145 -63.437823) (xy 401.870545 -63.412322) (xy 401.825187 -63.379871)
			(xy 401.785038 -63.341162) (xy 401.750952 -63.297019) (xy 401.723656 -63.248384) (xy 401.703733 -63.196293)
			(xy 401.691607 -63.141856) (xy 401.687536 -63.086234) (xy 398.439536 -63.086234) (xy 398.445077 -63.105105)
			(xy 398.452832 -63.15905) (xy 398.452832 -63.21355) (xy 398.445077 -63.267495) (xy 398.429724 -63.319787)
			(xy 398.407086 -63.369362) (xy 398.377623 -63.415212) (xy 398.341936 -63.456402) (xy 398.30075 -63.492094)
			(xy 398.254905 -63.521562) (xy 398.205332 -63.544207) (xy 398.153042 -63.559567) (xy 398.099098 -63.567329)
			(xy 398.071848 -63.567818) (xy 398.044478 -63.567344) (xy 397.990298 -63.559531) (xy 397.937795 -63.544045)
			(xy 397.888047 -63.521204) (xy 397.842081 -63.49148) (xy 397.82115 -63.473838) (xy 397.820896 -63.473584)
			(xy 397.813816 -63.467988) (xy 397.796894 -63.461747) (xy 397.787876 -63.461392) (xy 397.72082 -63.461392)
			(xy 397.711804 -63.46176) (xy 397.694887 -63.468) (xy 397.6878 -63.473584) (xy 397.687546 -63.473838)
			(xy 397.666613 -63.491479) (xy 397.620645 -63.521203) (xy 397.570899 -63.544049) (xy 397.518397 -63.559545)
			(xy 397.464219 -63.567374) (xy 397.409477 -63.567374) (xy 397.355299 -63.559545) (xy 397.302797 -63.544049)
			(xy 397.253051 -63.521203) (xy 397.207083 -63.491479) (xy 397.18615 -63.473838) (xy 397.185896 -63.473584)
			(xy 397.178816 -63.467988) (xy 397.161894 -63.461747) (xy 397.152876 -63.461392) (xy 397.08582 -63.461392)
			(xy 397.076804 -63.46176) (xy 397.059887 -63.468) (xy 397.0528 -63.473584) (xy 397.0528 -63.473838)
			(xy 397.052546 -63.473838) (xy 397.031613 -63.491475) (xy 396.98564 -63.521186) (xy 396.935892 -63.544022)
			(xy 396.883392 -63.559514) (xy 396.829217 -63.567343) (xy 396.801848 -63.567818) (xy 396.774594 -63.567338)
			(xy 396.720639 -63.559587) (xy 396.668337 -63.544235) (xy 396.618752 -63.521596) (xy 396.572894 -63.49213)
			(xy 396.531697 -63.456437) (xy 396.495999 -63.415245) (xy 396.466527 -63.36939) (xy 396.443882 -63.319808)
			(xy 396.428523 -63.267508) (xy 396.420765 -63.213554) (xy 393.436636 -63.213554) (xy 393.436636 -63.245552)
			(xy 393.428879 -63.299502) (xy 393.413524 -63.351798) (xy 393.390882 -63.401377) (xy 393.361415 -63.447229)
			(xy 393.325722 -63.488421) (xy 393.284531 -63.524114) (xy 393.238679 -63.553581) (xy 393.1891 -63.576223)
			(xy 393.136804 -63.591579) (xy 393.082854 -63.599336) (xy 393.055602 -63.599822) (xy 393.028231 -63.599374)
			(xy 392.97405 -63.591555) (xy 392.921546 -63.576062) (xy 392.8718 -63.553216) (xy 392.825834 -63.523486)
			(xy 392.804904 -63.505842) (xy 392.80465 -63.505588) (xy 392.797554 -63.500015) (xy 392.780644 -63.49376)
			(xy 392.77163 -63.493396) (xy 392.704574 -63.493396) (xy 392.695556 -63.493742) (xy 392.678639 -63.499997)
			(xy 392.671554 -63.505588) (xy 392.6713 -63.505842) (xy 392.650367 -63.523483) (xy 392.604399 -63.553207)
			(xy 392.554653 -63.576053) (xy 392.502151 -63.591549) (xy 392.447973 -63.599378) (xy 392.393231 -63.599378)
			(xy 392.339053 -63.591549) (xy 392.286551 -63.576053) (xy 392.236805 -63.553207) (xy 392.190837 -63.523483)
			(xy 392.169904 -63.505842) (xy 392.16965 -63.505588) (xy 392.162554 -63.500015) (xy 392.145644 -63.49376)
			(xy 392.13663 -63.493396) (xy 392.069574 -63.493396) (xy 392.060556 -63.493742) (xy 392.043639 -63.499997)
			(xy 392.036554 -63.505588) (xy 392.036554 -63.505842) (xy 392.0363 -63.505842) (xy 392.015384 -63.523501)
			(xy 391.969406 -63.553209) (xy 391.919655 -63.57604) (xy 391.867151 -63.591527) (xy 391.812972 -63.599351)
			(xy 391.785602 -63.599822) (xy 391.75835 -63.599331) (xy 391.704401 -63.591574) (xy 391.652105 -63.576219)
			(xy 391.602526 -63.553578) (xy 391.556674 -63.524111) (xy 391.515483 -63.488418) (xy 391.479791 -63.447227)
			(xy 391.450323 -63.401376) (xy 391.427682 -63.351797) (xy 391.412326 -63.299501) (xy 391.404569 -63.245552)
			(xy 378.716084 -63.245552) (xy 378.71654 -63.273432) (xy 378.71605 -63.3034) (xy 378.708227 -63.362822)
			(xy 378.692714 -63.420715) (xy 378.669778 -63.476088) (xy 378.639811 -63.527994) (xy 378.603324 -63.575544)
			(xy 378.560944 -63.617924) (xy 378.513394 -63.654411) (xy 378.461488 -63.684378) (xy 378.406115 -63.707314)
			(xy 378.348222 -63.722827) (xy 378.2888 -63.73065) (xy 378.228864 -63.73065) (xy 378.169442 -63.722827)
			(xy 378.111549 -63.707314) (xy 378.056176 -63.684378) (xy 378.00427 -63.654411) (xy 377.95672 -63.617924)
			(xy 377.91434 -63.575544) (xy 377.877853 -63.527994) (xy 377.847886 -63.476088) (xy 377.82495 -63.420715)
			(xy 377.809437 -63.362822) (xy 377.801614 -63.3034) (xy 376.382765 -63.3034) (xy 376.371972 -63.319713)
			(xy 376.334755 -63.36125) (xy 376.291887 -63.396925) (xy 376.244281 -63.425979) (xy 376.192952 -63.447791)
			(xy 376.138995 -63.461897) (xy 376.083558 -63.467997) (xy 376.027824 -63.46596) (xy 375.972981 -63.45583)
			(xy 375.920197 -63.437823) (xy 375.870597 -63.412322) (xy 375.825239 -63.379871) (xy 375.78509 -63.341162)
			(xy 375.751004 -63.297019) (xy 375.723708 -63.248384) (xy 375.703785 -63.196293) (xy 375.691659 -63.141856)
			(xy 375.687588 -63.086234) (xy 372.439636 -63.086234) (xy 372.445175 -63.105099) (xy 372.452932 -63.159048)
			(xy 372.452932 -63.213552) (xy 372.445175 -63.267501) (xy 372.42982 -63.319797) (xy 372.407178 -63.369376)
			(xy 372.377711 -63.415227) (xy 372.342019 -63.456419) (xy 372.300827 -63.492111) (xy 372.254976 -63.521578)
			(xy 372.205397 -63.54422) (xy 372.153101 -63.559575) (xy 372.099152 -63.567332) (xy 372.0719 -63.567818)
			(xy 372.044529 -63.567372) (xy 371.990348 -63.559552) (xy 371.937844 -63.54406) (xy 371.888097 -63.521213)
			(xy 371.842132 -63.491482) (xy 371.821202 -63.473838) (xy 371.820948 -63.473584) (xy 371.813853 -63.46801)
			(xy 371.796943 -63.461756) (xy 371.787928 -63.461392) (xy 371.720872 -63.461392) (xy 371.711854 -63.461738)
			(xy 371.694937 -63.467993) (xy 371.687852 -63.473584) (xy 371.687598 -63.473838) (xy 371.666665 -63.491479)
			(xy 371.620697 -63.521203) (xy 371.570951 -63.544049) (xy 371.518449 -63.559545) (xy 371.464271 -63.567374)
			(xy 371.409529 -63.567374) (xy 371.355351 -63.559545) (xy 371.302849 -63.544049) (xy 371.253103 -63.521203)
			(xy 371.207135 -63.491479) (xy 371.186202 -63.473838) (xy 371.185948 -63.473584) (xy 371.178853 -63.46801)
			(xy 371.161943 -63.461756) (xy 371.152928 -63.461392) (xy 371.085872 -63.461392) (xy 371.076854 -63.461738)
			(xy 371.059937 -63.467993) (xy 371.052852 -63.473584) (xy 371.052852 -63.473838) (xy 371.052598 -63.473838)
			(xy 371.031683 -63.491498) (xy 370.985705 -63.521205) (xy 370.935953 -63.544037) (xy 370.883449 -63.559523)
			(xy 370.82927 -63.567347) (xy 370.8019 -63.567818) (xy 370.77465 -63.567312) (xy 370.720703 -63.559555)
			(xy 370.66841 -63.544201) (xy 370.618834 -63.52156) (xy 370.572985 -63.492095) (xy 370.531796 -63.456404)
			(xy 370.496105 -63.415215) (xy 370.46664 -63.369366) (xy 370.443999 -63.31979) (xy 370.428645 -63.267497)
			(xy 370.420888 -63.21355) (xy 367.436759 -63.21355) (xy 367.436759 -63.245556) (xy 367.429001 -63.299513)
			(xy 367.413642 -63.351816) (xy 367.390995 -63.401402) (xy 367.361521 -63.447259) (xy 367.325821 -63.488454)
			(xy 367.284622 -63.524149) (xy 367.238761 -63.553617) (xy 367.189173 -63.576258) (xy 367.136868 -63.59161)
			(xy 367.08291 -63.599362) (xy 367.055654 -63.599822) (xy 367.028284 -63.599343) (xy 366.974105 -63.591531)
			(xy 366.921601 -63.576046) (xy 366.871854 -63.553207) (xy 366.825887 -63.523483) (xy 366.804956 -63.505842)
			(xy 366.804702 -63.505588) (xy 366.79762 -63.499995) (xy 366.7807 -63.493752) (xy 366.771682 -63.493396)
			(xy 366.704626 -63.493396) (xy 366.69561 -63.493766) (xy 366.678693 -63.500005) (xy 366.671606 -63.505588)
			(xy 366.671352 -63.505842) (xy 366.650419 -63.523483) (xy 366.604451 -63.553207) (xy 366.554705 -63.576053)
			(xy 366.502203 -63.591549) (xy 366.448025 -63.599378) (xy 366.393283 -63.599378) (xy 366.339105 -63.591549)
			(xy 366.286603 -63.576053) (xy 366.236857 -63.553207) (xy 366.190889 -63.523483) (xy 366.169956 -63.505842)
			(xy 366.169702 -63.505588) (xy 366.16262 -63.499995) (xy 366.1457 -63.493752) (xy 366.136682 -63.493396)
			(xy 366.069626 -63.493396) (xy 366.06061 -63.493766) (xy 366.043693 -63.500005) (xy 366.036606 -63.505588)
			(xy 366.036606 -63.505842) (xy 366.036352 -63.505842) (xy 366.015417 -63.523477) (xy 365.969444 -63.553188)
			(xy 365.919697 -63.576024) (xy 365.867198 -63.591517) (xy 365.813023 -63.599347) (xy 365.785654 -63.599822)
			(xy 365.758406 -63.599305) (xy 365.704465 -63.591543) (xy 365.652178 -63.576185) (xy 365.602608 -63.553542)
			(xy 365.556766 -63.524075) (xy 365.515582 -63.488385) (xy 365.479897 -63.447198) (xy 365.450436 -63.401351)
			(xy 365.427799 -63.351779) (xy 365.412447 -63.29949) (xy 365.404692 -63.245548) (xy 352.716136 -63.245548)
			(xy 352.716592 -63.273432) (xy 352.716102 -63.3034) (xy 352.708279 -63.362822) (xy 352.692766 -63.420715)
			(xy 352.66983 -63.476088) (xy 352.639863 -63.527994) (xy 352.603376 -63.575544) (xy 352.560996 -63.617924)
			(xy 352.513446 -63.654411) (xy 352.46154 -63.684378) (xy 352.406167 -63.707314) (xy 352.348274 -63.722827)
			(xy 352.288852 -63.73065) (xy 352.228916 -63.73065) (xy 352.169494 -63.722827) (xy 352.111601 -63.707314)
			(xy 352.056228 -63.684378) (xy 352.004322 -63.654411) (xy 351.956772 -63.617924) (xy 351.914392 -63.575544)
			(xy 351.877905 -63.527994) (xy 351.847938 -63.476088) (xy 351.825002 -63.420715) (xy 351.809489 -63.362822)
			(xy 351.801666 -63.3034) (xy 350.382817 -63.3034) (xy 350.372024 -63.319713) (xy 350.334807 -63.36125)
			(xy 350.291939 -63.396925) (xy 350.244333 -63.425979) (xy 350.193004 -63.447791) (xy 350.139047 -63.461897)
			(xy 350.08361 -63.467997) (xy 350.027876 -63.46596) (xy 349.973033 -63.45583) (xy 349.920249 -63.437823)
			(xy 349.870649 -63.412322) (xy 349.825291 -63.379871) (xy 349.785142 -63.341162) (xy 349.751056 -63.297019)
			(xy 349.72376 -63.248384) (xy 349.703837 -63.196293) (xy 349.691711 -63.141856) (xy 349.68764 -63.086234)
			(xy 334.339336 -63.086234) (xy 334.344877 -63.105105) (xy 334.352632 -63.15905) (xy 334.352632 -63.21355)
			(xy 334.344877 -63.267495) (xy 334.329524 -63.319787) (xy 334.306885 -63.369363) (xy 334.277422 -63.415212)
			(xy 334.241735 -63.456402) (xy 334.200549 -63.492095) (xy 334.154703 -63.521563) (xy 334.105131 -63.544208)
			(xy 334.05284 -63.559567) (xy 333.998896 -63.567329) (xy 333.971646 -63.567818) (xy 333.944276 -63.567345)
			(xy 333.890096 -63.559532) (xy 333.837592 -63.544046) (xy 333.787845 -63.521205) (xy 333.741879 -63.49148)
			(xy 333.720948 -63.473838) (xy 333.720694 -63.473584) (xy 333.713615 -63.467987) (xy 333.696692 -63.461747)
			(xy 333.687674 -63.461392) (xy 333.620618 -63.461392) (xy 333.611602 -63.461759) (xy 333.594685 -63.468)
			(xy 333.587598 -63.473584) (xy 333.587344 -63.473838) (xy 333.566411 -63.491479) (xy 333.520443 -63.521203)
			(xy 333.470697 -63.544049) (xy 333.418195 -63.559545) (xy 333.364017 -63.567374) (xy 333.309275 -63.567374)
			(xy 333.255097 -63.559545) (xy 333.202595 -63.544049) (xy 333.152849 -63.521203) (xy 333.106881 -63.491479)
			(xy 333.085948 -63.473838) (xy 333.085694 -63.473584) (xy 333.078615 -63.467987) (xy 333.061692 -63.461747)
			(xy 333.052674 -63.461392) (xy 332.985618 -63.461392) (xy 332.976602 -63.461759) (xy 332.959685 -63.468)
			(xy 332.952598 -63.473584) (xy 332.952598 -63.473838) (xy 332.952344 -63.473838) (xy 332.931411 -63.491476)
			(xy 332.885438 -63.521187) (xy 332.835691 -63.544023) (xy 332.78319 -63.559514) (xy 332.729015 -63.567344)
			(xy 332.701646 -63.567818) (xy 332.674392 -63.567338) (xy 332.620437 -63.559586) (xy 332.568135 -63.544235)
			(xy 332.518551 -63.521595) (xy 332.472693 -63.492129) (xy 332.431496 -63.456437) (xy 332.395798 -63.415244)
			(xy 332.366327 -63.36939) (xy 332.343681 -63.319808) (xy 332.328323 -63.267508) (xy 332.320565 -63.213554)
			(xy 329.336436 -63.213554) (xy 329.336436 -63.245552) (xy 329.328679 -63.299502) (xy 329.313324 -63.351799)
			(xy 329.290682 -63.401378) (xy 329.261214 -63.44723) (xy 329.225522 -63.488422) (xy 329.18433 -63.524114)
			(xy 329.138478 -63.553582) (xy 329.088899 -63.576224) (xy 329.036602 -63.591579) (xy 328.982652 -63.599336)
			(xy 328.9554 -63.599822) (xy 328.928029 -63.599375) (xy 328.873848 -63.591555) (xy 328.821344 -63.576063)
			(xy 328.771598 -63.553217) (xy 328.725632 -63.523486) (xy 328.704702 -63.505842) (xy 328.704448 -63.505588)
			(xy 328.697353 -63.500014) (xy 328.680443 -63.49376) (xy 328.671428 -63.493396) (xy 328.604372 -63.493396)
			(xy 328.595354 -63.493741) (xy 328.578437 -63.499997) (xy 328.571352 -63.505588) (xy 328.571098 -63.505842)
			(xy 328.550165 -63.523483) (xy 328.504197 -63.553207) (xy 328.454451 -63.576053) (xy 328.401949 -63.591549)
			(xy 328.347771 -63.599378) (xy 328.293029 -63.599378) (xy 328.238851 -63.591549) (xy 328.186349 -63.576053)
			(xy 328.136603 -63.553207) (xy 328.090635 -63.523483) (xy 328.069702 -63.505842) (xy 328.069448 -63.505588)
			(xy 328.062353 -63.500014) (xy 328.045443 -63.49376) (xy 328.036428 -63.493396) (xy 327.969372 -63.493396)
			(xy 327.960354 -63.493741) (xy 327.943437 -63.499997) (xy 327.936352 -63.505588) (xy 327.936352 -63.505842)
			(xy 327.936098 -63.505842) (xy 327.915183 -63.523502) (xy 327.869205 -63.55321) (xy 327.819453 -63.576041)
			(xy 327.766949 -63.591527) (xy 327.71277 -63.599351) (xy 327.6854 -63.599822) (xy 327.65815 -63.599308)
			(xy 327.604204 -63.591552) (xy 327.551911 -63.576197) (xy 327.502336 -63.553557) (xy 327.456487 -63.524092)
			(xy 327.415299 -63.488401) (xy 327.379608 -63.447213) (xy 327.350143 -63.401364) (xy 327.327503 -63.351789)
			(xy 327.312148 -63.299496) (xy 327.304392 -63.24555) (xy 314.615882 -63.24555) (xy 314.616338 -63.273432)
			(xy 314.615848 -63.3034) (xy 314.608025 -63.362822) (xy 314.592512 -63.420715) (xy 314.569576 -63.476088)
			(xy 314.539609 -63.527994) (xy 314.503122 -63.575544) (xy 314.460742 -63.617924) (xy 314.413192 -63.654411)
			(xy 314.361286 -63.684378) (xy 314.305913 -63.707314) (xy 314.24802 -63.722827) (xy 314.188598 -63.73065)
			(xy 314.128662 -63.73065) (xy 314.06924 -63.722827) (xy 314.011347 -63.707314) (xy 313.955974 -63.684378)
			(xy 313.904068 -63.654411) (xy 313.856518 -63.617924) (xy 313.814138 -63.575544) (xy 313.777651 -63.527994)
			(xy 313.747684 -63.476088) (xy 313.724748 -63.420715) (xy 313.709235 -63.362822) (xy 313.701412 -63.3034)
			(xy 312.282563 -63.3034) (xy 312.27177 -63.319713) (xy 312.234553 -63.36125) (xy 312.191685 -63.396925)
			(xy 312.144079 -63.425979) (xy 312.09275 -63.447791) (xy 312.038793 -63.461897) (xy 311.983356 -63.467997)
			(xy 311.927622 -63.46596) (xy 311.872779 -63.45583) (xy 311.819995 -63.437823) (xy 311.770395 -63.412322)
			(xy 311.725037 -63.379871) (xy 311.684888 -63.341162) (xy 311.650802 -63.297019) (xy 311.623506 -63.248384)
			(xy 311.603583 -63.196293) (xy 311.591457 -63.141856) (xy 311.587386 -63.086234) (xy 308.33946 -63.086234)
			(xy 308.344998 -63.105094) (xy 308.352755 -63.159046) (xy 308.352755 -63.213554) (xy 308.344998 -63.267506)
			(xy 308.329641 -63.319806) (xy 308.306998 -63.369387) (xy 308.277529 -63.415242) (xy 308.241834 -63.456436)
			(xy 308.20064 -63.49213) (xy 308.154786 -63.521599) (xy 308.105204 -63.544242) (xy 308.052904 -63.559598)
			(xy 307.998952 -63.567355) (xy 307.971698 -63.567818) (xy 307.944327 -63.567373) (xy 307.890146 -63.559553)
			(xy 307.837642 -63.54406) (xy 307.787895 -63.521213) (xy 307.74193 -63.491483) (xy 307.721 -63.473838)
			(xy 307.720746 -63.473584) (xy 307.713652 -63.468009) (xy 307.696741 -63.461756) (xy 307.687726 -63.461392)
			(xy 307.62067 -63.461392) (xy 307.611652 -63.461737) (xy 307.594735 -63.467993) (xy 307.58765 -63.473584)
			(xy 307.587396 -63.473838) (xy 307.566463 -63.491479) (xy 307.520495 -63.521203) (xy 307.470749 -63.544049)
			(xy 307.418247 -63.559545) (xy 307.364069 -63.567374) (xy 307.309327 -63.567374) (xy 307.255149 -63.559545)
			(xy 307.202647 -63.544049) (xy 307.152901 -63.521203) (xy 307.106933 -63.491479) (xy 307.086 -63.473838)
			(xy 307.085746 -63.473584) (xy 307.078652 -63.468009) (xy 307.061741 -63.461756) (xy 307.052726 -63.461392)
			(xy 306.98567 -63.461392) (xy 306.976652 -63.461737) (xy 306.959735 -63.467993) (xy 306.95265 -63.473584)
			(xy 306.95265 -63.473838) (xy 306.952396 -63.473838) (xy 306.931481 -63.491499) (xy 306.885503 -63.521206)
			(xy 306.835751 -63.544037) (xy 306.783247 -63.559524) (xy 306.729068 -63.567347) (xy 306.701698 -63.567818)
			(xy 306.674448 -63.567312) (xy 306.620502 -63.559555) (xy 306.568208 -63.5442) (xy 306.518633 -63.52156)
			(xy 306.472784 -63.492094) (xy 306.431595 -63.456403) (xy 306.395905 -63.415214) (xy 306.366439 -63.369365)
			(xy 306.343799 -63.31979) (xy 306.328444 -63.267496) (xy 306.320688 -63.21355) (xy 303.336559 -63.21355)
			(xy 303.336559 -63.245556) (xy 303.3288 -63.299513) (xy 303.313441 -63.351817) (xy 303.290795 -63.401402)
			(xy 303.261321 -63.447259) (xy 303.225621 -63.488455) (xy 303.184421 -63.52415) (xy 303.13856 -63.553618)
			(xy 303.088972 -63.576258) (xy 303.036666 -63.591611) (xy 302.982708 -63.599362) (xy 302.955452 -63.599822)
			(xy 302.928082 -63.599344) (xy 302.873903 -63.591532) (xy 302.821399 -63.576047) (xy 302.771652 -63.553207)
			(xy 302.725685 -63.523483) (xy 302.704754 -63.505842) (xy 302.7045 -63.505588) (xy 302.697419 -63.499994)
			(xy 302.680498 -63.493752) (xy 302.67148 -63.493396) (xy 302.604424 -63.493396) (xy 302.595408 -63.493765)
			(xy 302.578491 -63.500004) (xy 302.571404 -63.505588) (xy 302.57115 -63.505842) (xy 302.550217 -63.523483)
			(xy 302.504249 -63.553207) (xy 302.454503 -63.576053) (xy 302.402001 -63.591549) (xy 302.347823 -63.599378)
			(xy 302.293081 -63.599378) (xy 302.238903 -63.591549) (xy 302.186401 -63.576053) (xy 302.136655 -63.553207)
			(xy 302.090687 -63.523483) (xy 302.069754 -63.505842) (xy 302.0695 -63.505588) (xy 302.062419 -63.499994)
			(xy 302.045498 -63.493752) (xy 302.03648 -63.493396) (xy 301.969424 -63.493396) (xy 301.960408 -63.493765)
			(xy 301.943491 -63.500004) (xy 301.936404 -63.505588) (xy 301.936404 -63.505842) (xy 301.93615 -63.505842)
			(xy 301.915216 -63.523478) (xy 301.869243 -63.553189) (xy 301.819496 -63.576025) (xy 301.766996 -63.591517)
			(xy 301.712821 -63.599347) (xy 301.685452 -63.599822) (xy 301.658204 -63.599304) (xy 301.604264 -63.591543)
			(xy 301.551977 -63.576184) (xy 301.502407 -63.553541) (xy 301.456565 -63.524075) (xy 301.415382 -63.488384)
			(xy 301.379697 -63.447197) (xy 301.350236 -63.401351) (xy 301.327599 -63.351778) (xy 301.312247 -63.29949)
			(xy 301.304492 -63.245548) (xy 288.615934 -63.245548) (xy 288.61639 -63.273432) (xy 288.6159 -63.3034)
			(xy 288.608077 -63.362822) (xy 288.592564 -63.420715) (xy 288.569628 -63.476088) (xy 288.539661 -63.527994)
			(xy 288.503174 -63.575544) (xy 288.460794 -63.617924) (xy 288.413244 -63.654411) (xy 288.361338 -63.684378)
			(xy 288.305965 -63.707314) (xy 288.248072 -63.722827) (xy 288.18865 -63.73065) (xy 288.128714 -63.73065)
			(xy 288.069292 -63.722827) (xy 288.011399 -63.707314) (xy 287.956026 -63.684378) (xy 287.90412 -63.654411)
			(xy 287.85657 -63.617924) (xy 287.81419 -63.575544) (xy 287.777703 -63.527994) (xy 287.747736 -63.476088)
			(xy 287.7248 -63.420715) (xy 287.709287 -63.362822) (xy 287.701464 -63.3034) (xy 286.282615 -63.3034)
			(xy 286.271822 -63.319713) (xy 286.234605 -63.36125) (xy 286.191737 -63.396925) (xy 286.144131 -63.425979)
			(xy 286.092802 -63.447791) (xy 286.038845 -63.461897) (xy 285.983408 -63.467997) (xy 285.927674 -63.46596)
			(xy 285.872831 -63.45583) (xy 285.820047 -63.437823) (xy 285.770447 -63.412322) (xy 285.725089 -63.379871)
			(xy 285.68494 -63.341162) (xy 285.650854 -63.297019) (xy 285.623558 -63.248384) (xy 285.603635 -63.196293)
			(xy 285.591509 -63.141856) (xy 285.587438 -63.086234) (xy 282.339561 -63.086234) (xy 282.345097 -63.105087)
			(xy 282.352855 -63.159044) (xy 282.352855 -63.213556) (xy 282.345097 -63.267513) (xy 282.329738 -63.319816)
			(xy 282.307091 -63.369401) (xy 282.277617 -63.415258) (xy 282.241917 -63.456453) (xy 282.200717 -63.492147)
			(xy 282.154857 -63.521615) (xy 282.105269 -63.544255) (xy 282.052964 -63.559607) (xy 281.999006 -63.567359)
			(xy 281.97175 -63.567818) (xy 281.94438 -63.567343) (xy 281.8902 -63.55953) (xy 281.837697 -63.544044)
			(xy 281.787949 -63.521204) (xy 281.741983 -63.49148) (xy 281.721052 -63.473838) (xy 281.720798 -63.473584)
			(xy 281.713717 -63.467989) (xy 281.696796 -63.461748) (xy 281.687778 -63.461392) (xy 281.620722 -63.461392)
			(xy 281.611706 -63.461761) (xy 281.594789 -63.468) (xy 281.587702 -63.473584) (xy 281.587448 -63.473838)
			(xy 281.566515 -63.491479) (xy 281.520547 -63.521203) (xy 281.470801 -63.544049) (xy 281.418299 -63.559545)
			(xy 281.364121 -63.567374) (xy 281.309379 -63.567374) (xy 281.255201 -63.559545) (xy 281.202699 -63.544049)
			(xy 281.152953 -63.521203) (xy 281.106985 -63.491479) (xy 281.086052 -63.473838) (xy 281.085798 -63.473584)
			(xy 281.078717 -63.467989) (xy 281.061796 -63.461748) (xy 281.052778 -63.461392) (xy 280.985722 -63.461392)
			(xy 280.976706 -63.461761) (xy 280.959789 -63.468) (xy 280.952702 -63.473584) (xy 280.952702 -63.473838)
			(xy 280.952448 -63.473838) (xy 280.931514 -63.491474) (xy 280.885541 -63.521185) (xy 280.835794 -63.544021)
			(xy 280.783294 -63.559513) (xy 280.729119 -63.567343) (xy 280.70175 -63.567818) (xy 280.674502 -63.567308)
			(xy 280.620561 -63.559546) (xy 280.568274 -63.544187) (xy 280.518704 -63.521544) (xy 280.472861 -63.492077)
			(xy 280.431678 -63.456386) (xy 280.395993 -63.415199) (xy 280.366532 -63.369352) (xy 280.343895 -63.319779)
			(xy 280.328543 -63.26749) (xy 280.320788 -63.213548) (xy 277.336536 -63.213548) (xy 277.336536 -63.245552)
			(xy 277.32878 -63.299501) (xy 277.313424 -63.351798) (xy 277.290782 -63.401377) (xy 277.261315 -63.447228)
			(xy 277.225623 -63.48842) (xy 277.184432 -63.524113) (xy 277.13858 -63.55358) (xy 277.089002 -63.576223)
			(xy 277.036705 -63.591579) (xy 276.982756 -63.599336) (xy 276.955504 -63.599822) (xy 276.928133 -63.599373)
			(xy 276.873952 -63.591554) (xy 276.821448 -63.576062) (xy 276.771702 -63.553216) (xy 276.725736 -63.523486)
			(xy 276.704806 -63.505842) (xy 276.704552 -63.505588) (xy 276.697456 -63.500016) (xy 276.680546 -63.493761)
			(xy 276.671532 -63.493396) (xy 276.604476 -63.493396) (xy 276.595458 -63.493743) (xy 276.578541 -63.499998)
			(xy 276.571456 -63.505588) (xy 276.571202 -63.505842) (xy 276.550269 -63.523483) (xy 276.504301 -63.553207)
			(xy 276.454555 -63.576053) (xy 276.402053 -63.591549) (xy 276.347875 -63.599378) (xy 276.293133 -63.599378)
			(xy 276.238955 -63.591549) (xy 276.186453 -63.576053) (xy 276.136707 -63.553207) (xy 276.090739 -63.523483)
			(xy 276.069806 -63.505842) (xy 276.069552 -63.505588) (xy 276.062456 -63.500016) (xy 276.045546 -63.493761)
			(xy 276.036532 -63.493396) (xy 275.969476 -63.493396) (xy 275.960458 -63.493743) (xy 275.943541 -63.499998)
			(xy 275.936456 -63.505588) (xy 275.936456 -63.505842) (xy 275.936202 -63.505842) (xy 275.915286 -63.523501)
			(xy 275.869308 -63.553208) (xy 275.819556 -63.57604) (xy 275.767052 -63.591527) (xy 275.712874 -63.599351)
			(xy 275.685504 -63.599822) (xy 275.658252 -63.599331) (xy 275.604303 -63.591575) (xy 275.552006 -63.57622)
			(xy 275.502427 -63.553578) (xy 275.456575 -63.524111) (xy 275.415384 -63.488419) (xy 275.379691 -63.447228)
			(xy 275.350224 -63.401376) (xy 275.327582 -63.351798) (xy 275.312226 -63.299501) (xy 275.304469 -63.245552)
			(xy 262.615986 -63.245552) (xy 262.616442 -63.273432) (xy 262.615952 -63.3034) (xy 262.608129 -63.362822)
			(xy 262.592616 -63.420715) (xy 262.56968 -63.476088) (xy 262.539713 -63.527994) (xy 262.503226 -63.575544)
			(xy 262.460846 -63.617924) (xy 262.413296 -63.654411) (xy 262.36139 -63.684378) (xy 262.306017 -63.707314)
			(xy 262.248124 -63.722827) (xy 262.188702 -63.73065) (xy 262.128766 -63.73065) (xy 262.069344 -63.722827)
			(xy 262.011451 -63.707314) (xy 261.956078 -63.684378) (xy 261.904172 -63.654411) (xy 261.856622 -63.617924)
			(xy 261.814242 -63.575544) (xy 261.777755 -63.527994) (xy 261.747788 -63.476088) (xy 261.724852 -63.420715)
			(xy 261.709339 -63.362822) (xy 261.701516 -63.3034) (xy 260.282667 -63.3034) (xy 260.271874 -63.319713)
			(xy 260.234657 -63.36125) (xy 260.191789 -63.396925) (xy 260.144183 -63.425979) (xy 260.092854 -63.447791)
			(xy 260.038897 -63.461897) (xy 259.98346 -63.467997) (xy 259.927726 -63.46596) (xy 259.872883 -63.45583)
			(xy 259.820099 -63.437823) (xy 259.770499 -63.412322) (xy 259.725141 -63.379871) (xy 259.684992 -63.341162)
			(xy 259.650906 -63.297019) (xy 259.62361 -63.248384) (xy 259.603687 -63.196293) (xy 259.591561 -63.141856)
			(xy 259.58749 -63.086234) (xy 256.339537 -63.086234) (xy 256.345076 -63.105099) (xy 256.352832 -63.159048)
			(xy 256.352832 -63.213552) (xy 256.345076 -63.267501) (xy 256.32972 -63.319797) (xy 256.307079 -63.369375)
			(xy 256.277612 -63.415227) (xy 256.241919 -63.456418) (xy 256.200728 -63.49211) (xy 256.154877 -63.521578)
			(xy 256.105299 -63.544219) (xy 256.053003 -63.559575) (xy 255.999054 -63.567332) (xy 255.971802 -63.567818)
			(xy 255.944431 -63.567371) (xy 255.89025 -63.559551) (xy 255.837746 -63.544059) (xy 255.787999 -63.521213)
			(xy 255.742034 -63.491482) (xy 255.721104 -63.473838) (xy 255.72085 -63.473584) (xy 255.713755 -63.46801)
			(xy 255.696845 -63.461756) (xy 255.68783 -63.461392) (xy 255.620774 -63.461392) (xy 255.611756 -63.461739)
			(xy 255.594839 -63.467994) (xy 255.587754 -63.473584) (xy 255.5875 -63.473838) (xy 255.566567 -63.491479)
			(xy 255.520599 -63.521203) (xy 255.470853 -63.544049) (xy 255.418351 -63.559545) (xy 255.364173 -63.567374)
			(xy 255.309431 -63.567374) (xy 255.255253 -63.559545) (xy 255.202751 -63.544049) (xy 255.153005 -63.521203)
			(xy 255.107037 -63.491479) (xy 255.086104 -63.473838) (xy 255.08585 -63.473584) (xy 255.078755 -63.46801)
			(xy 255.061845 -63.461756) (xy 255.05283 -63.461392) (xy 254.985774 -63.461392) (xy 254.976756 -63.461739)
			(xy 254.959839 -63.467994) (xy 254.952754 -63.473584) (xy 254.952754 -63.473838) (xy 254.9525 -63.473838)
			(xy 254.931584 -63.491497) (xy 254.885606 -63.521205) (xy 254.835855 -63.544036) (xy 254.783351 -63.559523)
			(xy 254.729172 -63.567347) (xy 254.701802 -63.567818) (xy 254.67455 -63.567335) (xy 254.6206 -63.559578)
			(xy 254.568303 -63.544223) (xy 254.518724 -63.521581) (xy 254.472872 -63.492114) (xy 254.43168 -63.456421)
			(xy 254.395987 -63.41523) (xy 254.36652 -63.369378) (xy 254.343878 -63.319799) (xy 254.328522 -63.267502)
			(xy 254.320765 -63.213552) (xy 251.336659 -63.213552) (xy 251.336659 -63.245556) (xy 251.328901 -63.299513)
			(xy 251.313542 -63.351816) (xy 251.290895 -63.401401) (xy 251.261422 -63.447258) (xy 251.225722 -63.488453)
			(xy 251.184523 -63.524148) (xy 251.138662 -63.553616) (xy 251.089075 -63.576257) (xy 251.03677 -63.59161)
			(xy 250.982812 -63.599362) (xy 250.955556 -63.599822) (xy 250.928186 -63.599342) (xy 250.874007 -63.591531)
			(xy 250.821503 -63.576046) (xy 250.771756 -63.553207) (xy 250.725789 -63.523483) (xy 250.704858 -63.505842)
			(xy 250.704604 -63.505588) (xy 250.697521 -63.499996) (xy 250.680602 -63.493753) (xy 250.671584 -63.493396)
			(xy 250.604528 -63.493396) (xy 250.595513 -63.493767) (xy 250.578596 -63.500005) (xy 250.571508 -63.505588)
			(xy 250.571254 -63.505842) (xy 250.550321 -63.523483) (xy 250.504353 -63.553207) (xy 250.454607 -63.576053)
			(xy 250.402105 -63.591549) (xy 250.347927 -63.599378) (xy 250.293185 -63.599378) (xy 250.239007 -63.591549)
			(xy 250.186505 -63.576053) (xy 250.136759 -63.553207) (xy 250.090791 -63.523483) (xy 250.069858 -63.505842)
			(xy 250.069604 -63.505588) (xy 250.062521 -63.499996) (xy 250.045602 -63.493753) (xy 250.036584 -63.493396)
			(xy 249.969528 -63.493396) (xy 249.960513 -63.493767) (xy 249.943596 -63.500005) (xy 249.936508 -63.505588)
			(xy 249.936508 -63.505842) (xy 249.936254 -63.505842) (xy 249.915318 -63.523476) (xy 249.869346 -63.553187)
			(xy 249.819599 -63.576024) (xy 249.7671 -63.591516) (xy 249.712925 -63.599347) (xy 249.685556 -63.599822)
			(xy 249.658308 -63.599305) (xy 249.604367 -63.591543) (xy 249.552079 -63.576185) (xy 249.50251 -63.553542)
			(xy 249.456666 -63.524076) (xy 249.415483 -63.488386) (xy 249.379798 -63.447198) (xy 249.350337 -63.401352)
			(xy 249.3277 -63.351779) (xy 249.312347 -63.29949) (xy 249.304592 -63.245548) (xy 238.397692 -63.245548)
			(xy 238.399294 -63.248322) (xy 238.42223 -63.303695) (xy 238.437743 -63.361588) (xy 238.445566 -63.42101)
			(xy 238.446056 -63.450978) (xy 238.445566 -63.480946) (xy 238.437743 -63.540368) (xy 238.42223 -63.598261)
			(xy 238.401594 -63.648082) (xy 241.242594 -63.648082) (xy 241.246665 -63.59246) (xy 241.258791 -63.538023)
			(xy 241.278714 -63.485932) (xy 241.30601 -63.437297) (xy 241.340096 -63.393154) (xy 241.380245 -63.354445)
			(xy 241.425603 -63.321994) (xy 241.475203 -63.296493) (xy 241.527987 -63.278486) (xy 241.58283 -63.268356)
			(xy 241.638564 -63.266319) (xy 241.694001 -63.272419) (xy 241.747958 -63.286525) (xy 241.799287 -63.308337)
			(xy 241.846893 -63.337391) (xy 241.889761 -63.373066) (xy 241.926978 -63.414603) (xy 241.957751 -63.461116)
			(xy 241.981423 -63.511613) (xy 241.997491 -63.56502) (xy 242.005611 -63.620196) (xy 242.00612 -63.648082)
			(xy 242.005611 -63.675968) (xy 241.997491 -63.731144) (xy 241.981423 -63.784551) (xy 241.957751 -63.835048)
			(xy 241.926978 -63.881561) (xy 241.889761 -63.923098) (xy 241.846893 -63.958773) (xy 241.799287 -63.987827)
			(xy 241.747958 -64.009639) (xy 241.694001 -64.023745) (xy 241.638564 -64.029845) (xy 241.58283 -64.027808)
			(xy 241.527987 -64.017678) (xy 241.475203 -63.999671) (xy 241.425603 -63.97417) (xy 241.380245 -63.941719)
			(xy 241.340096 -63.90301) (xy 241.30601 -63.858867) (xy 241.278714 -63.810232) (xy 241.258791 -63.758141)
			(xy 241.246665 -63.703704) (xy 241.242594 -63.648082) (xy 238.401594 -63.648082) (xy 238.399294 -63.653634)
			(xy 238.369327 -63.70554) (xy 238.33284 -63.75309) (xy 238.29046 -63.79547) (xy 238.24291 -63.831957)
			(xy 238.191004 -63.861924) (xy 238.135631 -63.88486) (xy 238.077738 -63.900373) (xy 238.018316 -63.908196)
			(xy 237.95838 -63.908196) (xy 237.898958 -63.900373) (xy 237.841065 -63.88486) (xy 237.785692 -63.861924)
			(xy 237.733786 -63.831957) (xy 237.686236 -63.79547) (xy 237.643856 -63.75309) (xy 237.607369 -63.70554)
			(xy 237.577402 -63.653634) (xy 237.554466 -63.598261) (xy 237.538953 -63.540368) (xy 237.53113 -63.480946)
			(xy 230.059992 -63.480946) (xy 230.059992 -64.200024) (xy 231.00614 -64.200024) (xy 231.010211 -64.144402)
			(xy 231.022337 -64.089965) (xy 231.04226 -64.037874) (xy 231.069556 -63.989239) (xy 231.103642 -63.945096)
			(xy 231.143791 -63.906387) (xy 231.189149 -63.873936) (xy 231.238749 -63.848435) (xy 231.291533 -63.830428)
			(xy 231.346376 -63.820298) (xy 231.40211 -63.818261) (xy 231.457547 -63.824361) (xy 231.511504 -63.838467)
			(xy 231.562833 -63.860279) (xy 231.610439 -63.889333) (xy 231.653307 -63.925008) (xy 231.690524 -63.966545)
			(xy 231.721297 -64.013058) (xy 231.744969 -64.063555) (xy 231.761037 -64.116962) (xy 231.769157 -64.172138)
			(xy 231.769666 -64.200024) (xy 231.769157 -64.22791) (xy 231.764215 -64.261492) (xy 239.918238 -64.261492)
			(xy 239.922309 -64.20587) (xy 239.934435 -64.151433) (xy 239.954358 -64.099342) (xy 239.981654 -64.050707)
			(xy 240.01574 -64.006564) (xy 240.055889 -63.967855) (xy 240.101247 -63.935404) (xy 240.150847 -63.909903)
			(xy 240.203631 -63.891896) (xy 240.258474 -63.881766) (xy 240.314208 -63.879729) (xy 240.369645 -63.885829)
			(xy 240.423602 -63.899935) (xy 240.474931 -63.921747) (xy 240.522537 -63.950801) (xy 240.565405 -63.986476)
			(xy 240.602622 -64.028013) (xy 240.633395 -64.074526) (xy 240.646384 -64.102234) (xy 259.58749 -64.102234)
			(xy 259.591561 -64.046612) (xy 259.603687 -63.992175) (xy 259.62361 -63.940084) (xy 259.650906 -63.891449)
			(xy 259.684992 -63.847306) (xy 259.725141 -63.808597) (xy 259.770499 -63.776146) (xy 259.820099 -63.750645)
			(xy 259.872883 -63.732638) (xy 259.927726 -63.722508) (xy 259.98346 -63.720471) (xy 260.038897 -63.726571)
			(xy 260.092854 -63.740677) (xy 260.144183 -63.762489) (xy 260.191789 -63.791543) (xy 260.234657 -63.827218)
			(xy 260.271874 -63.868755) (xy 260.302647 -63.915268) (xy 260.326319 -63.965765) (xy 260.342387 -64.019172)
			(xy 260.350507 -64.074348) (xy 260.351016 -64.102234) (xy 260.350507 -64.13012) (xy 260.342387 -64.185296)
			(xy 260.326319 -64.238703) (xy 260.302647 -64.2892) (xy 260.287369 -64.312292) (xy 263.265918 -64.312292)
			(xy 263.269989 -64.25667) (xy 263.282115 -64.202233) (xy 263.302038 -64.150142) (xy 263.329334 -64.101507)
			(xy 263.36342 -64.057364) (xy 263.403569 -64.018655) (xy 263.448927 -63.986204) (xy 263.498527 -63.960703)
			(xy 263.551311 -63.942696) (xy 263.606154 -63.932566) (xy 263.661888 -63.930529) (xy 263.717325 -63.936629)
			(xy 263.771282 -63.950735) (xy 263.822611 -63.972547) (xy 263.870217 -64.001601) (xy 263.913085 -64.037276)
			(xy 263.950302 -64.078813) (xy 263.965797 -64.102234) (xy 285.587438 -64.102234) (xy 285.591509 -64.046612)
			(xy 285.603635 -63.992175) (xy 285.623558 -63.940084) (xy 285.650854 -63.891449) (xy 285.68494 -63.847306)
			(xy 285.725089 -63.808597) (xy 285.770447 -63.776146) (xy 285.820047 -63.750645) (xy 285.872831 -63.732638)
			(xy 285.927674 -63.722508) (xy 285.983408 -63.720471) (xy 286.038845 -63.726571) (xy 286.092802 -63.740677)
			(xy 286.144131 -63.762489) (xy 286.191737 -63.791543) (xy 286.234605 -63.827218) (xy 286.271822 -63.868755)
			(xy 286.302595 -63.915268) (xy 286.326267 -63.965765) (xy 286.342335 -64.019172) (xy 286.350455 -64.074348)
			(xy 286.350964 -64.102234) (xy 286.350455 -64.13012) (xy 286.342335 -64.185296) (xy 286.326267 -64.238703)
			(xy 286.302595 -64.2892) (xy 286.287317 -64.312292) (xy 289.265866 -64.312292) (xy 289.269937 -64.25667)
			(xy 289.282063 -64.202233) (xy 289.301986 -64.150142) (xy 289.329282 -64.101507) (xy 289.363368 -64.057364)
			(xy 289.403517 -64.018655) (xy 289.448875 -63.986204) (xy 289.498475 -63.960703) (xy 289.551259 -63.942696)
			(xy 289.606102 -63.932566) (xy 289.661836 -63.930529) (xy 289.717273 -63.936629) (xy 289.77123 -63.950735)
			(xy 289.822559 -63.972547) (xy 289.870165 -64.001601) (xy 289.913033 -64.037276) (xy 289.95025 -64.078813)
			(xy 289.981023 -64.125326) (xy 290.004695 -64.175823) (xy 290.020763 -64.22923) (xy 290.028883 -64.284406)
			(xy 290.029392 -64.312292) (xy 290.028883 -64.340178) (xy 290.028577 -64.34226) (xy 291.030642 -64.34226)
			(xy 291.030642 -64.282324) (xy 291.038465 -64.222902) (xy 291.053978 -64.165009) (xy 291.076914 -64.109636)
			(xy 291.106881 -64.05773) (xy 291.143368 -64.01018) (xy 291.185748 -63.9678) (xy 291.233298 -63.931313)
			(xy 291.285204 -63.901346) (xy 291.340577 -63.87841) (xy 291.39847 -63.862897) (xy 291.457892 -63.855074)
			(xy 291.517828 -63.855074) (xy 291.57725 -63.862897) (xy 291.635143 -63.87841) (xy 291.690516 -63.901346)
			(xy 291.742422 -63.931313) (xy 291.789972 -63.9678) (xy 291.832352 -64.01018) (xy 291.868839 -64.05773)
			(xy 291.894533 -64.102234) (xy 311.587386 -64.102234) (xy 311.591457 -64.046612) (xy 311.603583 -63.992175)
			(xy 311.623506 -63.940084) (xy 311.650802 -63.891449) (xy 311.684888 -63.847306) (xy 311.725037 -63.808597)
			(xy 311.770395 -63.776146) (xy 311.819995 -63.750645) (xy 311.872779 -63.732638) (xy 311.927622 -63.722508)
			(xy 311.983356 -63.720471) (xy 312.038793 -63.726571) (xy 312.09275 -63.740677) (xy 312.144079 -63.762489)
			(xy 312.191685 -63.791543) (xy 312.234553 -63.827218) (xy 312.27177 -63.868755) (xy 312.302543 -63.915268)
			(xy 312.326215 -63.965765) (xy 312.342283 -64.019172) (xy 312.350403 -64.074348) (xy 312.350912 -64.102234)
			(xy 312.350403 -64.13012) (xy 312.342283 -64.185296) (xy 312.326215 -64.238703) (xy 312.302543 -64.2892)
			(xy 312.287265 -64.312292) (xy 315.265814 -64.312292) (xy 315.269885 -64.25667) (xy 315.282011 -64.202233)
			(xy 315.301934 -64.150142) (xy 315.32923 -64.101507) (xy 315.363316 -64.057364) (xy 315.403465 -64.018655)
			(xy 315.448823 -63.986204) (xy 315.498423 -63.960703) (xy 315.551207 -63.942696) (xy 315.60605 -63.932566)
			(xy 315.661784 -63.930529) (xy 315.717221 -63.936629) (xy 315.771178 -63.950735) (xy 315.822507 -63.972547)
			(xy 315.870113 -64.001601) (xy 315.912981 -64.037276) (xy 315.950198 -64.078813) (xy 315.965693 -64.102234)
			(xy 349.68764 -64.102234) (xy 349.691711 -64.046612) (xy 349.703837 -63.992175) (xy 349.72376 -63.940084)
			(xy 349.751056 -63.891449) (xy 349.785142 -63.847306) (xy 349.825291 -63.808597) (xy 349.870649 -63.776146)
			(xy 349.920249 -63.750645) (xy 349.973033 -63.732638) (xy 350.027876 -63.722508) (xy 350.08361 -63.720471)
			(xy 350.139047 -63.726571) (xy 350.193004 -63.740677) (xy 350.244333 -63.762489) (xy 350.291939 -63.791543)
			(xy 350.334807 -63.827218) (xy 350.372024 -63.868755) (xy 350.402797 -63.915268) (xy 350.426469 -63.965765)
			(xy 350.442537 -64.019172) (xy 350.450657 -64.074348) (xy 350.451166 -64.102234) (xy 350.450657 -64.13012)
			(xy 350.442537 -64.185296) (xy 350.426469 -64.238703) (xy 350.402797 -64.2892) (xy 350.387519 -64.312292)
			(xy 353.366068 -64.312292) (xy 353.370139 -64.25667) (xy 353.382265 -64.202233) (xy 353.402188 -64.150142)
			(xy 353.429484 -64.101507) (xy 353.46357 -64.057364) (xy 353.503719 -64.018655) (xy 353.549077 -63.986204)
			(xy 353.598677 -63.960703) (xy 353.651461 -63.942696) (xy 353.706304 -63.932566) (xy 353.762038 -63.930529)
			(xy 353.817475 -63.936629) (xy 353.871432 -63.950735) (xy 353.922761 -63.972547) (xy 353.970367 -64.001601)
			(xy 354.013235 -64.037276) (xy 354.050452 -64.078813) (xy 354.065947 -64.102234) (xy 375.687588 -64.102234)
			(xy 375.691659 -64.046612) (xy 375.703785 -63.992175) (xy 375.723708 -63.940084) (xy 375.751004 -63.891449)
			(xy 375.78509 -63.847306) (xy 375.825239 -63.808597) (xy 375.870597 -63.776146) (xy 375.920197 -63.750645)
			(xy 375.972981 -63.732638) (xy 376.027824 -63.722508) (xy 376.083558 -63.720471) (xy 376.138995 -63.726571)
			(xy 376.192952 -63.740677) (xy 376.244281 -63.762489) (xy 376.291887 -63.791543) (xy 376.334755 -63.827218)
			(xy 376.371972 -63.868755) (xy 376.402745 -63.915268) (xy 376.426417 -63.965765) (xy 376.442485 -64.019172)
			(xy 376.450605 -64.074348) (xy 376.451114 -64.102234) (xy 376.450605 -64.13012) (xy 376.442485 -64.185296)
			(xy 376.426417 -64.238703) (xy 376.402745 -64.2892) (xy 376.387467 -64.312292) (xy 379.366016 -64.312292)
			(xy 379.370087 -64.25667) (xy 379.382213 -64.202233) (xy 379.402136 -64.150142) (xy 379.429432 -64.101507)
			(xy 379.463518 -64.057364) (xy 379.503667 -64.018655) (xy 379.549025 -63.986204) (xy 379.598625 -63.960703)
			(xy 379.651409 -63.942696) (xy 379.706252 -63.932566) (xy 379.761986 -63.930529) (xy 379.817423 -63.936629)
			(xy 379.87138 -63.950735) (xy 379.922709 -63.972547) (xy 379.970315 -64.001601) (xy 380.013183 -64.037276)
			(xy 380.0504 -64.078813) (xy 380.065895 -64.102234) (xy 401.687536 -64.102234) (xy 401.691607 -64.046612)
			(xy 401.703733 -63.992175) (xy 401.723656 -63.940084) (xy 401.750952 -63.891449) (xy 401.785038 -63.847306)
			(xy 401.825187 -63.808597) (xy 401.870545 -63.776146) (xy 401.920145 -63.750645) (xy 401.972929 -63.732638)
			(xy 402.027772 -63.722508) (xy 402.083506 -63.720471) (xy 402.138943 -63.726571) (xy 402.1929 -63.740677)
			(xy 402.244229 -63.762489) (xy 402.291835 -63.791543) (xy 402.334703 -63.827218) (xy 402.37192 -63.868755)
			(xy 402.402693 -63.915268) (xy 402.426365 -63.965765) (xy 402.442433 -64.019172) (xy 402.450553 -64.074348)
			(xy 402.451062 -64.102234) (xy 402.450553 -64.13012) (xy 402.442433 -64.185296) (xy 402.426365 -64.238703)
			(xy 402.402693 -64.2892) (xy 402.387415 -64.312292) (xy 405.365964 -64.312292) (xy 405.370035 -64.25667)
			(xy 405.382161 -64.202233) (xy 405.402084 -64.150142) (xy 405.42938 -64.101507) (xy 405.463466 -64.057364)
			(xy 405.503615 -64.018655) (xy 405.548973 -63.986204) (xy 405.598573 -63.960703) (xy 405.651357 -63.942696)
			(xy 405.7062 -63.932566) (xy 405.761934 -63.930529) (xy 405.817371 -63.936629) (xy 405.871328 -63.950735)
			(xy 405.922657 -63.972547) (xy 405.970263 -64.001601) (xy 406.013131 -64.037276) (xy 406.050348 -64.078813)
			(xy 406.081121 -64.125326) (xy 406.104793 -64.175823) (xy 406.120861 -64.22923) (xy 406.128981 -64.284406)
			(xy 406.12949 -64.312292) (xy 406.128981 -64.340178) (xy 406.128675 -64.34226) (xy 407.13074 -64.34226)
			(xy 407.13074 -64.282324) (xy 407.138563 -64.222902) (xy 407.154076 -64.165009) (xy 407.177012 -64.109636)
			(xy 407.206979 -64.05773) (xy 407.243466 -64.01018) (xy 407.285846 -63.9678) (xy 407.333396 -63.931313)
			(xy 407.385302 -63.901346) (xy 407.440675 -63.87841) (xy 407.498568 -63.862897) (xy 407.55799 -63.855074)
			(xy 407.617926 -63.855074) (xy 407.677348 -63.862897) (xy 407.735241 -63.87841) (xy 407.790614 -63.901346)
			(xy 407.84252 -63.931313) (xy 407.89007 -63.9678) (xy 407.93245 -64.01018) (xy 407.968937 -64.05773)
			(xy 407.994631 -64.102234) (xy 427.687484 -64.102234) (xy 427.691555 -64.046612) (xy 427.703681 -63.992175)
			(xy 427.723604 -63.940084) (xy 427.7509 -63.891449) (xy 427.784986 -63.847306) (xy 427.825135 -63.808597)
			(xy 427.870493 -63.776146) (xy 427.920093 -63.750645) (xy 427.972877 -63.732638) (xy 428.02772 -63.722508)
			(xy 428.083454 -63.720471) (xy 428.138891 -63.726571) (xy 428.192848 -63.740677) (xy 428.244177 -63.762489)
			(xy 428.291783 -63.791543) (xy 428.334651 -63.827218) (xy 428.371868 -63.868755) (xy 428.402641 -63.915268)
			(xy 428.426313 -63.965765) (xy 428.442381 -64.019172) (xy 428.450501 -64.074348) (xy 428.45101 -64.102234)
			(xy 428.450501 -64.13012) (xy 428.442381 -64.185296) (xy 428.426313 -64.238703) (xy 428.402641 -64.2892)
			(xy 428.387363 -64.312292) (xy 431.365912 -64.312292) (xy 431.369983 -64.25667) (xy 431.382109 -64.202233)
			(xy 431.402032 -64.150142) (xy 431.429328 -64.101507) (xy 431.463414 -64.057364) (xy 431.503563 -64.018655)
			(xy 431.548921 -63.986204) (xy 431.598521 -63.960703) (xy 431.651305 -63.942696) (xy 431.706148 -63.932566)
			(xy 431.761882 -63.930529) (xy 431.817319 -63.936629) (xy 431.871276 -63.950735) (xy 431.922605 -63.972547)
			(xy 431.970211 -64.001601) (xy 432.013079 -64.037276) (xy 432.050296 -64.078813) (xy 432.081069 -64.125326)
			(xy 432.104741 -64.175823) (xy 432.120809 -64.22923) (xy 432.128929 -64.284406) (xy 432.129438 -64.312292)
			(xy 432.128929 -64.340178) (xy 432.120809 -64.395354) (xy 432.104741 -64.448761) (xy 432.081069 -64.499258)
			(xy 432.050296 -64.545771) (xy 432.013079 -64.587308) (xy 431.970211 -64.622983) (xy 431.922605 -64.652037)
			(xy 431.871276 -64.673849) (xy 431.817319 -64.687955) (xy 431.761882 -64.694055) (xy 431.706148 -64.692018)
			(xy 431.651305 -64.681888) (xy 431.598521 -64.663881) (xy 431.548921 -64.63838) (xy 431.503563 -64.605929)
			(xy 431.463414 -64.56722) (xy 431.429328 -64.523077) (xy 431.402032 -64.474442) (xy 431.382109 -64.422351)
			(xy 431.369983 -64.367914) (xy 431.365912 -64.312292) (xy 428.387363 -64.312292) (xy 428.371868 -64.335713)
			(xy 428.334651 -64.37725) (xy 428.291783 -64.412925) (xy 428.244177 -64.441979) (xy 428.192848 -64.463791)
			(xy 428.138891 -64.477897) (xy 428.083454 -64.483997) (xy 428.02772 -64.48196) (xy 427.972877 -64.47183)
			(xy 427.920093 -64.453823) (xy 427.870493 -64.428322) (xy 427.825135 -64.395871) (xy 427.784986 -64.357162)
			(xy 427.7509 -64.313019) (xy 427.723604 -64.264384) (xy 427.703681 -64.212293) (xy 427.691555 -64.157856)
			(xy 427.687484 -64.102234) (xy 407.994631 -64.102234) (xy 407.998904 -64.109636) (xy 408.02184 -64.165009)
			(xy 408.037353 -64.222902) (xy 408.045176 -64.282324) (xy 408.045666 -64.312292) (xy 408.045176 -64.34226)
			(xy 408.037353 -64.401682) (xy 408.02184 -64.459575) (xy 407.998904 -64.514948) (xy 407.968937 -64.566854)
			(xy 407.93245 -64.614404) (xy 407.89007 -64.656784) (xy 407.84252 -64.693271) (xy 407.790614 -64.723238)
			(xy 407.735241 -64.746174) (xy 407.677348 -64.761687) (xy 407.617926 -64.76951) (xy 407.55799 -64.76951)
			(xy 407.498568 -64.761687) (xy 407.440675 -64.746174) (xy 407.385302 -64.723238) (xy 407.333396 -64.693271)
			(xy 407.285846 -64.656784) (xy 407.243466 -64.614404) (xy 407.206979 -64.566854) (xy 407.177012 -64.514948)
			(xy 407.154076 -64.459575) (xy 407.138563 -64.401682) (xy 407.13074 -64.34226) (xy 406.128675 -64.34226)
			(xy 406.120861 -64.395354) (xy 406.104793 -64.448761) (xy 406.081121 -64.499258) (xy 406.050348 -64.545771)
			(xy 406.013131 -64.587308) (xy 405.970263 -64.622983) (xy 405.922657 -64.652037) (xy 405.871328 -64.673849)
			(xy 405.817371 -64.687955) (xy 405.761934 -64.694055) (xy 405.7062 -64.692018) (xy 405.651357 -64.681888)
			(xy 405.598573 -64.663881) (xy 405.548973 -64.63838) (xy 405.503615 -64.605929) (xy 405.463466 -64.56722)
			(xy 405.42938 -64.523077) (xy 405.402084 -64.474442) (xy 405.382161 -64.422351) (xy 405.370035 -64.367914)
			(xy 405.365964 -64.312292) (xy 402.387415 -64.312292) (xy 402.37192 -64.335713) (xy 402.334703 -64.37725)
			(xy 402.291835 -64.412925) (xy 402.244229 -64.441979) (xy 402.1929 -64.463791) (xy 402.138943 -64.477897)
			(xy 402.083506 -64.483997) (xy 402.027772 -64.48196) (xy 401.972929 -64.47183) (xy 401.920145 -64.453823)
			(xy 401.870545 -64.428322) (xy 401.825187 -64.395871) (xy 401.785038 -64.357162) (xy 401.750952 -64.313019)
			(xy 401.723656 -64.264384) (xy 401.703733 -64.212293) (xy 401.691607 -64.157856) (xy 401.687536 -64.102234)
			(xy 380.065895 -64.102234) (xy 380.081173 -64.125326) (xy 380.104845 -64.175823) (xy 380.120913 -64.22923)
			(xy 380.129033 -64.284406) (xy 380.129542 -64.312292) (xy 380.129033 -64.340178) (xy 380.120913 -64.395354)
			(xy 380.104845 -64.448761) (xy 380.081173 -64.499258) (xy 380.0504 -64.545771) (xy 380.013183 -64.587308)
			(xy 379.970315 -64.622983) (xy 379.922709 -64.652037) (xy 379.87138 -64.673849) (xy 379.817423 -64.687955)
			(xy 379.761986 -64.694055) (xy 379.706252 -64.692018) (xy 379.651409 -64.681888) (xy 379.598625 -64.663881)
			(xy 379.549025 -64.63838) (xy 379.503667 -64.605929) (xy 379.463518 -64.56722) (xy 379.429432 -64.523077)
			(xy 379.402136 -64.474442) (xy 379.382213 -64.422351) (xy 379.370087 -64.367914) (xy 379.366016 -64.312292)
			(xy 376.387467 -64.312292) (xy 376.371972 -64.335713) (xy 376.334755 -64.37725) (xy 376.291887 -64.412925)
			(xy 376.244281 -64.441979) (xy 376.192952 -64.463791) (xy 376.138995 -64.477897) (xy 376.083558 -64.483997)
			(xy 376.027824 -64.48196) (xy 375.972981 -64.47183) (xy 375.920197 -64.453823) (xy 375.870597 -64.428322)
			(xy 375.825239 -64.395871) (xy 375.78509 -64.357162) (xy 375.751004 -64.313019) (xy 375.723708 -64.264384)
			(xy 375.703785 -64.212293) (xy 375.691659 -64.157856) (xy 375.687588 -64.102234) (xy 354.065947 -64.102234)
			(xy 354.081225 -64.125326) (xy 354.104897 -64.175823) (xy 354.120965 -64.22923) (xy 354.129085 -64.284406)
			(xy 354.129594 -64.312292) (xy 354.129085 -64.340178) (xy 354.120965 -64.395354) (xy 354.104897 -64.448761)
			(xy 354.081225 -64.499258) (xy 354.050452 -64.545771) (xy 354.013235 -64.587308) (xy 353.970367 -64.622983)
			(xy 353.922761 -64.652037) (xy 353.871432 -64.673849) (xy 353.817475 -64.687955) (xy 353.762038 -64.694055)
			(xy 353.706304 -64.692018) (xy 353.651461 -64.681888) (xy 353.598677 -64.663881) (xy 353.549077 -64.63838)
			(xy 353.503719 -64.605929) (xy 353.46357 -64.56722) (xy 353.429484 -64.523077) (xy 353.402188 -64.474442)
			(xy 353.382265 -64.422351) (xy 353.370139 -64.367914) (xy 353.366068 -64.312292) (xy 350.387519 -64.312292)
			(xy 350.372024 -64.335713) (xy 350.334807 -64.37725) (xy 350.291939 -64.412925) (xy 350.244333 -64.441979)
			(xy 350.193004 -64.463791) (xy 350.139047 -64.477897) (xy 350.08361 -64.483997) (xy 350.027876 -64.48196)
			(xy 349.973033 -64.47183) (xy 349.920249 -64.453823) (xy 349.870649 -64.428322) (xy 349.825291 -64.395871)
			(xy 349.785142 -64.357162) (xy 349.751056 -64.313019) (xy 349.72376 -64.264384) (xy 349.703837 -64.212293)
			(xy 349.691711 -64.157856) (xy 349.68764 -64.102234) (xy 315.965693 -64.102234) (xy 315.980971 -64.125326)
			(xy 316.004643 -64.175823) (xy 316.020711 -64.22923) (xy 316.028831 -64.284406) (xy 316.02934 -64.312292)
			(xy 316.028831 -64.340178) (xy 316.020711 -64.395354) (xy 316.004643 -64.448761) (xy 315.980971 -64.499258)
			(xy 315.950198 -64.545771) (xy 315.912981 -64.587308) (xy 315.870113 -64.622983) (xy 315.822507 -64.652037)
			(xy 315.771178 -64.673849) (xy 315.717221 -64.687955) (xy 315.661784 -64.694055) (xy 315.60605 -64.692018)
			(xy 315.551207 -64.681888) (xy 315.498423 -64.663881) (xy 315.448823 -64.63838) (xy 315.403465 -64.605929)
			(xy 315.363316 -64.56722) (xy 315.32923 -64.523077) (xy 315.301934 -64.474442) (xy 315.282011 -64.422351)
			(xy 315.269885 -64.367914) (xy 315.265814 -64.312292) (xy 312.287265 -64.312292) (xy 312.27177 -64.335713)
			(xy 312.234553 -64.37725) (xy 312.191685 -64.412925) (xy 312.144079 -64.441979) (xy 312.09275 -64.463791)
			(xy 312.038793 -64.477897) (xy 311.983356 -64.483997) (xy 311.927622 -64.48196) (xy 311.872779 -64.47183)
			(xy 311.819995 -64.453823) (xy 311.770395 -64.428322) (xy 311.725037 -64.395871) (xy 311.684888 -64.357162)
			(xy 311.650802 -64.313019) (xy 311.623506 -64.264384) (xy 311.603583 -64.212293) (xy 311.591457 -64.157856)
			(xy 311.587386 -64.102234) (xy 291.894533 -64.102234) (xy 291.898806 -64.109636) (xy 291.921742 -64.165009)
			(xy 291.937255 -64.222902) (xy 291.945078 -64.282324) (xy 291.945568 -64.312292) (xy 291.945078 -64.34226)
			(xy 291.937255 -64.401682) (xy 291.921742 -64.459575) (xy 291.898806 -64.514948) (xy 291.868839 -64.566854)
			(xy 291.832352 -64.614404) (xy 291.789972 -64.656784) (xy 291.742422 -64.693271) (xy 291.690516 -64.723238)
			(xy 291.635143 -64.746174) (xy 291.57725 -64.761687) (xy 291.517828 -64.76951) (xy 291.457892 -64.76951)
			(xy 291.39847 -64.761687) (xy 291.340577 -64.746174) (xy 291.285204 -64.723238) (xy 291.233298 -64.693271)
			(xy 291.185748 -64.656784) (xy 291.143368 -64.614404) (xy 291.106881 -64.566854) (xy 291.076914 -64.514948)
			(xy 291.053978 -64.459575) (xy 291.038465 -64.401682) (xy 291.030642 -64.34226) (xy 290.028577 -64.34226)
			(xy 290.020763 -64.395354) (xy 290.004695 -64.448761) (xy 289.981023 -64.499258) (xy 289.95025 -64.545771)
			(xy 289.913033 -64.587308) (xy 289.870165 -64.622983) (xy 289.822559 -64.652037) (xy 289.77123 -64.673849)
			(xy 289.717273 -64.687955) (xy 289.661836 -64.694055) (xy 289.606102 -64.692018) (xy 289.551259 -64.681888)
			(xy 289.498475 -64.663881) (xy 289.448875 -64.63838) (xy 289.403517 -64.605929) (xy 289.363368 -64.56722)
			(xy 289.329282 -64.523077) (xy 289.301986 -64.474442) (xy 289.282063 -64.422351) (xy 289.269937 -64.367914)
			(xy 289.265866 -64.312292) (xy 286.287317 -64.312292) (xy 286.271822 -64.335713) (xy 286.234605 -64.37725)
			(xy 286.191737 -64.412925) (xy 286.144131 -64.441979) (xy 286.092802 -64.463791) (xy 286.038845 -64.477897)
			(xy 285.983408 -64.483997) (xy 285.927674 -64.48196) (xy 285.872831 -64.47183) (xy 285.820047 -64.453823)
			(xy 285.770447 -64.428322) (xy 285.725089 -64.395871) (xy 285.68494 -64.357162) (xy 285.650854 -64.313019)
			(xy 285.623558 -64.264384) (xy 285.603635 -64.212293) (xy 285.591509 -64.157856) (xy 285.587438 -64.102234)
			(xy 263.965797 -64.102234) (xy 263.981075 -64.125326) (xy 264.004747 -64.175823) (xy 264.020815 -64.22923)
			(xy 264.028935 -64.284406) (xy 264.029444 -64.312292) (xy 264.028935 -64.340178) (xy 264.020815 -64.395354)
			(xy 264.004747 -64.448761) (xy 263.981075 -64.499258) (xy 263.950302 -64.545771) (xy 263.913085 -64.587308)
			(xy 263.870217 -64.622983) (xy 263.822611 -64.652037) (xy 263.771282 -64.673849) (xy 263.717325 -64.687955)
			(xy 263.661888 -64.694055) (xy 263.606154 -64.692018) (xy 263.551311 -64.681888) (xy 263.498527 -64.663881)
			(xy 263.448927 -64.63838) (xy 263.403569 -64.605929) (xy 263.36342 -64.56722) (xy 263.329334 -64.523077)
			(xy 263.302038 -64.474442) (xy 263.282115 -64.422351) (xy 263.269989 -64.367914) (xy 263.265918 -64.312292)
			(xy 260.287369 -64.312292) (xy 260.271874 -64.335713) (xy 260.234657 -64.37725) (xy 260.191789 -64.412925)
			(xy 260.144183 -64.441979) (xy 260.092854 -64.463791) (xy 260.038897 -64.477897) (xy 259.98346 -64.483997)
			(xy 259.927726 -64.48196) (xy 259.872883 -64.47183) (xy 259.820099 -64.453823) (xy 259.770499 -64.428322)
			(xy 259.725141 -64.395871) (xy 259.684992 -64.357162) (xy 259.650906 -64.313019) (xy 259.62361 -64.264384)
			(xy 259.603687 -64.212293) (xy 259.591561 -64.157856) (xy 259.58749 -64.102234) (xy 240.646384 -64.102234)
			(xy 240.657067 -64.125023) (xy 240.673135 -64.17843) (xy 240.681255 -64.233606) (xy 240.681764 -64.261492)
			(xy 240.681255 -64.289378) (xy 240.673135 -64.344554) (xy 240.657067 -64.397961) (xy 240.633395 -64.448458)
			(xy 240.602622 -64.494971) (xy 240.565405 -64.536508) (xy 240.522537 -64.572183) (xy 240.474931 -64.601237)
			(xy 240.423602 -64.623049) (xy 240.369645 -64.637155) (xy 240.314208 -64.643255) (xy 240.258474 -64.641218)
			(xy 240.203631 -64.631088) (xy 240.150847 -64.613081) (xy 240.101247 -64.58758) (xy 240.055889 -64.555129)
			(xy 240.01574 -64.51642) (xy 239.981654 -64.472277) (xy 239.954358 -64.423642) (xy 239.934435 -64.371551)
			(xy 239.922309 -64.317114) (xy 239.918238 -64.261492) (xy 231.764215 -64.261492) (xy 231.761037 -64.283086)
			(xy 231.744969 -64.336493) (xy 231.721297 -64.38699) (xy 231.690524 -64.433503) (xy 231.653307 -64.47504)
			(xy 231.610439 -64.510715) (xy 231.562833 -64.539769) (xy 231.511504 -64.561581) (xy 231.457547 -64.575687)
			(xy 231.40211 -64.581787) (xy 231.346376 -64.57975) (xy 231.291533 -64.56962) (xy 231.238749 -64.551613)
			(xy 231.189149 -64.526112) (xy 231.143791 -64.493661) (xy 231.103642 -64.454952) (xy 231.069556 -64.410809)
			(xy 231.04226 -64.362174) (xy 231.022337 -64.310083) (xy 231.010211 -64.255646) (xy 231.00614 -64.200024)
			(xy 230.059992 -64.200024) (xy 230.059992 -64.799972) (xy 233.19054 -64.799972) (xy 233.194611 -64.74435)
			(xy 233.206737 -64.689913) (xy 233.22666 -64.637822) (xy 233.253956 -64.589187) (xy 233.288042 -64.545044)
			(xy 233.328191 -64.506335) (xy 233.373549 -64.473884) (xy 233.423149 -64.448383) (xy 233.475933 -64.430376)
			(xy 233.530776 -64.420246) (xy 233.58651 -64.418209) (xy 233.641947 -64.424309) (xy 233.695904 -64.438415)
			(xy 233.747233 -64.460227) (xy 233.794839 -64.489281) (xy 233.837707 -64.524956) (xy 233.874924 -64.566493)
			(xy 233.905697 -64.613006) (xy 233.929369 -64.663503) (xy 233.945437 -64.71691) (xy 233.953557 -64.772086)
			(xy 233.954066 -64.799972) (xy 233.953557 -64.827858) (xy 233.945437 -64.883034) (xy 233.929369 -64.936441)
			(xy 233.905697 -64.986938) (xy 233.874924 -65.033451) (xy 233.837707 -65.074988) (xy 233.794839 -65.110663)
			(xy 233.747233 -65.139717) (xy 233.695904 -65.161529) (xy 233.641947 -65.175635) (xy 233.58651 -65.181735)
			(xy 233.530776 -65.179698) (xy 233.475933 -65.169568) (xy 233.423149 -65.151561) (xy 233.373549 -65.12606)
			(xy 233.328191 -65.093609) (xy 233.288042 -65.0549) (xy 233.253956 -65.010757) (xy 233.22666 -64.962122)
			(xy 233.206737 -64.910031) (xy 233.194611 -64.855594) (xy 233.19054 -64.799972) (xy 230.059992 -64.799972)
			(xy 230.059992 -65.761108) (xy 230.060482 -65.771115) (xy 230.068142 -65.789605) (xy 230.082295 -65.803758)
			(xy 230.100785 -65.811418) (xy 230.110792 -65.811908) (xy 231.093264 -65.811908) (xy 231.094534 -65.811908)
			(xy 231.106987 -65.810979) (xy 231.128713 -65.798726) (xy 231.135936 -65.78854) (xy 231.139238 -65.782444)
			(xy 231.154224 -65.750694) (xy 231.158375 -65.740401) (xy 231.158383 -65.718232) (xy 231.1491 -65.698099)
			(xy 231.141016 -65.690496) (xy 231.120338 -65.672293) (xy 231.083926 -65.630952) (xy 231.053847 -65.584799)
			(xy 231.030729 -65.534796) (xy 231.015052 -65.481984) (xy 231.007144 -65.427465) (xy 231.00665 -65.39992)
			(xy 231.007134 -65.372667) (xy 231.014888 -65.318715) (xy 231.030241 -65.266415) (xy 231.052881 -65.216833)
			(xy 231.082346 -65.170977) (xy 231.118037 -65.129781) (xy 231.159227 -65.094083) (xy 231.205078 -65.064611)
			(xy 231.254657 -65.041963) (xy 231.306954 -65.026602) (xy 231.360905 -65.018839) (xy 231.388158 -65.018412)
			(xy 231.421432 -65.019682) (xy 231.430068 -65.019682) (xy 231.463342 -65.018412) (xy 231.490591 -65.018901)
			(xy 231.544533 -65.026663) (xy 231.596821 -65.042022) (xy 231.646392 -65.064665) (xy 231.692236 -65.094133)
			(xy 231.733419 -65.129825) (xy 231.769104 -65.171014) (xy 231.798564 -65.216863) (xy 231.8212 -65.266437)
			(xy 231.836551 -65.318728) (xy 231.844303 -65.372671) (xy 231.84485 -65.39992) (xy 231.844385 -65.426549)
			(xy 231.836976 -65.47929) (xy 231.822303 -65.530488) (xy 231.800653 -65.579147) (xy 231.772445 -65.624322)
			(xy 231.755696 -65.64503) (xy 231.751132 -65.65071) (xy 231.745179 -65.664001) (xy 231.744012 -65.671192)
			(xy 231.74325 -65.678304) (xy 231.745282 -65.692274) (xy 231.787446 -65.782444) (xy 231.790748 -65.78854)
			(xy 231.79802 -65.798673) (xy 231.819717 -65.810919) (xy 231.83215 -65.811908) (xy 233.19867 -65.811908)
			(xy 233.2049 -65.811695) (xy 233.216975 -65.808609) (xy 233.222546 -65.805812) (xy 233.25328 -65.789556)
			(xy 233.256074 -65.785492) (xy 233.25963 -65.780666) (xy 233.260138 -65.77965) (xy 233.275546 -65.758621)
			(xy 233.311183 -65.720571) (xy 233.351671 -65.68773) (xy 233.396254 -65.66071) (xy 233.444103 -65.640015)
			(xy 233.494325 -65.626031) (xy 233.545983 -65.619018) (xy 233.57205 -65.618614) (xy 233.59818 -65.619012)
			(xy 233.649957 -65.626082) (xy 233.700285 -65.640152) (xy 233.748223 -65.660958) (xy 233.792873 -65.688111)
			(xy 233.8334 -65.721103) (xy 233.869045 -65.759317) (xy 233.88447 -65.780412) (xy 233.887772 -65.785238)
			(xy 233.896662 -65.793112) (xy 233.920538 -65.805812) (xy 233.926107 -65.808617) (xy 233.938183 -65.811707)
			(xy 233.944414 -65.811908) (xy 246.496332 -65.811908) (xy 246.506336 -65.811414) (xy 246.524818 -65.803749)
			(xy 246.538963 -65.789598) (xy 246.546619 -65.771112) (xy 246.547132 -65.761108) (xy 246.547132 -65.75552)
			(xy 246.547618 -65.728269) (xy 246.555374 -65.674321) (xy 246.570729 -65.622026) (xy 246.593371 -65.572449)
			(xy 246.622837 -65.526599) (xy 246.658528 -65.485408) (xy 246.699719 -65.449717) (xy 246.745569 -65.420251)
			(xy 246.795146 -65.397609) (xy 246.847441 -65.382254) (xy 246.901389 -65.374498) (xy 246.955891 -65.374498)
			(xy 247.009839 -65.382254) (xy 247.062134 -65.397609) (xy 247.111711 -65.420251) (xy 247.157561 -65.449717)
			(xy 247.198752 -65.485408) (xy 247.234443 -65.526599) (xy 247.263909 -65.572449) (xy 247.286551 -65.622026)
			(xy 247.301906 -65.674321) (xy 247.309662 -65.728269) (xy 247.310148 -65.75552) (xy 247.310148 -65.761108)
			(xy 247.31057 -65.771125) (xy 247.318243 -65.789631) (xy 247.332416 -65.803789) (xy 247.350931 -65.811441)
			(xy 247.360948 -65.811908) (xy 248.636536 -65.811908) (xy 248.645956 -65.811465) (xy 248.663537 -65.804685)
			(xy 248.670826 -65.7987) (xy 248.69851 -65.774255) (xy 248.758145 -65.730681) (xy 248.822023 -65.693604)
			(xy 248.889438 -65.663433) (xy 248.959646 -65.640503) (xy 249.031873 -65.625064) (xy 249.105321 -65.617289)
			(xy 249.14225 -65.616836) (xy 251.3711 -65.616836) (xy 251.381332 -65.616361) (xy 251.400173 -65.608369)
			(xy 251.414426 -65.593681) (xy 251.418598 -65.584324) (xy 251.452888 -65.495932) (xy 251.456106 -65.48636)
			(xy 251.455534 -65.466189) (xy 251.447234 -65.447797) (xy 251.440188 -65.44056) (xy 251.439934 -65.440306)
			(xy 251.42091 -65.422187) (xy 251.387521 -65.381626) (xy 251.360018 -65.336865) (xy 251.338921 -65.288751)
			(xy 251.324631 -65.238196) (xy 251.317419 -65.186158) (xy 251.316998 -65.15989) (xy 251.317484 -65.132639)
			(xy 251.32524 -65.078691) (xy 251.340595 -65.026396) (xy 251.363237 -64.976819) (xy 251.392703 -64.930969)
			(xy 251.428394 -64.889778) (xy 251.469585 -64.854087) (xy 251.515435 -64.824621) (xy 251.565012 -64.801979)
			(xy 251.617307 -64.786624) (xy 251.671255 -64.778868) (xy 251.725757 -64.778868) (xy 251.779705 -64.786624)
			(xy 251.832 -64.801979) (xy 251.881577 -64.824621) (xy 251.927427 -64.854087) (xy 251.968618 -64.889778)
			(xy 252.004309 -64.930969) (xy 252.033775 -64.976819) (xy 252.056417 -65.026396) (xy 252.071772 -65.078691)
			(xy 252.074974 -65.100962) (xy 252.332488 -65.100962) (xy 252.336559 -65.04534) (xy 252.348685 -64.990903)
			(xy 252.368608 -64.938812) (xy 252.395904 -64.890177) (xy 252.42999 -64.846034) (xy 252.470139 -64.807325)
			(xy 252.515497 -64.774874) (xy 252.565097 -64.749373) (xy 252.617881 -64.731366) (xy 252.672724 -64.721236)
			(xy 252.728458 -64.719199) (xy 252.783895 -64.725299) (xy 252.837852 -64.739405) (xy 252.889181 -64.761217)
			(xy 252.936787 -64.790271) (xy 252.979655 -64.825946) (xy 253.016872 -64.867483) (xy 253.047645 -64.913996)
			(xy 253.071317 -64.964493) (xy 253.087385 -65.0179) (xy 253.095505 -65.073076) (xy 253.096014 -65.100962)
			(xy 253.095505 -65.128848) (xy 253.087385 -65.184024) (xy 253.071317 -65.237431) (xy 253.047645 -65.287928)
			(xy 253.016872 -65.334441) (xy 252.979655 -65.375978) (xy 252.936787 -65.411653) (xy 252.889181 -65.440707)
			(xy 252.837852 -65.462519) (xy 252.783895 -65.476625) (xy 252.728458 -65.482725) (xy 252.672724 -65.480688)
			(xy 252.617881 -65.470558) (xy 252.565097 -65.452551) (xy 252.515497 -65.42705) (xy 252.470139 -65.394599)
			(xy 252.42999 -65.35589) (xy 252.395904 -65.311747) (xy 252.368608 -65.263112) (xy 252.348685 -65.211021)
			(xy 252.336559 -65.156584) (xy 252.332488 -65.100962) (xy 252.074974 -65.100962) (xy 252.079528 -65.132639)
			(xy 252.080014 -65.15989) (xy 252.079575 -65.186158) (xy 252.072365 -65.238195) (xy 252.058079 -65.288751)
			(xy 252.036988 -65.336866) (xy 252.009491 -65.381631) (xy 251.97611 -65.422197) (xy 251.957078 -65.440306)
			(xy 251.956824 -65.44056) (xy 251.949762 -65.44778) (xy 251.941486 -65.466184) (xy 251.940915 -65.486356)
			(xy 251.944124 -65.495932) (xy 251.978414 -65.584324) (xy 251.982521 -65.593725) (xy 251.996774 -65.608453)
			(xy 252.015662 -65.616412) (xy 252.025912 -65.616836) (xy 253.4031 -65.616836) (xy 253.413332 -65.616361)
			(xy 253.432173 -65.608369) (xy 253.446426 -65.593681) (xy 253.450598 -65.584324) (xy 253.484888 -65.495932)
			(xy 253.488106 -65.48636) (xy 253.487534 -65.466189) (xy 253.479234 -65.447797) (xy 253.472188 -65.44056)
			(xy 253.471934 -65.440306) (xy 253.45291 -65.422187) (xy 253.419521 -65.381626) (xy 253.392018 -65.336865)
			(xy 253.370921 -65.288751) (xy 253.356631 -65.238196) (xy 253.349419 -65.186158) (xy 253.348998 -65.15989)
			(xy 253.349484 -65.132639) (xy 253.35724 -65.078691) (xy 253.372595 -65.026396) (xy 253.395237 -64.976819)
			(xy 253.424703 -64.930969) (xy 253.460394 -64.889778) (xy 253.501585 -64.854087) (xy 253.547435 -64.824621)
			(xy 253.597012 -64.801979) (xy 253.649307 -64.786624) (xy 253.703255 -64.778868) (xy 253.757757 -64.778868)
			(xy 253.811705 -64.786624) (xy 253.864 -64.801979) (xy 253.913577 -64.824621) (xy 253.959427 -64.854087)
			(xy 254.000618 -64.889778) (xy 254.036309 -64.930969) (xy 254.065775 -64.976819) (xy 254.088417 -65.026396)
			(xy 254.103772 -65.078691) (xy 254.111528 -65.132639) (xy 254.11191 -65.154044) (xy 264.232118 -65.154044)
			(xy 264.232118 -65.094108) (xy 264.239941 -65.034686) (xy 264.255454 -64.976793) (xy 264.27839 -64.92142)
			(xy 264.308357 -64.869514) (xy 264.344844 -64.821964) (xy 264.387224 -64.779584) (xy 264.434774 -64.743097)
			(xy 264.48668 -64.71313) (xy 264.542053 -64.690194) (xy 264.599946 -64.674681) (xy 264.659368 -64.666858)
			(xy 264.719304 -64.666858) (xy 264.778726 -64.674681) (xy 264.836619 -64.690194) (xy 264.891992 -64.71313)
			(xy 264.943898 -64.743097) (xy 264.991448 -64.779584) (xy 265.033828 -64.821964) (xy 265.070315 -64.869514)
			(xy 265.100282 -64.92142) (xy 265.123218 -64.976793) (xy 265.138731 -65.034686) (xy 265.146554 -65.094108)
			(xy 265.147044 -65.124076) (xy 265.146554 -65.154044) (xy 265.145784 -65.15989) (xy 277.316436 -65.15989)
			(xy 277.320507 -65.104268) (xy 277.332633 -65.049831) (xy 277.352556 -64.99774) (xy 277.379852 -64.949105)
			(xy 277.413938 -64.904962) (xy 277.454087 -64.866253) (xy 277.499445 -64.833802) (xy 277.549045 -64.808301)
			(xy 277.601829 -64.790294) (xy 277.656672 -64.780164) (xy 277.712406 -64.778127) (xy 277.767843 -64.784227)
			(xy 277.8218 -64.798333) (xy 277.873129 -64.820145) (xy 277.920735 -64.849199) (xy 277.963603 -64.884874)
			(xy 278.00082 -64.926411) (xy 278.031593 -64.972924) (xy 278.055265 -65.023421) (xy 278.071333 -65.076828)
			(xy 278.074885 -65.100962) (xy 278.332436 -65.100962) (xy 278.336507 -65.04534) (xy 278.348633 -64.990903)
			(xy 278.368556 -64.938812) (xy 278.395852 -64.890177) (xy 278.429938 -64.846034) (xy 278.470087 -64.807325)
			(xy 278.515445 -64.774874) (xy 278.565045 -64.749373) (xy 278.617829 -64.731366) (xy 278.672672 -64.721236)
			(xy 278.728406 -64.719199) (xy 278.783843 -64.725299) (xy 278.8378 -64.739405) (xy 278.889129 -64.761217)
			(xy 278.936735 -64.790271) (xy 278.979603 -64.825946) (xy 279.01682 -64.867483) (xy 279.047593 -64.913996)
			(xy 279.071265 -64.964493) (xy 279.087333 -65.0179) (xy 279.095453 -65.073076) (xy 279.095962 -65.100962)
			(xy 279.095453 -65.128848) (xy 279.090885 -65.15989) (xy 279.348436 -65.15989) (xy 279.352507 -65.104268)
			(xy 279.364633 -65.049831) (xy 279.384556 -64.99774) (xy 279.411852 -64.949105) (xy 279.445938 -64.904962)
			(xy 279.486087 -64.866253) (xy 279.531445 -64.833802) (xy 279.581045 -64.808301) (xy 279.633829 -64.790294)
			(xy 279.688672 -64.780164) (xy 279.744406 -64.778127) (xy 279.799843 -64.784227) (xy 279.8538 -64.798333)
			(xy 279.905129 -64.820145) (xy 279.952735 -64.849199) (xy 279.995603 -64.884874) (xy 280.03282 -64.926411)
			(xy 280.063593 -64.972924) (xy 280.087265 -65.023421) (xy 280.103333 -65.076828) (xy 280.111453 -65.132004)
			(xy 280.111962 -65.15989) (xy 280.111453 -65.187776) (xy 280.103333 -65.242952) (xy 280.087265 -65.296359)
			(xy 280.063593 -65.346856) (xy 280.03282 -65.393369) (xy 279.995603 -65.434906) (xy 279.952735 -65.470581)
			(xy 279.905129 -65.499635) (xy 279.8538 -65.521447) (xy 279.799843 -65.535553) (xy 279.744406 -65.541653)
			(xy 279.688672 -65.539616) (xy 279.633829 -65.529486) (xy 279.581045 -65.511479) (xy 279.531445 -65.485978)
			(xy 279.486087 -65.453527) (xy 279.445938 -65.414818) (xy 279.411852 -65.370675) (xy 279.384556 -65.32204)
			(xy 279.364633 -65.269949) (xy 279.352507 -65.215512) (xy 279.348436 -65.15989) (xy 279.090885 -65.15989)
			(xy 279.087333 -65.184024) (xy 279.071265 -65.237431) (xy 279.047593 -65.287928) (xy 279.01682 -65.334441)
			(xy 278.979603 -65.375978) (xy 278.936735 -65.411653) (xy 278.889129 -65.440707) (xy 278.8378 -65.462519)
			(xy 278.783843 -65.476625) (xy 278.728406 -65.482725) (xy 278.672672 -65.480688) (xy 278.617829 -65.470558)
			(xy 278.565045 -65.452551) (xy 278.515445 -65.42705) (xy 278.470087 -65.394599) (xy 278.429938 -65.35589)
			(xy 278.395852 -65.311747) (xy 278.368556 -65.263112) (xy 278.348633 -65.211021) (xy 278.336507 -65.156584)
			(xy 278.332436 -65.100962) (xy 278.074885 -65.100962) (xy 278.079453 -65.132004) (xy 278.079962 -65.15989)
			(xy 278.079453 -65.187776) (xy 278.071333 -65.242952) (xy 278.055265 -65.296359) (xy 278.031593 -65.346856)
			(xy 278.00082 -65.393369) (xy 277.963603 -65.434906) (xy 277.920735 -65.470581) (xy 277.873129 -65.499635)
			(xy 277.8218 -65.521447) (xy 277.767843 -65.535553) (xy 277.712406 -65.541653) (xy 277.656672 -65.539616)
			(xy 277.601829 -65.529486) (xy 277.549045 -65.511479) (xy 277.499445 -65.485978) (xy 277.454087 -65.453527)
			(xy 277.413938 -65.414818) (xy 277.379852 -65.370675) (xy 277.352556 -65.32204) (xy 277.332633 -65.269949)
			(xy 277.320507 -65.215512) (xy 277.316436 -65.15989) (xy 265.145784 -65.15989) (xy 265.138731 -65.213466)
			(xy 265.123218 -65.271359) (xy 265.100282 -65.326732) (xy 265.070315 -65.378638) (xy 265.033828 -65.426188)
			(xy 264.991448 -65.468568) (xy 264.943898 -65.505055) (xy 264.891992 -65.535022) (xy 264.836619 -65.557958)
			(xy 264.778726 -65.573471) (xy 264.719304 -65.581294) (xy 264.659368 -65.581294) (xy 264.599946 -65.573471)
			(xy 264.542053 -65.557958) (xy 264.48668 -65.535022) (xy 264.434774 -65.505055) (xy 264.387224 -65.468568)
			(xy 264.344844 -65.426188) (xy 264.308357 -65.378638) (xy 264.27839 -65.326732) (xy 264.255454 -65.271359)
			(xy 264.239941 -65.213466) (xy 264.232118 -65.154044) (xy 254.11191 -65.154044) (xy 254.112014 -65.15989)
			(xy 254.111575 -65.186158) (xy 254.104365 -65.238195) (xy 254.090079 -65.288751) (xy 254.068988 -65.336866)
			(xy 254.041491 -65.381631) (xy 254.00811 -65.422197) (xy 253.989078 -65.440306) (xy 253.988824 -65.44056)
			(xy 253.981762 -65.44778) (xy 253.973486 -65.466184) (xy 253.972915 -65.486356) (xy 253.976124 -65.495932)
			(xy 254.010414 -65.584324) (xy 254.014521 -65.593725) (xy 254.028774 -65.608453) (xy 254.047662 -65.616412)
			(xy 254.057912 -65.616836) (xy 261.53237 -65.616836) (xy 261.566749 -65.617277) (xy 261.635174 -65.624045)
			(xy 261.70261 -65.63747) (xy 261.76841 -65.657423) (xy 261.80034 -65.670176) (xy 262.13308 -65.808098)
			(xy 262.137766 -65.809898) (xy 262.147619 -65.81182) (xy 262.152638 -65.811908) (xy 272.49628 -65.811908)
			(xy 272.506305 -65.811492) (xy 272.52483 -65.803826) (xy 272.53901 -65.789653) (xy 272.546686 -65.771132)
			(xy 272.54708 -65.761108) (xy 272.54708 -65.75552) (xy 272.547566 -65.728269) (xy 272.555322 -65.674321)
			(xy 272.570677 -65.622026) (xy 272.593319 -65.572449) (xy 272.622785 -65.526599) (xy 272.658476 -65.485408)
			(xy 272.699667 -65.449717) (xy 272.745517 -65.420251) (xy 272.795094 -65.397609) (xy 272.847389 -65.382254)
			(xy 272.901337 -65.374498) (xy 272.955839 -65.374498) (xy 273.009787 -65.382254) (xy 273.062082 -65.397609)
			(xy 273.111659 -65.420251) (xy 273.157509 -65.449717) (xy 273.1987 -65.485408) (xy 273.234391 -65.526599)
			(xy 273.263857 -65.572449) (xy 273.286499 -65.622026) (xy 273.301854 -65.674321) (xy 273.30961 -65.728269)
			(xy 273.310096 -65.75552) (xy 273.310096 -65.761108) (xy 273.310586 -65.771115) (xy 273.318246 -65.789605)
			(xy 273.332399 -65.803756) (xy 273.350889 -65.811415) (xy 273.360896 -65.811908) (xy 298.526708 -65.811908)
			(xy 298.538578 -65.81122) (xy 298.559762 -65.80049) (xy 298.567348 -65.791334) (xy 298.569126 -65.788794)
			(xy 298.615608 -65.716912) (xy 298.61894 -65.711396) (xy 298.623057 -65.69919) (xy 298.623736 -65.692782)
			(xy 298.624498 -65.680336) (xy 298.619164 -65.668398) (xy 298.608491 -65.643621) (xy 298.593444 -65.591812)
			(xy 298.585851 -65.538401) (xy 298.585382 -65.511426) (xy 298.585868 -65.484175) (xy 298.593624 -65.430227)
			(xy 298.608979 -65.377932) (xy 298.631621 -65.328355) (xy 298.661087 -65.282505) (xy 298.696778 -65.241314)
			(xy 298.737969 -65.205623) (xy 298.783819 -65.176157) (xy 298.833396 -65.153515) (xy 298.885691 -65.13816)
			(xy 298.939639 -65.130404) (xy 298.994141 -65.130404) (xy 299.048089 -65.13816) (xy 299.100384 -65.153515)
			(xy 299.114343 -65.15989) (xy 303.316384 -65.15989) (xy 303.320455 -65.104268) (xy 303.332581 -65.049831)
			(xy 303.352504 -64.99774) (xy 303.3798 -64.949105) (xy 303.413886 -64.904962) (xy 303.454035 -64.866253)
			(xy 303.499393 -64.833802) (xy 303.548993 -64.808301) (xy 303.601777 -64.790294) (xy 303.65662 -64.780164)
			(xy 303.712354 -64.778127) (xy 303.767791 -64.784227) (xy 303.821748 -64.798333) (xy 303.873077 -64.820145)
			(xy 303.920683 -64.849199) (xy 303.963551 -64.884874) (xy 304.000768 -64.926411) (xy 304.031541 -64.972924)
			(xy 304.055213 -65.023421) (xy 304.071281 -65.076828) (xy 304.074833 -65.100962) (xy 304.332384 -65.100962)
			(xy 304.336455 -65.04534) (xy 304.348581 -64.990903) (xy 304.368504 -64.938812) (xy 304.3958 -64.890177)
			(xy 304.429886 -64.846034) (xy 304.470035 -64.807325) (xy 304.515393 -64.774874) (xy 304.564993 -64.749373)
			(xy 304.617777 -64.731366) (xy 304.67262 -64.721236) (xy 304.728354 -64.719199) (xy 304.783791 -64.725299)
			(xy 304.837748 -64.739405) (xy 304.889077 -64.761217) (xy 304.936683 -64.790271) (xy 304.979551 -64.825946)
			(xy 305.016768 -64.867483) (xy 305.047541 -64.913996) (xy 305.071213 -64.964493) (xy 305.087281 -65.0179)
			(xy 305.095401 -65.073076) (xy 305.09591 -65.100962) (xy 305.095401 -65.128848) (xy 305.090833 -65.15989)
			(xy 305.348384 -65.15989) (xy 305.352455 -65.104268) (xy 305.364581 -65.049831) (xy 305.384504 -64.99774)
			(xy 305.4118 -64.949105) (xy 305.445886 -64.904962) (xy 305.486035 -64.866253) (xy 305.531393 -64.833802)
			(xy 305.580993 -64.808301) (xy 305.633777 -64.790294) (xy 305.68862 -64.780164) (xy 305.744354 -64.778127)
			(xy 305.799791 -64.784227) (xy 305.853748 -64.798333) (xy 305.905077 -64.820145) (xy 305.952683 -64.849199)
			(xy 305.995551 -64.884874) (xy 306.032768 -64.926411) (xy 306.063541 -64.972924) (xy 306.087213 -65.023421)
			(xy 306.103281 -65.076828) (xy 306.111401 -65.132004) (xy 306.111803 -65.154044) (xy 316.232014 -65.154044)
			(xy 316.232014 -65.094108) (xy 316.239837 -65.034686) (xy 316.25535 -64.976793) (xy 316.278286 -64.92142)
			(xy 316.308253 -64.869514) (xy 316.34474 -64.821964) (xy 316.38712 -64.779584) (xy 316.43467 -64.743097)
			(xy 316.486576 -64.71313) (xy 316.541949 -64.690194) (xy 316.599842 -64.674681) (xy 316.659264 -64.666858)
			(xy 316.7192 -64.666858) (xy 316.778622 -64.674681) (xy 316.836515 -64.690194) (xy 316.891888 -64.71313)
			(xy 316.943794 -64.743097) (xy 316.991344 -64.779584) (xy 317.033724 -64.821964) (xy 317.070211 -64.869514)
			(xy 317.100178 -64.92142) (xy 317.123114 -64.976793) (xy 317.138627 -65.034686) (xy 317.14645 -65.094108)
			(xy 317.14694 -65.124076) (xy 317.14645 -65.154044) (xy 317.14568 -65.15989) (xy 329.316332 -65.15989)
			(xy 329.320403 -65.104268) (xy 329.332529 -65.049831) (xy 329.352452 -64.99774) (xy 329.379748 -64.949105)
			(xy 329.413834 -64.904962) (xy 329.453983 -64.866253) (xy 329.499341 -64.833802) (xy 329.548941 -64.808301)
			(xy 329.601725 -64.790294) (xy 329.656568 -64.780164) (xy 329.712302 -64.778127) (xy 329.767739 -64.784227)
			(xy 329.821696 -64.798333) (xy 329.873025 -64.820145) (xy 329.920631 -64.849199) (xy 329.963499 -64.884874)
			(xy 330.000716 -64.926411) (xy 330.031489 -64.972924) (xy 330.055161 -65.023421) (xy 330.071229 -65.076828)
			(xy 330.074781 -65.100962) (xy 330.332332 -65.100962) (xy 330.336403 -65.04534) (xy 330.348529 -64.990903)
			(xy 330.368452 -64.938812) (xy 330.395748 -64.890177) (xy 330.429834 -64.846034) (xy 330.469983 -64.807325)
			(xy 330.515341 -64.774874) (xy 330.564941 -64.749373) (xy 330.617725 -64.731366) (xy 330.672568 -64.721236)
			(xy 330.728302 -64.719199) (xy 330.783739 -64.725299) (xy 330.837696 -64.739405) (xy 330.889025 -64.761217)
			(xy 330.936631 -64.790271) (xy 330.979499 -64.825946) (xy 331.016716 -64.867483) (xy 331.047489 -64.913996)
			(xy 331.071161 -64.964493) (xy 331.087229 -65.0179) (xy 331.095349 -65.073076) (xy 331.095858 -65.100962)
			(xy 331.095349 -65.128848) (xy 331.090781 -65.15989) (xy 331.348332 -65.15989) (xy 331.352403 -65.104268)
			(xy 331.364529 -65.049831) (xy 331.384452 -64.99774) (xy 331.411748 -64.949105) (xy 331.445834 -64.904962)
			(xy 331.485983 -64.866253) (xy 331.531341 -64.833802) (xy 331.580941 -64.808301) (xy 331.633725 -64.790294)
			(xy 331.688568 -64.780164) (xy 331.744302 -64.778127) (xy 331.799739 -64.784227) (xy 331.853696 -64.798333)
			(xy 331.905025 -64.820145) (xy 331.952631 -64.849199) (xy 331.995499 -64.884874) (xy 332.032716 -64.926411)
			(xy 332.063489 -64.972924) (xy 332.087161 -65.023421) (xy 332.103229 -65.076828) (xy 332.111349 -65.132004)
			(xy 332.111751 -65.154044) (xy 354.332268 -65.154044) (xy 354.332268 -65.094108) (xy 354.340091 -65.034686)
			(xy 354.355604 -64.976793) (xy 354.37854 -64.92142) (xy 354.408507 -64.869514) (xy 354.444994 -64.821964)
			(xy 354.487374 -64.779584) (xy 354.534924 -64.743097) (xy 354.58683 -64.71313) (xy 354.642203 -64.690194)
			(xy 354.700096 -64.674681) (xy 354.759518 -64.666858) (xy 354.819454 -64.666858) (xy 354.878876 -64.674681)
			(xy 354.936769 -64.690194) (xy 354.992142 -64.71313) (xy 355.044048 -64.743097) (xy 355.091598 -64.779584)
			(xy 355.133978 -64.821964) (xy 355.170465 -64.869514) (xy 355.200432 -64.92142) (xy 355.223368 -64.976793)
			(xy 355.238881 -65.034686) (xy 355.246704 -65.094108) (xy 355.247194 -65.124076) (xy 355.246704 -65.154044)
			(xy 355.245934 -65.15989) (xy 367.416586 -65.15989) (xy 367.420657 -65.104268) (xy 367.432783 -65.049831)
			(xy 367.452706 -64.99774) (xy 367.480002 -64.949105) (xy 367.514088 -64.904962) (xy 367.554237 -64.866253)
			(xy 367.599595 -64.833802) (xy 367.649195 -64.808301) (xy 367.701979 -64.790294) (xy 367.756822 -64.780164)
			(xy 367.812556 -64.778127) (xy 367.867993 -64.784227) (xy 367.92195 -64.798333) (xy 367.973279 -64.820145)
			(xy 368.020885 -64.849199) (xy 368.063753 -64.884874) (xy 368.10097 -64.926411) (xy 368.131743 -64.972924)
			(xy 368.155415 -65.023421) (xy 368.171483 -65.076828) (xy 368.175035 -65.100962) (xy 368.432586 -65.100962)
			(xy 368.436657 -65.04534) (xy 368.448783 -64.990903) (xy 368.468706 -64.938812) (xy 368.496002 -64.890177)
			(xy 368.530088 -64.846034) (xy 368.570237 -64.807325) (xy 368.615595 -64.774874) (xy 368.665195 -64.749373)
			(xy 368.717979 -64.731366) (xy 368.772822 -64.721236) (xy 368.828556 -64.719199) (xy 368.883993 -64.725299)
			(xy 368.93795 -64.739405) (xy 368.989279 -64.761217) (xy 369.036885 -64.790271) (xy 369.079753 -64.825946)
			(xy 369.11697 -64.867483) (xy 369.147743 -64.913996) (xy 369.171415 -64.964493) (xy 369.187483 -65.0179)
			(xy 369.195603 -65.073076) (xy 369.196112 -65.100962) (xy 369.195603 -65.128848) (xy 369.191035 -65.15989)
			(xy 369.448586 -65.15989) (xy 369.452657 -65.104268) (xy 369.464783 -65.049831) (xy 369.484706 -64.99774)
			(xy 369.512002 -64.949105) (xy 369.546088 -64.904962) (xy 369.586237 -64.866253) (xy 369.631595 -64.833802)
			(xy 369.681195 -64.808301) (xy 369.733979 -64.790294) (xy 369.788822 -64.780164) (xy 369.844556 -64.778127)
			(xy 369.899993 -64.784227) (xy 369.95395 -64.798333) (xy 370.005279 -64.820145) (xy 370.052885 -64.849199)
			(xy 370.095753 -64.884874) (xy 370.13297 -64.926411) (xy 370.163743 -64.972924) (xy 370.187415 -65.023421)
			(xy 370.203483 -65.076828) (xy 370.211603 -65.132004) (xy 370.212005 -65.154044) (xy 380.332216 -65.154044)
			(xy 380.332216 -65.094108) (xy 380.340039 -65.034686) (xy 380.355552 -64.976793) (xy 380.378488 -64.92142)
			(xy 380.408455 -64.869514) (xy 380.444942 -64.821964) (xy 380.487322 -64.779584) (xy 380.534872 -64.743097)
			(xy 380.586778 -64.71313) (xy 380.642151 -64.690194) (xy 380.700044 -64.674681) (xy 380.759466 -64.666858)
			(xy 380.819402 -64.666858) (xy 380.878824 -64.674681) (xy 380.936717 -64.690194) (xy 380.99209 -64.71313)
			(xy 381.043996 -64.743097) (xy 381.091546 -64.779584) (xy 381.133926 -64.821964) (xy 381.170413 -64.869514)
			(xy 381.20038 -64.92142) (xy 381.223316 -64.976793) (xy 381.238829 -65.034686) (xy 381.246652 -65.094108)
			(xy 381.247142 -65.124076) (xy 381.246652 -65.154044) (xy 381.245882 -65.15989) (xy 393.416534 -65.15989)
			(xy 393.420605 -65.104268) (xy 393.432731 -65.049831) (xy 393.452654 -64.99774) (xy 393.47995 -64.949105)
			(xy 393.514036 -64.904962) (xy 393.554185 -64.866253) (xy 393.599543 -64.833802) (xy 393.649143 -64.808301)
			(xy 393.701927 -64.790294) (xy 393.75677 -64.780164) (xy 393.812504 -64.778127) (xy 393.867941 -64.784227)
			(xy 393.921898 -64.798333) (xy 393.973227 -64.820145) (xy 394.020833 -64.849199) (xy 394.063701 -64.884874)
			(xy 394.100918 -64.926411) (xy 394.131691 -64.972924) (xy 394.155363 -65.023421) (xy 394.171431 -65.076828)
			(xy 394.174983 -65.100962) (xy 394.432534 -65.100962) (xy 394.436605 -65.04534) (xy 394.448731 -64.990903)
			(xy 394.468654 -64.938812) (xy 394.49595 -64.890177) (xy 394.530036 -64.846034) (xy 394.570185 -64.807325)
			(xy 394.615543 -64.774874) (xy 394.665143 -64.749373) (xy 394.717927 -64.731366) (xy 394.77277 -64.721236)
			(xy 394.828504 -64.719199) (xy 394.883941 -64.725299) (xy 394.937898 -64.739405) (xy 394.989227 -64.761217)
			(xy 395.036833 -64.790271) (xy 395.079701 -64.825946) (xy 395.116918 -64.867483) (xy 395.147691 -64.913996)
			(xy 395.171363 -64.964493) (xy 395.187431 -65.0179) (xy 395.195551 -65.073076) (xy 395.19606 -65.100962)
			(xy 395.195551 -65.128848) (xy 395.190983 -65.15989) (xy 395.448534 -65.15989) (xy 395.452605 -65.104268)
			(xy 395.464731 -65.049831) (xy 395.484654 -64.99774) (xy 395.51195 -64.949105) (xy 395.546036 -64.904962)
			(xy 395.586185 -64.866253) (xy 395.631543 -64.833802) (xy 395.681143 -64.808301) (xy 395.733927 -64.790294)
			(xy 395.78877 -64.780164) (xy 395.844504 -64.778127) (xy 395.899941 -64.784227) (xy 395.953898 -64.798333)
			(xy 396.005227 -64.820145) (xy 396.052833 -64.849199) (xy 396.095701 -64.884874) (xy 396.132918 -64.926411)
			(xy 396.163691 -64.972924) (xy 396.187363 -65.023421) (xy 396.203431 -65.076828) (xy 396.211551 -65.132004)
			(xy 396.21206 -65.15989) (xy 419.416482 -65.15989) (xy 419.420553 -65.104268) (xy 419.432679 -65.049831)
			(xy 419.452602 -64.99774) (xy 419.479898 -64.949105) (xy 419.513984 -64.904962) (xy 419.554133 -64.866253)
			(xy 419.599491 -64.833802) (xy 419.649091 -64.808301) (xy 419.701875 -64.790294) (xy 419.756718 -64.780164)
			(xy 419.812452 -64.778127) (xy 419.867889 -64.784227) (xy 419.921846 -64.798333) (xy 419.973175 -64.820145)
			(xy 420.020781 -64.849199) (xy 420.063649 -64.884874) (xy 420.100866 -64.926411) (xy 420.131639 -64.972924)
			(xy 420.155311 -65.023421) (xy 420.171379 -65.076828) (xy 420.174931 -65.100962) (xy 420.432482 -65.100962)
			(xy 420.436553 -65.04534) (xy 420.448679 -64.990903) (xy 420.468602 -64.938812) (xy 420.495898 -64.890177)
			(xy 420.529984 -64.846034) (xy 420.570133 -64.807325) (xy 420.615491 -64.774874) (xy 420.665091 -64.749373)
			(xy 420.717875 -64.731366) (xy 420.772718 -64.721236) (xy 420.828452 -64.719199) (xy 420.883889 -64.725299)
			(xy 420.937846 -64.739405) (xy 420.989175 -64.761217) (xy 421.036781 -64.790271) (xy 421.079649 -64.825946)
			(xy 421.116866 -64.867483) (xy 421.147639 -64.913996) (xy 421.171311 -64.964493) (xy 421.187379 -65.0179)
			(xy 421.195499 -65.073076) (xy 421.196008 -65.100962) (xy 421.195499 -65.128848) (xy 421.190931 -65.15989)
			(xy 421.448482 -65.15989) (xy 421.452553 -65.104268) (xy 421.464679 -65.049831) (xy 421.484602 -64.99774)
			(xy 421.511898 -64.949105) (xy 421.545984 -64.904962) (xy 421.586133 -64.866253) (xy 421.631491 -64.833802)
			(xy 421.681091 -64.808301) (xy 421.733875 -64.790294) (xy 421.788718 -64.780164) (xy 421.844452 -64.778127)
			(xy 421.899889 -64.784227) (xy 421.953846 -64.798333) (xy 422.005175 -64.820145) (xy 422.052781 -64.849199)
			(xy 422.095649 -64.884874) (xy 422.132866 -64.926411) (xy 422.163639 -64.972924) (xy 422.187311 -65.023421)
			(xy 422.203379 -65.076828) (xy 422.211499 -65.132004) (xy 422.211901 -65.154044) (xy 432.332112 -65.154044)
			(xy 432.332112 -65.094108) (xy 432.339935 -65.034686) (xy 432.355448 -64.976793) (xy 432.378384 -64.92142)
			(xy 432.408351 -64.869514) (xy 432.444838 -64.821964) (xy 432.487218 -64.779584) (xy 432.534768 -64.743097)
			(xy 432.586674 -64.71313) (xy 432.642047 -64.690194) (xy 432.69994 -64.674681) (xy 432.759362 -64.666858)
			(xy 432.819298 -64.666858) (xy 432.87872 -64.674681) (xy 432.936613 -64.690194) (xy 432.991986 -64.71313)
			(xy 433.043892 -64.743097) (xy 433.091442 -64.779584) (xy 433.133822 -64.821964) (xy 433.170309 -64.869514)
			(xy 433.200276 -64.92142) (xy 433.223212 -64.976793) (xy 433.238725 -65.034686) (xy 433.246548 -65.094108)
			(xy 433.247038 -65.124076) (xy 433.246548 -65.154044) (xy 433.245778 -65.15989) (xy 445.41643 -65.15989)
			(xy 445.420501 -65.104268) (xy 445.432627 -65.049831) (xy 445.45255 -64.99774) (xy 445.479846 -64.949105)
			(xy 445.513932 -64.904962) (xy 445.554081 -64.866253) (xy 445.599439 -64.833802) (xy 445.649039 -64.808301)
			(xy 445.701823 -64.790294) (xy 445.756666 -64.780164) (xy 445.8124 -64.778127) (xy 445.867837 -64.784227)
			(xy 445.921794 -64.798333) (xy 445.973123 -64.820145) (xy 446.020729 -64.849199) (xy 446.063597 -64.884874)
			(xy 446.100814 -64.926411) (xy 446.131587 -64.972924) (xy 446.155259 -65.023421) (xy 446.171327 -65.076828)
			(xy 446.174879 -65.100962) (xy 446.43243 -65.100962) (xy 446.436501 -65.04534) (xy 446.448627 -64.990903)
			(xy 446.46855 -64.938812) (xy 446.495846 -64.890177) (xy 446.529932 -64.846034) (xy 446.570081 -64.807325)
			(xy 446.615439 -64.774874) (xy 446.665039 -64.749373) (xy 446.717823 -64.731366) (xy 446.772666 -64.721236)
			(xy 446.8284 -64.719199) (xy 446.883837 -64.725299) (xy 446.937794 -64.739405) (xy 446.989123 -64.761217)
			(xy 447.036729 -64.790271) (xy 447.079597 -64.825946) (xy 447.116814 -64.867483) (xy 447.147587 -64.913996)
			(xy 447.171259 -64.964493) (xy 447.187327 -65.0179) (xy 447.195447 -65.073076) (xy 447.195956 -65.100962)
			(xy 447.195447 -65.128848) (xy 447.190879 -65.15989) (xy 447.44843 -65.15989) (xy 447.452501 -65.104268)
			(xy 447.464627 -65.049831) (xy 447.48455 -64.99774) (xy 447.511846 -64.949105) (xy 447.545932 -64.904962)
			(xy 447.586081 -64.866253) (xy 447.631439 -64.833802) (xy 447.681039 -64.808301) (xy 447.733823 -64.790294)
			(xy 447.788666 -64.780164) (xy 447.8444 -64.778127) (xy 447.899837 -64.784227) (xy 447.953794 -64.798333)
			(xy 448.005123 -64.820145) (xy 448.052729 -64.849199) (xy 448.095597 -64.884874) (xy 448.132814 -64.926411)
			(xy 448.163587 -64.972924) (xy 448.187259 -65.023421) (xy 448.203327 -65.076828) (xy 448.211447 -65.132004)
			(xy 448.211956 -65.15989) (xy 448.211447 -65.187776) (xy 448.203327 -65.242952) (xy 448.187259 -65.296359)
			(xy 448.163587 -65.346856) (xy 448.132814 -65.393369) (xy 448.095597 -65.434906) (xy 448.052729 -65.470581)
			(xy 448.005123 -65.499635) (xy 447.953794 -65.521447) (xy 447.899837 -65.535553) (xy 447.8444 -65.541653)
			(xy 447.788666 -65.539616) (xy 447.733823 -65.529486) (xy 447.681039 -65.511479) (xy 447.631439 -65.485978)
			(xy 447.586081 -65.453527) (xy 447.545932 -65.414818) (xy 447.511846 -65.370675) (xy 447.48455 -65.32204)
			(xy 447.464627 -65.269949) (xy 447.452501 -65.215512) (xy 447.44843 -65.15989) (xy 447.190879 -65.15989)
			(xy 447.187327 -65.184024) (xy 447.171259 -65.237431) (xy 447.147587 -65.287928) (xy 447.116814 -65.334441)
			(xy 447.079597 -65.375978) (xy 447.036729 -65.411653) (xy 446.989123 -65.440707) (xy 446.937794 -65.462519)
			(xy 446.883837 -65.476625) (xy 446.8284 -65.482725) (xy 446.772666 -65.480688) (xy 446.717823 -65.470558)
			(xy 446.665039 -65.452551) (xy 446.615439 -65.42705) (xy 446.570081 -65.394599) (xy 446.529932 -65.35589)
			(xy 446.495846 -65.311747) (xy 446.46855 -65.263112) (xy 446.448627 -65.211021) (xy 446.436501 -65.156584)
			(xy 446.43243 -65.100962) (xy 446.174879 -65.100962) (xy 446.179447 -65.132004) (xy 446.179956 -65.15989)
			(xy 446.179447 -65.187776) (xy 446.171327 -65.242952) (xy 446.155259 -65.296359) (xy 446.131587 -65.346856)
			(xy 446.100814 -65.393369) (xy 446.063597 -65.434906) (xy 446.020729 -65.470581) (xy 445.973123 -65.499635)
			(xy 445.921794 -65.521447) (xy 445.867837 -65.535553) (xy 445.8124 -65.541653) (xy 445.756666 -65.539616)
			(xy 445.701823 -65.529486) (xy 445.649039 -65.511479) (xy 445.599439 -65.485978) (xy 445.554081 -65.453527)
			(xy 445.513932 -65.414818) (xy 445.479846 -65.370675) (xy 445.45255 -65.32204) (xy 445.432627 -65.269949)
			(xy 445.420501 -65.215512) (xy 445.41643 -65.15989) (xy 433.245778 -65.15989) (xy 433.238725 -65.213466)
			(xy 433.223212 -65.271359) (xy 433.200276 -65.326732) (xy 433.170309 -65.378638) (xy 433.133822 -65.426188)
			(xy 433.091442 -65.468568) (xy 433.043892 -65.505055) (xy 432.991986 -65.535022) (xy 432.936613 -65.557958)
			(xy 432.87872 -65.573471) (xy 432.819298 -65.581294) (xy 432.759362 -65.581294) (xy 432.69994 -65.573471)
			(xy 432.642047 -65.557958) (xy 432.586674 -65.535022) (xy 432.534768 -65.505055) (xy 432.487218 -65.468568)
			(xy 432.444838 -65.426188) (xy 432.408351 -65.378638) (xy 432.378384 -65.326732) (xy 432.355448 -65.271359)
			(xy 432.339935 -65.213466) (xy 432.332112 -65.154044) (xy 422.211901 -65.154044) (xy 422.212008 -65.15989)
			(xy 422.211499 -65.187776) (xy 422.203379 -65.242952) (xy 422.187311 -65.296359) (xy 422.163639 -65.346856)
			(xy 422.132866 -65.393369) (xy 422.095649 -65.434906) (xy 422.052781 -65.470581) (xy 422.005175 -65.499635)
			(xy 421.953846 -65.521447) (xy 421.899889 -65.535553) (xy 421.844452 -65.541653) (xy 421.788718 -65.539616)
			(xy 421.733875 -65.529486) (xy 421.681091 -65.511479) (xy 421.631491 -65.485978) (xy 421.586133 -65.453527)
			(xy 421.545984 -65.414818) (xy 421.511898 -65.370675) (xy 421.484602 -65.32204) (xy 421.464679 -65.269949)
			(xy 421.452553 -65.215512) (xy 421.448482 -65.15989) (xy 421.190931 -65.15989) (xy 421.187379 -65.184024)
			(xy 421.171311 -65.237431) (xy 421.147639 -65.287928) (xy 421.116866 -65.334441) (xy 421.079649 -65.375978)
			(xy 421.036781 -65.411653) (xy 420.989175 -65.440707) (xy 420.937846 -65.462519) (xy 420.883889 -65.476625)
			(xy 420.828452 -65.482725) (xy 420.772718 -65.480688) (xy 420.717875 -65.470558) (xy 420.665091 -65.452551)
			(xy 420.615491 -65.42705) (xy 420.570133 -65.394599) (xy 420.529984 -65.35589) (xy 420.495898 -65.311747)
			(xy 420.468602 -65.263112) (xy 420.448679 -65.211021) (xy 420.436553 -65.156584) (xy 420.432482 -65.100962)
			(xy 420.174931 -65.100962) (xy 420.179499 -65.132004) (xy 420.180008 -65.15989) (xy 420.179499 -65.187776)
			(xy 420.171379 -65.242952) (xy 420.155311 -65.296359) (xy 420.131639 -65.346856) (xy 420.100866 -65.393369)
			(xy 420.063649 -65.434906) (xy 420.020781 -65.470581) (xy 419.973175 -65.499635) (xy 419.921846 -65.521447)
			(xy 419.867889 -65.535553) (xy 419.812452 -65.541653) (xy 419.756718 -65.539616) (xy 419.701875 -65.529486)
			(xy 419.649091 -65.511479) (xy 419.599491 -65.485978) (xy 419.554133 -65.453527) (xy 419.513984 -65.414818)
			(xy 419.479898 -65.370675) (xy 419.452602 -65.32204) (xy 419.432679 -65.269949) (xy 419.420553 -65.215512)
			(xy 419.416482 -65.15989) (xy 396.21206 -65.15989) (xy 396.211551 -65.187776) (xy 396.203431 -65.242952)
			(xy 396.187363 -65.296359) (xy 396.163691 -65.346856) (xy 396.132918 -65.393369) (xy 396.095701 -65.434906)
			(xy 396.052833 -65.470581) (xy 396.005227 -65.499635) (xy 395.953898 -65.521447) (xy 395.899941 -65.535553)
			(xy 395.844504 -65.541653) (xy 395.78877 -65.539616) (xy 395.733927 -65.529486) (xy 395.681143 -65.511479)
			(xy 395.631543 -65.485978) (xy 395.586185 -65.453527) (xy 395.546036 -65.414818) (xy 395.51195 -65.370675)
			(xy 395.484654 -65.32204) (xy 395.464731 -65.269949) (xy 395.452605 -65.215512) (xy 395.448534 -65.15989)
			(xy 395.190983 -65.15989) (xy 395.187431 -65.184024) (xy 395.171363 -65.237431) (xy 395.147691 -65.287928)
			(xy 395.116918 -65.334441) (xy 395.079701 -65.375978) (xy 395.036833 -65.411653) (xy 394.989227 -65.440707)
			(xy 394.937898 -65.462519) (xy 394.883941 -65.476625) (xy 394.828504 -65.482725) (xy 394.77277 -65.480688)
			(xy 394.717927 -65.470558) (xy 394.665143 -65.452551) (xy 394.615543 -65.42705) (xy 394.570185 -65.394599)
			(xy 394.530036 -65.35589) (xy 394.49595 -65.311747) (xy 394.468654 -65.263112) (xy 394.448731 -65.211021)
			(xy 394.436605 -65.156584) (xy 394.432534 -65.100962) (xy 394.174983 -65.100962) (xy 394.179551 -65.132004)
			(xy 394.18006 -65.15989) (xy 394.179551 -65.187776) (xy 394.171431 -65.242952) (xy 394.155363 -65.296359)
			(xy 394.131691 -65.346856) (xy 394.100918 -65.393369) (xy 394.063701 -65.434906) (xy 394.020833 -65.470581)
			(xy 393.973227 -65.499635) (xy 393.921898 -65.521447) (xy 393.867941 -65.535553) (xy 393.812504 -65.541653)
			(xy 393.75677 -65.539616) (xy 393.701927 -65.529486) (xy 393.649143 -65.511479) (xy 393.599543 -65.485978)
			(xy 393.554185 -65.453527) (xy 393.514036 -65.414818) (xy 393.47995 -65.370675) (xy 393.452654 -65.32204)
			(xy 393.432731 -65.269949) (xy 393.420605 -65.215512) (xy 393.416534 -65.15989) (xy 381.245882 -65.15989)
			(xy 381.238829 -65.213466) (xy 381.223316 -65.271359) (xy 381.20038 -65.326732) (xy 381.170413 -65.378638)
			(xy 381.133926 -65.426188) (xy 381.091546 -65.468568) (xy 381.043996 -65.505055) (xy 380.99209 -65.535022)
			(xy 380.936717 -65.557958) (xy 380.878824 -65.573471) (xy 380.819402 -65.581294) (xy 380.759466 -65.581294)
			(xy 380.700044 -65.573471) (xy 380.642151 -65.557958) (xy 380.586778 -65.535022) (xy 380.534872 -65.505055)
			(xy 380.487322 -65.468568) (xy 380.444942 -65.426188) (xy 380.408455 -65.378638) (xy 380.378488 -65.326732)
			(xy 380.355552 -65.271359) (xy 380.340039 -65.213466) (xy 380.332216 -65.154044) (xy 370.212005 -65.154044)
			(xy 370.212112 -65.15989) (xy 370.211603 -65.187776) (xy 370.203483 -65.242952) (xy 370.187415 -65.296359)
			(xy 370.163743 -65.346856) (xy 370.13297 -65.393369) (xy 370.095753 -65.434906) (xy 370.052885 -65.470581)
			(xy 370.005279 -65.499635) (xy 369.95395 -65.521447) (xy 369.899993 -65.535553) (xy 369.844556 -65.541653)
			(xy 369.788822 -65.539616) (xy 369.733979 -65.529486) (xy 369.681195 -65.511479) (xy 369.631595 -65.485978)
			(xy 369.586237 -65.453527) (xy 369.546088 -65.414818) (xy 369.512002 -65.370675) (xy 369.484706 -65.32204)
			(xy 369.464783 -65.269949) (xy 369.452657 -65.215512) (xy 369.448586 -65.15989) (xy 369.191035 -65.15989)
			(xy 369.187483 -65.184024) (xy 369.171415 -65.237431) (xy 369.147743 -65.287928) (xy 369.11697 -65.334441)
			(xy 369.079753 -65.375978) (xy 369.036885 -65.411653) (xy 368.989279 -65.440707) (xy 368.93795 -65.462519)
			(xy 368.883993 -65.476625) (xy 368.828556 -65.482725) (xy 368.772822 -65.480688) (xy 368.717979 -65.470558)
			(xy 368.665195 -65.452551) (xy 368.615595 -65.42705) (xy 368.570237 -65.394599) (xy 368.530088 -65.35589)
			(xy 368.496002 -65.311747) (xy 368.468706 -65.263112) (xy 368.448783 -65.211021) (xy 368.436657 -65.156584)
			(xy 368.432586 -65.100962) (xy 368.175035 -65.100962) (xy 368.179603 -65.132004) (xy 368.180112 -65.15989)
			(xy 368.179603 -65.187776) (xy 368.171483 -65.242952) (xy 368.155415 -65.296359) (xy 368.131743 -65.346856)
			(xy 368.10097 -65.393369) (xy 368.063753 -65.434906) (xy 368.020885 -65.470581) (xy 367.973279 -65.499635)
			(xy 367.92195 -65.521447) (xy 367.867993 -65.535553) (xy 367.812556 -65.541653) (xy 367.756822 -65.539616)
			(xy 367.701979 -65.529486) (xy 367.649195 -65.511479) (xy 367.599595 -65.485978) (xy 367.554237 -65.453527)
			(xy 367.514088 -65.414818) (xy 367.480002 -65.370675) (xy 367.452706 -65.32204) (xy 367.432783 -65.269949)
			(xy 367.420657 -65.215512) (xy 367.416586 -65.15989) (xy 355.245934 -65.15989) (xy 355.238881 -65.213466)
			(xy 355.223368 -65.271359) (xy 355.200432 -65.326732) (xy 355.170465 -65.378638) (xy 355.133978 -65.426188)
			(xy 355.091598 -65.468568) (xy 355.044048 -65.505055) (xy 354.992142 -65.535022) (xy 354.936769 -65.557958)
			(xy 354.878876 -65.573471) (xy 354.819454 -65.581294) (xy 354.759518 -65.581294) (xy 354.700096 -65.573471)
			(xy 354.642203 -65.557958) (xy 354.58683 -65.535022) (xy 354.534924 -65.505055) (xy 354.487374 -65.468568)
			(xy 354.444994 -65.426188) (xy 354.408507 -65.378638) (xy 354.37854 -65.326732) (xy 354.355604 -65.271359)
			(xy 354.340091 -65.213466) (xy 354.332268 -65.154044) (xy 332.111751 -65.154044) (xy 332.111858 -65.15989)
			(xy 332.111349 -65.187776) (xy 332.103229 -65.242952) (xy 332.087161 -65.296359) (xy 332.063489 -65.346856)
			(xy 332.032716 -65.393369) (xy 331.995499 -65.434906) (xy 331.952631 -65.470581) (xy 331.905025 -65.499635)
			(xy 331.853696 -65.521447) (xy 331.799739 -65.535553) (xy 331.744302 -65.541653) (xy 331.688568 -65.539616)
			(xy 331.633725 -65.529486) (xy 331.580941 -65.511479) (xy 331.531341 -65.485978) (xy 331.485983 -65.453527)
			(xy 331.445834 -65.414818) (xy 331.411748 -65.370675) (xy 331.384452 -65.32204) (xy 331.364529 -65.269949)
			(xy 331.352403 -65.215512) (xy 331.348332 -65.15989) (xy 331.090781 -65.15989) (xy 331.087229 -65.184024)
			(xy 331.071161 -65.237431) (xy 331.047489 -65.287928) (xy 331.016716 -65.334441) (xy 330.979499 -65.375978)
			(xy 330.936631 -65.411653) (xy 330.889025 -65.440707) (xy 330.837696 -65.462519) (xy 330.783739 -65.476625)
			(xy 330.728302 -65.482725) (xy 330.672568 -65.480688) (xy 330.617725 -65.470558) (xy 330.564941 -65.452551)
			(xy 330.515341 -65.42705) (xy 330.469983 -65.394599) (xy 330.429834 -65.35589) (xy 330.395748 -65.311747)
			(xy 330.368452 -65.263112) (xy 330.348529 -65.211021) (xy 330.336403 -65.156584) (xy 330.332332 -65.100962)
			(xy 330.074781 -65.100962) (xy 330.079349 -65.132004) (xy 330.079858 -65.15989) (xy 330.079349 -65.187776)
			(xy 330.071229 -65.242952) (xy 330.055161 -65.296359) (xy 330.031489 -65.346856) (xy 330.000716 -65.393369)
			(xy 329.963499 -65.434906) (xy 329.920631 -65.470581) (xy 329.873025 -65.499635) (xy 329.821696 -65.521447)
			(xy 329.767739 -65.535553) (xy 329.712302 -65.541653) (xy 329.656568 -65.539616) (xy 329.601725 -65.529486)
			(xy 329.548941 -65.511479) (xy 329.499341 -65.485978) (xy 329.453983 -65.453527) (xy 329.413834 -65.414818)
			(xy 329.379748 -65.370675) (xy 329.352452 -65.32204) (xy 329.332529 -65.269949) (xy 329.320403 -65.215512)
			(xy 329.316332 -65.15989) (xy 317.14568 -65.15989) (xy 317.138627 -65.213466) (xy 317.123114 -65.271359)
			(xy 317.100178 -65.326732) (xy 317.070211 -65.378638) (xy 317.033724 -65.426188) (xy 316.991344 -65.468568)
			(xy 316.943794 -65.505055) (xy 316.891888 -65.535022) (xy 316.836515 -65.557958) (xy 316.778622 -65.573471)
			(xy 316.7192 -65.581294) (xy 316.659264 -65.581294) (xy 316.599842 -65.573471) (xy 316.541949 -65.557958)
			(xy 316.486576 -65.535022) (xy 316.43467 -65.505055) (xy 316.38712 -65.468568) (xy 316.34474 -65.426188)
			(xy 316.308253 -65.378638) (xy 316.278286 -65.326732) (xy 316.25535 -65.271359) (xy 316.239837 -65.213466)
			(xy 316.232014 -65.154044) (xy 306.111803 -65.154044) (xy 306.11191 -65.15989) (xy 306.111401 -65.187776)
			(xy 306.103281 -65.242952) (xy 306.087213 -65.296359) (xy 306.063541 -65.346856) (xy 306.032768 -65.393369)
			(xy 305.995551 -65.434906) (xy 305.952683 -65.470581) (xy 305.905077 -65.499635) (xy 305.853748 -65.521447)
			(xy 305.799791 -65.535553) (xy 305.744354 -65.541653) (xy 305.68862 -65.539616) (xy 305.633777 -65.529486)
			(xy 305.580993 -65.511479) (xy 305.531393 -65.485978) (xy 305.486035 -65.453527) (xy 305.445886 -65.414818)
			(xy 305.4118 -65.370675) (xy 305.384504 -65.32204) (xy 305.364581 -65.269949) (xy 305.352455 -65.215512)
			(xy 305.348384 -65.15989) (xy 305.090833 -65.15989) (xy 305.087281 -65.184024) (xy 305.071213 -65.237431)
			(xy 305.047541 -65.287928) (xy 305.016768 -65.334441) (xy 304.979551 -65.375978) (xy 304.936683 -65.411653)
			(xy 304.889077 -65.440707) (xy 304.837748 -65.462519) (xy 304.783791 -65.476625) (xy 304.728354 -65.482725)
			(xy 304.67262 -65.480688) (xy 304.617777 -65.470558) (xy 304.564993 -65.452551) (xy 304.515393 -65.42705)
			(xy 304.470035 -65.394599) (xy 304.429886 -65.35589) (xy 304.3958 -65.311747) (xy 304.368504 -65.263112)
			(xy 304.348581 -65.211021) (xy 304.336455 -65.156584) (xy 304.332384 -65.100962) (xy 304.074833 -65.100962)
			(xy 304.079401 -65.132004) (xy 304.07991 -65.15989) (xy 304.079401 -65.187776) (xy 304.071281 -65.242952)
			(xy 304.055213 -65.296359) (xy 304.031541 -65.346856) (xy 304.000768 -65.393369) (xy 303.963551 -65.434906)
			(xy 303.920683 -65.470581) (xy 303.873077 -65.499635) (xy 303.821748 -65.521447) (xy 303.767791 -65.535553)
			(xy 303.712354 -65.541653) (xy 303.65662 -65.539616) (xy 303.601777 -65.529486) (xy 303.548993 -65.511479)
			(xy 303.499393 -65.485978) (xy 303.454035 -65.453527) (xy 303.413886 -65.414818) (xy 303.3798 -65.370675)
			(xy 303.352504 -65.32204) (xy 303.332581 -65.269949) (xy 303.320455 -65.215512) (xy 303.316384 -65.15989)
			(xy 299.114343 -65.15989) (xy 299.149961 -65.176157) (xy 299.195811 -65.205623) (xy 299.237002 -65.241314)
			(xy 299.272693 -65.282505) (xy 299.302159 -65.328355) (xy 299.324801 -65.377932) (xy 299.340156 -65.430227)
			(xy 299.347912 -65.484175) (xy 299.348398 -65.511426) (xy 299.347931 -65.5384) (xy 299.340331 -65.591811)
			(xy 299.325286 -65.643619) (xy 299.314616 -65.668398) (xy 299.314362 -65.668652) (xy 299.311971 -65.674442)
			(xy 299.309795 -65.686776) (xy 299.310044 -65.693036) (xy 299.31106 -65.70599) (xy 299.364654 -65.788794)
			(xy 299.366432 -65.791334) (xy 299.373992 -65.800525) (xy 299.39519 -65.811271) (xy 299.407072 -65.811908)
			(xy 324.496176 -65.811908) (xy 324.506201 -65.811493) (xy 324.524728 -65.803827) (xy 324.538909 -65.789654)
			(xy 324.546586 -65.771133) (xy 324.546976 -65.761108) (xy 324.546976 -65.75552) (xy 324.547462 -65.728269)
			(xy 324.555218 -65.674321) (xy 324.570573 -65.622026) (xy 324.593215 -65.572449) (xy 324.622681 -65.526599)
			(xy 324.658372 -65.485408) (xy 324.699563 -65.449717) (xy 324.745413 -65.420251) (xy 324.79499 -65.397609)
			(xy 324.847285 -65.382254) (xy 324.901233 -65.374498) (xy 324.955735 -65.374498) (xy 325.009683 -65.382254)
			(xy 325.061978 -65.397609) (xy 325.111555 -65.420251) (xy 325.157405 -65.449717) (xy 325.198596 -65.485408)
			(xy 325.234287 -65.526599) (xy 325.263753 -65.572449) (xy 325.286395 -65.622026) (xy 325.30175 -65.674321)
			(xy 325.309506 -65.728269) (xy 325.309992 -65.75552) (xy 325.309992 -65.761108) (xy 325.310482 -65.771115)
			(xy 325.318142 -65.789605) (xy 325.332295 -65.803758) (xy 325.350785 -65.811418) (xy 325.360792 -65.811908)
			(xy 362.59643 -65.811908) (xy 362.606434 -65.811415) (xy 362.624917 -65.80375) (xy 362.639062 -65.789599)
			(xy 362.646719 -65.771112) (xy 362.64723 -65.761108) (xy 362.64723 -65.75552) (xy 362.647716 -65.728269)
			(xy 362.655472 -65.674321) (xy 362.670827 -65.622026) (xy 362.693469 -65.572449) (xy 362.722935 -65.526599)
			(xy 362.758626 -65.485408) (xy 362.799817 -65.449717) (xy 362.845667 -65.420251) (xy 362.895244 -65.397609)
			(xy 362.947539 -65.382254) (xy 363.001487 -65.374498) (xy 363.055989 -65.374498) (xy 363.109937 -65.382254)
			(xy 363.162232 -65.397609) (xy 363.211809 -65.420251) (xy 363.257659 -65.449717) (xy 363.29885 -65.485408)
			(xy 363.334541 -65.526599) (xy 363.364007 -65.572449) (xy 363.386649 -65.622026) (xy 363.402004 -65.674321)
			(xy 363.40976 -65.728269) (xy 363.410246 -65.75552) (xy 363.410246 -65.761108) (xy 363.410668 -65.771125)
			(xy 363.418341 -65.789631) (xy 363.432514 -65.80379) (xy 363.451029 -65.811443) (xy 363.461046 -65.811908)
			(xy 388.596378 -65.811908) (xy 388.606403 -65.811492) (xy 388.624929 -65.803827) (xy 388.63911 -65.789654)
			(xy 388.646786 -65.771133) (xy 388.647178 -65.761108) (xy 388.647178 -65.75552) (xy 388.647664 -65.728269)
			(xy 388.65542 -65.674321) (xy 388.670775 -65.622026) (xy 388.693417 -65.572449) (xy 388.722883 -65.526599)
			(xy 388.758574 -65.485408) (xy 388.799765 -65.449717) (xy 388.845615 -65.420251) (xy 388.895192 -65.397609)
			(xy 388.947487 -65.382254) (xy 389.001435 -65.374498) (xy 389.055937 -65.374498) (xy 389.109885 -65.382254)
			(xy 389.16218 -65.397609) (xy 389.211757 -65.420251) (xy 389.257607 -65.449717) (xy 389.298798 -65.485408)
			(xy 389.334489 -65.526599) (xy 389.363955 -65.572449) (xy 389.386597 -65.622026) (xy 389.401952 -65.674321)
			(xy 389.409708 -65.728269) (xy 389.410194 -65.75552) (xy 389.410194 -65.761108) (xy 389.410684 -65.771115)
			(xy 389.418344 -65.789605) (xy 389.432497 -65.803757) (xy 389.450987 -65.811417) (xy 389.460994 -65.811908)
			(xy 414.596326 -65.811908) (xy 414.606331 -65.811415) (xy 414.624815 -65.803752) (xy 414.638962 -65.7896)
			(xy 414.646619 -65.771113) (xy 414.647126 -65.761108) (xy 414.647126 -65.75552) (xy 414.647612 -65.728269)
			(xy 414.655368 -65.674321) (xy 414.670723 -65.622026) (xy 414.693365 -65.572449) (xy 414.722831 -65.526599)
			(xy 414.758522 -65.485408) (xy 414.799713 -65.449717) (xy 414.845563 -65.420251) (xy 414.89514 -65.397609)
			(xy 414.947435 -65.382254) (xy 415.001383 -65.374498) (xy 415.055885 -65.374498) (xy 415.109833 -65.382254)
			(xy 415.162128 -65.397609) (xy 415.211705 -65.420251) (xy 415.257555 -65.449717) (xy 415.298746 -65.485408)
			(xy 415.334437 -65.526599) (xy 415.363903 -65.572449) (xy 415.386545 -65.622026) (xy 415.4019 -65.674321)
			(xy 415.409656 -65.728269) (xy 415.410142 -65.75552) (xy 415.410142 -65.761108) (xy 415.410564 -65.771125)
			(xy 415.418236 -65.789632) (xy 415.43241 -65.803792) (xy 415.450924 -65.811446) (xy 415.460942 -65.811908)
			(xy 440.596274 -65.811908) (xy 440.606299 -65.811493) (xy 440.624827 -65.803828) (xy 440.639009 -65.789655)
			(xy 440.646686 -65.771133) (xy 440.647074 -65.761108) (xy 440.647074 -65.75552) (xy 440.64756 -65.728269)
			(xy 440.655316 -65.674321) (xy 440.670671 -65.622026) (xy 440.693313 -65.572449) (xy 440.722779 -65.526599)
			(xy 440.75847 -65.485408) (xy 440.799661 -65.449717) (xy 440.845511 -65.420251) (xy 440.895088 -65.397609)
			(xy 440.947383 -65.382254) (xy 441.001331 -65.374498) (xy 441.055833 -65.374498) (xy 441.109781 -65.382254)
			(xy 441.162076 -65.397609) (xy 441.211653 -65.420251) (xy 441.257503 -65.449717) (xy 441.298694 -65.485408)
			(xy 441.334385 -65.526599) (xy 441.363851 -65.572449) (xy 441.386493 -65.622026) (xy 441.401848 -65.674321)
			(xy 441.409604 -65.728269) (xy 441.41009 -65.75552) (xy 441.41009 -65.761108) (xy 441.410579 -65.771115)
			(xy 441.41824 -65.789606) (xy 441.432392 -65.803759) (xy 441.450883 -65.81142) (xy 441.46089 -65.811908)
			(xy 450.180202 -65.811908) (xy 450.189854 -65.810892) (xy 450.197098 -65.809265) (xy 450.210269 -65.802425)
			(xy 450.215762 -65.79743) (xy 456.080368 -59.932824) (xy 456.085355 -59.927325) (xy 456.092203 -59.914159)
			(xy 456.09383 -59.906916) (xy 456.094846 -59.897264) (xy 456.094846 -56.070754) (xy 456.09468 -56.064744)
			(xy 456.091859 -56.05306) (xy 456.089258 -56.04764) (xy 456.08742 -56.044164) (xy 456.082829 -56.037783)
			(xy 456.080114 -56.03494) (xy 454.162414 -54.11724) (xy 454.15288 -54.108827) (xy 454.128487 -54.101766)
			(xy 454.115932 -54.103778) (xy 454.05929 -54.119018) (xy 454.028302 -54.1274) (xy 454.021904 -54.129352)
			(xy 454.010324 -54.136036) (xy 454.005442 -54.140608) (xy 454.00087 -54.14518) (xy 453.994266 -54.15661)
			(xy 453.992488 -54.163468) (xy 453.984998 -54.190373) (xy 453.963229 -54.241803) (xy 453.934194 -54.28951)
			(xy 453.898512 -54.332472) (xy 453.856947 -54.369772) (xy 453.810387 -54.400613) (xy 453.759827 -54.424334)
			(xy 453.706349 -54.440429) (xy 453.651096 -54.448554) (xy 453.623172 -54.448964) (xy 453.595922 -54.448499)
			(xy 453.541976 -54.440738) (xy 453.489684 -54.425379) (xy 453.44011 -54.402735) (xy 453.394264 -54.373265)
			(xy 453.353078 -54.337571) (xy 453.317392 -54.296378) (xy 453.287931 -54.250526) (xy 453.265295 -54.200948)
			(xy 453.249946 -54.148654) (xy 453.242196 -54.094707) (xy 453.241664 -54.067456) (xy 453.242153 -54.039537)
			(xy 453.250294 -53.984296) (xy 453.266395 -53.93083) (xy 453.290114 -53.88028) (xy 453.320943 -53.833725)
			(xy 453.358226 -53.792157) (xy 453.401166 -53.756464) (xy 453.448848 -53.727408) (xy 453.500255 -53.705607)
			(xy 453.52716 -53.69814) (xy 453.527414 -53.69814) (xy 453.533812 -53.696188) (xy 453.545394 -53.689505)
			(xy 453.550274 -53.684932) (xy 453.554846 -53.68036) (xy 453.56145 -53.66893) (xy 453.57161 -53.631338)
			(xy 453.58685 -53.574696) (xy 453.588364 -53.566392) (xy 453.586416 -53.549635) (xy 453.579092 -53.534438)
			(xy 453.573388 -53.528214) (xy 453.559164 -53.51399) (xy 453.556415 -53.511384) (xy 453.550292 -53.506925)
			(xy 453.546972 -53.5051) (xy 453.540876 -53.501798) (xy 453.533256 -53.500274) (xy 453.505113 -53.494194)
			(xy 453.45052 -53.475895) (xy 453.398652 -53.450897) (xy 453.350327 -53.419593) (xy 453.306308 -53.382478)
			(xy 453.267289 -53.340137) (xy 453.233886 -53.293239) (xy 453.206626 -53.242523) (xy 453.18594 -53.188789)
			(xy 453.178672 -53.16093) (xy 453.178672 -53.160676) (xy 453.176325 -53.152407) (xy 453.166979 -53.137994)
			(xy 453.160384 -53.132482) (xy 453.154288 -53.127656) (xy 453.138286 -53.122322) (xy 445.0842 -53.122322)
			(xy 445.076306 -53.122658) (xy 445.061301 -53.127576) (xy 445.054736 -53.131974) (xy 445.048386 -53.136292)
			(xy 445.039242 -53.148738) (xy 445.036448 -53.156612) (xy 445.026224 -53.185088) (xy 444.999321 -53.23928)
			(xy 444.965505 -53.28945) (xy 444.925367 -53.334721) (xy 444.879608 -53.374303) (xy 444.854584 -53.391308)
			(xy 444.84544 -53.39715) (xy 444.839852 -53.405786) (xy 444.837172 -53.410113) (xy 444.83345 -53.419585)
			(xy 444.832486 -53.424582) (xy 444.819786 -53.49875) (xy 444.819071 -53.504024) (xy 444.819581 -53.514652)
			(xy 444.820802 -53.519832) (xy 444.823088 -53.52923) (xy 444.829692 -53.537866) (xy 444.844584 -53.55792)
			(xy 444.869586 -53.601161) (xy 444.888735 -53.647294) (xy 444.901703 -53.695531) (xy 444.908267 -53.745048)
			(xy 444.908686 -53.770022) (xy 444.908686 -53.77053) (xy 444.908198 -53.797779) (xy 444.900438 -53.851722)
			(xy 444.88508 -53.904012) (xy 444.862437 -53.953584) (xy 444.832969 -53.999429) (xy 444.797277 -54.040614)
			(xy 444.756088 -54.0763) (xy 444.710239 -54.105761) (xy 444.660664 -54.128398) (xy 444.608372 -54.143749)
			(xy 444.554427 -54.151501) (xy 444.527178 -54.152038) (xy 444.499809 -54.151565) (xy 444.445633 -54.143737)
			(xy 444.393133 -54.128245) (xy 444.343386 -54.105408) (xy 444.297414 -54.075695) (xy 444.27648 -54.058058)
			(xy 444.269368 -54.051962) (xy 444.260986 -54.048914) (xy 444.256698 -54.047395) (xy 444.247754 -54.045736)
			(xy 444.243206 -54.045612) (xy 444.17615 -54.045612) (xy 444.171602 -54.045734) (xy 444.162657 -54.047391)
			(xy 444.15837 -54.048914) (xy 444.149988 -54.051962) (xy 444.142876 -54.058058) (xy 444.121945 -54.0757)
			(xy 444.075979 -54.105427) (xy 444.026232 -54.128269) (xy 443.973728 -54.143758) (xy 443.919548 -54.151574)
			(xy 443.892178 -54.152038) (xy 443.864927 -54.151551) (xy 443.81098 -54.143792) (xy 443.758686 -54.128435)
			(xy 443.70911 -54.105793) (xy 443.66326 -54.076327) (xy 443.62207 -54.040636) (xy 443.586378 -53.999446)
			(xy 443.556911 -53.953597) (xy 443.534268 -53.904021) (xy 443.51891 -53.851728) (xy 443.51115 -53.797781)
			(xy 443.51067 -53.77053) (xy 443.511202 -53.741613) (xy 443.519926 -53.684441) (xy 443.537179 -53.62924)
			(xy 443.562566 -53.577276) (xy 443.595505 -53.529739) (xy 443.635241 -53.487718) (xy 443.657736 -53.46954)
			(xy 443.66512 -53.463257) (xy 443.674915 -53.446542) (xy 443.676786 -53.437028) (xy 443.677294 -53.429408)
			(xy 443.677294 -53.349652) (xy 443.676786 -53.342032) (xy 443.675029 -53.333302) (xy 443.666454 -53.31771)
			(xy 443.660022 -53.311552) (xy 443.657736 -53.30952) (xy 443.637891 -53.29356) (xy 443.6022 -53.257232)
			(xy 443.571665 -53.216474) (xy 443.54683 -53.172013) (xy 443.537086 -53.148484) (xy 443.53353 -53.139594)
			(xy 443.52083 -53.130958) (xy 443.514423 -53.12693) (xy 443.499947 -53.12254) (xy 443.492382 -53.122322)
			(xy 443.180978 -53.122322) (xy 443.180216 -53.122322) (xy 443.170165 -53.122898) (xy 443.1517 -53.130882)
			(xy 443.144402 -53.137816) (xy 443.132718 -53.15077) (xy 443.131702 -53.151786) (xy 443.127081 -53.156706)
			(xy 443.12039 -53.168422) (xy 443.118494 -53.1749) (xy 443.116716 -53.1876) (xy 443.116716 -53.219604)
			(xy 443.116852 -53.224637) (xy 443.118893 -53.234495) (xy 443.12078 -53.239162) (xy 443.139778 -53.257452)
			(xy 443.173099 -53.298326) (xy 443.200535 -53.343362) (xy 443.221574 -53.391718) (xy 443.235821 -53.442492)
			(xy 443.243012 -53.494735) (xy 443.243462 -53.521102) (xy 443.242897 -53.550665) (xy 443.233877 -53.609099)
			(xy 443.216047 -53.665473) (xy 443.189826 -53.718468) (xy 443.155827 -53.766841) (xy 443.135766 -53.788564)
			(xy 443.132972 -53.79593) (xy 443.132972 -53.87213) (xy 443.133093 -53.876678) (xy 443.134748 -53.885624)
			(xy 443.136274 -53.88991) (xy 443.139322 -53.898292) (xy 443.145418 -53.905404) (xy 443.163057 -53.926338)
			(xy 443.192778 -53.972306) (xy 443.21562 -54.022053) (xy 443.231114 -54.074554) (xy 443.238942 -54.128732)
			(xy 443.238941 -54.183471) (xy 443.231114 -54.237649) (xy 443.215619 -54.29015) (xy 443.201827 -54.320186)
			(xy 445.430402 -54.320186) (xy 445.430859 -54.292815) (xy 445.438679 -54.238636) (xy 445.45417 -54.186133)
			(xy 445.477014 -54.136386) (xy 445.50674 -54.09042) (xy 445.524382 -54.069488) (xy 445.524636 -54.069234)
			(xy 445.530218 -54.062145) (xy 445.536467 -54.04523) (xy 445.536828 -54.036214) (xy 445.536828 -53.969158)
			(xy 445.536437 -53.960145) (xy 445.530212 -53.943228) (xy 445.524636 -53.936138) (xy 445.524382 -53.936138)
			(xy 445.524382 -53.935884) (xy 445.506766 -53.914933) (xy 445.477051 -53.868965) (xy 445.454211 -53.819223)
			(xy 445.438715 -53.766726) (xy 445.43088 -53.712554) (xy 445.430402 -53.685186) (xy 445.430888 -53.657935)
			(xy 445.438644 -53.603987) (xy 445.453999 -53.551692) (xy 445.476641 -53.502115) (xy 445.506107 -53.456265)
			(xy 445.541798 -53.415074) (xy 445.582989 -53.379383) (xy 445.628839 -53.349917) (xy 445.678416 -53.327275)
			(xy 445.730711 -53.31192) (xy 445.784659 -53.304164) (xy 445.839161 -53.304164) (xy 445.893109 -53.31192)
			(xy 445.945404 -53.327275) (xy 445.994981 -53.349917) (xy 446.040831 -53.379383) (xy 446.082022 -53.415074)
			(xy 446.117713 -53.456265) (xy 446.147179 -53.502115) (xy 446.169821 -53.551692) (xy 446.185176 -53.603987)
			(xy 446.192932 -53.657935) (xy 446.193418 -53.685186) (xy 446.192964 -53.712557) (xy 446.185146 -53.766737)
			(xy 446.169655 -53.819241) (xy 446.14681 -53.868988) (xy 446.117082 -53.914954) (xy 446.099438 -53.935884)
			(xy 446.099184 -53.936138) (xy 446.093615 -53.943237) (xy 446.087358 -53.960144) (xy 446.086992 -53.969158)
			(xy 446.086992 -54.036214) (xy 446.087344 -54.045231) (xy 446.093595 -54.062148) (xy 446.099184 -54.069234)
			(xy 446.099438 -54.069234) (xy 446.099438 -54.069488) (xy 446.117091 -54.090409) (xy 446.1468 -54.136385)
			(xy 446.169632 -54.186136) (xy 446.18512 -54.238639) (xy 446.192946 -54.292816) (xy 446.193418 -54.320186)
			(xy 446.192932 -54.347437) (xy 446.185176 -54.401385) (xy 446.169821 -54.45368) (xy 446.147179 -54.503257)
			(xy 446.117713 -54.549107) (xy 446.082022 -54.590298) (xy 446.040831 -54.625989) (xy 445.994981 -54.655455)
			(xy 445.945404 -54.678097) (xy 445.893109 -54.693452) (xy 445.839161 -54.701208) (xy 445.784659 -54.701208)
			(xy 445.730711 -54.693452) (xy 445.678416 -54.678097) (xy 445.628839 -54.655455) (xy 445.582989 -54.625989)
			(xy 445.541798 -54.590298) (xy 445.506107 -54.549107) (xy 445.476641 -54.503257) (xy 445.453999 -54.45368)
			(xy 445.438644 -54.401385) (xy 445.430888 -54.347437) (xy 445.430402 -54.320186) (xy 443.201827 -54.320186)
			(xy 443.192776 -54.339896) (xy 443.163055 -54.385865) (xy 443.145418 -54.4068) (xy 443.139322 -54.413912)
			(xy 443.136274 -54.422294) (xy 443.134746 -54.42658) (xy 443.133081 -54.435525) (xy 443.132972 -54.440074)
			(xy 443.132972 -54.50713) (xy 443.133093 -54.511678) (xy 443.134748 -54.520624) (xy 443.136274 -54.52491)
			(xy 443.139322 -54.533292) (xy 443.145418 -54.540404) (xy 443.163059 -54.561336) (xy 443.192783 -54.607303)
			(xy 443.215625 -54.65705) (xy 443.231114 -54.709553) (xy 443.238931 -54.763732) (xy 443.239047 -54.770528)
			(xy 446.370964 -54.770528) (xy 446.371431 -54.743158) (xy 446.379246 -54.688978) (xy 446.394734 -54.636474)
			(xy 446.417576 -54.586727) (xy 446.447302 -54.540761) (xy 446.464944 -54.51983) (xy 446.465198 -54.519576)
			(xy 446.470801 -54.5125) (xy 446.477038 -54.495575) (xy 446.47739 -54.486556) (xy 446.47739 -54.4195)
			(xy 446.477035 -54.410483) (xy 446.470786 -54.393566) (xy 446.465198 -54.38648) (xy 446.464944 -54.38648)
			(xy 446.464944 -54.386226) (xy 446.44731 -54.365289) (xy 446.417596 -54.319318) (xy 446.394759 -54.269572)
			(xy 446.379266 -54.217072) (xy 446.371438 -54.162897) (xy 446.370964 -54.135528) (xy 446.37145 -54.108277)
			(xy 446.379206 -54.054329) (xy 446.394561 -54.002034) (xy 446.417203 -53.952457) (xy 446.446669 -53.906607)
			(xy 446.48236 -53.865416) (xy 446.523551 -53.829725) (xy 446.569401 -53.800259) (xy 446.618978 -53.777617)
			(xy 446.671273 -53.762262) (xy 446.725221 -53.754506) (xy 446.779723 -53.754506) (xy 446.833671 -53.762262)
			(xy 446.885966 -53.777617) (xy 446.935543 -53.800259) (xy 446.981393 -53.829725) (xy 447.022584 -53.865416)
			(xy 447.058275 -53.906607) (xy 447.087741 -53.952457) (xy 447.106503 -53.993538) (xy 450.996794 -53.993538)
			(xy 450.996794 -53.933602) (xy 451.004617 -53.87418) (xy 451.02013 -53.816287) (xy 451.043066 -53.760914)
			(xy 451.073033 -53.709008) (xy 451.10952 -53.661458) (xy 451.1519 -53.619078) (xy 451.19945 -53.582591)
			(xy 451.251356 -53.552624) (xy 451.306729 -53.529688) (xy 451.364622 -53.514175) (xy 451.424044 -53.506352)
			(xy 451.48398 -53.506352) (xy 451.543402 -53.514175) (xy 451.601295 -53.529688) (xy 451.656668 -53.552624)
			(xy 451.708574 -53.582591) (xy 451.756124 -53.619078) (xy 451.798504 -53.661458) (xy 451.834991 -53.709008)
			(xy 451.864958 -53.760914) (xy 451.887894 -53.816287) (xy 451.903407 -53.87418) (xy 451.91123 -53.933602)
			(xy 451.91172 -53.96357) (xy 451.91123 -53.993538) (xy 451.903407 -54.05296) (xy 451.887894 -54.110853)
			(xy 451.864958 -54.166226) (xy 451.834991 -54.218132) (xy 451.798504 -54.265682) (xy 451.756124 -54.308062)
			(xy 451.708574 -54.344549) (xy 451.656668 -54.374516) (xy 451.601295 -54.397452) (xy 451.543402 -54.412965)
			(xy 451.48398 -54.420788) (xy 451.424044 -54.420788) (xy 451.364622 -54.412965) (xy 451.306729 -54.397452)
			(xy 451.251356 -54.374516) (xy 451.19945 -54.344549) (xy 451.1519 -54.308062) (xy 451.10952 -54.265682)
			(xy 451.073033 -54.218132) (xy 451.043066 -54.166226) (xy 451.02013 -54.110853) (xy 451.004617 -54.05296)
			(xy 450.996794 -53.993538) (xy 447.106503 -53.993538) (xy 447.110383 -54.002034) (xy 447.125738 -54.054329)
			(xy 447.133494 -54.108277) (xy 447.13398 -54.135528) (xy 447.133535 -54.162899) (xy 447.125713 -54.217079)
			(xy 447.110219 -54.269583) (xy 447.087373 -54.319329) (xy 447.057643 -54.365295) (xy 447.04 -54.386226)
			(xy 447.039746 -54.38648) (xy 447.034155 -54.393563) (xy 447.027912 -54.410483) (xy 447.027554 -54.4195)
			(xy 447.027554 -54.486556) (xy 447.02792 -54.495572) (xy 447.03416 -54.51249) (xy 447.039746 -54.519576)
			(xy 447.04 -54.519576) (xy 447.04 -54.51983) (xy 447.05762 -54.540778) (xy 447.087334 -54.586746)
			(xy 447.110174 -54.63649) (xy 447.12567 -54.688987) (xy 447.133503 -54.74316) (xy 447.13398 -54.770528)
			(xy 447.133494 -54.797779) (xy 447.125738 -54.851727) (xy 447.110383 -54.904022) (xy 447.087741 -54.953599)
			(xy 447.058275 -54.999449) (xy 447.022584 -55.04064) (xy 446.981393 -55.076331) (xy 446.970306 -55.083456)
			(xy 453.241154 -55.083456) (xy 453.245225 -55.027834) (xy 453.257351 -54.973397) (xy 453.277274 -54.921306)
			(xy 453.30457 -54.872671) (xy 453.338656 -54.828528) (xy 453.378805 -54.789819) (xy 453.424163 -54.757368)
			(xy 453.473763 -54.731867) (xy 453.526547 -54.71386) (xy 453.58139 -54.70373) (xy 453.637124 -54.701693)
			(xy 453.692561 -54.707793) (xy 453.746518 -54.721899) (xy 453.797847 -54.743711) (xy 453.845453 -54.772765)
			(xy 453.888321 -54.80844) (xy 453.925538 -54.849977) (xy 453.956311 -54.89649) (xy 453.979983 -54.946987)
			(xy 453.996051 -55.000394) (xy 454.004171 -55.05557) (xy 454.00468 -55.083456) (xy 454.004171 -55.111342)
			(xy 453.996051 -55.166518) (xy 453.979983 -55.219925) (xy 453.956311 -55.270422) (xy 453.925538 -55.316935)
			(xy 453.888321 -55.358472) (xy 453.845453 -55.394147) (xy 453.797847 -55.423201) (xy 453.746518 -55.445013)
			(xy 453.692561 -55.459119) (xy 453.637124 -55.465219) (xy 453.58139 -55.463182) (xy 453.526547 -55.453052)
			(xy 453.473763 -55.435045) (xy 453.424163 -55.409544) (xy 453.378805 -55.377093) (xy 453.338656 -55.338384)
			(xy 453.30457 -55.294241) (xy 453.277274 -55.245606) (xy 453.257351 -55.193515) (xy 453.245225 -55.139078)
			(xy 453.241154 -55.083456) (xy 446.970306 -55.083456) (xy 446.935543 -55.105797) (xy 446.885966 -55.128439)
			(xy 446.833671 -55.143794) (xy 446.779723 -55.15155) (xy 446.725221 -55.15155) (xy 446.671273 -55.143794)
			(xy 446.618978 -55.128439) (xy 446.569401 -55.105797) (xy 446.523551 -55.076331) (xy 446.48236 -55.04064)
			(xy 446.446669 -54.999449) (xy 446.417203 -54.953599) (xy 446.394561 -54.904022) (xy 446.379206 -54.851727)
			(xy 446.37145 -54.797779) (xy 446.370964 -54.770528) (xy 443.239047 -54.770528) (xy 443.239398 -54.791102)
			(xy 443.238912 -54.818353) (xy 443.231156 -54.872301) (xy 443.215801 -54.924596) (xy 443.193159 -54.974173)
			(xy 443.163693 -55.020023) (xy 443.128002 -55.061214) (xy 443.086811 -55.096905) (xy 443.040961 -55.126371)
			(xy 442.991384 -55.149013) (xy 442.939089 -55.164368) (xy 442.885141 -55.172124) (xy 442.830639 -55.172124)
			(xy 442.776691 -55.164368) (xy 442.724396 -55.149013) (xy 442.674819 -55.126371) (xy 442.628969 -55.096905)
			(xy 442.587778 -55.061214) (xy 442.552087 -55.020023) (xy 442.522621 -54.974173) (xy 442.499979 -54.924596)
			(xy 442.484624 -54.872301) (xy 442.476868 -54.818353) (xy 442.476382 -54.791102) (xy 442.476853 -54.763732)
			(xy 442.484676 -54.709553) (xy 442.500163 -54.657049) (xy 442.522994 -54.607297) (xy 442.552701 -54.561319)
			(xy 442.570362 -54.540404) (xy 442.576458 -54.533292) (xy 442.579506 -54.52491) (xy 442.581035 -54.520624)
			(xy 442.582701 -54.511679) (xy 442.582808 -54.50713) (xy 442.582808 -54.440074) (xy 442.582688 -54.435526)
			(xy 442.581035 -54.426579) (xy 442.579506 -54.422294) (xy 442.576458 -54.413912) (xy 442.570362 -54.4068)
			(xy 442.55272 -54.385868) (xy 442.522992 -54.339901) (xy 442.500144 -54.290155) (xy 442.484646 -54.237652)
			(xy 442.476817 -54.183473) (xy 442.476816 -54.12873) (xy 442.484646 -54.074551) (xy 442.500143 -54.022048)
			(xy 442.522991 -53.972302) (xy 442.552718 -53.926334) (xy 442.570362 -53.905404) (xy 442.576458 -53.898292)
			(xy 442.579506 -53.88991) (xy 442.581035 -53.885624) (xy 442.582701 -53.876679) (xy 442.582808 -53.87213)
			(xy 442.582808 -53.79593) (xy 442.580014 -53.788564) (xy 442.559942 -53.766853) (xy 442.525964 -53.718467)
			(xy 442.499756 -53.665469) (xy 442.481931 -53.609095) (xy 442.472906 -53.550664) (xy 442.472318 -53.521102)
			(xy 442.472751 -53.494703) (xy 442.479959 -53.4424) (xy 442.494239 -53.39157) (xy 442.515324 -53.343166)
			(xy 442.542819 -53.298093) (xy 442.57621 -53.257195) (xy 442.595254 -53.238908) (xy 442.59701 -53.234341)
			(xy 442.598931 -53.224749) (xy 442.599064 -53.219858) (xy 442.599064 -53.187854) (xy 442.598302 -53.17871)
			(xy 442.597286 -53.1749) (xy 442.595393 -53.168421) (xy 442.588702 -53.156703) (xy 442.584078 -53.151786)
			(xy 442.583062 -53.15077) (xy 442.571378 -53.137816) (xy 442.564089 -53.130863) (xy 442.545622 -53.122859)
			(xy 442.535564 -53.122322) (xy 440.62269 -53.122322) (xy 440.613881 -53.122741) (xy 440.597329 -53.128786)
			(xy 440.583784 -53.140059) (xy 440.579002 -53.147468) (xy 440.534552 -53.22316) (xy 440.531386 -53.229097)
			(xy 440.527916 -53.24209) (xy 440.527694 -53.248814) (xy 440.527694 -53.262022) (xy 440.529472 -53.265324)
			(xy 440.534298 -53.273706) (xy 440.545994 -53.295242) (xy 440.564412 -53.340656) (xy 440.576873 -53.388053)
			(xy 440.58317 -53.436655) (xy 440.583574 -53.461158) (xy 440.583574 -53.461412) (xy 440.583101 -53.488782)
			(xy 440.575276 -53.542959) (xy 440.559786 -53.595461) (xy 440.536952 -53.64521) (xy 440.507241 -53.691184)
			(xy 440.489594 -53.71211) (xy 440.483498 -53.719222) (xy 440.48045 -53.727604) (xy 440.478929 -53.731892)
			(xy 440.477267 -53.740836) (xy 440.477148 -53.745384) (xy 440.477148 -53.81244) (xy 440.477269 -53.816988)
			(xy 440.478926 -53.825933) (xy 440.48045 -53.83022) (xy 440.483498 -53.838602) (xy 440.489594 -53.845714)
			(xy 440.507233 -53.866647) (xy 440.536954 -53.912615) (xy 440.559797 -53.962361) (xy 440.575291 -54.014862)
			(xy 440.583117 -54.069039) (xy 440.583116 -54.123779) (xy 440.575287 -54.177956) (xy 440.559791 -54.230456)
			(xy 440.536946 -54.280201) (xy 440.507222 -54.326167) (xy 440.489594 -54.34711) (xy 440.483498 -54.354222)
			(xy 440.48045 -54.362604) (xy 440.478929 -54.366892) (xy 440.477267 -54.375836) (xy 440.477148 -54.380384)
			(xy 440.477148 -54.44744) (xy 440.477269 -54.451988) (xy 440.478926 -54.460933) (xy 440.48045 -54.46522)
			(xy 440.483498 -54.473602) (xy 440.489594 -54.480714) (xy 440.507235 -54.501646) (xy 440.53696 -54.547612)
			(xy 440.559802 -54.597359) (xy 440.575291 -54.649862) (xy 440.583107 -54.704042) (xy 440.583574 -54.731412)
			(xy 440.583088 -54.758663) (xy 440.575332 -54.812611) (xy 440.559977 -54.864906) (xy 440.537335 -54.914483)
			(xy 440.507869 -54.960333) (xy 440.472178 -55.001524) (xy 440.430987 -55.037215) (xy 440.385137 -55.066681)
			(xy 440.33556 -55.089323) (xy 440.283265 -55.104678) (xy 440.229317 -55.112434) (xy 440.174815 -55.112434)
			(xy 440.120867 -55.104678) (xy 440.068572 -55.089323) (xy 440.018995 -55.066681) (xy 439.973145 -55.037215)
			(xy 439.931954 -55.001524) (xy 439.896263 -54.960333) (xy 439.866797 -54.914483) (xy 439.844155 -54.864906)
			(xy 439.8288 -54.812611) (xy 439.821044 -54.758663) (xy 439.820558 -54.731412) (xy 439.821036 -54.704045)
			(xy 439.828872 -54.649873) (xy 439.844371 -54.597378) (xy 439.867214 -54.547637) (xy 439.896932 -54.501673)
			(xy 439.914538 -54.480714) (xy 439.920634 -54.473602) (xy 439.923682 -54.46522) (xy 439.925204 -54.460932)
			(xy 439.926869 -54.451988) (xy 439.926984 -54.44744) (xy 439.926984 -54.380384) (xy 439.926856 -54.375837)
			(xy 439.925188 -54.366896) (xy 439.923682 -54.362604) (xy 439.920634 -54.354222) (xy 439.914538 -54.34711)
			(xy 439.896896 -54.326177) (xy 439.867169 -54.28021) (xy 439.844321 -54.230463) (xy 439.828823 -54.17796)
			(xy 439.820992 -54.12378) (xy 439.820991 -54.069038) (xy 439.828819 -54.014858) (xy 439.844315 -53.962354)
			(xy 439.86716 -53.912606) (xy 439.896885 -53.866637) (xy 439.914538 -53.845714) (xy 439.920634 -53.838602)
			(xy 439.923682 -53.83022) (xy 439.925204 -53.825932) (xy 439.926869 -53.816988) (xy 439.926984 -53.81244)
			(xy 439.926984 -53.745384) (xy 439.926856 -53.740837) (xy 439.925188 -53.731896) (xy 439.923682 -53.727604)
			(xy 439.920634 -53.719222) (xy 439.914538 -53.71211) (xy 439.896894 -53.69118) (xy 439.867164 -53.645214)
			(xy 439.844317 -53.595468) (xy 439.828824 -53.542964) (xy 439.821003 -53.488783) (xy 439.820558 -53.461412)
			(xy 439.820558 -53.461158) (xy 439.820934 -53.436652) (xy 439.827214 -53.388045) (xy 439.839679 -53.340644)
			(xy 439.858121 -53.295235) (xy 439.869834 -53.273706) (xy 439.87466 -53.265324) (xy 439.876438 -53.262022)
			(xy 439.876438 -53.248814) (xy 439.876264 -53.242083) (xy 439.872782 -53.229083) (xy 439.86958 -53.22316)
			(xy 439.82513 -53.147468) (xy 439.820369 -53.140035) (xy 439.806837 -53.128723) (xy 439.79026 -53.122698)
			(xy 439.781442 -53.122322) (xy 433.865528 -53.122322) (xy 433.856967 -53.122705) (xy 433.840824 -53.128432)
			(xy 433.827448 -53.139129) (xy 433.822602 -53.146198) (xy 433.787296 -53.20792) (xy 433.777644 -53.224684)
			(xy 433.77455 -53.230501) (xy 433.771213 -53.243243) (xy 433.77104 -53.24983) (xy 433.77104 -53.263546)
			(xy 433.778152 -53.275484) (xy 433.790706 -53.297591) (xy 433.810487 -53.344425) (xy 433.823859 -53.393474)
			(xy 433.830586 -53.443866) (xy 433.830984 -53.469286) (xy 433.830984 -53.475382) (xy 433.830087 -53.502346)
			(xy 433.821634 -53.555631) (xy 433.805758 -53.607192) (xy 433.782774 -53.656002) (xy 433.753141 -53.701087)
			(xy 433.717452 -53.741546) (xy 433.676418 -53.776572) (xy 433.630857 -53.805467) (xy 433.581679 -53.827654)
			(xy 433.529866 -53.84269) (xy 433.476452 -53.850274) (xy 433.449476 -53.850794) (xy 433.422107 -53.850321)
			(xy 433.36793 -53.842494) (xy 433.315429 -53.827004) (xy 433.26568 -53.804169) (xy 433.219706 -53.774458)
			(xy 433.198778 -53.756814) (xy 433.191666 -53.750718) (xy 433.183284 -53.74767) (xy 433.178998 -53.746144)
			(xy 433.170053 -53.744483) (xy 433.165504 -53.744368) (xy 433.098448 -53.744368) (xy 433.0939 -53.744491)
			(xy 433.084956 -53.74615) (xy 433.080668 -53.74767) (xy 433.072286 -53.750718) (xy 433.065174 -53.756814)
			(xy 433.044242 -53.774454) (xy 432.998274 -53.804176) (xy 432.948527 -53.827015) (xy 432.896024 -53.842501)
			(xy 432.841846 -53.850315) (xy 432.814476 -53.850794) (xy 432.7875 -53.850326) (xy 432.734087 -53.842724)
			(xy 432.682278 -53.827674) (xy 432.633105 -53.805477) (xy 432.587548 -53.776574) (xy 432.546516 -53.741544)
			(xy 432.510828 -53.701083) (xy 432.481195 -53.655999) (xy 432.458207 -53.60719) (xy 432.442322 -53.55563)
			(xy 432.433859 -53.502347) (xy 432.432968 -53.475382) (xy 432.432968 -53.469286) (xy 432.433393 -53.443869)
			(xy 432.440146 -53.393486) (xy 432.453518 -53.344442) (xy 432.473273 -53.297603) (xy 432.4858 -53.275484)
			(xy 432.489356 -53.269642) (xy 432.492912 -53.256434) (xy 432.492912 -53.24983) (xy 432.492705 -53.243249)
			(xy 432.489365 -53.230516) (xy 432.486308 -53.224684) (xy 432.476656 -53.20792) (xy 432.44135 -53.146198)
			(xy 432.436538 -53.139095) (xy 432.423169 -53.12836) (xy 432.406997 -53.122667) (xy 432.398424 -53.122322)
			(xy 428.116492 -53.122322) (xy 428.108132 -53.122697) (xy 428.092314 -53.128128) (xy 428.085504 -53.13299)
			(xy 428.079154 -53.13807) (xy 428.07001 -53.15204) (xy 428.067724 -53.16093) (xy 428.05996 -53.190366)
			(xy 428.037696 -53.247025) (xy 428.008118 -53.300234) (xy 427.971749 -53.349053) (xy 427.92923 -53.392621)
			(xy 427.881312 -53.43017) (xy 427.828841 -53.461036) (xy 427.772741 -53.484675) (xy 427.714002 -53.50067)
			(xy 427.653662 -53.508738) (xy 427.592786 -53.508738) (xy 427.532446 -53.50067) (xy 427.473707 -53.484675)
			(xy 427.417607 -53.461036) (xy 427.365136 -53.43017) (xy 427.317218 -53.392621) (xy 427.274699 -53.349053)
			(xy 427.23833 -53.300234) (xy 427.208752 -53.247025) (xy 427.186488 -53.190366) (xy 427.178724 -53.16093)
			(xy 427.178724 -53.160676) (xy 427.17638 -53.152405) (xy 427.16704 -53.137985) (xy 427.160436 -53.132482)
			(xy 427.15434 -53.127656) (xy 427.138338 -53.122322) (xy 419.084252 -53.122322) (xy 419.076355 -53.12265)
			(xy 419.061341 -53.127556) (xy 419.054788 -53.131974) (xy 419.048438 -53.136292) (xy 419.039294 -53.148738)
			(xy 419.0365 -53.156612) (xy 419.026276 -53.185087) (xy 418.99937 -53.239277) (xy 418.965552 -53.289444)
			(xy 418.925411 -53.334712) (xy 418.879651 -53.37429) (xy 418.854636 -53.391308) (xy 418.845492 -53.39715)
			(xy 418.839904 -53.405786) (xy 418.837226 -53.410114) (xy 418.833508 -53.419586) (xy 418.832538 -53.424582)
			(xy 418.819838 -53.49875) (xy 418.819123 -53.504024) (xy 418.819633 -53.514652) (xy 418.820854 -53.519832)
			(xy 418.82314 -53.52923) (xy 418.829744 -53.537866) (xy 418.844634 -53.55792) (xy 418.869633 -53.601163)
			(xy 418.888779 -53.647296) (xy 418.901745 -53.695533) (xy 418.908308 -53.745048) (xy 418.908738 -53.770022)
			(xy 418.908738 -53.77053) (xy 418.90825 -53.797781) (xy 418.90049 -53.851727) (xy 418.885133 -53.90402)
			(xy 418.862491 -53.953595) (xy 418.833024 -53.999444) (xy 418.797333 -54.040633) (xy 418.756144 -54.076324)
			(xy 418.710295 -54.105791) (xy 418.66072 -54.128433) (xy 418.608427 -54.14379) (xy 418.554481 -54.15155)
			(xy 418.52723 -54.152038) (xy 418.499862 -54.151561) (xy 418.44569 -54.143727) (xy 418.393193 -54.128231)
			(xy 418.343451 -54.105389) (xy 418.297484 -54.075672) (xy 418.276532 -54.058058) (xy 418.26942 -54.051962)
			(xy 418.261038 -54.048914) (xy 418.25675 -54.047391) (xy 418.247807 -54.045722) (xy 418.243258 -54.045612)
			(xy 418.176202 -54.045612) (xy 418.171655 -54.045738) (xy 418.162713 -54.047403) (xy 418.158422 -54.048914)
			(xy 418.15004 -54.051962) (xy 418.142928 -54.058058) (xy 418.121998 -54.075703) (xy 418.076033 -54.105436)
			(xy 418.026287 -54.128285) (xy 417.973783 -54.143781) (xy 417.919602 -54.151605) (xy 417.89223 -54.152038)
			(xy 417.864977 -54.151554) (xy 417.811024 -54.143801) (xy 417.758724 -54.128449) (xy 417.709141 -54.10581)
			(xy 417.663285 -54.076345) (xy 417.622088 -54.040654) (xy 417.586391 -53.999463) (xy 417.556919 -53.953612)
			(xy 417.534272 -53.904032) (xy 417.518911 -53.851735) (xy 417.51115 -53.797783) (xy 417.510722 -53.77053)
			(xy 417.511254 -53.741613) (xy 417.519977 -53.684439) (xy 417.537229 -53.629237) (xy 417.562613 -53.577271)
			(xy 417.59555 -53.529731) (xy 417.635283 -53.487705) (xy 417.657788 -53.46954) (xy 417.665167 -53.463253)
			(xy 417.674951 -53.446537) (xy 417.676838 -53.437028) (xy 417.677346 -53.429408) (xy 417.677346 -53.349652)
			(xy 417.676838 -53.342032) (xy 417.675083 -53.3333) (xy 417.666515 -53.317702) (xy 417.660074 -53.311552)
			(xy 417.657788 -53.30952) (xy 417.637945 -53.293558) (xy 417.602257 -53.257228) (xy 417.571726 -53.216469)
			(xy 417.546894 -53.172008) (xy 417.537138 -53.148484) (xy 417.533582 -53.139594) (xy 417.520882 -53.130958)
			(xy 417.514477 -53.126923) (xy 417.500001 -53.122518) (xy 417.492434 -53.122322) (xy 417.18103 -53.122322)
			(xy 417.180268 -53.122322) (xy 417.170236 -53.122975) (xy 417.151809 -53.13096) (xy 417.144454 -53.137816)
			(xy 417.13277 -53.15077) (xy 417.131754 -53.151786) (xy 417.127137 -53.156708) (xy 417.120452 -53.168426)
			(xy 417.118546 -53.1749) (xy 417.116768 -53.1876) (xy 417.116768 -53.219604) (xy 417.116904 -53.224637)
			(xy 417.118943 -53.234495) (xy 417.120832 -53.239162) (xy 417.139832 -53.257451) (xy 417.173157 -53.298323)
			(xy 417.200597 -53.343359) (xy 417.221638 -53.391715) (xy 417.235888 -53.44249) (xy 417.243079 -53.494734)
			(xy 417.243514 -53.521102) (xy 417.242949 -53.550666) (xy 417.23393 -53.609101) (xy 417.216102 -53.665476)
			(xy 417.189884 -53.718472) (xy 417.155888 -53.766849) (xy 417.135818 -53.788564) (xy 417.133024 -53.79593)
			(xy 417.133024 -53.87213) (xy 417.133144 -53.876678) (xy 417.134799 -53.885624) (xy 417.136326 -53.88991)
			(xy 417.139374 -53.898292) (xy 417.14547 -53.905404) (xy 417.163111 -53.926337) (xy 417.192835 -53.972304)
			(xy 417.215681 -54.022051) (xy 417.231177 -54.074553) (xy 417.239005 -54.128731) (xy 417.239005 -54.183472)
			(xy 417.231176 -54.23765) (xy 417.21568 -54.290152) (xy 417.201887 -54.320186) (xy 419.430454 -54.320186)
			(xy 419.430899 -54.292815) (xy 419.43872 -54.238634) (xy 419.454213 -54.18613) (xy 419.47706 -54.136384)
			(xy 419.50679 -54.090418) (xy 419.524434 -54.069488) (xy 419.524688 -54.069234) (xy 419.530265 -54.062141)
			(xy 419.536518 -54.045229) (xy 419.53688 -54.036214) (xy 419.53688 -53.969158) (xy 419.536499 -53.960143)
			(xy 419.530269 -53.943226) (xy 419.524688 -53.936138) (xy 419.524434 -53.936138) (xy 419.524434 -53.935884)
			(xy 419.506826 -53.914927) (xy 419.477108 -53.868961) (xy 419.454266 -53.81922) (xy 419.438768 -53.766725)
			(xy 419.430932 -53.712554) (xy 419.430454 -53.685186) (xy 419.43094 -53.657935) (xy 419.438696 -53.603987)
			(xy 419.454051 -53.551692) (xy 419.476693 -53.502115) (xy 419.506159 -53.456265) (xy 419.54185 -53.415074)
			(xy 419.583041 -53.379383) (xy 419.628891 -53.349917) (xy 419.678468 -53.327275) (xy 419.730763 -53.31192)
			(xy 419.784711 -53.304164) (xy 419.839213 -53.304164) (xy 419.893161 -53.31192) (xy 419.945456 -53.327275)
			(xy 419.995033 -53.349917) (xy 420.040883 -53.379383) (xy 420.082074 -53.415074) (xy 420.117765 -53.456265)
			(xy 420.147231 -53.502115) (xy 420.169873 -53.551692) (xy 420.185228 -53.603987) (xy 420.192984 -53.657935)
			(xy 420.19347 -53.685186) (xy 420.193003 -53.712556) (xy 420.185187 -53.766736) (xy 420.169698 -53.819239)
			(xy 420.146856 -53.868986) (xy 420.117132 -53.914953) (xy 420.09949 -53.935884) (xy 420.099236 -53.936138)
			(xy 420.093662 -53.943233) (xy 420.087409 -53.960143) (xy 420.087044 -53.969158) (xy 420.087044 -54.036214)
			(xy 420.087385 -54.045233) (xy 420.093642 -54.06215) (xy 420.099236 -54.069234) (xy 420.09949 -54.069234)
			(xy 420.09949 -54.069488) (xy 420.117135 -54.090415) (xy 420.146847 -54.136389) (xy 420.169682 -54.186138)
			(xy 420.185171 -54.23864) (xy 420.192997 -54.292816) (xy 420.19347 -54.320186) (xy 420.192984 -54.347437)
			(xy 420.185228 -54.401385) (xy 420.169873 -54.45368) (xy 420.147231 -54.503257) (xy 420.117765 -54.549107)
			(xy 420.082074 -54.590298) (xy 420.040883 -54.625989) (xy 419.995033 -54.655455) (xy 419.945456 -54.678097)
			(xy 419.893161 -54.693452) (xy 419.839213 -54.701208) (xy 419.784711 -54.701208) (xy 419.730763 -54.693452)
			(xy 419.678468 -54.678097) (xy 419.628891 -54.655455) (xy 419.583041 -54.625989) (xy 419.54185 -54.590298)
			(xy 419.506159 -54.549107) (xy 419.476693 -54.503257) (xy 419.454051 -54.45368) (xy 419.438696 -54.401385)
			(xy 419.43094 -54.347437) (xy 419.430454 -54.320186) (xy 417.201887 -54.320186) (xy 417.192834 -54.339898)
			(xy 417.163109 -54.385866) (xy 417.14547 -54.4068) (xy 417.139374 -54.413912) (xy 417.136326 -54.422294)
			(xy 417.134805 -54.426582) (xy 417.133142 -54.435526) (xy 417.133024 -54.440074) (xy 417.133024 -54.50713)
			(xy 417.133144 -54.511678) (xy 417.134799 -54.520624) (xy 417.136326 -54.52491) (xy 417.139374 -54.533292)
			(xy 417.14547 -54.540404) (xy 417.163113 -54.561335) (xy 417.192841 -54.607301) (xy 417.215685 -54.657047)
			(xy 417.231176 -54.709551) (xy 417.238995 -54.763731) (xy 417.239108 -54.770528) (xy 420.371016 -54.770528)
			(xy 420.371495 -54.743158) (xy 420.379309 -54.688979) (xy 420.394795 -54.636476) (xy 420.417634 -54.586729)
			(xy 420.447356 -54.540762) (xy 420.464996 -54.51983) (xy 420.46525 -54.519576) (xy 420.470859 -54.512505)
			(xy 420.477091 -54.495576) (xy 420.477442 -54.486556) (xy 420.477442 -54.4195) (xy 420.477097 -54.410482)
			(xy 420.470843 -54.393564) (xy 420.46525 -54.38648) (xy 420.464996 -54.38648) (xy 420.464996 -54.386226)
			(xy 420.447355 -54.365295) (xy 420.417644 -54.319322) (xy 420.394808 -54.269574) (xy 420.379317 -54.217073)
			(xy 420.37149 -54.162897) (xy 420.371016 -54.135528) (xy 420.371502 -54.108277) (xy 420.379258 -54.054329)
			(xy 420.394613 -54.002034) (xy 420.417255 -53.952457) (xy 420.446721 -53.906607) (xy 420.482412 -53.865416)
			(xy 420.523603 -53.829725) (xy 420.569453 -53.800259) (xy 420.61903 -53.777617) (xy 420.671325 -53.762262)
			(xy 420.725273 -53.754506) (xy 420.779775 -53.754506) (xy 420.833723 -53.762262) (xy 420.886018 -53.777617)
			(xy 420.935595 -53.800259) (xy 420.981445 -53.829725) (xy 421.022636 -53.865416) (xy 421.058327 -53.906607)
			(xy 421.087793 -53.952457) (xy 421.106555 -53.993538) (xy 424.996846 -53.993538) (xy 424.996846 -53.933602)
			(xy 425.004669 -53.87418) (xy 425.020182 -53.816287) (xy 425.043118 -53.760914) (xy 425.073085 -53.709008)
			(xy 425.109572 -53.661458) (xy 425.151952 -53.619078) (xy 425.199502 -53.582591) (xy 425.251408 -53.552624)
			(xy 425.306781 -53.529688) (xy 425.364674 -53.514175) (xy 425.424096 -53.506352) (xy 425.484032 -53.506352)
			(xy 425.543454 -53.514175) (xy 425.601347 -53.529688) (xy 425.65672 -53.552624) (xy 425.708626 -53.582591)
			(xy 425.756176 -53.619078) (xy 425.798556 -53.661458) (xy 425.835043 -53.709008) (xy 425.86501 -53.760914)
			(xy 425.887946 -53.816287) (xy 425.903459 -53.87418) (xy 425.911282 -53.933602) (xy 425.911772 -53.96357)
			(xy 425.911282 -53.993538) (xy 425.903459 -54.05296) (xy 425.899575 -54.067456) (xy 427.241206 -54.067456)
			(xy 427.245277 -54.011834) (xy 427.257403 -53.957397) (xy 427.277326 -53.905306) (xy 427.304622 -53.856671)
			(xy 427.338708 -53.812528) (xy 427.378857 -53.773819) (xy 427.424215 -53.741368) (xy 427.473815 -53.715867)
			(xy 427.526599 -53.69786) (xy 427.581442 -53.68773) (xy 427.637176 -53.685693) (xy 427.692613 -53.691793)
			(xy 427.74657 -53.705899) (xy 427.797899 -53.727711) (xy 427.845505 -53.756765) (xy 427.888373 -53.79244)
			(xy 427.92559 -53.833977) (xy 427.956363 -53.88049) (xy 427.980035 -53.930987) (xy 427.996103 -53.984394)
			(xy 428.004223 -54.03957) (xy 428.004732 -54.067456) (xy 428.004223 -54.095342) (xy 427.996103 -54.150518)
			(xy 427.980035 -54.203925) (xy 427.963637 -54.238906) (xy 434.685946 -54.238906) (xy 434.690017 -54.183284)
			(xy 434.702143 -54.128847) (xy 434.722066 -54.076756) (xy 434.749362 -54.028121) (xy 434.783448 -53.983978)
			(xy 434.823597 -53.945269) (xy 434.868955 -53.912818) (xy 434.918555 -53.887317) (xy 434.971339 -53.86931)
			(xy 435.026182 -53.85918) (xy 435.081916 -53.857143) (xy 435.137353 -53.863243) (xy 435.19131 -53.877349)
			(xy 435.242639 -53.899161) (xy 435.290245 -53.928215) (xy 435.333113 -53.96389) (xy 435.37033 -54.005427)
			(xy 435.401103 -54.05194) (xy 435.424775 -54.102437) (xy 435.440843 -54.155844) (xy 435.448963 -54.21102)
			(xy 435.449472 -54.238906) (xy 435.448963 -54.266792) (xy 435.440843 -54.321968) (xy 435.424775 -54.375375)
			(xy 435.401103 -54.425872) (xy 435.37033 -54.472385) (xy 435.333113 -54.513922) (xy 435.290245 -54.549597)
			(xy 435.242639 -54.578651) (xy 435.19131 -54.600463) (xy 435.137353 -54.614569) (xy 435.081916 -54.620669)
			(xy 435.026182 -54.618632) (xy 434.971339 -54.608502) (xy 434.918555 -54.590495) (xy 434.868955 -54.564994)
			(xy 434.823597 -54.532543) (xy 434.783448 -54.493834) (xy 434.749362 -54.449691) (xy 434.722066 -54.401056)
			(xy 434.702143 -54.348965) (xy 434.690017 -54.294528) (xy 434.685946 -54.238906) (xy 427.963637 -54.238906)
			(xy 427.956363 -54.254422) (xy 427.92559 -54.300935) (xy 427.888373 -54.342472) (xy 427.845505 -54.378147)
			(xy 427.797899 -54.407201) (xy 427.74657 -54.429013) (xy 427.692613 -54.443119) (xy 427.637176 -54.449219)
			(xy 427.581442 -54.447182) (xy 427.526599 -54.437052) (xy 427.473815 -54.419045) (xy 427.424215 -54.393544)
			(xy 427.378857 -54.361093) (xy 427.338708 -54.322384) (xy 427.304622 -54.278241) (xy 427.277326 -54.229606)
			(xy 427.257403 -54.177515) (xy 427.245277 -54.123078) (xy 427.241206 -54.067456) (xy 425.899575 -54.067456)
			(xy 425.887946 -54.110853) (xy 425.86501 -54.166226) (xy 425.835043 -54.218132) (xy 425.798556 -54.265682)
			(xy 425.756176 -54.308062) (xy 425.708626 -54.344549) (xy 425.65672 -54.374516) (xy 425.601347 -54.397452)
			(xy 425.543454 -54.412965) (xy 425.484032 -54.420788) (xy 425.424096 -54.420788) (xy 425.364674 -54.412965)
			(xy 425.306781 -54.397452) (xy 425.251408 -54.374516) (xy 425.199502 -54.344549) (xy 425.151952 -54.308062)
			(xy 425.109572 -54.265682) (xy 425.073085 -54.218132) (xy 425.043118 -54.166226) (xy 425.020182 -54.110853)
			(xy 425.004669 -54.05296) (xy 424.996846 -53.993538) (xy 421.106555 -53.993538) (xy 421.110435 -54.002034)
			(xy 421.12579 -54.054329) (xy 421.133546 -54.108277) (xy 421.134032 -54.135528) (xy 421.133599 -54.1629)
			(xy 421.125776 -54.217081) (xy 421.11028 -54.269585) (xy 421.08743 -54.319331) (xy 421.057697 -54.365296)
			(xy 421.040052 -54.386226) (xy 421.039798 -54.38648) (xy 421.034213 -54.393568) (xy 421.027966 -54.410484)
			(xy 421.027606 -54.4195) (xy 421.027606 -54.486556) (xy 421.027983 -54.495571) (xy 421.034217 -54.512488)
			(xy 421.039798 -54.519576) (xy 421.040052 -54.519576) (xy 421.040052 -54.51983) (xy 421.057664 -54.540784)
			(xy 421.087382 -54.58675) (xy 421.110224 -54.636492) (xy 421.125721 -54.688988) (xy 421.133555 -54.74316)
			(xy 421.134032 -54.770528) (xy 421.133546 -54.797779) (xy 421.12579 -54.851727) (xy 421.110435 -54.904022)
			(xy 421.087793 -54.953599) (xy 421.058327 -54.999449) (xy 421.022636 -55.04064) (xy 420.981445 -55.076331)
			(xy 420.970358 -55.083456) (xy 427.241206 -55.083456) (xy 427.245277 -55.027834) (xy 427.257403 -54.973397)
			(xy 427.277326 -54.921306) (xy 427.304622 -54.872671) (xy 427.338708 -54.828528) (xy 427.378857 -54.789819)
			(xy 427.424215 -54.757368) (xy 427.473815 -54.731867) (xy 427.526599 -54.71386) (xy 427.581442 -54.70373)
			(xy 427.637176 -54.701693) (xy 427.692613 -54.707793) (xy 427.74657 -54.721899) (xy 427.797899 -54.743711)
			(xy 427.845505 -54.772765) (xy 427.888373 -54.80844) (xy 427.92559 -54.849977) (xy 427.956363 -54.89649)
			(xy 427.980035 -54.946987) (xy 427.99269 -54.989051) (xy 430.201068 -54.989051) (xy 430.201068 -54.934549)
			(xy 430.208824 -54.880603) (xy 430.224178 -54.828309) (xy 430.246817 -54.778733) (xy 430.276281 -54.732882)
			(xy 430.311971 -54.691692) (xy 430.353158 -54.655999) (xy 430.399006 -54.626532) (xy 430.448581 -54.603888)
			(xy 430.500874 -54.58853) (xy 430.554819 -54.58077) (xy 430.58207 -54.580282) (xy 430.610161 -54.580801)
			(xy 430.665737 -54.589023) (xy 430.719505 -54.60531) (xy 430.770303 -54.629309) (xy 430.81703 -54.6605)
			(xy 430.858675 -54.698209) (xy 430.894339 -54.741619) (xy 430.909222 -54.765448) (xy 430.914556 -54.774338)
			(xy 430.931574 -54.78653) (xy 431.024792 -54.80685) (xy 431.045366 -54.802532) (xy 431.054002 -54.79669)
			(xy 431.078063 -54.780686) (xy 431.129996 -54.755344) (xy 431.185154 -54.73812) (xy 431.242279 -54.729406)
			(xy 431.271172 -54.728872) (xy 431.298423 -54.729381) (xy 431.352371 -54.737134) (xy 431.404667 -54.752485)
			(xy 431.454246 -54.775123) (xy 431.500098 -54.804586) (xy 431.541291 -54.840275) (xy 431.576985 -54.881463)
			(xy 431.606454 -54.927312) (xy 431.629098 -54.976888) (xy 431.644456 -55.029182) (xy 431.652215 -55.083129)
			(xy 431.65268 -55.11038) (xy 431.652207 -55.13775) (xy 431.644392 -55.191929) (xy 431.628904 -55.244432)
			(xy 431.606064 -55.294179) (xy 431.576341 -55.340146) (xy 431.5587 -55.361078) (xy 431.558446 -55.361332)
			(xy 431.552875 -55.368429) (xy 431.54662 -55.385338) (xy 431.546254 -55.394352) (xy 431.546254 -55.461408)
			(xy 431.546596 -55.470427) (xy 431.552853 -55.487344) (xy 431.558446 -55.494428) (xy 431.5587 -55.494428)
			(xy 431.5587 -55.494682) (xy 431.57632 -55.515631) (xy 431.606044 -55.561597) (xy 431.628888 -55.61134)
			(xy 431.644385 -55.66384) (xy 431.652215 -55.718016) (xy 431.652217 -55.772754) (xy 431.644392 -55.826931)
			(xy 431.628899 -55.879431) (xy 431.606058 -55.929177) (xy 431.576338 -55.975145) (xy 431.5587 -55.996078)
			(xy 431.558446 -55.996332) (xy 431.552875 -56.003429) (xy 431.54662 -56.020338) (xy 431.546254 -56.029352)
			(xy 431.546254 -56.096408) (xy 431.546596 -56.105427) (xy 431.552853 -56.122344) (xy 431.558446 -56.129428)
			(xy 431.5587 -56.129428) (xy 431.5587 -56.129682) (xy 431.576344 -56.15061) (xy 431.606055 -56.196584)
			(xy 431.62889 -56.246332) (xy 431.64438 -56.298834) (xy 431.652207 -56.353011) (xy 431.65268 -56.38038)
			(xy 431.652194 -56.407631) (xy 431.644438 -56.461579) (xy 431.629083 -56.513874) (xy 431.606441 -56.563451)
			(xy 431.576975 -56.609301) (xy 431.541284 -56.650492) (xy 431.500093 -56.686183) (xy 431.454243 -56.715649)
			(xy 431.404666 -56.738291) (xy 431.352371 -56.753646) (xy 431.298423 -56.761402) (xy 431.243921 -56.761402)
			(xy 431.189973 -56.753646) (xy 431.137678 -56.738291) (xy 431.088101 -56.715649) (xy 431.042251 -56.686183)
			(xy 431.00106 -56.650492) (xy 430.965369 -56.609301) (xy 430.935903 -56.563451) (xy 430.913261 -56.513874)
			(xy 430.897906 -56.461579) (xy 430.89015 -56.407631) (xy 430.889664 -56.38038) (xy 430.890103 -56.353009)
			(xy 430.897925 -56.298828) (xy 430.913419 -56.246324) (xy 430.936268 -56.196577) (xy 430.965999 -56.150612)
			(xy 430.983644 -56.129682) (xy 430.983898 -56.129428) (xy 430.989479 -56.122337) (xy 430.995729 -56.105424)
			(xy 430.99609 -56.096408) (xy 430.99609 -56.029352) (xy 430.99571 -56.020337) (xy 430.989479 -56.00342)
			(xy 430.983898 -55.996332) (xy 430.983644 -55.996332) (xy 430.983644 -55.996078) (xy 430.965983 -55.975161)
			(xy 430.936258 -55.929191) (xy 430.913412 -55.879442) (xy 430.897917 -55.826938) (xy 430.89009 -55.772757)
			(xy 430.890092 -55.718013) (xy 430.897923 -55.663833) (xy 430.913423 -55.611329) (xy 430.936272 -55.561582)
			(xy 430.966001 -55.515614) (xy 430.983644 -55.494682) (xy 430.983898 -55.494428) (xy 430.989479 -55.487337)
			(xy 430.995729 -55.470424) (xy 430.99609 -55.461408) (xy 430.99609 -55.394352) (xy 430.99571 -55.385337)
			(xy 430.989479 -55.36842) (xy 430.983898 -55.361332) (xy 430.983644 -55.360824) (xy 430.972697 -55.348092)
			(xy 430.952858 -55.320999) (xy 430.94402 -55.306722) (xy 430.938686 -55.297832) (xy 430.921668 -55.28564)
			(xy 430.82845 -55.26532) (xy 430.807876 -55.269638) (xy 430.79924 -55.27548) (xy 430.775165 -55.291463)
			(xy 430.723238 -55.31681) (xy 430.668083 -55.334041) (xy 430.610962 -55.342761) (xy 430.58207 -55.343298)
			(xy 430.554819 -55.34283) (xy 430.500874 -55.33507) (xy 430.448581 -55.319712) (xy 430.399006 -55.297068)
			(xy 430.353158 -55.267601) (xy 430.311971 -55.231908) (xy 430.276281 -55.190718) (xy 430.246817 -55.144867)
			(xy 430.224178 -55.095291) (xy 430.208824 -55.042997) (xy 430.201068 -54.989051) (xy 427.99269 -54.989051)
			(xy 427.996103 -55.000394) (xy 428.004223 -55.05557) (xy 428.004732 -55.083456) (xy 428.004223 -55.111342)
			(xy 427.996103 -55.166518) (xy 427.980035 -55.219925) (xy 427.956363 -55.270422) (xy 427.92559 -55.316935)
			(xy 427.888373 -55.358472) (xy 427.845505 -55.394147) (xy 427.80175 -55.420851) (xy 428.524668 -55.420851)
			(xy 428.524668 -55.366349) (xy 428.532424 -55.312403) (xy 428.547778 -55.260109) (xy 428.570417 -55.210533)
			(xy 428.599881 -55.164682) (xy 428.635571 -55.123492) (xy 428.676758 -55.087799) (xy 428.722606 -55.058332)
			(xy 428.772181 -55.035688) (xy 428.824474 -55.02033) (xy 428.878419 -55.01257) (xy 428.90567 -55.012082)
			(xy 428.931985 -55.012509) (xy 428.984115 -55.019753) (xy 429.034759 -55.03408) (xy 429.082957 -55.05522)
			(xy 429.1278 -55.082773) (xy 429.168438 -55.116218) (xy 429.186594 -55.135272) (xy 429.19412 -55.142669)
			(xy 429.213396 -55.151197) (xy 429.223932 -55.151782) (xy 429.298608 -55.151782) (xy 429.30916 -55.151276)
			(xy 429.328456 -55.142725) (xy 429.335946 -55.135272) (xy 429.354081 -55.116196) (xy 429.394716 -55.082742)
			(xy 429.43956 -55.055186) (xy 429.487765 -55.034051) (xy 429.538416 -55.019738) (xy 429.590553 -55.012518)
			(xy 429.61687 -55.012082) (xy 429.644124 -55.012563) (xy 429.698076 -55.020317) (xy 429.750376 -55.03567)
			(xy 429.799959 -55.05831) (xy 429.845815 -55.087776) (xy 429.88701 -55.123469) (xy 429.922706 -55.164661)
			(xy 429.952176 -55.210515) (xy 429.97482 -55.260095) (xy 429.990177 -55.312394) (xy 429.997935 -55.366347)
			(xy 429.997935 -55.420854) (xy 429.990177 -55.474806) (xy 429.97482 -55.527105) (xy 429.952176 -55.576685)
			(xy 429.922706 -55.622539) (xy 429.88701 -55.663731) (xy 429.845815 -55.699424) (xy 429.799959 -55.72889)
			(xy 429.750376 -55.75153) (xy 429.698076 -55.766883) (xy 429.644124 -55.774637) (xy 429.61687 -55.775098)
			(xy 429.590555 -55.774651) (xy 429.538426 -55.767412) (xy 429.487783 -55.753089) (xy 429.439584 -55.731953)
			(xy 429.394741 -55.704403) (xy 429.354102 -55.670961) (xy 429.335946 -55.651908) (xy 429.328445 -55.644482)
			(xy 429.309149 -55.635971) (xy 429.298608 -55.635398) (xy 429.223932 -55.635398) (xy 429.213383 -55.635932)
			(xy 429.194087 -55.644464) (xy 429.186594 -55.651908) (xy 429.168436 -55.670961) (xy 429.127807 -55.704418)
			(xy 429.082967 -55.731977) (xy 429.034767 -55.753116) (xy 428.98412 -55.767434) (xy 428.931986 -55.774659)
			(xy 428.90567 -55.775098) (xy 428.878419 -55.77463) (xy 428.824474 -55.76687) (xy 428.772181 -55.751512)
			(xy 428.722606 -55.728868) (xy 428.676758 -55.699401) (xy 428.635571 -55.663708) (xy 428.599881 -55.622518)
			(xy 428.570417 -55.576667) (xy 428.547778 -55.527091) (xy 428.532424 -55.474797) (xy 428.524668 -55.420851)
			(xy 427.80175 -55.420851) (xy 427.797899 -55.423201) (xy 427.74657 -55.445013) (xy 427.692613 -55.459119)
			(xy 427.637176 -55.465219) (xy 427.581442 -55.463182) (xy 427.526599 -55.453052) (xy 427.473815 -55.435045)
			(xy 427.424215 -55.409544) (xy 427.378857 -55.377093) (xy 427.338708 -55.338384) (xy 427.304622 -55.294241)
			(xy 427.277326 -55.245606) (xy 427.257403 -55.193515) (xy 427.245277 -55.139078) (xy 427.241206 -55.083456)
			(xy 420.970358 -55.083456) (xy 420.935595 -55.105797) (xy 420.886018 -55.128439) (xy 420.833723 -55.143794)
			(xy 420.779775 -55.15155) (xy 420.725273 -55.15155) (xy 420.671325 -55.143794) (xy 420.61903 -55.128439)
			(xy 420.569453 -55.105797) (xy 420.523603 -55.076331) (xy 420.482412 -55.04064) (xy 420.446721 -54.999449)
			(xy 420.417255 -54.953599) (xy 420.394613 -54.904022) (xy 420.379258 -54.851727) (xy 420.371502 -54.797779)
			(xy 420.371016 -54.770528) (xy 417.239108 -54.770528) (xy 417.23945 -54.791102) (xy 417.238964 -54.818353)
			(xy 417.231208 -54.872301) (xy 417.215853 -54.924596) (xy 417.193211 -54.974173) (xy 417.163745 -55.020023)
			(xy 417.128054 -55.061214) (xy 417.086863 -55.096905) (xy 417.041013 -55.126371) (xy 416.991436 -55.149013)
			(xy 416.939141 -55.164368) (xy 416.885193 -55.172124) (xy 416.830691 -55.172124) (xy 416.776743 -55.164368)
			(xy 416.724448 -55.149013) (xy 416.674871 -55.126371) (xy 416.629021 -55.096905) (xy 416.58783 -55.061214)
			(xy 416.552139 -55.020023) (xy 416.522673 -54.974173) (xy 416.500031 -54.924596) (xy 416.484676 -54.872301)
			(xy 416.47692 -54.818353) (xy 416.476434 -54.791102) (xy 416.476906 -54.763732) (xy 416.48473 -54.709554)
			(xy 416.500218 -54.657051) (xy 416.523051 -54.607301) (xy 416.552762 -54.561326) (xy 416.570414 -54.540404)
			(xy 416.57651 -54.533292) (xy 416.579558 -54.52491) (xy 416.58108 -54.520622) (xy 416.582744 -54.511678)
			(xy 416.58286 -54.50713) (xy 416.58286 -54.440074) (xy 416.58274 -54.435526) (xy 416.581086 -54.42658)
			(xy 416.579558 -54.422294) (xy 416.57651 -54.413912) (xy 416.570414 -54.4068) (xy 416.552774 -54.385867)
			(xy 416.52305 -54.339899) (xy 416.500205 -54.290153) (xy 416.484709 -54.23765) (xy 416.47688 -54.183472)
			(xy 416.47688 -54.128731) (xy 416.484708 -54.074552) (xy 416.500204 -54.02205) (xy 416.523048 -53.972304)
			(xy 416.552772 -53.926335) (xy 416.570414 -53.905404) (xy 416.57651 -53.898292) (xy 416.579558 -53.88991)
			(xy 416.58108 -53.885622) (xy 416.582744 -53.876678) (xy 416.58286 -53.87213) (xy 416.58286 -53.79593)
			(xy 416.580066 -53.788564) (xy 416.559992 -53.766854) (xy 416.526009 -53.71847) (xy 416.499798 -53.665472)
			(xy 416.48197 -53.609097) (xy 416.472943 -53.550665) (xy 416.47237 -53.521102) (xy 416.472804 -53.494704)
			(xy 416.480012 -53.442401) (xy 416.494293 -53.391573) (xy 416.51538 -53.34317) (xy 416.542878 -53.298099)
			(xy 416.576272 -53.257205) (xy 416.595306 -53.238908) (xy 416.59706 -53.234341) (xy 416.598979 -53.224749)
			(xy 416.599116 -53.219858) (xy 416.599116 -53.187854) (xy 416.598354 -53.17871) (xy 416.597338 -53.1749)
			(xy 416.595446 -53.16842) (xy 416.58876 -53.156698) (xy 416.58413 -53.151786) (xy 416.583114 -53.15077)
			(xy 416.57143 -53.137816) (xy 416.564138 -53.130871) (xy 416.54567 -53.122884) (xy 416.535616 -53.122322)
			(xy 414.622742 -53.122322) (xy 414.613938 -53.122749) (xy 414.597397 -53.128804) (xy 414.583866 -53.140081)
			(xy 414.579054 -53.147468) (xy 414.534604 -53.22316) (xy 414.531441 -53.229097) (xy 414.527974 -53.24209)
			(xy 414.527746 -53.248814) (xy 414.527746 -53.262022) (xy 414.529524 -53.265324) (xy 414.53435 -53.273706)
			(xy 414.546044 -53.295242) (xy 414.56446 -53.340657) (xy 414.576919 -53.388054) (xy 414.583215 -53.436655)
			(xy 414.583626 -53.461158) (xy 414.583626 -53.461412) (xy 414.583153 -53.488781) (xy 414.575327 -53.542958)
			(xy 414.559836 -53.595459) (xy 414.536999 -53.645206) (xy 414.507285 -53.691178) (xy 414.489646 -53.71211)
			(xy 414.48355 -53.719222) (xy 414.480502 -53.727604) (xy 414.478982 -53.731892) (xy 414.477322 -53.740836)
			(xy 414.4772 -53.745384) (xy 414.4772 -53.81244) (xy 414.477321 -53.816988) (xy 414.478976 -53.825934)
			(xy 414.480502 -53.83022) (xy 414.48355 -53.838602) (xy 414.489646 -53.845714) (xy 414.507287 -53.866646)
			(xy 414.537012 -53.912613) (xy 414.559857 -53.962359) (xy 414.575353 -54.014861) (xy 414.583181 -54.069039)
			(xy 414.58318 -54.123779) (xy 414.575349 -54.177957) (xy 414.559851 -54.230458) (xy 414.537003 -54.280203)
			(xy 414.507276 -54.326168) (xy 414.489646 -54.34711) (xy 414.48355 -54.354222) (xy 414.480502 -54.362604)
			(xy 414.478982 -54.366892) (xy 414.477322 -54.375836) (xy 414.4772 -54.380384) (xy 414.4772 -54.44744)
			(xy 414.477321 -54.451988) (xy 414.478976 -54.460934) (xy 414.480502 -54.46522) (xy 414.48355 -54.473602)
			(xy 414.489646 -54.480714) (xy 414.507289 -54.501645) (xy 414.537018 -54.54761) (xy 414.559863 -54.597357)
			(xy 414.575353 -54.649861) (xy 414.583171 -54.704041) (xy 414.583626 -54.731412) (xy 414.58314 -54.758663)
			(xy 414.575384 -54.812611) (xy 414.560029 -54.864906) (xy 414.537387 -54.914483) (xy 414.507921 -54.960333)
			(xy 414.47223 -55.001524) (xy 414.431039 -55.037215) (xy 414.385189 -55.066681) (xy 414.335612 -55.089323)
			(xy 414.283317 -55.104678) (xy 414.229369 -55.112434) (xy 414.174867 -55.112434) (xy 414.120919 -55.104678)
			(xy 414.068624 -55.089323) (xy 414.019047 -55.066681) (xy 413.973197 -55.037215) (xy 413.932006 -55.001524)
			(xy 413.896315 -54.960333) (xy 413.866849 -54.914483) (xy 413.844207 -54.864906) (xy 413.828852 -54.812611)
			(xy 413.821096 -54.758663) (xy 413.82061 -54.731412) (xy 413.821088 -54.704044) (xy 413.828923 -54.649872)
			(xy 413.84442 -54.597376) (xy 413.867261 -54.547634) (xy 413.896976 -54.501666) (xy 413.91459 -54.480714)
			(xy 413.920686 -54.473602) (xy 413.923734 -54.46522) (xy 413.925257 -54.460932) (xy 413.926924 -54.451988)
			(xy 413.927036 -54.44744) (xy 413.927036 -54.380384) (xy 413.926908 -54.375837) (xy 413.925238 -54.366897)
			(xy 413.923734 -54.362604) (xy 413.920686 -54.354222) (xy 413.91459 -54.34711) (xy 413.89695 -54.326177)
			(xy 413.867226 -54.280208) (xy 413.844382 -54.230461) (xy 413.828885 -54.177958) (xy 413.821056 -54.12378)
			(xy 413.821055 -54.069038) (xy 413.828881 -54.014859) (xy 413.844375 -53.962356) (xy 413.867218 -53.912608)
			(xy 413.896939 -53.866638) (xy 413.91459 -53.845714) (xy 413.920686 -53.838602) (xy 413.923734 -53.83022)
			(xy 413.925257 -53.825932) (xy 413.926924 -53.816988) (xy 413.927036 -53.81244) (xy 413.927036 -53.745384)
			(xy 413.926908 -53.740837) (xy 413.925238 -53.731897) (xy 413.923734 -53.727604) (xy 413.920686 -53.719222)
			(xy 413.91459 -53.71211) (xy 413.896948 -53.691179) (xy 413.867221 -53.645212) (xy 413.844378 -53.595466)
			(xy 413.828886 -53.542962) (xy 413.821067 -53.488783) (xy 413.82061 -53.461412) (xy 413.82061 -53.461158)
			(xy 413.820986 -53.436652) (xy 413.827266 -53.388044) (xy 413.839728 -53.340643) (xy 413.858168 -53.295233)
			(xy 413.869886 -53.273706) (xy 413.874712 -53.265324) (xy 413.87649 -53.262022) (xy 413.87649 -53.248814)
			(xy 413.876317 -53.242083) (xy 413.872838 -53.229081) (xy 413.869632 -53.22316) (xy 413.825182 -53.147468)
			(xy 413.820419 -53.14004) (xy 413.806885 -53.12874) (xy 413.79031 -53.122732) (xy 413.781494 -53.122322)
			(xy 407.86558 -53.122322) (xy 407.857014 -53.122697) (xy 407.84086 -53.128413) (xy 407.827469 -53.139106)
			(xy 407.822654 -53.146198) (xy 407.787348 -53.20792) (xy 407.777696 -53.224684) (xy 407.774604 -53.230502)
			(xy 407.771271 -53.243243) (xy 407.771092 -53.24983) (xy 407.771092 -53.263546) (xy 407.778204 -53.275484)
			(xy 407.790757 -53.297592) (xy 407.810534 -53.344426) (xy 407.823905 -53.393475) (xy 407.830631 -53.443866)
			(xy 407.831036 -53.469286) (xy 407.831036 -53.475382) (xy 407.830139 -53.502348) (xy 407.821687 -53.555635)
			(xy 407.80581 -53.6072) (xy 407.782827 -53.656013) (xy 407.753196 -53.701101) (xy 407.717507 -53.741564)
			(xy 407.676473 -53.776596) (xy 407.630913 -53.805496) (xy 407.581735 -53.827689) (xy 407.529921 -53.842731)
			(xy 407.476505 -53.850323) (xy 407.449528 -53.850794) (xy 407.42216 -53.850317) (xy 407.367987 -53.842484)
			(xy 407.315489 -53.826989) (xy 407.265745 -53.80415) (xy 407.219776 -53.774436) (xy 407.19883 -53.756814)
			(xy 407.191718 -53.750718) (xy 407.183336 -53.74767) (xy 407.179049 -53.746145) (xy 407.170105 -53.744475)
			(xy 407.165556 -53.744368) (xy 407.0985 -53.744368) (xy 407.093953 -53.744495) (xy 407.085012 -53.746162)
			(xy 407.08072 -53.74767) (xy 407.072338 -53.750718) (xy 407.065226 -53.756814) (xy 407.044295 -53.774457)
			(xy 406.998329 -53.804185) (xy 406.948582 -53.827031) (xy 406.896079 -53.842524) (xy 406.841899 -53.850346)
			(xy 406.814528 -53.850794) (xy 406.787555 -53.850323) (xy 406.734147 -53.842715) (xy 406.682343 -53.827661)
			(xy 406.633176 -53.805461) (xy 406.587625 -53.776557) (xy 406.546599 -53.741527) (xy 406.510916 -53.701067)
			(xy 406.481287 -53.655985) (xy 406.458302 -53.607179) (xy 406.442421 -53.555623) (xy 406.433959 -53.502344)
			(xy 406.43302 -53.475382) (xy 406.43302 -53.469286) (xy 406.433445 -53.443869) (xy 406.440199 -53.393486)
			(xy 406.453573 -53.344443) (xy 406.47333 -53.297606) (xy 406.485852 -53.275484) (xy 406.489408 -53.269642)
			(xy 406.492964 -53.256434) (xy 406.492964 -53.24983) (xy 406.492758 -53.243248) (xy 406.489421 -53.230514)
			(xy 406.48636 -53.224684) (xy 406.476708 -53.20792) (xy 406.441402 -53.146198) (xy 406.436588 -53.1391)
			(xy 406.423217 -53.128378) (xy 406.407046 -53.122699) (xy 406.398476 -53.122322) (xy 402.116544 -53.122322)
			(xy 402.108187 -53.122705) (xy 402.092378 -53.128147) (xy 402.085556 -53.13299) (xy 402.079206 -53.13807)
			(xy 402.070062 -53.15204) (xy 402.067776 -53.16093) (xy 402.060012 -53.190366) (xy 402.037748 -53.247025)
			(xy 402.00817 -53.300234) (xy 401.971801 -53.349053) (xy 401.929282 -53.392621) (xy 401.881364 -53.43017)
			(xy 401.828893 -53.461036) (xy 401.772793 -53.484675) (xy 401.714054 -53.50067) (xy 401.653714 -53.508738)
			(xy 401.592838 -53.508738) (xy 401.532498 -53.50067) (xy 401.473759 -53.484675) (xy 401.417659 -53.461036)
			(xy 401.365188 -53.43017) (xy 401.31727 -53.392621) (xy 401.274751 -53.349053) (xy 401.238382 -53.300234)
			(xy 401.208804 -53.247025) (xy 401.18654 -53.190366) (xy 401.178776 -53.16093) (xy 401.178776 -53.160676)
			(xy 401.176429 -53.152407) (xy 401.167083 -53.137994) (xy 401.160488 -53.132482) (xy 401.154392 -53.127656)
			(xy 401.13839 -53.122322) (xy 393.084304 -53.122322) (xy 393.07641 -53.122657) (xy 393.061404 -53.127575)
			(xy 393.05484 -53.131974) (xy 393.04849 -53.136292) (xy 393.039346 -53.148738) (xy 393.036552 -53.156612)
			(xy 393.026329 -53.185088) (xy 392.999425 -53.23928) (xy 392.965609 -53.28945) (xy 392.925471 -53.334722)
			(xy 392.879713 -53.374304) (xy 392.854688 -53.391308) (xy 392.845544 -53.39715) (xy 392.839956 -53.405786)
			(xy 392.837276 -53.410113) (xy 392.833553 -53.419585) (xy 392.83259 -53.424582) (xy 392.81989 -53.49875)
			(xy 392.819175 -53.504024) (xy 392.819685 -53.514652) (xy 392.820906 -53.519832) (xy 392.823192 -53.52923)
			(xy 392.829796 -53.537866) (xy 392.844687 -53.55792) (xy 392.86969 -53.601161) (xy 392.888838 -53.647294)
			(xy 392.901806 -53.695531) (xy 392.90837 -53.745048) (xy 392.90879 -53.770022) (xy 392.90879 -53.77053)
			(xy 392.908302 -53.797779) (xy 392.900542 -53.851723) (xy 392.885184 -53.904013) (xy 392.862541 -53.953585)
			(xy 392.833073 -53.99943) (xy 392.797382 -54.040616) (xy 392.756192 -54.076302) (xy 392.710343 -54.105764)
			(xy 392.660768 -54.1284) (xy 392.608476 -54.143752) (xy 392.554531 -54.151505) (xy 392.527282 -54.152038)
			(xy 392.499913 -54.151565) (xy 392.445737 -54.143738) (xy 392.393236 -54.128247) (xy 392.343489 -54.10541)
			(xy 392.297517 -54.075697) (xy 392.276584 -54.058058) (xy 392.269472 -54.051962) (xy 392.26109 -54.048914)
			(xy 392.256802 -54.047395) (xy 392.247858 -54.045735) (xy 392.24331 -54.045612) (xy 392.176254 -54.045612)
			(xy 392.171706 -54.045734) (xy 392.162761 -54.04739) (xy 392.158474 -54.048914) (xy 392.150092 -54.051962)
			(xy 392.14298 -54.058058) (xy 392.122049 -54.075701) (xy 392.076083 -54.105427) (xy 392.026336 -54.128271)
			(xy 391.973832 -54.14376) (xy 391.919653 -54.151576) (xy 391.892282 -54.152038) (xy 391.865031 -54.151551)
			(xy 391.811083 -54.143793) (xy 391.758789 -54.128436) (xy 391.709212 -54.105794) (xy 391.663362 -54.076328)
			(xy 391.622171 -54.040637) (xy 391.586479 -53.999448) (xy 391.557011 -53.953598) (xy 391.534368 -53.904022)
			(xy 391.51901 -53.851728) (xy 391.51125 -53.797781) (xy 391.510774 -53.77053) (xy 391.511306 -53.741613)
			(xy 391.52003 -53.684441) (xy 391.537284 -53.629241) (xy 391.56267 -53.577277) (xy 391.595609 -53.52974)
			(xy 391.635346 -53.487719) (xy 391.65784 -53.46954) (xy 391.665224 -53.463256) (xy 391.675017 -53.446541)
			(xy 391.67689 -53.437028) (xy 391.677398 -53.429408) (xy 391.677398 -53.349652) (xy 391.67689 -53.342032)
			(xy 391.675125 -53.333015) (xy 391.666127 -53.317012) (xy 391.659364 -53.31079) (xy 391.65784 -53.30952)
			(xy 391.63857 -53.294011) (xy 391.6038 -53.258827) (xy 391.573863 -53.219449) (xy 391.54926 -53.176536)
			(xy 391.539476 -53.153818) (xy 391.535158 -53.143404) (xy 391.52703 -53.135784) (xy 391.520426 -53.130704)
			(xy 391.51433 -53.12664) (xy 391.50036 -53.122322) (xy 391.181082 -53.122322) (xy 391.18032 -53.122322)
			(xy 391.170269 -53.122897) (xy 391.151803 -53.13088) (xy 391.144506 -53.137816) (xy 391.132822 -53.15077)
			(xy 391.131806 -53.151786) (xy 391.127185 -53.156706) (xy 391.120493 -53.168422) (xy 391.118598 -53.1749)
			(xy 391.11682 -53.1876) (xy 391.11682 -53.219604) (xy 391.116956 -53.224637) (xy 391.118997 -53.234494)
			(xy 391.120884 -53.239162) (xy 391.139881 -53.257452) (xy 391.173202 -53.298326) (xy 391.200638 -53.343362)
			(xy 391.221677 -53.391719) (xy 391.235924 -53.442492) (xy 391.243115 -53.494735) (xy 391.243566 -53.521102)
			(xy 391.243001 -53.550665) (xy 391.233981 -53.609099) (xy 391.216152 -53.665474) (xy 391.189931 -53.718468)
			(xy 391.155932 -53.766842) (xy 391.13587 -53.788564) (xy 391.133076 -53.79593) (xy 391.133076 -53.87213)
			(xy 391.133197 -53.876678) (xy 391.134853 -53.885624) (xy 391.136378 -53.88991) (xy 391.139426 -53.898292)
			(xy 391.145522 -53.905404) (xy 391.163161 -53.926338) (xy 391.192881 -53.972307) (xy 391.215723 -54.022053)
			(xy 391.231217 -54.074554) (xy 391.239045 -54.128732) (xy 391.239044 -54.183471) (xy 391.231217 -54.237649)
			(xy 391.215722 -54.29015) (xy 391.20193 -54.320186) (xy 393.430506 -54.320186) (xy 393.430962 -54.292815)
			(xy 393.438782 -54.238636) (xy 393.454274 -54.186133) (xy 393.477117 -54.136386) (xy 393.506844 -54.090419)
			(xy 393.524486 -54.069488) (xy 393.52474 -54.069234) (xy 393.530323 -54.062145) (xy 393.536571 -54.04523)
			(xy 393.536932 -54.036214) (xy 393.536932 -53.969158) (xy 393.53654 -53.960145) (xy 393.530316 -53.943228)
			(xy 393.52474 -53.936138) (xy 393.524486 -53.936138) (xy 393.524486 -53.935884) (xy 393.506871 -53.914933)
			(xy 393.477156 -53.868965) (xy 393.454315 -53.819222) (xy 393.438819 -53.766726) (xy 393.430984 -53.712554)
			(xy 393.430506 -53.685186) (xy 393.430992 -53.657935) (xy 393.438748 -53.603987) (xy 393.454103 -53.551692)
			(xy 393.476745 -53.502115) (xy 393.506211 -53.456265) (xy 393.541902 -53.415074) (xy 393.583093 -53.379383)
			(xy 393.628943 -53.349917) (xy 393.67852 -53.327275) (xy 393.730815 -53.31192) (xy 393.784763 -53.304164)
			(xy 393.839265 -53.304164) (xy 393.893213 -53.31192) (xy 393.945508 -53.327275) (xy 393.995085 -53.349917)
			(xy 394.040935 -53.379383) (xy 394.082126 -53.415074) (xy 394.117817 -53.456265) (xy 394.147283 -53.502115)
			(xy 394.169925 -53.551692) (xy 394.18528 -53.603987) (xy 394.193036 -53.657935) (xy 394.193522 -53.685186)
			(xy 394.193067 -53.712557) (xy 394.185249 -53.766737) (xy 394.169759 -53.819241) (xy 394.146914 -53.868988)
			(xy 394.117186 -53.914953) (xy 394.099542 -53.935884) (xy 394.099288 -53.936138) (xy 394.09372 -53.943237)
			(xy 394.087462 -53.960144) (xy 394.087096 -53.969158) (xy 394.087096 -54.036214) (xy 394.087447 -54.045231)
			(xy 394.093699 -54.062148) (xy 394.099288 -54.069234) (xy 394.099542 -54.069234) (xy 394.099542 -54.069488)
			(xy 394.117196 -54.090408) (xy 394.146904 -54.136385) (xy 394.169737 -54.186135) (xy 394.185225 -54.238639)
			(xy 394.19305 -54.292816) (xy 394.193522 -54.320186) (xy 394.193036 -54.347437) (xy 394.18528 -54.401385)
			(xy 394.169925 -54.45368) (xy 394.147283 -54.503257) (xy 394.117817 -54.549107) (xy 394.082126 -54.590298)
			(xy 394.040935 -54.625989) (xy 393.995085 -54.655455) (xy 393.945508 -54.678097) (xy 393.893213 -54.693452)
			(xy 393.839265 -54.701208) (xy 393.784763 -54.701208) (xy 393.730815 -54.693452) (xy 393.67852 -54.678097)
			(xy 393.628943 -54.655455) (xy 393.583093 -54.625989) (xy 393.541902 -54.590298) (xy 393.506211 -54.549107)
			(xy 393.476745 -54.503257) (xy 393.454103 -54.45368) (xy 393.438748 -54.401385) (xy 393.430992 -54.347437)
			(xy 393.430506 -54.320186) (xy 391.20193 -54.320186) (xy 391.19288 -54.339896) (xy 391.163159 -54.385865)
			(xy 391.145522 -54.4068) (xy 391.139426 -54.413912) (xy 391.136378 -54.422294) (xy 391.13485 -54.42658)
			(xy 391.133185 -54.435525) (xy 391.133076 -54.440074) (xy 391.133076 -54.50713) (xy 391.133197 -54.511678)
			(xy 391.134853 -54.520624) (xy 391.136378 -54.52491) (xy 391.139426 -54.533292) (xy 391.145522 -54.540404)
			(xy 391.163163 -54.561336) (xy 391.192887 -54.607303) (xy 391.215728 -54.65705) (xy 391.231217 -54.709553)
			(xy 391.239034 -54.763732) (xy 391.23915 -54.770528) (xy 394.371068 -54.770528) (xy 394.371534 -54.743158)
			(xy 394.379349 -54.688978) (xy 394.394837 -54.636474) (xy 394.41768 -54.586727) (xy 394.447406 -54.540761)
			(xy 394.465048 -54.51983) (xy 394.465302 -54.519576) (xy 394.470905 -54.512501) (xy 394.477142 -54.495575)
			(xy 394.477494 -54.486556) (xy 394.477494 -54.4195) (xy 394.477138 -54.410483) (xy 394.47089 -54.393566)
			(xy 394.465302 -54.38648) (xy 394.465048 -54.38648) (xy 394.465048 -54.386226) (xy 394.447415 -54.365289)
			(xy 394.417701 -54.319318) (xy 394.394863 -54.269572) (xy 394.37937 -54.217072) (xy 394.371542 -54.162897)
			(xy 394.371068 -54.135528) (xy 394.371554 -54.108277) (xy 394.37931 -54.054329) (xy 394.394665 -54.002034)
			(xy 394.417307 -53.952457) (xy 394.446773 -53.906607) (xy 394.482464 -53.865416) (xy 394.523655 -53.829725)
			(xy 394.569505 -53.800259) (xy 394.619082 -53.777617) (xy 394.671377 -53.762262) (xy 394.725325 -53.754506)
			(xy 394.779827 -53.754506) (xy 394.833775 -53.762262) (xy 394.88607 -53.777617) (xy 394.935647 -53.800259)
			(xy 394.981497 -53.829725) (xy 395.022688 -53.865416) (xy 395.058379 -53.906607) (xy 395.087845 -53.952457)
			(xy 395.106607 -53.993538) (xy 398.996898 -53.993538) (xy 398.996898 -53.933602) (xy 399.004721 -53.87418)
			(xy 399.020234 -53.816287) (xy 399.04317 -53.760914) (xy 399.073137 -53.709008) (xy 399.109624 -53.661458)
			(xy 399.152004 -53.619078) (xy 399.199554 -53.582591) (xy 399.25146 -53.552624) (xy 399.306833 -53.529688)
			(xy 399.364726 -53.514175) (xy 399.424148 -53.506352) (xy 399.484084 -53.506352) (xy 399.543506 -53.514175)
			(xy 399.601399 -53.529688) (xy 399.656772 -53.552624) (xy 399.708678 -53.582591) (xy 399.756228 -53.619078)
			(xy 399.798608 -53.661458) (xy 399.835095 -53.709008) (xy 399.865062 -53.760914) (xy 399.887998 -53.816287)
			(xy 399.903511 -53.87418) (xy 399.911334 -53.933602) (xy 399.911824 -53.96357) (xy 399.911334 -53.993538)
			(xy 399.903511 -54.05296) (xy 399.899627 -54.067456) (xy 401.241258 -54.067456) (xy 401.245329 -54.011834)
			(xy 401.257455 -53.957397) (xy 401.277378 -53.905306) (xy 401.304674 -53.856671) (xy 401.33876 -53.812528)
			(xy 401.378909 -53.773819) (xy 401.424267 -53.741368) (xy 401.473867 -53.715867) (xy 401.526651 -53.69786)
			(xy 401.581494 -53.68773) (xy 401.637228 -53.685693) (xy 401.692665 -53.691793) (xy 401.746622 -53.705899)
			(xy 401.797951 -53.727711) (xy 401.845557 -53.756765) (xy 401.888425 -53.79244) (xy 401.925642 -53.833977)
			(xy 401.956415 -53.88049) (xy 401.980087 -53.930987) (xy 401.996155 -53.984394) (xy 402.004275 -54.03957)
			(xy 402.004784 -54.067456) (xy 402.004275 -54.095342) (xy 401.996155 -54.150518) (xy 401.980087 -54.203925)
			(xy 401.963689 -54.238906) (xy 408.685998 -54.238906) (xy 408.690069 -54.183284) (xy 408.702195 -54.128847)
			(xy 408.722118 -54.076756) (xy 408.749414 -54.028121) (xy 408.7835 -53.983978) (xy 408.823649 -53.945269)
			(xy 408.869007 -53.912818) (xy 408.918607 -53.887317) (xy 408.971391 -53.86931) (xy 409.026234 -53.85918)
			(xy 409.081968 -53.857143) (xy 409.137405 -53.863243) (xy 409.191362 -53.877349) (xy 409.242691 -53.899161)
			(xy 409.290297 -53.928215) (xy 409.333165 -53.96389) (xy 409.370382 -54.005427) (xy 409.401155 -54.05194)
			(xy 409.424827 -54.102437) (xy 409.440895 -54.155844) (xy 409.449015 -54.21102) (xy 409.449524 -54.238906)
			(xy 409.449015 -54.266792) (xy 409.440895 -54.321968) (xy 409.424827 -54.375375) (xy 409.401155 -54.425872)
			(xy 409.370382 -54.472385) (xy 409.333165 -54.513922) (xy 409.290297 -54.549597) (xy 409.242691 -54.578651)
			(xy 409.191362 -54.600463) (xy 409.137405 -54.614569) (xy 409.081968 -54.620669) (xy 409.026234 -54.618632)
			(xy 408.971391 -54.608502) (xy 408.918607 -54.590495) (xy 408.869007 -54.564994) (xy 408.823649 -54.532543)
			(xy 408.7835 -54.493834) (xy 408.749414 -54.449691) (xy 408.722118 -54.401056) (xy 408.702195 -54.348965)
			(xy 408.690069 -54.294528) (xy 408.685998 -54.238906) (xy 401.963689 -54.238906) (xy 401.956415 -54.254422)
			(xy 401.925642 -54.300935) (xy 401.888425 -54.342472) (xy 401.845557 -54.378147) (xy 401.797951 -54.407201)
			(xy 401.746622 -54.429013) (xy 401.692665 -54.443119) (xy 401.637228 -54.449219) (xy 401.581494 -54.447182)
			(xy 401.526651 -54.437052) (xy 401.473867 -54.419045) (xy 401.424267 -54.393544) (xy 401.378909 -54.361093)
			(xy 401.33876 -54.322384) (xy 401.304674 -54.278241) (xy 401.277378 -54.229606) (xy 401.257455 -54.177515)
			(xy 401.245329 -54.123078) (xy 401.241258 -54.067456) (xy 399.899627 -54.067456) (xy 399.887998 -54.110853)
			(xy 399.865062 -54.166226) (xy 399.835095 -54.218132) (xy 399.798608 -54.265682) (xy 399.756228 -54.308062)
			(xy 399.708678 -54.344549) (xy 399.656772 -54.374516) (xy 399.601399 -54.397452) (xy 399.543506 -54.412965)
			(xy 399.484084 -54.420788) (xy 399.424148 -54.420788) (xy 399.364726 -54.412965) (xy 399.306833 -54.397452)
			(xy 399.25146 -54.374516) (xy 399.199554 -54.344549) (xy 399.152004 -54.308062) (xy 399.109624 -54.265682)
			(xy 399.073137 -54.218132) (xy 399.04317 -54.166226) (xy 399.020234 -54.110853) (xy 399.004721 -54.05296)
			(xy 398.996898 -53.993538) (xy 395.106607 -53.993538) (xy 395.110487 -54.002034) (xy 395.125842 -54.054329)
			(xy 395.133598 -54.108277) (xy 395.134084 -54.135528) (xy 395.133638 -54.162899) (xy 395.125816 -54.217079)
			(xy 395.110322 -54.269583) (xy 395.087476 -54.319329) (xy 395.057747 -54.365295) (xy 395.040104 -54.386226)
			(xy 395.03985 -54.38648) (xy 395.03426 -54.393564) (xy 395.028016 -54.410483) (xy 395.027658 -54.4195)
			(xy 395.027658 -54.486556) (xy 395.028023 -54.495572) (xy 395.034264 -54.51249) (xy 395.03985 -54.519576)
			(xy 395.040104 -54.519576) (xy 395.040104 -54.51983) (xy 395.057724 -54.540777) (xy 395.087439 -54.586746)
			(xy 395.110278 -54.63649) (xy 395.125774 -54.688987) (xy 395.133607 -54.74316) (xy 395.134084 -54.770528)
			(xy 395.133598 -54.797779) (xy 395.125842 -54.851727) (xy 395.110487 -54.904022) (xy 395.087845 -54.953599)
			(xy 395.058379 -54.999449) (xy 395.022688 -55.04064) (xy 394.981497 -55.076331) (xy 394.97041 -55.083456)
			(xy 401.241258 -55.083456) (xy 401.245329 -55.027834) (xy 401.257455 -54.973397) (xy 401.277378 -54.921306)
			(xy 401.304674 -54.872671) (xy 401.33876 -54.828528) (xy 401.378909 -54.789819) (xy 401.424267 -54.757368)
			(xy 401.473867 -54.731867) (xy 401.526651 -54.71386) (xy 401.581494 -54.70373) (xy 401.637228 -54.701693)
			(xy 401.692665 -54.707793) (xy 401.746622 -54.721899) (xy 401.797951 -54.743711) (xy 401.845557 -54.772765)
			(xy 401.888425 -54.80844) (xy 401.925642 -54.849977) (xy 401.956415 -54.89649) (xy 401.980087 -54.946987)
			(xy 401.992744 -54.989055) (xy 404.201045 -54.989055) (xy 404.201045 -54.934545) (xy 404.208803 -54.880591)
			(xy 404.22416 -54.82829) (xy 404.246805 -54.778707) (xy 404.276276 -54.732852) (xy 404.311973 -54.691657)
			(xy 404.353169 -54.655963) (xy 404.399026 -54.626494) (xy 404.448611 -54.603853) (xy 404.500913 -54.588498)
			(xy 404.554867 -54.580743) (xy 404.582122 -54.580282) (xy 404.610214 -54.580759) (xy 404.665792 -54.58899)
			(xy 404.719562 -54.605284) (xy 404.770359 -54.629289) (xy 404.817086 -54.660487) (xy 404.85873 -54.698201)
			(xy 404.894392 -54.741616) (xy 404.909274 -54.765448) (xy 404.914608 -54.774338) (xy 404.931626 -54.78653)
			(xy 405.024844 -54.80685) (xy 405.045418 -54.802532) (xy 405.054054 -54.79669) (xy 405.078128 -54.780706)
			(xy 405.130056 -54.75536) (xy 405.185211 -54.73813) (xy 405.242332 -54.72941) (xy 405.271224 -54.728872)
			(xy 405.298475 -54.729355) (xy 405.352422 -54.737115) (xy 405.404715 -54.752472) (xy 405.454291 -54.775114)
			(xy 405.500141 -54.804581) (xy 405.54133 -54.840273) (xy 405.577021 -54.881463) (xy 405.606488 -54.927312)
			(xy 405.62913 -54.976888) (xy 405.644486 -55.029182) (xy 405.652245 -55.083129) (xy 405.652732 -55.11038)
			(xy 405.652271 -55.137751) (xy 405.644454 -55.191931) (xy 405.628965 -55.244434) (xy 405.606122 -55.294181)
			(xy 405.576395 -55.340147) (xy 405.558752 -55.361078) (xy 405.558498 -55.361332) (xy 405.552934 -55.368434)
			(xy 405.546674 -55.385339) (xy 405.546306 -55.394352) (xy 405.546306 -55.461408) (xy 405.546658 -55.470425)
			(xy 405.552909 -55.487342) (xy 405.558498 -55.494428) (xy 405.558752 -55.494428) (xy 405.558752 -55.494682)
			(xy 405.576374 -55.51563) (xy 405.606101 -55.561595) (xy 405.628949 -55.611338) (xy 405.644448 -55.663838)
			(xy 405.652279 -55.718015) (xy 405.652281 -55.772755) (xy 405.644454 -55.826932) (xy 405.62896 -55.879433)
			(xy 405.606116 -55.929179) (xy 405.576392 -55.975146) (xy 405.558752 -55.996078) (xy 405.558498 -55.996332)
			(xy 405.552934 -56.003434) (xy 405.546674 -56.020339) (xy 405.546306 -56.029352) (xy 405.546306 -56.096408)
			(xy 405.546658 -56.105425) (xy 405.552909 -56.122342) (xy 405.558498 -56.129428) (xy 405.558752 -56.129428)
			(xy 405.558752 -56.129682) (xy 405.576389 -56.150616) (xy 405.606103 -56.196588) (xy 405.62894 -56.246335)
			(xy 405.644431 -56.298835) (xy 405.652259 -56.353011) (xy 405.652732 -56.38038) (xy 405.652246 -56.407631)
			(xy 405.64449 -56.461579) (xy 405.629135 -56.513874) (xy 405.606493 -56.563451) (xy 405.577027 -56.609301)
			(xy 405.541336 -56.650492) (xy 405.500145 -56.686183) (xy 405.454295 -56.715649) (xy 405.404718 -56.738291)
			(xy 405.352423 -56.753646) (xy 405.298475 -56.761402) (xy 405.243973 -56.761402) (xy 405.190025 -56.753646)
			(xy 405.13773 -56.738291) (xy 405.088153 -56.715649) (xy 405.042303 -56.686183) (xy 405.001112 -56.650492)
			(xy 404.965421 -56.609301) (xy 404.935955 -56.563451) (xy 404.913313 -56.513874) (xy 404.897958 -56.461579)
			(xy 404.890202 -56.407631) (xy 404.889716 -56.38038) (xy 404.890166 -56.353009) (xy 404.897987 -56.298829)
			(xy 404.91348 -56.246326) (xy 404.936325 -56.196579) (xy 404.966053 -56.150613) (xy 404.983696 -56.129682)
			(xy 404.98395 -56.129428) (xy 404.989537 -56.122342) (xy 404.995782 -56.105425) (xy 404.996142 -56.096408)
			(xy 404.996142 -56.029352) (xy 404.995773 -56.020336) (xy 404.989535 -56.003418) (xy 404.98395 -55.996332)
			(xy 404.983696 -55.996332) (xy 404.983696 -55.996078) (xy 404.966037 -55.975161) (xy 404.936315 -55.929189)
			(xy 404.913473 -55.87944) (xy 404.89798 -55.826936) (xy 404.890154 -55.772756) (xy 404.890156 -55.718014)
			(xy 404.897986 -55.663834) (xy 404.913484 -55.611331) (xy 404.93633 -55.561584) (xy 404.966055 -55.515615)
			(xy 404.983696 -55.494682) (xy 404.98395 -55.494428) (xy 404.989537 -55.487342) (xy 404.995782 -55.470425)
			(xy 404.996142 -55.461408) (xy 404.996142 -55.394352) (xy 404.995773 -55.385336) (xy 404.989535 -55.368418)
			(xy 404.98395 -55.361332) (xy 404.983696 -55.360824) (xy 404.972752 -55.348089) (xy 404.952911 -55.320998)
			(xy 404.944072 -55.306722) (xy 404.938738 -55.297832) (xy 404.92172 -55.28564) (xy 404.828502 -55.26532)
			(xy 404.807928 -55.269638) (xy 404.799292 -55.27548) (xy 404.77523 -55.291483) (xy 404.723298 -55.316826)
			(xy 404.66814 -55.334051) (xy 404.611015 -55.342764) (xy 404.582122 -55.343298) (xy 404.554867 -55.342857)
			(xy 404.500913 -55.335102) (xy 404.448611 -55.319747) (xy 404.399026 -55.297106) (xy 404.353169 -55.267637)
			(xy 404.311973 -55.231943) (xy 404.276276 -55.190748) (xy 404.246805 -55.144893) (xy 404.22416 -55.09531)
			(xy 404.208803 -55.043009) (xy 404.201045 -54.989055) (xy 401.992744 -54.989055) (xy 401.996155 -55.000394)
			(xy 402.004275 -55.05557) (xy 402.004784 -55.083456) (xy 402.004275 -55.111342) (xy 401.996155 -55.166518)
			(xy 401.980087 -55.219925) (xy 401.956415 -55.270422) (xy 401.925642 -55.316935) (xy 401.888425 -55.358472)
			(xy 401.845557 -55.394147) (xy 401.801795 -55.420855) (xy 402.524645 -55.420855) (xy 402.524645 -55.366345)
			(xy 402.532403 -55.312391) (xy 402.54776 -55.26009) (xy 402.570405 -55.210507) (xy 402.599876 -55.164652)
			(xy 402.635573 -55.123457) (xy 402.676769 -55.087763) (xy 402.722626 -55.058294) (xy 402.772211 -55.035653)
			(xy 402.824513 -55.020298) (xy 402.878467 -55.012543) (xy 402.905722 -55.012082) (xy 402.932036 -55.012541)
			(xy 402.984165 -55.019778) (xy 403.034808 -55.034099) (xy 403.083006 -55.055233) (xy 403.12785 -55.082781)
			(xy 403.168489 -55.11622) (xy 403.186646 -55.135272) (xy 403.194152 -55.142692) (xy 403.213444 -55.151207)
			(xy 403.223984 -55.151782) (xy 403.29866 -55.151782) (xy 403.30921 -55.15125) (xy 403.328505 -55.142718)
			(xy 403.335998 -55.135272) (xy 403.354156 -55.116219) (xy 403.394786 -55.082763) (xy 403.439626 -55.055204)
			(xy 403.487826 -55.034065) (xy 403.538473 -55.019747) (xy 403.590606 -55.012521) (xy 403.616922 -55.012082)
			(xy 403.644171 -55.01259) (xy 403.698115 -55.020349) (xy 403.750406 -55.035705) (xy 403.799979 -55.058347)
			(xy 403.845825 -55.087813) (xy 403.887012 -55.123504) (xy 403.9227 -55.164692) (xy 403.952164 -55.21054)
			(xy 403.974802 -55.260115) (xy 403.990156 -55.312406) (xy 403.997912 -55.366351) (xy 403.997912 -55.420849)
			(xy 403.990156 -55.474794) (xy 403.974802 -55.527085) (xy 403.952164 -55.57666) (xy 403.9227 -55.622508)
			(xy 403.887012 -55.663696) (xy 403.845826 -55.699387) (xy 403.799979 -55.728853) (xy 403.750406 -55.751495)
			(xy 403.698115 -55.766851) (xy 403.644171 -55.77461) (xy 403.616922 -55.775098) (xy 403.590609 -55.774617)
			(xy 403.538481 -55.767385) (xy 403.487838 -55.753068) (xy 403.439639 -55.731939) (xy 403.394795 -55.704395)
			(xy 403.354155 -55.670959) (xy 403.335998 -55.651908) (xy 403.328478 -55.644505) (xy 403.309197 -55.635981)
			(xy 403.29866 -55.635398) (xy 403.223984 -55.635398) (xy 403.213432 -55.635905) (xy 403.194137 -55.644456)
			(xy 403.186646 -55.651908) (xy 403.168511 -55.670984) (xy 403.127877 -55.704439) (xy 403.083032 -55.731995)
			(xy 403.034827 -55.75313) (xy 402.984176 -55.767443) (xy 402.932039 -55.774662) (xy 402.905722 -55.775098)
			(xy 402.878467 -55.774657) (xy 402.824513 -55.766902) (xy 402.772211 -55.751547) (xy 402.722626 -55.728906)
			(xy 402.676769 -55.699437) (xy 402.635573 -55.663743) (xy 402.599876 -55.622548) (xy 402.570405 -55.576693)
			(xy 402.54776 -55.52711) (xy 402.532403 -55.474809) (xy 402.524645 -55.420855) (xy 401.801795 -55.420855)
			(xy 401.797951 -55.423201) (xy 401.746622 -55.445013) (xy 401.692665 -55.459119) (xy 401.637228 -55.465219)
			(xy 401.581494 -55.463182) (xy 401.526651 -55.453052) (xy 401.473867 -55.435045) (xy 401.424267 -55.409544)
			(xy 401.378909 -55.377093) (xy 401.33876 -55.338384) (xy 401.304674 -55.294241) (xy 401.277378 -55.245606)
			(xy 401.257455 -55.193515) (xy 401.245329 -55.139078) (xy 401.241258 -55.083456) (xy 394.97041 -55.083456)
			(xy 394.935647 -55.105797) (xy 394.88607 -55.128439) (xy 394.833775 -55.143794) (xy 394.779827 -55.15155)
			(xy 394.725325 -55.15155) (xy 394.671377 -55.143794) (xy 394.619082 -55.128439) (xy 394.569505 -55.105797)
			(xy 394.523655 -55.076331) (xy 394.482464 -55.04064) (xy 394.446773 -54.999449) (xy 394.417307 -54.953599)
			(xy 394.394665 -54.904022) (xy 394.37931 -54.851727) (xy 394.371554 -54.797779) (xy 394.371068 -54.770528)
			(xy 391.23915 -54.770528) (xy 391.239502 -54.791102) (xy 391.239016 -54.818353) (xy 391.23126 -54.872301)
			(xy 391.215905 -54.924596) (xy 391.193263 -54.974173) (xy 391.163797 -55.020023) (xy 391.128106 -55.061214)
			(xy 391.086915 -55.096905) (xy 391.041065 -55.126371) (xy 390.991488 -55.149013) (xy 390.939193 -55.164368)
			(xy 390.885245 -55.172124) (xy 390.830743 -55.172124) (xy 390.776795 -55.164368) (xy 390.7245 -55.149013)
			(xy 390.674923 -55.126371) (xy 390.629073 -55.096905) (xy 390.587882 -55.061214) (xy 390.552191 -55.020023)
			(xy 390.522725 -54.974173) (xy 390.500083 -54.924596) (xy 390.484728 -54.872301) (xy 390.476972 -54.818353)
			(xy 390.476486 -54.791102) (xy 390.476958 -54.763732) (xy 390.484781 -54.709553) (xy 390.500267 -54.657049)
			(xy 390.523099 -54.607297) (xy 390.552806 -54.561319) (xy 390.570466 -54.540404) (xy 390.576562 -54.533292)
			(xy 390.57961 -54.52491) (xy 390.581139 -54.520624) (xy 390.582805 -54.511679) (xy 390.582912 -54.50713)
			(xy 390.582912 -54.440074) (xy 390.582792 -54.435526) (xy 390.581139 -54.426579) (xy 390.57961 -54.422294)
			(xy 390.576562 -54.413912) (xy 390.570466 -54.4068) (xy 390.552824 -54.385868) (xy 390.523095 -54.339901)
			(xy 390.500247 -54.290155) (xy 390.484749 -54.237652) (xy 390.47692 -54.183473) (xy 390.476919 -54.12873)
			(xy 390.484749 -54.074551) (xy 390.500246 -54.022048) (xy 390.523094 -53.972302) (xy 390.552822 -53.926334)
			(xy 390.570466 -53.905404) (xy 390.576562 -53.898292) (xy 390.57961 -53.88991) (xy 390.581139 -53.885624)
			(xy 390.582805 -53.876679) (xy 390.582912 -53.87213) (xy 390.582912 -53.79593) (xy 390.580118 -53.788564)
			(xy 390.560046 -53.766853) (xy 390.526067 -53.718468) (xy 390.499859 -53.665469) (xy 390.482034 -53.609096)
			(xy 390.473008 -53.550664) (xy 390.472422 -53.521102) (xy 390.472855 -53.494703) (xy 390.480063 -53.4424)
			(xy 390.494343 -53.39157) (xy 390.515428 -53.343166) (xy 390.542924 -53.298093) (xy 390.576315 -53.257196)
			(xy 390.595358 -53.238908) (xy 390.597114 -53.234341) (xy 390.599034 -53.224749) (xy 390.599168 -53.219858)
			(xy 390.599168 -53.187854) (xy 390.598406 -53.17871) (xy 390.59739 -53.1749) (xy 390.595497 -53.168421)
			(xy 390.588806 -53.156703) (xy 390.584182 -53.151786) (xy 390.583166 -53.15077) (xy 390.571482 -53.137816)
			(xy 390.564193 -53.130863) (xy 390.545726 -53.122857) (xy 390.535668 -53.122322) (xy 388.622794 -53.122322)
			(xy 388.613985 -53.122741) (xy 388.597431 -53.128784) (xy 388.583886 -53.140057) (xy 388.579106 -53.147468)
			(xy 388.534656 -53.22316) (xy 388.531491 -53.229097) (xy 388.52802 -53.24209) (xy 388.527798 -53.248814)
			(xy 388.527798 -53.262022) (xy 388.529576 -53.265324) (xy 388.534402 -53.273706) (xy 388.546098 -53.295242)
			(xy 388.564516 -53.340657) (xy 388.576976 -53.388053) (xy 388.583274 -53.436655) (xy 388.583678 -53.461158)
			(xy 388.583678 -53.461412) (xy 388.583205 -53.488782) (xy 388.57538 -53.542959) (xy 388.559891 -53.595461)
			(xy 388.537056 -53.64521) (xy 388.507346 -53.691185) (xy 388.489698 -53.71211) (xy 388.483602 -53.719222)
			(xy 388.480554 -53.727604) (xy 388.479033 -53.731892) (xy 388.477371 -53.740836) (xy 388.477252 -53.745384)
			(xy 388.477252 -53.81244) (xy 388.477373 -53.816988) (xy 388.47903 -53.825933) (xy 388.480554 -53.83022)
			(xy 388.483602 -53.838602) (xy 388.489698 -53.845714) (xy 388.507337 -53.866647) (xy 388.537058 -53.912615)
			(xy 388.5599 -53.962361) (xy 388.575394 -54.014862) (xy 388.58322 -54.069039) (xy 388.583219 -54.123779)
			(xy 388.57539 -54.177956) (xy 388.559894 -54.230456) (xy 388.537049 -54.280201) (xy 388.507326 -54.326167)
			(xy 388.489698 -54.34711) (xy 388.483602 -54.354222) (xy 388.480554 -54.362604) (xy 388.479033 -54.366892)
			(xy 388.477371 -54.375836) (xy 388.477252 -54.380384) (xy 388.477252 -54.44744) (xy 388.477373 -54.451988)
			(xy 388.47903 -54.460933) (xy 388.480554 -54.46522) (xy 388.483602 -54.473602) (xy 388.489698 -54.480714)
			(xy 388.507339 -54.501646) (xy 388.537064 -54.547612) (xy 388.559905 -54.597359) (xy 388.575394 -54.649863)
			(xy 388.58321 -54.704042) (xy 388.583678 -54.731412) (xy 388.583192 -54.758663) (xy 388.575436 -54.812611)
			(xy 388.560081 -54.864906) (xy 388.537439 -54.914483) (xy 388.507973 -54.960333) (xy 388.472282 -55.001524)
			(xy 388.431091 -55.037215) (xy 388.385241 -55.066681) (xy 388.335664 -55.089323) (xy 388.283369 -55.104678)
			(xy 388.229421 -55.112434) (xy 388.174919 -55.112434) (xy 388.120971 -55.104678) (xy 388.068676 -55.089323)
			(xy 388.019099 -55.066681) (xy 387.973249 -55.037215) (xy 387.932058 -55.001524) (xy 387.896367 -54.960333)
			(xy 387.866901 -54.914483) (xy 387.844259 -54.864906) (xy 387.828904 -54.812611) (xy 387.821148 -54.758663)
			(xy 387.820662 -54.731412) (xy 387.82114 -54.704045) (xy 387.828976 -54.649873) (xy 387.844475 -54.597378)
			(xy 387.867318 -54.547638) (xy 387.897036 -54.501673) (xy 387.914642 -54.480714) (xy 387.920738 -54.473602)
			(xy 387.923786 -54.46522) (xy 387.925308 -54.460932) (xy 387.926973 -54.451988) (xy 387.927088 -54.44744)
			(xy 387.927088 -54.380384) (xy 387.92696 -54.375837) (xy 387.925292 -54.366896) (xy 387.923786 -54.362604)
			(xy 387.920738 -54.354222) (xy 387.914642 -54.34711) (xy 387.897 -54.326178) (xy 387.867272 -54.28021)
			(xy 387.844424 -54.230463) (xy 387.828926 -54.17796) (xy 387.821095 -54.12378) (xy 387.821094 -54.069038)
			(xy 387.828922 -54.014858) (xy 387.844418 -53.962354) (xy 387.867263 -53.912606) (xy 387.896989 -53.866637)
			(xy 387.914642 -53.845714) (xy 387.920738 -53.838602) (xy 387.923786 -53.83022) (xy 387.925308 -53.825932)
			(xy 387.926973 -53.816988) (xy 387.927088 -53.81244) (xy 387.927088 -53.745384) (xy 387.92696 -53.740837)
			(xy 387.925292 -53.731896) (xy 387.923786 -53.727604) (xy 387.920738 -53.719222) (xy 387.914642 -53.71211)
			(xy 387.896998 -53.69118) (xy 387.867267 -53.645214) (xy 387.84442 -53.595468) (xy 387.828927 -53.542964)
			(xy 387.821106 -53.488783) (xy 387.820662 -53.461412) (xy 387.820662 -53.461158) (xy 387.821038 -53.436652)
			(xy 387.827318 -53.388045) (xy 387.839783 -53.340644) (xy 387.858225 -53.295235) (xy 387.869938 -53.273706)
			(xy 387.874764 -53.265324) (xy 387.876542 -53.262022) (xy 387.876542 -53.248814) (xy 387.876368 -53.242083)
			(xy 387.872886 -53.229083) (xy 387.869684 -53.22316) (xy 387.825234 -53.147468) (xy 387.820473 -53.140035)
			(xy 387.806942 -53.128721) (xy 387.790365 -53.122696) (xy 387.781546 -53.122322) (xy 381.865632 -53.122322)
			(xy 381.85707 -53.122705) (xy 381.840927 -53.12843) (xy 381.82755 -53.139127) (xy 381.822706 -53.146198)
			(xy 381.7874 -53.20792) (xy 381.777748 -53.224684) (xy 381.774659 -53.230503) (xy 381.771329 -53.243244)
			(xy 381.771144 -53.24983) (xy 381.771144 -53.263546) (xy 381.778256 -53.275484) (xy 381.79081 -53.297591)
			(xy 381.81059 -53.344425) (xy 381.823963 -53.393474) (xy 381.83069 -53.443866) (xy 381.831088 -53.469286)
			(xy 381.831088 -53.475382) (xy 381.830191 -53.502347) (xy 381.821738 -53.555631) (xy 381.805862 -53.607193)
			(xy 381.782878 -53.656003) (xy 381.753246 -53.701088) (xy 381.717556 -53.741547) (xy 381.676522 -53.776574)
			(xy 381.630961 -53.805469) (xy 381.581784 -53.827657) (xy 381.529971 -53.842693) (xy 381.476556 -53.850278)
			(xy 381.44958 -53.850794) (xy 381.42221 -53.850321) (xy 381.368034 -53.842494) (xy 381.315532 -53.827005)
			(xy 381.265783 -53.804171) (xy 381.219808 -53.77446) (xy 381.198882 -53.756814) (xy 381.19177 -53.750718)
			(xy 381.183388 -53.74767) (xy 381.179102 -53.746143) (xy 381.170157 -53.744482) (xy 381.165608 -53.744368)
			(xy 381.098552 -53.744368) (xy 381.094004 -53.74449) (xy 381.08506 -53.746149) (xy 381.080772 -53.74767)
			(xy 381.07239 -53.750718) (xy 381.065278 -53.756814) (xy 381.044346 -53.774454) (xy 380.998379 -53.804176)
			(xy 380.948632 -53.827016) (xy 380.896129 -53.842503) (xy 380.84195 -53.850318) (xy 380.81458 -53.850794)
			(xy 380.787604 -53.850327) (xy 380.734191 -53.842725) (xy 380.682381 -53.827675) (xy 380.633207 -53.805478)
			(xy 380.58765 -53.776576) (xy 380.546618 -53.741545) (xy 380.510929 -53.701084) (xy 380.481295 -53.656)
			(xy 380.458307 -53.607191) (xy 380.442423 -53.555631) (xy 380.433959 -53.502347) (xy 380.433072 -53.475382)
			(xy 380.433072 -53.469286) (xy 380.433497 -53.443869) (xy 380.44025 -53.393486) (xy 380.453622 -53.344442)
			(xy 380.473377 -53.297604) (xy 380.485904 -53.275484) (xy 380.48946 -53.269642) (xy 380.493016 -53.256434)
			(xy 380.493016 -53.24983) (xy 380.492809 -53.243248) (xy 380.48947 -53.230515) (xy 380.486412 -53.224684)
			(xy 380.47676 -53.20792) (xy 380.441454 -53.146198) (xy 380.436642 -53.139095) (xy 380.423273 -53.128359)
			(xy 380.407101 -53.122664) (xy 380.398528 -53.122322) (xy 376.03811 -53.122322) (xy 376.029916 -53.12263)
			(xy 376.014369 -53.127812) (xy 376.00763 -53.132482) (xy 376.000772 -53.137562) (xy 375.991882 -53.15077)
			(xy 375.989342 -53.158898) (xy 375.981222 -53.184915) (xy 375.958584 -53.234493) (xy 375.929121 -53.280344)
			(xy 375.893432 -53.321536) (xy 375.852244 -53.357228) (xy 375.806395 -53.386696) (xy 375.756819 -53.409338)
			(xy 375.704526 -53.424694) (xy 375.650579 -53.43245) (xy 375.596077 -53.43245) (xy 375.54213 -53.424694)
			(xy 375.489837 -53.409338) (xy 375.440261 -53.386696) (xy 375.394412 -53.357228) (xy 375.353224 -53.321536)
			(xy 375.317535 -53.280344) (xy 375.288072 -53.234493) (xy 375.265434 -53.184915) (xy 375.257314 -53.158898)
			(xy 375.257314 -53.158644) (xy 375.254715 -53.150922) (xy 375.245386 -53.137575) (xy 375.239026 -53.132482)
			(xy 375.232422 -53.127402) (xy 375.216928 -53.122322) (xy 367.084356 -53.122322) (xy 367.076459 -53.12265)
			(xy 367.061444 -53.127555) (xy 367.054892 -53.131974) (xy 367.048542 -53.136292) (xy 367.039398 -53.148738)
			(xy 367.036604 -53.156612) (xy 367.02638 -53.185087) (xy 366.999474 -53.239277) (xy 366.965656 -53.289444)
			(xy 366.925516 -53.334713) (xy 366.879755 -53.374291) (xy 366.85474 -53.391308) (xy 366.845596 -53.39715)
			(xy 366.840008 -53.405786) (xy 366.83733 -53.410114) (xy 366.833611 -53.419586) (xy 366.832642 -53.424582)
			(xy 366.819942 -53.49875) (xy 366.819227 -53.504024) (xy 366.819737 -53.514652) (xy 366.820958 -53.519832)
			(xy 366.823244 -53.52923) (xy 366.829848 -53.537866) (xy 366.844738 -53.55792) (xy 366.869737 -53.601163)
			(xy 366.888883 -53.647296) (xy 366.901848 -53.695533) (xy 366.908412 -53.745048) (xy 366.908842 -53.770022)
			(xy 366.908842 -53.77053) (xy 366.908354 -53.797781) (xy 366.900594 -53.851727) (xy 366.885237 -53.90402)
			(xy 366.862595 -53.953596) (xy 366.833128 -53.999445) (xy 366.797437 -54.040634) (xy 366.756248 -54.076326)
			(xy 366.710399 -54.105793) (xy 366.660824 -54.128436) (xy 366.608531 -54.143794) (xy 366.554585 -54.151554)
			(xy 366.527334 -54.152038) (xy 366.499966 -54.151561) (xy 366.445793 -54.143728) (xy 366.393296 -54.128232)
			(xy 366.343554 -54.105391) (xy 366.297587 -54.075674) (xy 366.276636 -54.058058) (xy 366.269524 -54.051962)
			(xy 366.261142 -54.048914) (xy 366.256853 -54.047399) (xy 366.247909 -54.045747) (xy 366.243362 -54.045612)
			(xy 366.176306 -54.045612) (xy 366.171759 -54.045738) (xy 366.162817 -54.047402) (xy 366.158526 -54.048914)
			(xy 366.150144 -54.051962) (xy 366.143032 -54.058058) (xy 366.122102 -54.075704) (xy 366.076137 -54.105437)
			(xy 366.026391 -54.128287) (xy 365.973887 -54.143783) (xy 365.919706 -54.151607) (xy 365.892334 -54.152038)
			(xy 365.865079 -54.151578) (xy 365.811122 -54.143825) (xy 365.758819 -54.128472) (xy 365.709232 -54.105832)
			(xy 365.663373 -54.076365) (xy 365.622174 -54.040672) (xy 365.586473 -53.999478) (xy 365.556999 -53.953624)
			(xy 365.534351 -53.904041) (xy 365.518989 -53.85174) (xy 365.511227 -53.797785) (xy 365.510826 -53.77053)
			(xy 365.511358 -53.741613) (xy 365.520081 -53.684439) (xy 365.537333 -53.629238) (xy 365.562718 -53.577272)
			(xy 365.595654 -53.529732) (xy 365.635388 -53.487706) (xy 365.657892 -53.46954) (xy 365.66527 -53.463253)
			(xy 365.675053 -53.446537) (xy 365.676942 -53.437028) (xy 365.67745 -53.429408) (xy 365.67745 -53.349652)
			(xy 365.676942 -53.342032) (xy 365.67518 -53.333013) (xy 365.666188 -53.317003) (xy 365.659416 -53.31079)
			(xy 365.657892 -53.30952) (xy 365.63862 -53.294013) (xy 365.603846 -53.258831) (xy 365.573905 -53.219455)
			(xy 365.549299 -53.176543) (xy 365.539528 -53.153818) (xy 365.53521 -53.143404) (xy 365.527082 -53.135784)
			(xy 365.520478 -53.130704) (xy 365.514382 -53.12664) (xy 365.500412 -53.122322) (xy 365.181134 -53.122322)
			(xy 365.180372 -53.122322) (xy 365.17034 -53.122974) (xy 365.151911 -53.130958) (xy 365.144558 -53.137816)
			(xy 365.132874 -53.15077) (xy 365.131858 -53.151786) (xy 365.127241 -53.156708) (xy 365.120555 -53.168425)
			(xy 365.11865 -53.1749) (xy 365.116872 -53.1876) (xy 365.116872 -53.219604) (xy 365.117008 -53.224637)
			(xy 365.119047 -53.234495) (xy 365.120936 -53.239162) (xy 365.139936 -53.257451) (xy 365.17326 -53.298323)
			(xy 365.2007 -53.343359) (xy 365.221741 -53.391716) (xy 365.23599 -53.44249) (xy 365.243182 -53.494734)
			(xy 365.243618 -53.521102) (xy 365.243053 -53.550666) (xy 365.234034 -53.609101) (xy 365.216206 -53.665476)
			(xy 365.189988 -53.718473) (xy 365.155993 -53.76685) (xy 365.135922 -53.788564) (xy 365.133128 -53.79593)
			(xy 365.133128 -53.87213) (xy 365.133248 -53.876678) (xy 365.134903 -53.885624) (xy 365.13643 -53.88991)
			(xy 365.139478 -53.898292) (xy 365.145574 -53.905404) (xy 365.163215 -53.926337) (xy 365.192939 -53.972305)
			(xy 365.215784 -54.022051) (xy 365.23128 -54.074553) (xy 365.239108 -54.128731) (xy 365.239108 -54.183472)
			(xy 365.231279 -54.23765) (xy 365.215783 -54.290152) (xy 365.20199 -54.320186) (xy 367.430558 -54.320186)
			(xy 367.431002 -54.292815) (xy 367.438823 -54.238634) (xy 367.454316 -54.18613) (xy 367.477163 -54.136384)
			(xy 367.506894 -54.090418) (xy 367.524538 -54.069488) (xy 367.524792 -54.069234) (xy 367.53037 -54.062141)
			(xy 367.536622 -54.045229) (xy 367.536984 -54.036214) (xy 367.536984 -53.969158) (xy 367.536603 -53.960144)
			(xy 367.530372 -53.943226) (xy 367.524792 -53.936138) (xy 367.524538 -53.936138) (xy 367.524538 -53.935884)
			(xy 367.506931 -53.914926) (xy 367.477213 -53.868961) (xy 367.45437 -53.81922) (xy 367.438872 -53.766725)
			(xy 367.431036 -53.712554) (xy 367.430558 -53.685186) (xy 367.431044 -53.657935) (xy 367.4388 -53.603987)
			(xy 367.454155 -53.551692) (xy 367.476797 -53.502115) (xy 367.506263 -53.456265) (xy 367.541954 -53.415074)
			(xy 367.583145 -53.379383) (xy 367.628995 -53.349917) (xy 367.678572 -53.327275) (xy 367.730867 -53.31192)
			(xy 367.784815 -53.304164) (xy 367.839317 -53.304164) (xy 367.893265 -53.31192) (xy 367.94556 -53.327275)
			(xy 367.995137 -53.349917) (xy 368.040987 -53.379383) (xy 368.082178 -53.415074) (xy 368.117869 -53.456265)
			(xy 368.147335 -53.502115) (xy 368.169977 -53.551692) (xy 368.185332 -53.603987) (xy 368.193088 -53.657935)
			(xy 368.193574 -53.685186) (xy 368.193106 -53.712556) (xy 368.18529 -53.766735) (xy 368.169801 -53.819239)
			(xy 368.14696 -53.868986) (xy 368.117235 -53.914952) (xy 368.099594 -53.935884) (xy 368.09934 -53.936138)
			(xy 368.093766 -53.943233) (xy 368.087513 -53.960144) (xy 368.087148 -53.969158) (xy 368.087148 -54.036214)
			(xy 368.087488 -54.045233) (xy 368.093746 -54.06215) (xy 368.09934 -54.069234) (xy 368.099594 -54.069234)
			(xy 368.099594 -54.069488) (xy 368.11724 -54.090415) (xy 368.146951 -54.136389) (xy 368.169786 -54.186138)
			(xy 368.185275 -54.23864) (xy 368.193101 -54.292816) (xy 368.193574 -54.320186) (xy 368.193088 -54.347437)
			(xy 368.185332 -54.401385) (xy 368.169977 -54.45368) (xy 368.147335 -54.503257) (xy 368.117869 -54.549107)
			(xy 368.082178 -54.590298) (xy 368.040987 -54.625989) (xy 367.995137 -54.655455) (xy 367.94556 -54.678097)
			(xy 367.893265 -54.693452) (xy 367.839317 -54.701208) (xy 367.784815 -54.701208) (xy 367.730867 -54.693452)
			(xy 367.678572 -54.678097) (xy 367.628995 -54.655455) (xy 367.583145 -54.625989) (xy 367.541954 -54.590298)
			(xy 367.506263 -54.549107) (xy 367.476797 -54.503257) (xy 367.454155 -54.45368) (xy 367.4388 -54.401385)
			(xy 367.431044 -54.347437) (xy 367.430558 -54.320186) (xy 365.20199 -54.320186) (xy 365.192937 -54.339898)
			(xy 365.163213 -54.385866) (xy 365.145574 -54.4068) (xy 365.139478 -54.413912) (xy 365.13643 -54.422294)
			(xy 365.134909 -54.426582) (xy 365.133246 -54.435526) (xy 365.133128 -54.440074) (xy 365.133128 -54.50713)
			(xy 365.133248 -54.511678) (xy 365.134903 -54.520624) (xy 365.13643 -54.52491) (xy 365.139478 -54.533292)
			(xy 365.145574 -54.540404) (xy 365.163217 -54.561335) (xy 365.192944 -54.607301) (xy 365.215789 -54.657048)
			(xy 365.231279 -54.709551) (xy 365.239098 -54.763731) (xy 365.239211 -54.770528) (xy 368.37112 -54.770528)
			(xy 368.371598 -54.743158) (xy 368.379412 -54.688979) (xy 368.394898 -54.636476) (xy 368.417737 -54.586729)
			(xy 368.44746 -54.540762) (xy 368.4651 -54.51983) (xy 368.465354 -54.519576) (xy 368.470963 -54.512505)
			(xy 368.477195 -54.495576) (xy 368.477546 -54.486556) (xy 368.477546 -54.4195) (xy 368.477201 -54.410482)
			(xy 368.470946 -54.393564) (xy 368.465354 -54.38648) (xy 368.4651 -54.38648) (xy 368.4651 -54.386226)
			(xy 368.44746 -54.365295) (xy 368.417748 -54.319322) (xy 368.394912 -54.269574) (xy 368.379422 -54.217073)
			(xy 368.371594 -54.162897) (xy 368.37112 -54.135528) (xy 368.371606 -54.108277) (xy 368.379362 -54.054329)
			(xy 368.394717 -54.002034) (xy 368.417359 -53.952457) (xy 368.446825 -53.906607) (xy 368.482516 -53.865416)
			(xy 368.523707 -53.829725) (xy 368.569557 -53.800259) (xy 368.619134 -53.777617) (xy 368.671429 -53.762262)
			(xy 368.725377 -53.754506) (xy 368.779879 -53.754506) (xy 368.833827 -53.762262) (xy 368.886122 -53.777617)
			(xy 368.935699 -53.800259) (xy 368.981549 -53.829725) (xy 369.02274 -53.865416) (xy 369.058431 -53.906607)
			(xy 369.087897 -53.952457) (xy 369.106659 -53.993538) (xy 372.99695 -53.993538) (xy 372.99695 -53.933602)
			(xy 373.004773 -53.87418) (xy 373.020286 -53.816287) (xy 373.043222 -53.760914) (xy 373.073189 -53.709008)
			(xy 373.109676 -53.661458) (xy 373.152056 -53.619078) (xy 373.199606 -53.582591) (xy 373.251512 -53.552624)
			(xy 373.306885 -53.529688) (xy 373.364778 -53.514175) (xy 373.4242 -53.506352) (xy 373.484136 -53.506352)
			(xy 373.543558 -53.514175) (xy 373.601451 -53.529688) (xy 373.656824 -53.552624) (xy 373.70873 -53.582591)
			(xy 373.75628 -53.619078) (xy 373.79866 -53.661458) (xy 373.835147 -53.709008) (xy 373.865114 -53.760914)
			(xy 373.88805 -53.816287) (xy 373.903563 -53.87418) (xy 373.911386 -53.933602) (xy 373.911876 -53.96357)
			(xy 373.911386 -53.993538) (xy 373.903563 -54.05296) (xy 373.899679 -54.067456) (xy 375.24131 -54.067456)
			(xy 375.245381 -54.011834) (xy 375.257507 -53.957397) (xy 375.27743 -53.905306) (xy 375.304726 -53.856671)
			(xy 375.338812 -53.812528) (xy 375.378961 -53.773819) (xy 375.424319 -53.741368) (xy 375.473919 -53.715867)
			(xy 375.526703 -53.69786) (xy 375.581546 -53.68773) (xy 375.63728 -53.685693) (xy 375.692717 -53.691793)
			(xy 375.746674 -53.705899) (xy 375.798003 -53.727711) (xy 375.845609 -53.756765) (xy 375.888477 -53.79244)
			(xy 375.925694 -53.833977) (xy 375.956467 -53.88049) (xy 375.980139 -53.930987) (xy 375.996207 -53.984394)
			(xy 376.004327 -54.03957) (xy 376.004836 -54.067456) (xy 376.004327 -54.095342) (xy 375.996207 -54.150518)
			(xy 375.980139 -54.203925) (xy 375.963741 -54.238906) (xy 382.68605 -54.238906) (xy 382.690121 -54.183284)
			(xy 382.702247 -54.128847) (xy 382.72217 -54.076756) (xy 382.749466 -54.028121) (xy 382.783552 -53.983978)
			(xy 382.823701 -53.945269) (xy 382.869059 -53.912818) (xy 382.918659 -53.887317) (xy 382.971443 -53.86931)
			(xy 383.026286 -53.85918) (xy 383.08202 -53.857143) (xy 383.137457 -53.863243) (xy 383.191414 -53.877349)
			(xy 383.242743 -53.899161) (xy 383.290349 -53.928215) (xy 383.333217 -53.96389) (xy 383.370434 -54.005427)
			(xy 383.401207 -54.05194) (xy 383.424879 -54.102437) (xy 383.440947 -54.155844) (xy 383.449067 -54.21102)
			(xy 383.449576 -54.238906) (xy 383.449067 -54.266792) (xy 383.440947 -54.321968) (xy 383.424879 -54.375375)
			(xy 383.401207 -54.425872) (xy 383.370434 -54.472385) (xy 383.333217 -54.513922) (xy 383.290349 -54.549597)
			(xy 383.242743 -54.578651) (xy 383.191414 -54.600463) (xy 383.137457 -54.614569) (xy 383.08202 -54.620669)
			(xy 383.026286 -54.618632) (xy 382.971443 -54.608502) (xy 382.918659 -54.590495) (xy 382.869059 -54.564994)
			(xy 382.823701 -54.532543) (xy 382.783552 -54.493834) (xy 382.749466 -54.449691) (xy 382.72217 -54.401056)
			(xy 382.702247 -54.348965) (xy 382.690121 -54.294528) (xy 382.68605 -54.238906) (xy 375.963741 -54.238906)
			(xy 375.956467 -54.254422) (xy 375.925694 -54.300935) (xy 375.888477 -54.342472) (xy 375.845609 -54.378147)
			(xy 375.798003 -54.407201) (xy 375.746674 -54.429013) (xy 375.692717 -54.443119) (xy 375.63728 -54.449219)
			(xy 375.581546 -54.447182) (xy 375.526703 -54.437052) (xy 375.473919 -54.419045) (xy 375.424319 -54.393544)
			(xy 375.378961 -54.361093) (xy 375.338812 -54.322384) (xy 375.304726 -54.278241) (xy 375.27743 -54.229606)
			(xy 375.257507 -54.177515) (xy 375.245381 -54.123078) (xy 375.24131 -54.067456) (xy 373.899679 -54.067456)
			(xy 373.88805 -54.110853) (xy 373.865114 -54.166226) (xy 373.835147 -54.218132) (xy 373.79866 -54.265682)
			(xy 373.75628 -54.308062) (xy 373.70873 -54.344549) (xy 373.656824 -54.374516) (xy 373.601451 -54.397452)
			(xy 373.543558 -54.412965) (xy 373.484136 -54.420788) (xy 373.4242 -54.420788) (xy 373.364778 -54.412965)
			(xy 373.306885 -54.397452) (xy 373.251512 -54.374516) (xy 373.199606 -54.344549) (xy 373.152056 -54.308062)
			(xy 373.109676 -54.265682) (xy 373.073189 -54.218132) (xy 373.043222 -54.166226) (xy 373.020286 -54.110853)
			(xy 373.004773 -54.05296) (xy 372.99695 -53.993538) (xy 369.106659 -53.993538) (xy 369.110539 -54.002034)
			(xy 369.125894 -54.054329) (xy 369.13365 -54.108277) (xy 369.134136 -54.135528) (xy 369.133702 -54.1629)
			(xy 369.125879 -54.217081) (xy 369.110383 -54.269585) (xy 369.087534 -54.319331) (xy 369.057801 -54.365296)
			(xy 369.040156 -54.386226) (xy 369.039902 -54.38648) (xy 369.034318 -54.393568) (xy 369.02807 -54.410484)
			(xy 369.02771 -54.4195) (xy 369.02771 -54.486556) (xy 369.028086 -54.495571) (xy 369.03432 -54.512488)
			(xy 369.039902 -54.519576) (xy 369.040156 -54.519576) (xy 369.040156 -54.51983) (xy 369.057769 -54.540783)
			(xy 369.087486 -54.58675) (xy 369.110328 -54.636492) (xy 369.125825 -54.688988) (xy 369.133659 -54.74316)
			(xy 369.134136 -54.770528) (xy 369.13365 -54.797779) (xy 369.125894 -54.851727) (xy 369.110539 -54.904022)
			(xy 369.087897 -54.953599) (xy 369.058431 -54.999449) (xy 369.02274 -55.04064) (xy 368.981549 -55.076331)
			(xy 368.970462 -55.083456) (xy 375.24131 -55.083456) (xy 375.245381 -55.027834) (xy 375.257507 -54.973397)
			(xy 375.27743 -54.921306) (xy 375.304726 -54.872671) (xy 375.338812 -54.828528) (xy 375.378961 -54.789819)
			(xy 375.424319 -54.757368) (xy 375.473919 -54.731867) (xy 375.526703 -54.71386) (xy 375.581546 -54.70373)
			(xy 375.63728 -54.701693) (xy 375.692717 -54.707793) (xy 375.746674 -54.721899) (xy 375.798003 -54.743711)
			(xy 375.845609 -54.772765) (xy 375.888477 -54.80844) (xy 375.925694 -54.849977) (xy 375.956467 -54.89649)
			(xy 375.980139 -54.946987) (xy 375.992794 -54.989051) (xy 378.201168 -54.989051) (xy 378.201168 -54.934549)
			(xy 378.208924 -54.880602) (xy 378.224278 -54.828308) (xy 378.246918 -54.778732) (xy 378.276382 -54.732881)
			(xy 378.312072 -54.691691) (xy 378.35326 -54.655998) (xy 378.399109 -54.62653) (xy 378.448684 -54.603887)
			(xy 378.500977 -54.588529) (xy 378.554923 -54.58077) (xy 378.582174 -54.580282) (xy 378.610265 -54.580797)
			(xy 378.665841 -54.589021) (xy 378.71961 -54.605308) (xy 378.770407 -54.629308) (xy 378.817134 -54.660499)
			(xy 378.85878 -54.698208) (xy 378.894443 -54.741619) (xy 378.909326 -54.765448) (xy 378.91466 -54.774338)
			(xy 378.931678 -54.78653) (xy 379.024896 -54.80685) (xy 379.04547 -54.802532) (xy 379.054106 -54.79669)
			(xy 379.078166 -54.780684) (xy 379.130099 -54.755343) (xy 379.185258 -54.738119) (xy 379.242383 -54.729406)
			(xy 379.271276 -54.728872) (xy 379.298527 -54.729378) (xy 379.352476 -54.737131) (xy 379.404772 -54.752483)
			(xy 379.45435 -54.775121) (xy 379.500203 -54.804585) (xy 379.541395 -54.840274) (xy 379.577089 -54.881462)
			(xy 379.606558 -54.927311) (xy 379.629202 -54.976887) (xy 379.64456 -55.029181) (xy 379.652319 -55.083129)
			(xy 379.652784 -55.11038) (xy 379.65231 -55.13775) (xy 379.644495 -55.191929) (xy 379.629008 -55.244432)
			(xy 379.606168 -55.294179) (xy 379.576445 -55.340146) (xy 379.558804 -55.361078) (xy 379.55855 -55.361332)
			(xy 379.55298 -55.36843) (xy 379.546724 -55.385338) (xy 379.546358 -55.394352) (xy 379.546358 -55.461408)
			(xy 379.546699 -55.470427) (xy 379.552956 -55.487344) (xy 379.55855 -55.494428) (xy 379.558804 -55.494428)
			(xy 379.558804 -55.494682) (xy 379.576424 -55.515631) (xy 379.606147 -55.561597) (xy 379.628992 -55.611341)
			(xy 379.644488 -55.66384) (xy 379.652318 -55.718016) (xy 379.65232 -55.772754) (xy 379.644495 -55.826931)
			(xy 379.629002 -55.879431) (xy 379.606162 -55.929177) (xy 379.576442 -55.975145) (xy 379.558804 -55.996078)
			(xy 379.55855 -55.996332) (xy 379.55298 -56.00343) (xy 379.546724 -56.020338) (xy 379.546358 -56.029352)
			(xy 379.546358 -56.096408) (xy 379.546699 -56.105427) (xy 379.552956 -56.122344) (xy 379.55855 -56.129428)
			(xy 379.558804 -56.129428) (xy 379.558804 -56.129682) (xy 379.576449 -56.15061) (xy 379.60616 -56.196584)
			(xy 379.628994 -56.246332) (xy 379.644484 -56.298834) (xy 379.652311 -56.353011) (xy 379.652784 -56.38038)
			(xy 379.652298 -56.407631) (xy 379.644542 -56.461579) (xy 379.629187 -56.513874) (xy 379.606545 -56.563451)
			(xy 379.577079 -56.609301) (xy 379.541388 -56.650492) (xy 379.500197 -56.686183) (xy 379.454347 -56.715649)
			(xy 379.40477 -56.738291) (xy 379.352475 -56.753646) (xy 379.298527 -56.761402) (xy 379.244025 -56.761402)
			(xy 379.190077 -56.753646) (xy 379.137782 -56.738291) (xy 379.088205 -56.715649) (xy 379.042355 -56.686183)
			(xy 379.001164 -56.650492) (xy 378.965473 -56.609301) (xy 378.936007 -56.563451) (xy 378.913365 -56.513874)
			(xy 378.89801 -56.461579) (xy 378.890254 -56.407631) (xy 378.889768 -56.38038) (xy 378.890206 -56.353009)
			(xy 378.898028 -56.298828) (xy 378.913523 -56.246324) (xy 378.936371 -56.196577) (xy 378.966103 -56.150612)
			(xy 378.983748 -56.129682) (xy 378.984002 -56.129428) (xy 378.989583 -56.122338) (xy 378.995833 -56.105424)
			(xy 378.996194 -56.096408) (xy 378.996194 -56.029352) (xy 378.995813 -56.020338) (xy 378.989582 -56.00342)
			(xy 378.984002 -55.996332) (xy 378.983748 -55.996332) (xy 378.983748 -55.996078) (xy 378.966087 -55.975162)
			(xy 378.936361 -55.929191) (xy 378.913516 -55.879443) (xy 378.89802 -55.826938) (xy 378.890193 -55.772757)
			(xy 378.890195 -55.718013) (xy 378.898027 -55.663833) (xy 378.913526 -55.611329) (xy 378.936376 -55.561582)
			(xy 378.966105 -55.515614) (xy 378.983748 -55.494682) (xy 378.984002 -55.494428) (xy 378.989583 -55.487338)
			(xy 378.995833 -55.470424) (xy 378.996194 -55.461408) (xy 378.996194 -55.394352) (xy 378.995813 -55.385338)
			(xy 378.989582 -55.36842) (xy 378.984002 -55.361332) (xy 378.983748 -55.360824) (xy 378.972801 -55.348092)
			(xy 378.952962 -55.320999) (xy 378.944124 -55.306722) (xy 378.93879 -55.297832) (xy 378.921772 -55.28564)
			(xy 378.828554 -55.26532) (xy 378.80798 -55.269638) (xy 378.799344 -55.27548) (xy 378.775268 -55.291461)
			(xy 378.723341 -55.316809) (xy 378.668187 -55.33404) (xy 378.611066 -55.342761) (xy 378.582174 -55.343298)
			(xy 378.554923 -55.34283) (xy 378.500977 -55.335071) (xy 378.448684 -55.319713) (xy 378.399109 -55.29707)
			(xy 378.35326 -55.267602) (xy 378.312072 -55.231909) (xy 378.276382 -55.190719) (xy 378.246918 -55.144868)
			(xy 378.224278 -55.095292) (xy 378.208924 -55.042998) (xy 378.201168 -54.989051) (xy 375.992794 -54.989051)
			(xy 375.996207 -55.000394) (xy 376.004327 -55.05557) (xy 376.004836 -55.083456) (xy 376.004327 -55.111342)
			(xy 375.996207 -55.166518) (xy 375.980139 -55.219925) (xy 375.956467 -55.270422) (xy 375.925694 -55.316935)
			(xy 375.888477 -55.358472) (xy 375.845609 -55.394147) (xy 375.801854 -55.420851) (xy 376.524768 -55.420851)
			(xy 376.524768 -55.366349) (xy 376.532524 -55.312402) (xy 376.547878 -55.260108) (xy 376.570518 -55.210532)
			(xy 376.599982 -55.164681) (xy 376.635672 -55.123491) (xy 376.67686 -55.087798) (xy 376.722709 -55.05833)
			(xy 376.772284 -55.035687) (xy 376.824577 -55.020329) (xy 376.878523 -55.01257) (xy 376.905774 -55.012082)
			(xy 376.932087 -55.012572) (xy 376.984214 -55.019803) (xy 377.034856 -55.034118) (xy 377.083055 -55.055247)
			(xy 377.127899 -55.082788) (xy 377.16854 -55.116223) (xy 377.186698 -55.135272) (xy 377.194222 -55.142671)
			(xy 377.2135 -55.151198) (xy 377.224036 -55.151782) (xy 377.298712 -55.151782) (xy 377.309265 -55.151278)
			(xy 377.32856 -55.142726) (xy 377.33605 -55.135272) (xy 377.354183 -55.116194) (xy 377.394818 -55.08274)
			(xy 377.439663 -55.055184) (xy 377.487868 -55.03405) (xy 377.53852 -55.019738) (xy 377.590657 -55.012518)
			(xy 377.616974 -55.012082) (xy 377.644227 -55.012564) (xy 377.69818 -55.020317) (xy 377.750479 -55.035671)
			(xy 377.800061 -55.058311) (xy 377.845917 -55.087778) (xy 377.887111 -55.12347) (xy 377.922807 -55.164663)
			(xy 377.952276 -55.210516) (xy 377.97492 -55.260096) (xy 377.990277 -55.312395) (xy 377.998035 -55.366347)
			(xy 377.998035 -55.420853) (xy 377.990277 -55.474805) (xy 377.97492 -55.527104) (xy 377.952276 -55.576684)
			(xy 377.922807 -55.622537) (xy 377.887111 -55.66373) (xy 377.845917 -55.699422) (xy 377.800061 -55.728889)
			(xy 377.750479 -55.751529) (xy 377.69818 -55.766883) (xy 377.644227 -55.774636) (xy 377.616974 -55.775098)
			(xy 377.590659 -55.774649) (xy 377.53853 -55.76741) (xy 377.487887 -55.753088) (xy 377.439688 -55.731952)
			(xy 377.394845 -55.704402) (xy 377.354206 -55.670961) (xy 377.33605 -55.651908) (xy 377.328548 -55.644484)
			(xy 377.309253 -55.635972) (xy 377.298712 -55.635398) (xy 377.224036 -55.635398) (xy 377.213487 -55.635934)
			(xy 377.194192 -55.644464) (xy 377.186698 -55.651908) (xy 377.168538 -55.670959) (xy 377.127909 -55.704416)
			(xy 377.08307 -55.731976) (xy 377.03487 -55.753115) (xy 376.984223 -55.767433) (xy 376.93209 -55.774659)
			(xy 376.905774 -55.775098) (xy 376.878523 -55.77463) (xy 376.824577 -55.766871) (xy 376.772284 -55.751513)
			(xy 376.722709 -55.72887) (xy 376.67686 -55.699402) (xy 376.635672 -55.663709) (xy 376.599982 -55.622519)
			(xy 376.570518 -55.576668) (xy 376.547878 -55.527092) (xy 376.532524 -55.474798) (xy 376.524768 -55.420851)
			(xy 375.801854 -55.420851) (xy 375.798003 -55.423201) (xy 375.746674 -55.445013) (xy 375.692717 -55.459119)
			(xy 375.63728 -55.465219) (xy 375.581546 -55.463182) (xy 375.526703 -55.453052) (xy 375.473919 -55.435045)
			(xy 375.424319 -55.409544) (xy 375.378961 -55.377093) (xy 375.338812 -55.338384) (xy 375.304726 -55.294241)
			(xy 375.27743 -55.245606) (xy 375.257507 -55.193515) (xy 375.245381 -55.139078) (xy 375.24131 -55.083456)
			(xy 368.970462 -55.083456) (xy 368.935699 -55.105797) (xy 368.886122 -55.128439) (xy 368.833827 -55.143794)
			(xy 368.779879 -55.15155) (xy 368.725377 -55.15155) (xy 368.671429 -55.143794) (xy 368.619134 -55.128439)
			(xy 368.569557 -55.105797) (xy 368.523707 -55.076331) (xy 368.482516 -55.04064) (xy 368.446825 -54.999449)
			(xy 368.417359 -54.953599) (xy 368.394717 -54.904022) (xy 368.379362 -54.851727) (xy 368.371606 -54.797779)
			(xy 368.37112 -54.770528) (xy 365.239211 -54.770528) (xy 365.239554 -54.791102) (xy 365.239068 -54.818353)
			(xy 365.231312 -54.872301) (xy 365.215957 -54.924596) (xy 365.193315 -54.974173) (xy 365.163849 -55.020023)
			(xy 365.128158 -55.061214) (xy 365.086967 -55.096905) (xy 365.041117 -55.126371) (xy 364.99154 -55.149013)
			(xy 364.939245 -55.164368) (xy 364.885297 -55.172124) (xy 364.830795 -55.172124) (xy 364.776847 -55.164368)
			(xy 364.724552 -55.149013) (xy 364.674975 -55.126371) (xy 364.629125 -55.096905) (xy 364.587934 -55.061214)
			(xy 364.552243 -55.020023) (xy 364.522777 -54.974173) (xy 364.500135 -54.924596) (xy 364.48478 -54.872301)
			(xy 364.477024 -54.818353) (xy 364.476538 -54.791102) (xy 364.47701 -54.763732) (xy 364.484834 -54.709554)
			(xy 364.500322 -54.657051) (xy 364.523156 -54.607301) (xy 364.552866 -54.561326) (xy 364.570518 -54.540404)
			(xy 364.576614 -54.533292) (xy 364.579662 -54.52491) (xy 364.581184 -54.520622) (xy 364.582848 -54.511678)
			(xy 364.582964 -54.50713) (xy 364.582964 -54.440074) (xy 364.582844 -54.435526) (xy 364.58119 -54.426579)
			(xy 364.579662 -54.422294) (xy 364.576614 -54.413912) (xy 364.570518 -54.4068) (xy 364.552878 -54.385867)
			(xy 364.523153 -54.339899) (xy 364.500308 -54.290153) (xy 364.484812 -54.237651) (xy 364.476983 -54.183472)
			(xy 364.476983 -54.128731) (xy 364.484811 -54.074552) (xy 364.500307 -54.02205) (xy 364.523152 -53.972304)
			(xy 364.552876 -53.926335) (xy 364.570518 -53.905404) (xy 364.576614 -53.898292) (xy 364.579662 -53.88991)
			(xy 364.581184 -53.885622) (xy 364.582848 -53.876678) (xy 364.582964 -53.87213) (xy 364.582964 -53.79593)
			(xy 364.58017 -53.788564) (xy 364.560096 -53.766854) (xy 364.526113 -53.71847) (xy 364.499901 -53.665472)
			(xy 364.482073 -53.609098) (xy 364.473046 -53.550665) (xy 364.472474 -53.521102) (xy 364.472908 -53.494704)
			(xy 364.480116 -53.442401) (xy 364.494397 -53.391573) (xy 364.515484 -53.34317) (xy 364.542983 -53.2981)
			(xy 364.576377 -53.257206) (xy 364.59541 -53.238908) (xy 364.597164 -53.234341) (xy 364.599083 -53.224749)
			(xy 364.59922 -53.219858) (xy 364.59922 -53.187854) (xy 364.598458 -53.17871) (xy 364.597442 -53.1749)
			(xy 364.59555 -53.16842) (xy 364.588865 -53.156697) (xy 364.584234 -53.151786) (xy 364.583218 -53.15077)
			(xy 364.571534 -53.137816) (xy 364.564243 -53.13087) (xy 364.545775 -53.122882) (xy 364.53572 -53.122322)
			(xy 362.622846 -53.122322) (xy 362.614041 -53.122748) (xy 362.597499 -53.128802) (xy 362.583967 -53.140079)
			(xy 362.579158 -53.147468) (xy 362.534708 -53.22316) (xy 362.531545 -53.229097) (xy 362.528078 -53.24209)
			(xy 362.52785 -53.248814) (xy 362.52785 -53.262022) (xy 362.529628 -53.265324) (xy 362.534454 -53.273706)
			(xy 362.546148 -53.295242) (xy 362.564564 -53.340657) (xy 362.577023 -53.388054) (xy 362.583319 -53.436655)
			(xy 362.58373 -53.461158) (xy 362.58373 -53.461412) (xy 362.583257 -53.488781) (xy 362.575431 -53.542958)
			(xy 362.55994 -53.595459) (xy 362.537103 -53.645206) (xy 362.50739 -53.691179) (xy 362.48975 -53.71211)
			(xy 362.483654 -53.719222) (xy 362.480606 -53.727604) (xy 362.479086 -53.731892) (xy 362.477426 -53.740836)
			(xy 362.477304 -53.745384) (xy 362.477304 -53.81244) (xy 362.477425 -53.816988) (xy 362.479081 -53.825934)
			(xy 362.480606 -53.83022) (xy 362.483654 -53.838602) (xy 362.48975 -53.845714) (xy 362.507391 -53.866646)
			(xy 362.537116 -53.912613) (xy 362.559961 -53.962359) (xy 362.575456 -54.014861) (xy 362.583284 -54.069039)
			(xy 362.583283 -54.123779) (xy 362.575453 -54.177957) (xy 362.559954 -54.230458) (xy 362.537107 -54.280203)
			(xy 362.50738 -54.326168) (xy 362.48975 -54.34711) (xy 362.483654 -54.354222) (xy 362.480606 -54.362604)
			(xy 362.479086 -54.366892) (xy 362.477426 -54.375836) (xy 362.477304 -54.380384) (xy 362.477304 -54.44744)
			(xy 362.477425 -54.451988) (xy 362.479081 -54.460934) (xy 362.480606 -54.46522) (xy 362.483654 -54.473602)
			(xy 362.48975 -54.480714) (xy 362.507393 -54.501645) (xy 362.537121 -54.54761) (xy 362.559966 -54.597357)
			(xy 362.575456 -54.649861) (xy 362.583274 -54.704041) (xy 362.58373 -54.731412) (xy 362.583244 -54.758663)
			(xy 362.575488 -54.812611) (xy 362.560133 -54.864906) (xy 362.537491 -54.914483) (xy 362.508025 -54.960333)
			(xy 362.472334 -55.001524) (xy 362.431143 -55.037215) (xy 362.385293 -55.066681) (xy 362.335716 -55.089323)
			(xy 362.283421 -55.104678) (xy 362.229473 -55.112434) (xy 362.174971 -55.112434) (xy 362.121023 -55.104678)
			(xy 362.068728 -55.089323) (xy 362.019151 -55.066681) (xy 361.973301 -55.037215) (xy 361.93211 -55.001524)
			(xy 361.896419 -54.960333) (xy 361.866953 -54.914483) (xy 361.844311 -54.864906) (xy 361.828956 -54.812611)
			(xy 361.8212 -54.758663) (xy 361.820714 -54.731412) (xy 361.821192 -54.704044) (xy 361.829027 -54.649872)
			(xy 361.844524 -54.597376) (xy 361.867365 -54.547634) (xy 361.897081 -54.501667) (xy 361.914694 -54.480714)
			(xy 361.92079 -54.473602) (xy 361.923838 -54.46522) (xy 361.925361 -54.460932) (xy 361.927028 -54.451988)
			(xy 361.92714 -54.44744) (xy 361.92714 -54.380384) (xy 361.927012 -54.375837) (xy 361.925342 -54.366897)
			(xy 361.923838 -54.362604) (xy 361.92079 -54.354222) (xy 361.914694 -54.34711) (xy 361.897054 -54.326177)
			(xy 361.86733 -54.280208) (xy 361.844485 -54.230461) (xy 361.828988 -54.177959) (xy 361.821159 -54.12378)
			(xy 361.821158 -54.069038) (xy 361.828985 -54.014859) (xy 361.844478 -53.962356) (xy 361.867321 -53.912608)
			(xy 361.897043 -53.866638) (xy 361.914694 -53.845714) (xy 361.92079 -53.838602) (xy 361.923838 -53.83022)
			(xy 361.925361 -53.825932) (xy 361.927028 -53.816988) (xy 361.92714 -53.81244) (xy 361.92714 -53.745384)
			(xy 361.927012 -53.740837) (xy 361.925342 -53.731897) (xy 361.923838 -53.727604) (xy 361.92079 -53.719222)
			(xy 361.914694 -53.71211) (xy 361.897052 -53.691179) (xy 361.867325 -53.645212) (xy 361.844481 -53.595466)
			(xy 361.828989 -53.542962) (xy 361.82117 -53.488783) (xy 361.820714 -53.461412) (xy 361.820714 -53.461158)
			(xy 361.82109 -53.436652) (xy 361.82737 -53.388044) (xy 361.839833 -53.340643) (xy 361.858273 -53.295233)
			(xy 361.86999 -53.273706) (xy 361.874816 -53.265324) (xy 361.876594 -53.262022) (xy 361.876594 -53.248814)
			(xy 361.876421 -53.242083) (xy 361.872942 -53.229081) (xy 361.869736 -53.22316) (xy 361.825286 -53.147468)
			(xy 361.820523 -53.14004) (xy 361.80699 -53.128739) (xy 361.790414 -53.122729) (xy 361.781598 -53.122322)
			(xy 355.865684 -53.122322) (xy 355.857118 -53.122697) (xy 355.840962 -53.128411) (xy 355.827571 -53.139104)
			(xy 355.822758 -53.146198) (xy 355.787452 -53.20792) (xy 355.7778 -53.224684) (xy 355.774708 -53.230502)
			(xy 355.771374 -53.243243) (xy 355.771196 -53.24983) (xy 355.771196 -53.263546) (xy 355.778308 -53.275484)
			(xy 355.790861 -53.297592) (xy 355.810638 -53.344426) (xy 355.824009 -53.393475) (xy 355.830735 -53.443866)
			(xy 355.83114 -53.469286) (xy 355.83114 -53.475382) (xy 355.830243 -53.502348) (xy 355.821791 -53.555635)
			(xy 355.805915 -53.6072) (xy 355.782932 -53.656014) (xy 355.7533 -53.701102) (xy 355.717611 -53.741566)
			(xy 355.676578 -53.776598) (xy 355.631017 -53.805498) (xy 355.58184 -53.827691) (xy 355.530026 -53.842734)
			(xy 355.476609 -53.850326) (xy 355.449632 -53.850794) (xy 355.422264 -53.850317) (xy 355.36809 -53.842485)
			(xy 355.315592 -53.82699) (xy 355.265848 -53.804151) (xy 355.219878 -53.774438) (xy 355.198934 -53.756814)
			(xy 355.191822 -53.750718) (xy 355.18344 -53.74767) (xy 355.179153 -53.746145) (xy 355.170209 -53.744474)
			(xy 355.16566 -53.744368) (xy 355.098604 -53.744368) (xy 355.094057 -53.744494) (xy 355.085115 -53.746161)
			(xy 355.080824 -53.74767) (xy 355.072442 -53.750718) (xy 355.06533 -53.756814) (xy 355.044399 -53.774457)
			(xy 354.998433 -53.804186) (xy 354.948686 -53.827032) (xy 354.896183 -53.842526) (xy 354.842003 -53.850348)
			(xy 354.814632 -53.850794) (xy 354.787658 -53.850323) (xy 354.73425 -53.842716) (xy 354.682446 -53.827662)
			(xy 354.633278 -53.805462) (xy 354.587727 -53.776559) (xy 354.546701 -53.741528) (xy 354.511017 -53.701068)
			(xy 354.481387 -53.655986) (xy 354.458403 -53.60718) (xy 354.442521 -53.555624) (xy 354.434059 -53.502344)
			(xy 354.433124 -53.475382) (xy 354.433124 -53.469286) (xy 354.433549 -53.443869) (xy 354.440303 -53.393486)
			(xy 354.453677 -53.344443) (xy 354.473434 -53.297606) (xy 354.485956 -53.275484) (xy 354.489512 -53.269642)
			(xy 354.493068 -53.256434) (xy 354.493068 -53.24983) (xy 354.492862 -53.243248) (xy 354.489525 -53.230514)
			(xy 354.486464 -53.224684) (xy 354.476812 -53.20792) (xy 354.441506 -53.146198) (xy 354.436692 -53.1391)
			(xy 354.423321 -53.128376) (xy 354.40715 -53.122697) (xy 354.39858 -53.122322) (xy 338.016342 -53.122322)
			(xy 338.007985 -53.122705) (xy 337.992176 -53.128148) (xy 337.985354 -53.13299) (xy 337.979004 -53.13807)
			(xy 337.96986 -53.15204) (xy 337.967574 -53.16093) (xy 337.95981 -53.190366) (xy 337.937546 -53.247025)
			(xy 337.907968 -53.300234) (xy 337.871599 -53.349053) (xy 337.82908 -53.392621) (xy 337.781162 -53.43017)
			(xy 337.728691 -53.461036) (xy 337.672591 -53.484675) (xy 337.613852 -53.50067) (xy 337.553512 -53.508738)
			(xy 337.492636 -53.508738) (xy 337.432296 -53.50067) (xy 337.373557 -53.484675) (xy 337.317457 -53.461036)
			(xy 337.264986 -53.43017) (xy 337.217068 -53.392621) (xy 337.174549 -53.349053) (xy 337.13818 -53.300234)
			(xy 337.108602 -53.247025) (xy 337.086338 -53.190366) (xy 337.078574 -53.16093) (xy 337.078574 -53.160676)
			(xy 337.076227 -53.152407) (xy 337.066881 -53.137994) (xy 337.060286 -53.132482) (xy 337.05419 -53.127656)
			(xy 337.038188 -53.122322) (xy 328.984102 -53.122322) (xy 328.976208 -53.122658) (xy 328.961202 -53.127576)
			(xy 328.954638 -53.131974) (xy 328.948288 -53.136292) (xy 328.939144 -53.148738) (xy 328.93635 -53.156612)
			(xy 328.926127 -53.185088) (xy 328.899223 -53.23928) (xy 328.865407 -53.28945) (xy 328.825269 -53.334722)
			(xy 328.779511 -53.374304) (xy 328.754486 -53.391308) (xy 328.745342 -53.39715) (xy 328.739754 -53.405786)
			(xy 328.737074 -53.410113) (xy 328.733351 -53.419585) (xy 328.732388 -53.424582) (xy 328.719688 -53.49875)
			(xy 328.718973 -53.504024) (xy 328.719483 -53.514652) (xy 328.720704 -53.519832) (xy 328.72299 -53.52923)
			(xy 328.729594 -53.537866) (xy 328.744486 -53.55792) (xy 328.769488 -53.601161) (xy 328.788637 -53.647294)
			(xy 328.801604 -53.695531) (xy 328.808169 -53.745048) (xy 328.808588 -53.770022) (xy 328.808588 -53.77053)
			(xy 328.8081 -53.797779) (xy 328.80034 -53.851723) (xy 328.784982 -53.904013) (xy 328.762339 -53.953585)
			(xy 328.732871 -53.99943) (xy 328.697179 -54.040615) (xy 328.65599 -54.076301) (xy 328.610141 -54.105763)
			(xy 328.560566 -54.128399) (xy 328.508274 -54.14375) (xy 328.454329 -54.151503) (xy 328.42708 -54.152038)
			(xy 328.399711 -54.151565) (xy 328.345535 -54.143737) (xy 328.293034 -54.128246) (xy 328.243287 -54.105409)
			(xy 328.197315 -54.075696) (xy 328.176382 -54.058058) (xy 328.16927 -54.051962) (xy 328.160888 -54.048914)
			(xy 328.1566 -54.047395) (xy 328.147656 -54.045735) (xy 328.143108 -54.045612) (xy 328.076052 -54.045612)
			(xy 328.071504 -54.045734) (xy 328.062559 -54.047391) (xy 328.058272 -54.048914) (xy 328.04989 -54.051962)
			(xy 328.042778 -54.058058) (xy 328.021847 -54.0757) (xy 327.975881 -54.105427) (xy 327.926134 -54.12827)
			(xy 327.87363 -54.143759) (xy 327.819451 -54.151575) (xy 327.79208 -54.152038) (xy 327.764829 -54.151551)
			(xy 327.710882 -54.143792) (xy 327.658588 -54.128436) (xy 327.609011 -54.105794) (xy 327.563161 -54.076327)
			(xy 327.521971 -54.040636) (xy 327.486279 -53.999447) (xy 327.456811 -53.953598) (xy 327.434168 -53.904022)
			(xy 327.41881 -53.851728) (xy 327.41105 -53.797781) (xy 327.410572 -53.77053) (xy 327.411104 -53.741613)
			(xy 327.419828 -53.684441) (xy 327.437081 -53.629241) (xy 327.462468 -53.577277) (xy 327.495407 -53.529739)
			(xy 327.535143 -53.487718) (xy 327.557638 -53.46954) (xy 327.565022 -53.463257) (xy 327.574816 -53.446541)
			(xy 327.576688 -53.437028) (xy 327.577196 -53.429408) (xy 327.577196 -53.349652) (xy 327.576688 -53.342032)
			(xy 327.574923 -53.333015) (xy 327.565925 -53.317012) (xy 327.559162 -53.31079) (xy 327.557638 -53.30952)
			(xy 327.538368 -53.294011) (xy 327.503598 -53.258827) (xy 327.473662 -53.219449) (xy 327.449059 -53.176536)
			(xy 327.439274 -53.153818) (xy 327.434956 -53.143404) (xy 327.426828 -53.135784) (xy 327.420224 -53.130704)
			(xy 327.414128 -53.12664) (xy 327.400158 -53.122322) (xy 327.08088 -53.122322) (xy 327.080118 -53.122322)
			(xy 327.070067 -53.122898) (xy 327.051602 -53.130881) (xy 327.044304 -53.137816) (xy 327.03262 -53.15077)
			(xy 327.031604 -53.151786) (xy 327.026983 -53.156706) (xy 327.020292 -53.168422) (xy 327.018396 -53.1749)
			(xy 327.016618 -53.1876) (xy 327.016618 -53.219604) (xy 327.016754 -53.224637) (xy 327.018795 -53.234495)
			(xy 327.020682 -53.239162) (xy 327.03968 -53.257452) (xy 327.073001 -53.298326) (xy 327.100437 -53.343362)
			(xy 327.121475 -53.391718) (xy 327.135723 -53.442492) (xy 327.142914 -53.494735) (xy 327.143364 -53.521102)
			(xy 327.142799 -53.550665) (xy 327.133779 -53.609099) (xy 327.115949 -53.665474) (xy 327.089728 -53.718468)
			(xy 327.05573 -53.766841) (xy 327.035668 -53.788564) (xy 327.032874 -53.79593) (xy 327.032874 -53.87213)
			(xy 327.032995 -53.876678) (xy 327.034651 -53.885624) (xy 327.036176 -53.88991) (xy 327.039224 -53.898292)
			(xy 327.04532 -53.905404) (xy 327.062959 -53.926338) (xy 327.09268 -53.972306) (xy 327.115522 -54.022053)
			(xy 327.131016 -54.074554) (xy 327.138843 -54.128732) (xy 327.138843 -54.183471) (xy 327.131015 -54.237649)
			(xy 327.115521 -54.29015) (xy 327.101729 -54.320186) (xy 329.330304 -54.320186) (xy 329.330761 -54.292815)
			(xy 329.338581 -54.238636) (xy 329.354072 -54.186133) (xy 329.376916 -54.136386) (xy 329.406642 -54.090419)
			(xy 329.424284 -54.069488) (xy 329.424538 -54.069234) (xy 329.430121 -54.062145) (xy 329.436369 -54.04523)
			(xy 329.43673 -54.036214) (xy 329.43673 -53.969158) (xy 329.436339 -53.960145) (xy 329.430114 -53.943228)
			(xy 329.424538 -53.936138) (xy 329.424284 -53.936138) (xy 329.424284 -53.935884) (xy 329.406668 -53.914933)
			(xy 329.376954 -53.868965) (xy 329.354113 -53.819222) (xy 329.338617 -53.766726) (xy 329.330782 -53.712554)
			(xy 329.330304 -53.685186) (xy 329.33079 -53.657935) (xy 329.338546 -53.603987) (xy 329.353901 -53.551692)
			(xy 329.376543 -53.502115) (xy 329.406009 -53.456265) (xy 329.4417 -53.415074) (xy 329.482891 -53.379383)
			(xy 329.528741 -53.349917) (xy 329.578318 -53.327275) (xy 329.630613 -53.31192) (xy 329.684561 -53.304164)
			(xy 329.739063 -53.304164) (xy 329.793011 -53.31192) (xy 329.845306 -53.327275) (xy 329.894883 -53.349917)
			(xy 329.940733 -53.379383) (xy 329.981924 -53.415074) (xy 330.017615 -53.456265) (xy 330.047081 -53.502115)
			(xy 330.069723 -53.551692) (xy 330.085078 -53.603987) (xy 330.092834 -53.657935) (xy 330.09332 -53.685186)
			(xy 330.092865 -53.712557) (xy 330.085048 -53.766737) (xy 330.069557 -53.819241) (xy 330.046712 -53.868988)
			(xy 330.016984 -53.914954) (xy 329.99934 -53.935884) (xy 329.999086 -53.936138) (xy 329.993518 -53.943237)
			(xy 329.98726 -53.960144) (xy 329.986894 -53.969158) (xy 329.986894 -54.036214) (xy 329.987246 -54.045231)
			(xy 329.993497 -54.062148) (xy 329.999086 -54.069234) (xy 329.99934 -54.069234) (xy 329.99934 -54.069488)
			(xy 330.016994 -54.090408) (xy 330.046702 -54.136385) (xy 330.069535 -54.186136) (xy 330.085022 -54.238639)
			(xy 330.092848 -54.292816) (xy 330.09332 -54.320186) (xy 330.092834 -54.347437) (xy 330.085078 -54.401385)
			(xy 330.069723 -54.45368) (xy 330.047081 -54.503257) (xy 330.017615 -54.549107) (xy 329.981924 -54.590298)
			(xy 329.940733 -54.625989) (xy 329.894883 -54.655455) (xy 329.845306 -54.678097) (xy 329.793011 -54.693452)
			(xy 329.739063 -54.701208) (xy 329.684561 -54.701208) (xy 329.630613 -54.693452) (xy 329.578318 -54.678097)
			(xy 329.528741 -54.655455) (xy 329.482891 -54.625989) (xy 329.4417 -54.590298) (xy 329.406009 -54.549107)
			(xy 329.376543 -54.503257) (xy 329.353901 -54.45368) (xy 329.338546 -54.401385) (xy 329.33079 -54.347437)
			(xy 329.330304 -54.320186) (xy 327.101729 -54.320186) (xy 327.092678 -54.339896) (xy 327.062957 -54.385865)
			(xy 327.04532 -54.4068) (xy 327.039224 -54.413912) (xy 327.036176 -54.422294) (xy 327.034648 -54.42658)
			(xy 327.032983 -54.435525) (xy 327.032874 -54.440074) (xy 327.032874 -54.50713) (xy 327.032995 -54.511678)
			(xy 327.034651 -54.520624) (xy 327.036176 -54.52491) (xy 327.039224 -54.533292) (xy 327.04532 -54.540404)
			(xy 327.062961 -54.561336) (xy 327.092685 -54.607303) (xy 327.115526 -54.65705) (xy 327.131015 -54.709553)
			(xy 327.138833 -54.763732) (xy 327.138949 -54.770528) (xy 330.270866 -54.770528) (xy 330.271332 -54.743158)
			(xy 330.279148 -54.688978) (xy 330.294636 -54.636474) (xy 330.317478 -54.586727) (xy 330.347204 -54.540761)
			(xy 330.364846 -54.51983) (xy 330.3651 -54.519576) (xy 330.370703 -54.5125) (xy 330.37694 -54.495575)
			(xy 330.377292 -54.486556) (xy 330.377292 -54.4195) (xy 330.376937 -54.410483) (xy 330.370688 -54.393566)
			(xy 330.3651 -54.38648) (xy 330.364846 -54.38648) (xy 330.364846 -54.386226) (xy 330.347213 -54.365289)
			(xy 330.317498 -54.319318) (xy 330.294661 -54.269572) (xy 330.279168 -54.217072) (xy 330.27134 -54.162897)
			(xy 330.270866 -54.135528) (xy 330.271352 -54.108277) (xy 330.279108 -54.054329) (xy 330.294463 -54.002034)
			(xy 330.317105 -53.952457) (xy 330.346571 -53.906607) (xy 330.382262 -53.865416) (xy 330.423453 -53.829725)
			(xy 330.469303 -53.800259) (xy 330.51888 -53.777617) (xy 330.571175 -53.762262) (xy 330.625123 -53.754506)
			(xy 330.679625 -53.754506) (xy 330.733573 -53.762262) (xy 330.785868 -53.777617) (xy 330.835445 -53.800259)
			(xy 330.881295 -53.829725) (xy 330.922486 -53.865416) (xy 330.958177 -53.906607) (xy 330.987643 -53.952457)
			(xy 331.006405 -53.993538) (xy 334.896696 -53.993538) (xy 334.896696 -53.933602) (xy 334.904519 -53.87418)
			(xy 334.920032 -53.816287) (xy 334.942968 -53.760914) (xy 334.972935 -53.709008) (xy 335.009422 -53.661458)
			(xy 335.051802 -53.619078) (xy 335.099352 -53.582591) (xy 335.151258 -53.552624) (xy 335.206631 -53.529688)
			(xy 335.264524 -53.514175) (xy 335.323946 -53.506352) (xy 335.383882 -53.506352) (xy 335.443304 -53.514175)
			(xy 335.501197 -53.529688) (xy 335.55657 -53.552624) (xy 335.608476 -53.582591) (xy 335.656026 -53.619078)
			(xy 335.698406 -53.661458) (xy 335.734893 -53.709008) (xy 335.76486 -53.760914) (xy 335.787796 -53.816287)
			(xy 335.803309 -53.87418) (xy 335.811132 -53.933602) (xy 335.811622 -53.96357) (xy 335.811132 -53.993538)
			(xy 335.803309 -54.05296) (xy 335.799425 -54.067456) (xy 337.141056 -54.067456) (xy 337.145127 -54.011834)
			(xy 337.157253 -53.957397) (xy 337.177176 -53.905306) (xy 337.204472 -53.856671) (xy 337.238558 -53.812528)
			(xy 337.278707 -53.773819) (xy 337.324065 -53.741368) (xy 337.373665 -53.715867) (xy 337.426449 -53.69786)
			(xy 337.481292 -53.68773) (xy 337.537026 -53.685693) (xy 337.592463 -53.691793) (xy 337.64642 -53.705899)
			(xy 337.697749 -53.727711) (xy 337.745355 -53.756765) (xy 337.788223 -53.79244) (xy 337.82544 -53.833977)
			(xy 337.856213 -53.88049) (xy 337.879885 -53.930987) (xy 337.895953 -53.984394) (xy 337.904073 -54.03957)
			(xy 337.904582 -54.067456) (xy 337.904073 -54.095342) (xy 337.895953 -54.150518) (xy 337.879885 -54.203925)
			(xy 337.863487 -54.238906) (xy 356.686102 -54.238906) (xy 356.690173 -54.183284) (xy 356.702299 -54.128847)
			(xy 356.722222 -54.076756) (xy 356.749518 -54.028121) (xy 356.783604 -53.983978) (xy 356.823753 -53.945269)
			(xy 356.869111 -53.912818) (xy 356.918711 -53.887317) (xy 356.971495 -53.86931) (xy 357.026338 -53.85918)
			(xy 357.082072 -53.857143) (xy 357.137509 -53.863243) (xy 357.191466 -53.877349) (xy 357.242795 -53.899161)
			(xy 357.290401 -53.928215) (xy 357.333269 -53.96389) (xy 357.370486 -54.005427) (xy 357.401259 -54.05194)
			(xy 357.424931 -54.102437) (xy 357.440999 -54.155844) (xy 357.449119 -54.21102) (xy 357.449628 -54.238906)
			(xy 357.449119 -54.266792) (xy 357.440999 -54.321968) (xy 357.424931 -54.375375) (xy 357.401259 -54.425872)
			(xy 357.370486 -54.472385) (xy 357.333269 -54.513922) (xy 357.290401 -54.549597) (xy 357.242795 -54.578651)
			(xy 357.191466 -54.600463) (xy 357.137509 -54.614569) (xy 357.082072 -54.620669) (xy 357.026338 -54.618632)
			(xy 356.971495 -54.608502) (xy 356.918711 -54.590495) (xy 356.869111 -54.564994) (xy 356.823753 -54.532543)
			(xy 356.783604 -54.493834) (xy 356.749518 -54.449691) (xy 356.722222 -54.401056) (xy 356.702299 -54.348965)
			(xy 356.690173 -54.294528) (xy 356.686102 -54.238906) (xy 337.863487 -54.238906) (xy 337.856213 -54.254422)
			(xy 337.82544 -54.300935) (xy 337.788223 -54.342472) (xy 337.745355 -54.378147) (xy 337.697749 -54.407201)
			(xy 337.64642 -54.429013) (xy 337.592463 -54.443119) (xy 337.537026 -54.449219) (xy 337.481292 -54.447182)
			(xy 337.426449 -54.437052) (xy 337.373665 -54.419045) (xy 337.324065 -54.393544) (xy 337.278707 -54.361093)
			(xy 337.238558 -54.322384) (xy 337.204472 -54.278241) (xy 337.177176 -54.229606) (xy 337.157253 -54.177515)
			(xy 337.145127 -54.123078) (xy 337.141056 -54.067456) (xy 335.799425 -54.067456) (xy 335.787796 -54.110853)
			(xy 335.76486 -54.166226) (xy 335.734893 -54.218132) (xy 335.698406 -54.265682) (xy 335.656026 -54.308062)
			(xy 335.608476 -54.344549) (xy 335.55657 -54.374516) (xy 335.501197 -54.397452) (xy 335.443304 -54.412965)
			(xy 335.383882 -54.420788) (xy 335.323946 -54.420788) (xy 335.264524 -54.412965) (xy 335.206631 -54.397452)
			(xy 335.151258 -54.374516) (xy 335.099352 -54.344549) (xy 335.051802 -54.308062) (xy 335.009422 -54.265682)
			(xy 334.972935 -54.218132) (xy 334.942968 -54.166226) (xy 334.920032 -54.110853) (xy 334.904519 -54.05296)
			(xy 334.896696 -53.993538) (xy 331.006405 -53.993538) (xy 331.010285 -54.002034) (xy 331.02564 -54.054329)
			(xy 331.033396 -54.108277) (xy 331.033882 -54.135528) (xy 331.033437 -54.162899) (xy 331.025615 -54.217079)
			(xy 331.010121 -54.269583) (xy 330.987274 -54.319329) (xy 330.957545 -54.365295) (xy 330.939902 -54.386226)
			(xy 330.939648 -54.38648) (xy 330.934057 -54.393564) (xy 330.927814 -54.410483) (xy 330.927456 -54.4195)
			(xy 330.927456 -54.486556) (xy 330.927822 -54.495572) (xy 330.934062 -54.51249) (xy 330.939648 -54.519576)
			(xy 330.939902 -54.519576) (xy 330.939902 -54.51983) (xy 330.957522 -54.540777) (xy 330.987237 -54.586746)
			(xy 331.010076 -54.63649) (xy 331.025572 -54.688987) (xy 331.033405 -54.74316) (xy 331.033882 -54.770528)
			(xy 331.033396 -54.797779) (xy 331.02564 -54.851727) (xy 331.010285 -54.904022) (xy 330.987643 -54.953599)
			(xy 330.958177 -54.999449) (xy 330.922486 -55.04064) (xy 330.881295 -55.076331) (xy 330.870208 -55.083456)
			(xy 337.141056 -55.083456) (xy 337.145127 -55.027834) (xy 337.157253 -54.973397) (xy 337.177176 -54.921306)
			(xy 337.204472 -54.872671) (xy 337.238558 -54.828528) (xy 337.278707 -54.789819) (xy 337.324065 -54.757368)
			(xy 337.373665 -54.731867) (xy 337.426449 -54.71386) (xy 337.481292 -54.70373) (xy 337.537026 -54.701693)
			(xy 337.592463 -54.707793) (xy 337.64642 -54.721899) (xy 337.697749 -54.743711) (xy 337.745355 -54.772765)
			(xy 337.788223 -54.80844) (xy 337.82544 -54.849977) (xy 337.856213 -54.89649) (xy 337.879885 -54.946987)
			(xy 337.895953 -55.000394) (xy 337.904073 -55.05557) (xy 337.904582 -55.083456) (xy 337.904073 -55.111342)
			(xy 337.895953 -55.166518) (xy 337.879885 -55.219925) (xy 337.856213 -55.270422) (xy 337.82544 -55.316935)
			(xy 337.788223 -55.358472) (xy 337.745355 -55.394147) (xy 337.697749 -55.423201) (xy 337.696878 -55.423571)
			(xy 350.448551 -55.423571) (xy 350.448551 -55.363629) (xy 350.456375 -55.304201) (xy 350.47189 -55.246302)
			(xy 350.494829 -55.190923) (xy 350.524801 -55.139013) (xy 350.561292 -55.091459) (xy 350.603679 -55.049075)
			(xy 350.651235 -55.012587) (xy 350.703147 -54.982618) (xy 350.758526 -54.959682) (xy 350.816426 -54.94417)
			(xy 350.875855 -54.936349) (xy 350.905826 -54.935882) (xy 350.90608 -54.935882) (xy 350.937605 -54.936408)
			(xy 351.000056 -54.945082) (xy 351.060727 -54.962243) (xy 351.118469 -54.987565) (xy 351.120894 -54.989055)
			(xy 352.201145 -54.989055) (xy 352.201145 -54.934545) (xy 352.208903 -54.880591) (xy 352.224261 -54.828289)
			(xy 352.246906 -54.778706) (xy 352.276377 -54.73285) (xy 352.312074 -54.691656) (xy 352.353271 -54.655961)
			(xy 352.399129 -54.626493) (xy 352.448714 -54.603851) (xy 352.501016 -54.588497) (xy 352.554971 -54.580743)
			(xy 352.582226 -54.580282) (xy 352.610318 -54.580756) (xy 352.665896 -54.588987) (xy 352.719666 -54.605282)
			(xy 352.770463 -54.629288) (xy 352.81719 -54.660486) (xy 352.858835 -54.698201) (xy 352.894496 -54.741616)
			(xy 352.909378 -54.765448) (xy 352.914712 -54.774338) (xy 352.93173 -54.78653) (xy 353.024948 -54.80685)
			(xy 353.045522 -54.802532) (xy 353.054158 -54.79669) (xy 353.078231 -54.780705) (xy 353.130159 -54.755359)
			(xy 353.185314 -54.738129) (xy 353.242436 -54.729409) (xy 353.271328 -54.728872) (xy 353.298579 -54.729352)
			(xy 353.352526 -54.737112) (xy 353.40482 -54.752469) (xy 353.454396 -54.775112) (xy 353.500245 -54.804579)
			(xy 353.541434 -54.840271) (xy 353.577125 -54.881462) (xy 353.606592 -54.927311) (xy 353.629234 -54.976888)
			(xy 353.64459 -55.029182) (xy 353.652349 -55.083129) (xy 353.652836 -55.11038) (xy 353.652374 -55.137751)
			(xy 353.644557 -55.19193) (xy 353.629068 -55.244434) (xy 353.606225 -55.294181) (xy 353.576499 -55.340147)
			(xy 353.558856 -55.361078) (xy 353.558602 -55.361332) (xy 353.553038 -55.368434) (xy 353.546778 -55.385339)
			(xy 353.54641 -55.394352) (xy 353.54641 -55.461408) (xy 353.546761 -55.470426) (xy 353.553012 -55.487343)
			(xy 353.558602 -55.494428) (xy 353.558856 -55.494428) (xy 353.558856 -55.494682) (xy 353.576478 -55.51563)
			(xy 353.606205 -55.561595) (xy 353.629052 -55.611339) (xy 353.644551 -55.663838) (xy 353.652382 -55.718015)
			(xy 353.652384 -55.772755) (xy 353.644557 -55.826932) (xy 353.629063 -55.879433) (xy 353.606219 -55.929179)
			(xy 353.576496 -55.975146) (xy 353.558856 -55.996078) (xy 353.558602 -55.996332) (xy 353.553038 -56.003434)
			(xy 353.546778 -56.020339) (xy 353.54641 -56.029352) (xy 353.54641 -56.096408) (xy 353.546761 -56.105426)
			(xy 353.553012 -56.122343) (xy 353.558602 -56.129428) (xy 353.558856 -56.129428) (xy 353.558856 -56.129682)
			(xy 353.576493 -56.150616) (xy 353.606207 -56.196587) (xy 353.629044 -56.246334) (xy 353.644535 -56.298835)
			(xy 353.652363 -56.353011) (xy 353.652836 -56.38038) (xy 353.65235 -56.407631) (xy 353.644594 -56.461579)
			(xy 353.629239 -56.513874) (xy 353.606597 -56.563451) (xy 353.577131 -56.609301) (xy 353.54144 -56.650492)
			(xy 353.500249 -56.686183) (xy 353.454399 -56.715649) (xy 353.404822 -56.738291) (xy 353.352527 -56.753646)
			(xy 353.298579 -56.761402) (xy 353.244077 -56.761402) (xy 353.190129 -56.753646) (xy 353.137834 -56.738291)
			(xy 353.088257 -56.715649) (xy 353.042407 -56.686183) (xy 353.001216 -56.650492) (xy 352.965525 -56.609301)
			(xy 352.936059 -56.563451) (xy 352.913417 -56.513874) (xy 352.898062 -56.461579) (xy 352.890306 -56.407631)
			(xy 352.88982 -56.38038) (xy 352.890269 -56.353009) (xy 352.898091 -56.298829) (xy 352.913583 -56.246326)
			(xy 352.936429 -56.196579) (xy 352.966157 -56.150613) (xy 352.9838 -56.129682) (xy 352.984054 -56.129428)
			(xy 352.989641 -56.122342) (xy 352.995886 -56.105425) (xy 352.996246 -56.096408) (xy 352.996246 -56.029352)
			(xy 352.995876 -56.020336) (xy 352.989639 -56.003418) (xy 352.984054 -55.996332) (xy 352.9838 -55.996332)
			(xy 352.9838 -55.996078) (xy 352.966141 -55.975161) (xy 352.936419 -55.929189) (xy 352.913576 -55.879441)
			(xy 352.898083 -55.826936) (xy 352.890257 -55.772756) (xy 352.890259 -55.718014) (xy 352.898089 -55.663834)
			(xy 352.913587 -55.611331) (xy 352.936433 -55.561584) (xy 352.966159 -55.515615) (xy 352.9838 -55.494682)
			(xy 352.984054 -55.494428) (xy 352.989641 -55.487342) (xy 352.995886 -55.470425) (xy 352.996246 -55.461408)
			(xy 352.996246 -55.394352) (xy 352.995876 -55.385336) (xy 352.989639 -55.368418) (xy 352.984054 -55.361332)
			(xy 352.9838 -55.360824) (xy 352.972856 -55.348089) (xy 352.953015 -55.320998) (xy 352.944176 -55.306722)
			(xy 352.938842 -55.297832) (xy 352.921824 -55.28564) (xy 352.828606 -55.26532) (xy 352.808032 -55.269638)
			(xy 352.799396 -55.27548) (xy 352.775333 -55.291482) (xy 352.723402 -55.316825) (xy 352.668243 -55.33405)
			(xy 352.611119 -55.342764) (xy 352.582226 -55.343298) (xy 352.554971 -55.342857) (xy 352.501016 -55.335103)
			(xy 352.448714 -55.319749) (xy 352.399129 -55.297107) (xy 352.353271 -55.267639) (xy 352.312074 -55.231944)
			(xy 352.276377 -55.19075) (xy 352.246906 -55.144894) (xy 352.224261 -55.095311) (xy 352.208903 -55.043009)
			(xy 352.201145 -54.989055) (xy 351.120894 -54.989055) (xy 351.172192 -55.020569) (xy 351.220878 -55.060631)
			(xy 351.24263 -55.083456) (xy 351.249234 -55.090568) (xy 351.266252 -55.09895) (xy 351.344738 -55.1053)
			(xy 351.354304 -55.105684) (xy 351.372588 -55.100054) (xy 351.380298 -55.094378) (xy 351.400605 -55.078873)
			(xy 351.444548 -55.052809) (xy 351.491576 -55.032839) (xy 351.540846 -55.019321) (xy 351.59148 -55.012496)
			(xy 351.617026 -55.012082) (xy 351.644275 -55.01259) (xy 351.698219 -55.020349) (xy 351.750509 -55.035706)
			(xy 351.800082 -55.058348) (xy 351.845927 -55.087814) (xy 351.887113 -55.123505) (xy 351.922801 -55.164693)
			(xy 351.952264 -55.210541) (xy 351.974903 -55.260115) (xy 351.990256 -55.312407) (xy 351.998012 -55.366351)
			(xy 351.998012 -55.420849) (xy 351.990256 -55.474793) (xy 351.974903 -55.527085) (xy 351.952264 -55.576659)
			(xy 351.922801 -55.622507) (xy 351.887113 -55.663695) (xy 351.845927 -55.699386) (xy 351.800082 -55.728852)
			(xy 351.750509 -55.751494) (xy 351.698219 -55.766851) (xy 351.644275 -55.77461) (xy 351.617026 -55.775098)
			(xy 351.591478 -55.774689) (xy 351.540839 -55.767882) (xy 351.491562 -55.754373) (xy 351.44453 -55.734404)
			(xy 351.400587 -55.708333) (xy 351.380298 -55.692802) (xy 351.372573 -55.687164) (xy 351.354297 -55.681564)
			(xy 351.344738 -55.68188) (xy 351.266252 -55.68823) (xy 351.249234 -55.696612) (xy 351.24263 -55.703724)
			(xy 351.220864 -55.726537) (xy 351.172192 -55.766619) (xy 351.118476 -55.799635) (xy 351.060734 -55.82496)
			(xy 351.00006 -55.842114) (xy 350.937606 -55.850771) (xy 350.90608 -55.851298) (xy 350.905826 -55.851298)
			(xy 350.875855 -55.850851) (xy 350.816426 -55.84303) (xy 350.758526 -55.827518) (xy 350.703147 -55.804582)
			(xy 350.651235 -55.774613) (xy 350.603679 -55.738125) (xy 350.561292 -55.695741) (xy 350.524801 -55.648187)
			(xy 350.494829 -55.596277) (xy 350.47189 -55.540898) (xy 350.456375 -55.482999) (xy 350.448551 -55.423571)
			(xy 337.696878 -55.423571) (xy 337.64642 -55.445013) (xy 337.592463 -55.459119) (xy 337.537026 -55.465219)
			(xy 337.481292 -55.463182) (xy 337.426449 -55.453052) (xy 337.373665 -55.435045) (xy 337.324065 -55.409544)
			(xy 337.278707 -55.377093) (xy 337.238558 -55.338384) (xy 337.204472 -55.294241) (xy 337.177176 -55.245606)
			(xy 337.157253 -55.193515) (xy 337.145127 -55.139078) (xy 337.141056 -55.083456) (xy 330.870208 -55.083456)
			(xy 330.835445 -55.105797) (xy 330.785868 -55.128439) (xy 330.733573 -55.143794) (xy 330.679625 -55.15155)
			(xy 330.625123 -55.15155) (xy 330.571175 -55.143794) (xy 330.51888 -55.128439) (xy 330.469303 -55.105797)
			(xy 330.423453 -55.076331) (xy 330.382262 -55.04064) (xy 330.346571 -54.999449) (xy 330.317105 -54.953599)
			(xy 330.294463 -54.904022) (xy 330.279108 -54.851727) (xy 330.271352 -54.797779) (xy 330.270866 -54.770528)
			(xy 327.138949 -54.770528) (xy 327.1393 -54.791102) (xy 327.138814 -54.818353) (xy 327.131058 -54.872301)
			(xy 327.115703 -54.924596) (xy 327.093061 -54.974173) (xy 327.063595 -55.020023) (xy 327.027904 -55.061214)
			(xy 326.986713 -55.096905) (xy 326.940863 -55.126371) (xy 326.891286 -55.149013) (xy 326.838991 -55.164368)
			(xy 326.785043 -55.172124) (xy 326.730541 -55.172124) (xy 326.676593 -55.164368) (xy 326.624298 -55.149013)
			(xy 326.574721 -55.126371) (xy 326.528871 -55.096905) (xy 326.48768 -55.061214) (xy 326.451989 -55.020023)
			(xy 326.422523 -54.974173) (xy 326.399881 -54.924596) (xy 326.384526 -54.872301) (xy 326.37677 -54.818353)
			(xy 326.376284 -54.791102) (xy 326.376756 -54.763732) (xy 326.384579 -54.709553) (xy 326.400065 -54.657049)
			(xy 326.422896 -54.607297) (xy 326.452604 -54.561319) (xy 326.470264 -54.540404) (xy 326.47636 -54.533292)
			(xy 326.479408 -54.52491) (xy 326.480937 -54.520624) (xy 326.482603 -54.511679) (xy 326.48271 -54.50713)
			(xy 326.48271 -54.440074) (xy 326.48259 -54.435526) (xy 326.480937 -54.426579) (xy 326.479408 -54.422294)
			(xy 326.47636 -54.413912) (xy 326.470264 -54.4068) (xy 326.452622 -54.385868) (xy 326.422894 -54.339901)
			(xy 326.400046 -54.290155) (xy 326.384548 -54.237652) (xy 326.376718 -54.183473) (xy 326.376718 -54.12873)
			(xy 326.384547 -54.074551) (xy 326.400045 -54.022048) (xy 326.422892 -53.972302) (xy 326.45262 -53.926334)
			(xy 326.470264 -53.905404) (xy 326.47636 -53.898292) (xy 326.479408 -53.88991) (xy 326.480937 -53.885624)
			(xy 326.482603 -53.876679) (xy 326.48271 -53.87213) (xy 326.48271 -53.79593) (xy 326.479916 -53.788564)
			(xy 326.459844 -53.766853) (xy 326.425866 -53.718468) (xy 326.399658 -53.665469) (xy 326.381833 -53.609096)
			(xy 326.372807 -53.550664) (xy 326.37222 -53.521102) (xy 326.372653 -53.494703) (xy 326.379861 -53.4424)
			(xy 326.394141 -53.39157) (xy 326.415226 -53.343166) (xy 326.442722 -53.298093) (xy 326.476113 -53.257195)
			(xy 326.495156 -53.238908) (xy 326.496912 -53.234341) (xy 326.498833 -53.224749) (xy 326.498966 -53.219858)
			(xy 326.498966 -53.187854) (xy 326.498204 -53.17871) (xy 326.497188 -53.1749) (xy 326.495295 -53.168421)
			(xy 326.488604 -53.156703) (xy 326.48398 -53.151786) (xy 326.482964 -53.15077) (xy 326.47128 -53.137816)
			(xy 326.463991 -53.130863) (xy 326.445524 -53.122858) (xy 326.435466 -53.122322) (xy 324.522592 -53.122322)
			(xy 324.513783 -53.122741) (xy 324.49723 -53.128785) (xy 324.483685 -53.140058) (xy 324.478904 -53.147468)
			(xy 324.434454 -53.22316) (xy 324.431288 -53.229097) (xy 324.427818 -53.24209) (xy 324.427596 -53.248814)
			(xy 324.427596 -53.262022) (xy 324.429374 -53.265324) (xy 324.4342 -53.273706) (xy 324.445896 -53.295242)
			(xy 324.464314 -53.340657) (xy 324.476774 -53.388053) (xy 324.483072 -53.436655) (xy 324.483476 -53.461158)
			(xy 324.483476 -53.461412) (xy 324.483003 -53.488782) (xy 324.475178 -53.542959) (xy 324.459688 -53.595461)
			(xy 324.436854 -53.64521) (xy 324.407143 -53.691184) (xy 324.389496 -53.71211) (xy 324.3834 -53.719222)
			(xy 324.380352 -53.727604) (xy 324.378831 -53.731892) (xy 324.377169 -53.740836) (xy 324.37705 -53.745384)
			(xy 324.37705 -53.81244) (xy 324.377171 -53.816988) (xy 324.378828 -53.825933) (xy 324.380352 -53.83022)
			(xy 324.3834 -53.838602) (xy 324.389496 -53.845714) (xy 324.407135 -53.866647) (xy 324.436856 -53.912615)
			(xy 324.459699 -53.962361) (xy 324.475192 -54.014862) (xy 324.483019 -54.069039) (xy 324.483018 -54.123779)
			(xy 324.475188 -54.177956) (xy 324.459692 -54.230456) (xy 324.436848 -54.280201) (xy 324.407124 -54.326167)
			(xy 324.389496 -54.34711) (xy 324.3834 -54.354222) (xy 324.380352 -54.362604) (xy 324.378831 -54.366892)
			(xy 324.377169 -54.375836) (xy 324.37705 -54.380384) (xy 324.37705 -54.44744) (xy 324.377171 -54.451988)
			(xy 324.378828 -54.460933) (xy 324.380352 -54.46522) (xy 324.3834 -54.473602) (xy 324.389496 -54.480714)
			(xy 324.407137 -54.501646) (xy 324.436862 -54.547612) (xy 324.459704 -54.597359) (xy 324.475192 -54.649862)
			(xy 324.483009 -54.704042) (xy 324.483476 -54.731412) (xy 324.48299 -54.758663) (xy 324.475234 -54.812611)
			(xy 324.459879 -54.864906) (xy 324.437237 -54.914483) (xy 324.407771 -54.960333) (xy 324.37208 -55.001524)
			(xy 324.330889 -55.037215) (xy 324.285039 -55.066681) (xy 324.235462 -55.089323) (xy 324.183167 -55.104678)
			(xy 324.129219 -55.112434) (xy 324.074717 -55.112434) (xy 324.020769 -55.104678) (xy 323.968474 -55.089323)
			(xy 323.918897 -55.066681) (xy 323.873047 -55.037215) (xy 323.831856 -55.001524) (xy 323.796165 -54.960333)
			(xy 323.766699 -54.914483) (xy 323.744057 -54.864906) (xy 323.728702 -54.812611) (xy 323.720946 -54.758663)
			(xy 323.72046 -54.731412) (xy 323.720938 -54.704045) (xy 323.728774 -54.649873) (xy 323.744273 -54.597378)
			(xy 323.767116 -54.547638) (xy 323.796834 -54.501673) (xy 323.81444 -54.480714) (xy 323.820536 -54.473602)
			(xy 323.823584 -54.46522) (xy 323.825106 -54.460932) (xy 323.826771 -54.451988) (xy 323.826886 -54.44744)
			(xy 323.826886 -54.380384) (xy 323.826758 -54.375837) (xy 323.82509 -54.366896) (xy 323.823584 -54.362604)
			(xy 323.820536 -54.354222) (xy 323.81444 -54.34711) (xy 323.796798 -54.326177) (xy 323.76707 -54.28021)
			(xy 323.744223 -54.230463) (xy 323.728724 -54.17796) (xy 323.720894 -54.12378) (xy 323.720893 -54.069038)
			(xy 323.72872 -54.014858) (xy 323.744216 -53.962354) (xy 323.767062 -53.912606) (xy 323.796787 -53.866637)
			(xy 323.81444 -53.845714) (xy 323.820536 -53.838602) (xy 323.823584 -53.83022) (xy 323.825106 -53.825932)
			(xy 323.826771 -53.816988) (xy 323.826886 -53.81244) (xy 323.826886 -53.745384) (xy 323.826758 -53.740837)
			(xy 323.82509 -53.731896) (xy 323.823584 -53.727604) (xy 323.820536 -53.719222) (xy 323.81444 -53.71211)
			(xy 323.796796 -53.69118) (xy 323.767065 -53.645214) (xy 323.744219 -53.595468) (xy 323.728725 -53.542964)
			(xy 323.720904 -53.488783) (xy 323.72046 -53.461412) (xy 323.72046 -53.461158) (xy 323.720836 -53.436652)
			(xy 323.727116 -53.388045) (xy 323.739581 -53.340644) (xy 323.758023 -53.295235) (xy 323.769736 -53.273706)
			(xy 323.774562 -53.265324) (xy 323.77634 -53.262022) (xy 323.77634 -53.248814) (xy 323.776166 -53.242083)
			(xy 323.772684 -53.229083) (xy 323.769482 -53.22316) (xy 323.725032 -53.147468) (xy 323.720271 -53.140035)
			(xy 323.70674 -53.128722) (xy 323.690163 -53.122697) (xy 323.681344 -53.122322) (xy 317.76543 -53.122322)
			(xy 317.756868 -53.122705) (xy 317.740726 -53.128431) (xy 317.727349 -53.139128) (xy 317.722504 -53.146198)
			(xy 317.687198 -53.20792) (xy 317.677546 -53.224684) (xy 317.674452 -53.230501) (xy 317.671115 -53.243243)
			(xy 317.670942 -53.24983) (xy 317.670942 -53.263546) (xy 317.678054 -53.275484) (xy 317.690608 -53.297591)
			(xy 317.710389 -53.344425) (xy 317.723761 -53.393474) (xy 317.730488 -53.443866) (xy 317.730886 -53.469286)
			(xy 317.730886 -53.475382) (xy 317.729989 -53.502347) (xy 317.721536 -53.555631) (xy 317.70566 -53.607193)
			(xy 317.682676 -53.656003) (xy 317.653043 -53.701087) (xy 317.617354 -53.741547) (xy 317.57632 -53.776573)
			(xy 317.530759 -53.805468) (xy 317.481582 -53.827655) (xy 317.429768 -53.842691) (xy 317.376354 -53.850276)
			(xy 317.349378 -53.850794) (xy 317.322009 -53.850321) (xy 317.267832 -53.842494) (xy 317.21533 -53.827004)
			(xy 317.165581 -53.80417) (xy 317.119607 -53.774459) (xy 317.09868 -53.756814) (xy 317.091568 -53.750718)
			(xy 317.083186 -53.74767) (xy 317.0789 -53.746144) (xy 317.069955 -53.744482) (xy 317.065406 -53.744368)
			(xy 316.99835 -53.744368) (xy 316.993802 -53.74449) (xy 316.984858 -53.746149) (xy 316.98057 -53.74767)
			(xy 316.972188 -53.750718) (xy 316.965076 -53.756814) (xy 316.944144 -53.774454) (xy 316.898177 -53.804176)
			(xy 316.84843 -53.827015) (xy 316.795926 -53.842502) (xy 316.741748 -53.850316) (xy 316.714378 -53.850794)
			(xy 316.687402 -53.850326) (xy 316.633989 -53.842724) (xy 316.582179 -53.827675) (xy 316.533006 -53.805477)
			(xy 316.487449 -53.776575) (xy 316.446417 -53.741544) (xy 316.410729 -53.701084) (xy 316.381095 -53.655999)
			(xy 316.358107 -53.60719) (xy 316.342223 -53.55563) (xy 316.333759 -53.502347) (xy 316.33287 -53.475382)
			(xy 316.33287 -53.469286) (xy 316.333295 -53.443869) (xy 316.340048 -53.393486) (xy 316.35342 -53.344442)
			(xy 316.373175 -53.297604) (xy 316.385702 -53.275484) (xy 316.389258 -53.269642) (xy 316.392814 -53.256434)
			(xy 316.392814 -53.24983) (xy 316.392607 -53.243248) (xy 316.389268 -53.230515) (xy 316.38621 -53.224684)
			(xy 316.376558 -53.20792) (xy 316.341252 -53.146198) (xy 316.33644 -53.139095) (xy 316.323071 -53.12836)
			(xy 316.306899 -53.122665) (xy 316.298326 -53.122322) (xy 312.016394 -53.122322) (xy 312.008034 -53.122697)
			(xy 311.992215 -53.128127) (xy 311.985406 -53.13299) (xy 311.979056 -53.13807) (xy 311.969912 -53.15204)
			(xy 311.967626 -53.16093) (xy 311.959862 -53.190366) (xy 311.937598 -53.247025) (xy 311.90802 -53.300234)
			(xy 311.871651 -53.349053) (xy 311.829132 -53.392621) (xy 311.781214 -53.43017) (xy 311.728743 -53.461036)
			(xy 311.672643 -53.484675) (xy 311.613904 -53.50067) (xy 311.553564 -53.508738) (xy 311.492688 -53.508738)
			(xy 311.432348 -53.50067) (xy 311.373609 -53.484675) (xy 311.317509 -53.461036) (xy 311.265038 -53.43017)
			(xy 311.21712 -53.392621) (xy 311.174601 -53.349053) (xy 311.138232 -53.300234) (xy 311.108654 -53.247025)
			(xy 311.08639 -53.190366) (xy 311.078626 -53.16093) (xy 311.078626 -53.160676) (xy 311.076282 -53.152405)
			(xy 311.066942 -53.137985) (xy 311.060338 -53.132482) (xy 311.054242 -53.127656) (xy 311.03824 -53.122322)
			(xy 302.984154 -53.122322) (xy 302.976257 -53.12265) (xy 302.961242 -53.127555) (xy 302.95469 -53.131974)
			(xy 302.94834 -53.136292) (xy 302.939196 -53.148738) (xy 302.936402 -53.156612) (xy 302.926178 -53.185087)
			(xy 302.899272 -53.239277) (xy 302.865454 -53.289444) (xy 302.825314 -53.334712) (xy 302.779553 -53.37429)
			(xy 302.754538 -53.391308) (xy 302.745394 -53.39715) (xy 302.739806 -53.405786) (xy 302.737128 -53.410114)
			(xy 302.733409 -53.419586) (xy 302.73244 -53.424582) (xy 302.71974 -53.49875) (xy 302.719025 -53.504024)
			(xy 302.719535 -53.514652) (xy 302.720756 -53.519832) (xy 302.723042 -53.52923) (xy 302.729646 -53.537866)
			(xy 302.744536 -53.55792) (xy 302.769535 -53.601163) (xy 302.788681 -53.647296) (xy 302.801646 -53.695533)
			(xy 302.80821 -53.745048) (xy 302.80864 -53.770022) (xy 302.80864 -53.77053) (xy 302.808152 -53.797781)
			(xy 302.800392 -53.851727) (xy 302.785035 -53.90402) (xy 302.762393 -53.953595) (xy 302.732926 -53.999444)
			(xy 302.697235 -54.040634) (xy 302.656046 -54.076325) (xy 302.610197 -54.105792) (xy 302.560622 -54.128434)
			(xy 302.508329 -54.143792) (xy 302.454383 -54.151552) (xy 302.427132 -54.152038) (xy 302.399764 -54.151561)
			(xy 302.345591 -54.143728) (xy 302.293095 -54.128231) (xy 302.243352 -54.10539) (xy 302.197386 -54.075673)
			(xy 302.176434 -54.058058) (xy 302.169322 -54.051962) (xy 302.16094 -54.048914) (xy 302.156652 -54.04739)
			(xy 302.147709 -54.045722) (xy 302.14316 -54.045612) (xy 302.076104 -54.045612) (xy 302.071557 -54.045738)
			(xy 302.062615 -54.047403) (xy 302.058324 -54.048914) (xy 302.049942 -54.051962) (xy 302.04283 -54.058058)
			(xy 302.0219 -54.075703) (xy 301.975935 -54.105436) (xy 301.926189 -54.128286) (xy 301.873685 -54.143782)
			(xy 301.819504 -54.151606) (xy 301.792132 -54.152038) (xy 301.764877 -54.151577) (xy 301.710921 -54.143824)
			(xy 301.658617 -54.128471) (xy 301.609031 -54.105831) (xy 301.563172 -54.076364) (xy 301.521973 -54.040671)
			(xy 301.486273 -53.999478) (xy 301.456799 -53.953623) (xy 301.43415 -53.904041) (xy 301.418789 -53.85174)
			(xy 301.411027 -53.797785) (xy 301.410624 -53.77053) (xy 301.411156 -53.741613) (xy 301.419879 -53.684439)
			(xy 301.437131 -53.629238) (xy 301.462516 -53.577271) (xy 301.495452 -53.529731) (xy 301.535185 -53.487706)
			(xy 301.55769 -53.46954) (xy 301.565068 -53.463253) (xy 301.574852 -53.446537) (xy 301.57674 -53.437028)
			(xy 301.577248 -53.429408) (xy 301.577248 -53.349652) (xy 301.57674 -53.342032) (xy 301.574978 -53.333013)
			(xy 301.565985 -53.317004) (xy 301.559214 -53.31079) (xy 301.55769 -53.30952) (xy 301.538418 -53.294013)
			(xy 301.503644 -53.258831) (xy 301.473704 -53.219455) (xy 301.449097 -53.176542) (xy 301.439326 -53.153818)
			(xy 301.435008 -53.143404) (xy 301.42688 -53.135784) (xy 301.420276 -53.130704) (xy 301.41418 -53.12664)
			(xy 301.40021 -53.122322) (xy 301.080932 -53.122322) (xy 301.08017 -53.122322) (xy 301.070138 -53.122975)
			(xy 301.05171 -53.130959) (xy 301.044356 -53.137816) (xy 301.032672 -53.15077) (xy 301.031656 -53.151786)
			(xy 301.027039 -53.156708) (xy 301.020354 -53.168425) (xy 301.018448 -53.1749) (xy 301.01667 -53.1876)
			(xy 301.01667 -53.219604) (xy 301.016806 -53.224637) (xy 301.018845 -53.234495) (xy 301.020734 -53.239162)
			(xy 301.039734 -53.257451) (xy 301.073059 -53.298323) (xy 301.100498 -53.343359) (xy 301.121539 -53.391716)
			(xy 301.135789 -53.44249) (xy 301.142981 -53.494734) (xy 301.143416 -53.521102) (xy 301.142851 -53.550666)
			(xy 301.133832 -53.609101) (xy 301.116004 -53.665476) (xy 301.089786 -53.718473) (xy 301.05579 -53.766849)
			(xy 301.03572 -53.788564) (xy 301.032926 -53.79593) (xy 301.032926 -53.87213) (xy 301.033046 -53.876678)
			(xy 301.034701 -53.885624) (xy 301.036228 -53.88991) (xy 301.039276 -53.898292) (xy 301.045372 -53.905404)
			(xy 301.063013 -53.926337) (xy 301.092737 -53.972304) (xy 301.115582 -54.022051) (xy 301.131078 -54.074553)
			(xy 301.138907 -54.128731) (xy 301.138907 -54.183472) (xy 301.131078 -54.23765) (xy 301.115581 -54.290152)
			(xy 301.101788 -54.320186) (xy 303.330356 -54.320186) (xy 303.3308 -54.292815) (xy 303.338621 -54.238634)
			(xy 303.354115 -54.18613) (xy 303.376962 -54.136384) (xy 303.406692 -54.090418) (xy 303.424336 -54.069488)
			(xy 303.42459 -54.069234) (xy 303.430167 -54.062141) (xy 303.43642 -54.045229) (xy 303.436782 -54.036214)
			(xy 303.436782 -53.969158) (xy 303.436401 -53.960143) (xy 303.43017 -53.943226) (xy 303.42459 -53.936138)
			(xy 303.424336 -53.936138) (xy 303.424336 -53.935884) (xy 303.406728 -53.914926) (xy 303.377011 -53.868961)
			(xy 303.354168 -53.81922) (xy 303.33867 -53.766725) (xy 303.330834 -53.712554) (xy 303.330356 -53.685186)
			(xy 303.330842 -53.657935) (xy 303.338598 -53.603987) (xy 303.353953 -53.551692) (xy 303.376595 -53.502115)
			(xy 303.406061 -53.456265) (xy 303.441752 -53.415074) (xy 303.482943 -53.379383) (xy 303.528793 -53.349917)
			(xy 303.57837 -53.327275) (xy 303.630665 -53.31192) (xy 303.684613 -53.304164) (xy 303.739115 -53.304164)
			(xy 303.793063 -53.31192) (xy 303.845358 -53.327275) (xy 303.894935 -53.349917) (xy 303.940785 -53.379383)
			(xy 303.981976 -53.415074) (xy 304.017667 -53.456265) (xy 304.047133 -53.502115) (xy 304.069775 -53.551692)
			(xy 304.08513 -53.603987) (xy 304.092886 -53.657935) (xy 304.093372 -53.685186) (xy 304.092905 -53.712556)
			(xy 304.085088 -53.766736) (xy 304.0696 -53.819239) (xy 304.046758 -53.868986) (xy 304.017033 -53.914952)
			(xy 303.999392 -53.935884) (xy 303.999138 -53.936138) (xy 303.993564 -53.943233) (xy 303.987311 -53.960144)
			(xy 303.986946 -53.969158) (xy 303.986946 -54.036214) (xy 303.987286 -54.045233) (xy 303.993544 -54.06215)
			(xy 303.999138 -54.069234) (xy 303.999392 -54.069234) (xy 303.999392 -54.069488) (xy 304.017038 -54.090415)
			(xy 304.046749 -54.136389) (xy 304.069584 -54.186138) (xy 304.085073 -54.23864) (xy 304.092899 -54.292816)
			(xy 304.093372 -54.320186) (xy 304.092886 -54.347437) (xy 304.08513 -54.401385) (xy 304.069775 -54.45368)
			(xy 304.047133 -54.503257) (xy 304.017667 -54.549107) (xy 303.981976 -54.590298) (xy 303.940785 -54.625989)
			(xy 303.894935 -54.655455) (xy 303.845358 -54.678097) (xy 303.793063 -54.693452) (xy 303.739115 -54.701208)
			(xy 303.684613 -54.701208) (xy 303.630665 -54.693452) (xy 303.57837 -54.678097) (xy 303.528793 -54.655455)
			(xy 303.482943 -54.625989) (xy 303.441752 -54.590298) (xy 303.406061 -54.549107) (xy 303.376595 -54.503257)
			(xy 303.353953 -54.45368) (xy 303.338598 -54.401385) (xy 303.330842 -54.347437) (xy 303.330356 -54.320186)
			(xy 301.101788 -54.320186) (xy 301.092736 -54.339898) (xy 301.063011 -54.385866) (xy 301.045372 -54.4068)
			(xy 301.039276 -54.413912) (xy 301.036228 -54.422294) (xy 301.034707 -54.426582) (xy 301.033044 -54.435526)
			(xy 301.032926 -54.440074) (xy 301.032926 -54.50713) (xy 301.033046 -54.511678) (xy 301.034701 -54.520624)
			(xy 301.036228 -54.52491) (xy 301.039276 -54.533292) (xy 301.045372 -54.540404) (xy 301.063015 -54.561335)
			(xy 301.092743 -54.607301) (xy 301.115587 -54.657048) (xy 301.131078 -54.709551) (xy 301.138896 -54.763731)
			(xy 301.139009 -54.770528) (xy 304.270918 -54.770528) (xy 304.271396 -54.743158) (xy 304.27921 -54.688979)
			(xy 304.294696 -54.636476) (xy 304.317536 -54.586729) (xy 304.347258 -54.540762) (xy 304.364898 -54.51983)
			(xy 304.365152 -54.519576) (xy 304.370761 -54.512505) (xy 304.376993 -54.495576) (xy 304.377344 -54.486556)
			(xy 304.377344 -54.4195) (xy 304.376999 -54.410482) (xy 304.370744 -54.393564) (xy 304.365152 -54.38648)
			(xy 304.364898 -54.38648) (xy 304.364898 -54.386226) (xy 304.347257 -54.365295) (xy 304.317546 -54.319322)
			(xy 304.29471 -54.269574) (xy 304.279219 -54.217073) (xy 304.271392 -54.162897) (xy 304.270918 -54.135528)
			(xy 304.271404 -54.108277) (xy 304.27916 -54.054329) (xy 304.294515 -54.002034) (xy 304.317157 -53.952457)
			(xy 304.346623 -53.906607) (xy 304.382314 -53.865416) (xy 304.423505 -53.829725) (xy 304.469355 -53.800259)
			(xy 304.518932 -53.777617) (xy 304.571227 -53.762262) (xy 304.625175 -53.754506) (xy 304.679677 -53.754506)
			(xy 304.733625 -53.762262) (xy 304.78592 -53.777617) (xy 304.835497 -53.800259) (xy 304.881347 -53.829725)
			(xy 304.922538 -53.865416) (xy 304.958229 -53.906607) (xy 304.987695 -53.952457) (xy 305.006457 -53.993538)
			(xy 308.896748 -53.993538) (xy 308.896748 -53.933602) (xy 308.904571 -53.87418) (xy 308.920084 -53.816287)
			(xy 308.94302 -53.760914) (xy 308.972987 -53.709008) (xy 309.009474 -53.661458) (xy 309.051854 -53.619078)
			(xy 309.099404 -53.582591) (xy 309.15131 -53.552624) (xy 309.206683 -53.529688) (xy 309.264576 -53.514175)
			(xy 309.323998 -53.506352) (xy 309.383934 -53.506352) (xy 309.443356 -53.514175) (xy 309.501249 -53.529688)
			(xy 309.556622 -53.552624) (xy 309.608528 -53.582591) (xy 309.656078 -53.619078) (xy 309.698458 -53.661458)
			(xy 309.734945 -53.709008) (xy 309.764912 -53.760914) (xy 309.787848 -53.816287) (xy 309.803361 -53.87418)
			(xy 309.811184 -53.933602) (xy 309.811674 -53.96357) (xy 309.811184 -53.993538) (xy 309.803361 -54.05296)
			(xy 309.799477 -54.067456) (xy 311.141108 -54.067456) (xy 311.145179 -54.011834) (xy 311.157305 -53.957397)
			(xy 311.177228 -53.905306) (xy 311.204524 -53.856671) (xy 311.23861 -53.812528) (xy 311.278759 -53.773819)
			(xy 311.324117 -53.741368) (xy 311.373717 -53.715867) (xy 311.426501 -53.69786) (xy 311.481344 -53.68773)
			(xy 311.537078 -53.685693) (xy 311.592515 -53.691793) (xy 311.646472 -53.705899) (xy 311.697801 -53.727711)
			(xy 311.745407 -53.756765) (xy 311.788275 -53.79244) (xy 311.825492 -53.833977) (xy 311.856265 -53.88049)
			(xy 311.879937 -53.930987) (xy 311.896005 -53.984394) (xy 311.904125 -54.03957) (xy 311.904634 -54.067456)
			(xy 311.904125 -54.095342) (xy 311.896005 -54.150518) (xy 311.879937 -54.203925) (xy 311.863539 -54.238906)
			(xy 318.585848 -54.238906) (xy 318.589919 -54.183284) (xy 318.602045 -54.128847) (xy 318.621968 -54.076756)
			(xy 318.649264 -54.028121) (xy 318.68335 -53.983978) (xy 318.723499 -53.945269) (xy 318.768857 -53.912818)
			(xy 318.818457 -53.887317) (xy 318.871241 -53.86931) (xy 318.926084 -53.85918) (xy 318.981818 -53.857143)
			(xy 319.037255 -53.863243) (xy 319.091212 -53.877349) (xy 319.142541 -53.899161) (xy 319.190147 -53.928215)
			(xy 319.233015 -53.96389) (xy 319.270232 -54.005427) (xy 319.301005 -54.05194) (xy 319.324677 -54.102437)
			(xy 319.340745 -54.155844) (xy 319.348865 -54.21102) (xy 319.349374 -54.238906) (xy 319.348865 -54.266792)
			(xy 319.340745 -54.321968) (xy 319.324677 -54.375375) (xy 319.301005 -54.425872) (xy 319.270232 -54.472385)
			(xy 319.233015 -54.513922) (xy 319.190147 -54.549597) (xy 319.142541 -54.578651) (xy 319.091212 -54.600463)
			(xy 319.037255 -54.614569) (xy 318.981818 -54.620669) (xy 318.926084 -54.618632) (xy 318.871241 -54.608502)
			(xy 318.818457 -54.590495) (xy 318.768857 -54.564994) (xy 318.723499 -54.532543) (xy 318.68335 -54.493834)
			(xy 318.649264 -54.449691) (xy 318.621968 -54.401056) (xy 318.602045 -54.348965) (xy 318.589919 -54.294528)
			(xy 318.585848 -54.238906) (xy 311.863539 -54.238906) (xy 311.856265 -54.254422) (xy 311.825492 -54.300935)
			(xy 311.788275 -54.342472) (xy 311.745407 -54.378147) (xy 311.697801 -54.407201) (xy 311.646472 -54.429013)
			(xy 311.592515 -54.443119) (xy 311.537078 -54.449219) (xy 311.481344 -54.447182) (xy 311.426501 -54.437052)
			(xy 311.373717 -54.419045) (xy 311.324117 -54.393544) (xy 311.278759 -54.361093) (xy 311.23861 -54.322384)
			(xy 311.204524 -54.278241) (xy 311.177228 -54.229606) (xy 311.157305 -54.177515) (xy 311.145179 -54.123078)
			(xy 311.141108 -54.067456) (xy 309.799477 -54.067456) (xy 309.787848 -54.110853) (xy 309.764912 -54.166226)
			(xy 309.734945 -54.218132) (xy 309.698458 -54.265682) (xy 309.656078 -54.308062) (xy 309.608528 -54.344549)
			(xy 309.556622 -54.374516) (xy 309.501249 -54.397452) (xy 309.443356 -54.412965) (xy 309.383934 -54.420788)
			(xy 309.323998 -54.420788) (xy 309.264576 -54.412965) (xy 309.206683 -54.397452) (xy 309.15131 -54.374516)
			(xy 309.099404 -54.344549) (xy 309.051854 -54.308062) (xy 309.009474 -54.265682) (xy 308.972987 -54.218132)
			(xy 308.94302 -54.166226) (xy 308.920084 -54.110853) (xy 308.904571 -54.05296) (xy 308.896748 -53.993538)
			(xy 305.006457 -53.993538) (xy 305.010337 -54.002034) (xy 305.025692 -54.054329) (xy 305.033448 -54.108277)
			(xy 305.033934 -54.135528) (xy 305.0335 -54.1629) (xy 305.025677 -54.217081) (xy 305.010181 -54.269585)
			(xy 304.987332 -54.319331) (xy 304.957599 -54.365296) (xy 304.939954 -54.386226) (xy 304.9397 -54.38648)
			(xy 304.934116 -54.393568) (xy 304.927868 -54.410484) (xy 304.927508 -54.4195) (xy 304.927508 -54.486556)
			(xy 304.927885 -54.495571) (xy 304.934119 -54.512488) (xy 304.9397 -54.519576) (xy 304.939954 -54.519576)
			(xy 304.939954 -54.51983) (xy 304.957567 -54.540784) (xy 304.987284 -54.58675) (xy 305.010126 -54.636492)
			(xy 305.025623 -54.688988) (xy 305.033457 -54.74316) (xy 305.033934 -54.770528) (xy 305.033448 -54.797779)
			(xy 305.025692 -54.851727) (xy 305.010337 -54.904022) (xy 304.987695 -54.953599) (xy 304.958229 -54.999449)
			(xy 304.922538 -55.04064) (xy 304.881347 -55.076331) (xy 304.87026 -55.083456) (xy 311.141108 -55.083456)
			(xy 311.145179 -55.027834) (xy 311.157305 -54.973397) (xy 311.177228 -54.921306) (xy 311.204524 -54.872671)
			(xy 311.23861 -54.828528) (xy 311.278759 -54.789819) (xy 311.324117 -54.757368) (xy 311.373717 -54.731867)
			(xy 311.426501 -54.71386) (xy 311.481344 -54.70373) (xy 311.537078 -54.701693) (xy 311.592515 -54.707793)
			(xy 311.646472 -54.721899) (xy 311.697801 -54.743711) (xy 311.745407 -54.772765) (xy 311.788275 -54.80844)
			(xy 311.825492 -54.849977) (xy 311.856265 -54.89649) (xy 311.879937 -54.946987) (xy 311.892592 -54.989051)
			(xy 314.100968 -54.989051) (xy 314.100968 -54.934549) (xy 314.108724 -54.880603) (xy 314.124078 -54.828309)
			(xy 314.146718 -54.778732) (xy 314.176182 -54.732882) (xy 314.211871 -54.691691) (xy 314.253059 -54.655999)
			(xy 314.298907 -54.626531) (xy 314.348482 -54.603888) (xy 314.400775 -54.58853) (xy 314.454721 -54.58077)
			(xy 314.481972 -54.580282) (xy 314.510063 -54.580799) (xy 314.565639 -54.589022) (xy 314.619407 -54.605309)
			(xy 314.670205 -54.629308) (xy 314.716932 -54.6605) (xy 314.758578 -54.698209) (xy 314.794241 -54.741619)
			(xy 314.809124 -54.765448) (xy 314.814458 -54.774338) (xy 314.831476 -54.78653) (xy 314.924694 -54.80685)
			(xy 314.945268 -54.802532) (xy 314.953904 -54.79669) (xy 314.977965 -54.780685) (xy 315.029897 -54.755344)
			(xy 315.085056 -54.738119) (xy 315.142181 -54.729406) (xy 315.171074 -54.728872) (xy 315.198325 -54.729379)
			(xy 315.252274 -54.737132) (xy 315.304569 -54.752484) (xy 315.354148 -54.775122) (xy 315.4 -54.804586)
			(xy 315.441193 -54.840275) (xy 315.476887 -54.881463) (xy 315.506356 -54.927311) (xy 315.529 -54.976887)
			(xy 315.544358 -55.029181) (xy 315.552117 -55.083129) (xy 315.552582 -55.11038) (xy 315.552109 -55.13775)
			(xy 315.544293 -55.191929) (xy 315.528806 -55.244432) (xy 315.505966 -55.294179) (xy 315.476243 -55.340146)
			(xy 315.458602 -55.361078) (xy 315.458348 -55.361332) (xy 315.452778 -55.368429) (xy 315.446522 -55.385338)
			(xy 315.446156 -55.394352) (xy 315.446156 -55.461408) (xy 315.446497 -55.470427) (xy 315.452755 -55.487344)
			(xy 315.458348 -55.494428) (xy 315.458602 -55.494428) (xy 315.458602 -55.494682) (xy 315.476222 -55.515631)
			(xy 315.505945 -55.561597) (xy 315.52879 -55.611341) (xy 315.544287 -55.66384) (xy 315.552116 -55.718016)
			(xy 315.552119 -55.772754) (xy 315.544293 -55.826931) (xy 315.528801 -55.879431) (xy 315.50596 -55.929177)
			(xy 315.47624 -55.975145) (xy 315.458602 -55.996078) (xy 315.458348 -55.996332) (xy 315.452778 -56.003429)
			(xy 315.446522 -56.020338) (xy 315.446156 -56.029352) (xy 315.446156 -56.096408) (xy 315.446497 -56.105427)
			(xy 315.452755 -56.122344) (xy 315.458348 -56.129428) (xy 315.458602 -56.129428) (xy 315.458602 -56.129682)
			(xy 315.476246 -56.15061) (xy 315.505957 -56.196584) (xy 315.528792 -56.246332) (xy 315.544282 -56.298834)
			(xy 315.552109 -56.353011) (xy 315.552582 -56.38038) (xy 315.552096 -56.407631) (xy 315.54434 -56.461579)
			(xy 315.528985 -56.513874) (xy 315.506343 -56.563451) (xy 315.476877 -56.609301) (xy 315.441186 -56.650492)
			(xy 315.399995 -56.686183) (xy 315.354145 -56.715649) (xy 315.304568 -56.738291) (xy 315.252273 -56.753646)
			(xy 315.198325 -56.761402) (xy 315.143823 -56.761402) (xy 315.089875 -56.753646) (xy 315.03758 -56.738291)
			(xy 314.988003 -56.715649) (xy 314.942153 -56.686183) (xy 314.900962 -56.650492) (xy 314.865271 -56.609301)
			(xy 314.835805 -56.563451) (xy 314.813163 -56.513874) (xy 314.797808 -56.461579) (xy 314.790052 -56.407631)
			(xy 314.789566 -56.38038) (xy 314.790004 -56.353009) (xy 314.797826 -56.298828) (xy 314.813321 -56.246324)
			(xy 314.836169 -56.196577) (xy 314.865901 -56.150612) (xy 314.883546 -56.129682) (xy 314.8838 -56.129428)
			(xy 314.889381 -56.122338) (xy 314.895631 -56.105424) (xy 314.895992 -56.096408) (xy 314.895992 -56.029352)
			(xy 314.895612 -56.020337) (xy 314.88938 -56.00342) (xy 314.8838 -55.996332) (xy 314.883546 -55.996332)
			(xy 314.883546 -55.996078) (xy 314.865885 -55.975162) (xy 314.836159 -55.929191) (xy 314.813314 -55.879443)
			(xy 314.797819 -55.826938) (xy 314.789991 -55.772757) (xy 314.789994 -55.718013) (xy 314.797825 -55.663833)
			(xy 314.813325 -55.611329) (xy 314.836174 -55.561582) (xy 314.865903 -55.515614) (xy 314.883546 -55.494682)
			(xy 314.8838 -55.494428) (xy 314.889381 -55.487338) (xy 314.895631 -55.470424) (xy 314.895992 -55.461408)
			(xy 314.895992 -55.394352) (xy 314.895612 -55.385337) (xy 314.88938 -55.36842) (xy 314.8838 -55.361332)
			(xy 314.883546 -55.360824) (xy 314.872599 -55.348092) (xy 314.85276 -55.320999) (xy 314.843922 -55.306722)
			(xy 314.838588 -55.297832) (xy 314.82157 -55.28564) (xy 314.728352 -55.26532) (xy 314.707778 -55.269638)
			(xy 314.699142 -55.27548) (xy 314.675067 -55.291462) (xy 314.62314 -55.316809) (xy 314.567985 -55.33404)
			(xy 314.510864 -55.342761) (xy 314.481972 -55.343298) (xy 314.454721 -55.34283) (xy 314.400775 -55.33507)
			(xy 314.348482 -55.319712) (xy 314.298907 -55.297069) (xy 314.253059 -55.267601) (xy 314.211871 -55.231909)
			(xy 314.176182 -55.190718) (xy 314.146718 -55.144868) (xy 314.124078 -55.095291) (xy 314.108724 -55.042997)
			(xy 314.100968 -54.989051) (xy 311.892592 -54.989051) (xy 311.896005 -55.000394) (xy 311.904125 -55.05557)
			(xy 311.904634 -55.083456) (xy 311.904125 -55.111342) (xy 311.896005 -55.166518) (xy 311.879937 -55.219925)
			(xy 311.856265 -55.270422) (xy 311.825492 -55.316935) (xy 311.788275 -55.358472) (xy 311.745407 -55.394147)
			(xy 311.701652 -55.420851) (xy 312.424568 -55.420851) (xy 312.424568 -55.366349) (xy 312.432324 -55.312403)
			(xy 312.447678 -55.260109) (xy 312.470318 -55.210532) (xy 312.499782 -55.164682) (xy 312.535471 -55.123491)
			(xy 312.576659 -55.087799) (xy 312.622507 -55.058331) (xy 312.672082 -55.035688) (xy 312.724375 -55.02033)
			(xy 312.778321 -55.01257) (xy 312.805572 -55.012082) (xy 312.831887 -55.012507) (xy 312.884017 -55.019751)
			(xy 312.934661 -55.034079) (xy 312.982859 -55.05522) (xy 313.027702 -55.082773) (xy 313.06834 -55.116218)
			(xy 313.086496 -55.135272) (xy 313.094021 -55.14267) (xy 313.113298 -55.151197) (xy 313.123834 -55.151782)
			(xy 313.19851 -55.151782) (xy 313.209063 -55.151277) (xy 313.228358 -55.142725) (xy 313.235848 -55.135272)
			(xy 313.253982 -55.116195) (xy 313.294617 -55.082741) (xy 313.339462 -55.055185) (xy 313.387667 -55.034051)
			(xy 313.438318 -55.019738) (xy 313.490455 -55.012518) (xy 313.516772 -55.012082) (xy 313.544025 -55.012563)
			(xy 313.597978 -55.020317) (xy 313.650278 -55.03567) (xy 313.69986 -55.05831) (xy 313.745716 -55.087777)
			(xy 313.786911 -55.12347) (xy 313.822606 -55.164662) (xy 313.852076 -55.210515) (xy 313.87472 -55.260096)
			(xy 313.890077 -55.312395) (xy 313.897835 -55.366347) (xy 313.897835 -55.420853) (xy 313.890077 -55.474805)
			(xy 313.87472 -55.527104) (xy 313.852076 -55.576685) (xy 313.822606 -55.622538) (xy 313.786911 -55.66373)
			(xy 313.745716 -55.699423) (xy 313.69986 -55.72889) (xy 313.650278 -55.75153) (xy 313.597978 -55.766883)
			(xy 313.544025 -55.774637) (xy 313.516772 -55.775098) (xy 313.490457 -55.77465) (xy 313.438328 -55.767411)
			(xy 313.387685 -55.753088) (xy 313.339486 -55.731952) (xy 313.294643 -55.704403) (xy 313.254004 -55.670961)
			(xy 313.235848 -55.651908) (xy 313.228347 -55.644483) (xy 313.209051 -55.635972) (xy 313.19851 -55.635398)
			(xy 313.123834 -55.635398) (xy 313.113285 -55.635933) (xy 313.09399 -55.644464) (xy 313.086496 -55.651908)
			(xy 313.068337 -55.67096) (xy 313.027708 -55.704417) (xy 312.982868 -55.731976) (xy 312.934668 -55.753115)
			(xy 312.884021 -55.767433) (xy 312.831888 -55.774659) (xy 312.805572 -55.775098) (xy 312.778321 -55.77463)
			(xy 312.724375 -55.76687) (xy 312.672082 -55.751512) (xy 312.622507 -55.728869) (xy 312.576659 -55.699401)
			(xy 312.535471 -55.663709) (xy 312.499782 -55.622518) (xy 312.470318 -55.576668) (xy 312.447678 -55.527091)
			(xy 312.432324 -55.474797) (xy 312.424568 -55.420851) (xy 311.701652 -55.420851) (xy 311.697801 -55.423201)
			(xy 311.646472 -55.445013) (xy 311.592515 -55.459119) (xy 311.537078 -55.465219) (xy 311.481344 -55.463182)
			(xy 311.426501 -55.453052) (xy 311.373717 -55.435045) (xy 311.324117 -55.409544) (xy 311.278759 -55.377093)
			(xy 311.23861 -55.338384) (xy 311.204524 -55.294241) (xy 311.177228 -55.245606) (xy 311.157305 -55.193515)
			(xy 311.145179 -55.139078) (xy 311.141108 -55.083456) (xy 304.87026 -55.083456) (xy 304.835497 -55.105797)
			(xy 304.78592 -55.128439) (xy 304.733625 -55.143794) (xy 304.679677 -55.15155) (xy 304.625175 -55.15155)
			(xy 304.571227 -55.143794) (xy 304.518932 -55.128439) (xy 304.469355 -55.105797) (xy 304.423505 -55.076331)
			(xy 304.382314 -55.04064) (xy 304.346623 -54.999449) (xy 304.317157 -54.953599) (xy 304.294515 -54.904022)
			(xy 304.27916 -54.851727) (xy 304.271404 -54.797779) (xy 304.270918 -54.770528) (xy 301.139009 -54.770528)
			(xy 301.139352 -54.791102) (xy 301.138866 -54.818353) (xy 301.13111 -54.872301) (xy 301.115755 -54.924596)
			(xy 301.093113 -54.974173) (xy 301.063647 -55.020023) (xy 301.027956 -55.061214) (xy 300.986765 -55.096905)
			(xy 300.940915 -55.126371) (xy 300.891338 -55.149013) (xy 300.839043 -55.164368) (xy 300.785095 -55.172124)
			(xy 300.730593 -55.172124) (xy 300.676645 -55.164368) (xy 300.62435 -55.149013) (xy 300.574773 -55.126371)
			(xy 300.528923 -55.096905) (xy 300.487732 -55.061214) (xy 300.452041 -55.020023) (xy 300.422575 -54.974173)
			(xy 300.399933 -54.924596) (xy 300.384578 -54.872301) (xy 300.376822 -54.818353) (xy 300.376336 -54.791102)
			(xy 300.376808 -54.763732) (xy 300.384632 -54.709554) (xy 300.40012 -54.657051) (xy 300.422954 -54.607301)
			(xy 300.452664 -54.561326) (xy 300.470316 -54.540404) (xy 300.476412 -54.533292) (xy 300.47946 -54.52491)
			(xy 300.480982 -54.520622) (xy 300.482646 -54.511678) (xy 300.482762 -54.50713) (xy 300.482762 -54.440074)
			(xy 300.482642 -54.435526) (xy 300.480988 -54.42658) (xy 300.47946 -54.422294) (xy 300.476412 -54.413912)
			(xy 300.470316 -54.4068) (xy 300.452676 -54.385867) (xy 300.422951 -54.339899) (xy 300.400106 -54.290153)
			(xy 300.38461 -54.237651) (xy 300.376782 -54.183472) (xy 300.376782 -54.128731) (xy 300.38461 -54.074552)
			(xy 300.400105 -54.02205) (xy 300.42295 -53.972304) (xy 300.452674 -53.926335) (xy 300.470316 -53.905404)
			(xy 300.476412 -53.898292) (xy 300.47946 -53.88991) (xy 300.480982 -53.885622) (xy 300.482646 -53.876678)
			(xy 300.482762 -53.87213) (xy 300.482762 -53.79593) (xy 300.479968 -53.788564) (xy 300.459894 -53.766854)
			(xy 300.425911 -53.71847) (xy 300.399699 -53.665472) (xy 300.381872 -53.609098) (xy 300.372845 -53.550665)
			(xy 300.372272 -53.521102) (xy 300.372706 -53.494704) (xy 300.379914 -53.442401) (xy 300.394195 -53.391573)
			(xy 300.415282 -53.34317) (xy 300.442781 -53.2981) (xy 300.476175 -53.257206) (xy 300.495208 -53.238908)
			(xy 300.496962 -53.234341) (xy 300.498881 -53.224749) (xy 300.499018 -53.219858) (xy 300.499018 -53.187854)
			(xy 300.498256 -53.17871) (xy 300.49724 -53.1749) (xy 300.495348 -53.16842) (xy 300.488663 -53.156697)
			(xy 300.484032 -53.151786) (xy 300.483016 -53.15077) (xy 300.471332 -53.137816) (xy 300.464041 -53.13087)
			(xy 300.445573 -53.122883) (xy 300.435518 -53.122322) (xy 298.522644 -53.122322) (xy 298.513839 -53.122748)
			(xy 298.497298 -53.128803) (xy 298.483767 -53.14008) (xy 298.478956 -53.147468) (xy 298.434506 -53.22316)
			(xy 298.431343 -53.229097) (xy 298.427876 -53.24209) (xy 298.427648 -53.248814) (xy 298.427648 -53.262022)
			(xy 298.429426 -53.265324) (xy 298.434252 -53.273706) (xy 298.445946 -53.295242) (xy 298.464362 -53.340657)
			(xy 298.476821 -53.388054) (xy 298.483117 -53.436655) (xy 298.483528 -53.461158) (xy 298.483528 -53.461412)
			(xy 298.483055 -53.488781) (xy 298.475229 -53.542958) (xy 298.459738 -53.595459) (xy 298.436901 -53.645206)
			(xy 298.407188 -53.691178) (xy 298.389548 -53.71211) (xy 298.383452 -53.719222) (xy 298.380404 -53.727604)
			(xy 298.378884 -53.731892) (xy 298.377224 -53.740836) (xy 298.377102 -53.745384) (xy 298.377102 -53.81244)
			(xy 298.377223 -53.816988) (xy 298.378879 -53.825934) (xy 298.380404 -53.83022) (xy 298.383452 -53.838602)
			(xy 298.389548 -53.845714) (xy 298.407189 -53.866646) (xy 298.436914 -53.912613) (xy 298.459759 -53.962359)
			(xy 298.475255 -54.014861) (xy 298.483083 -54.069039) (xy 298.483081 -54.123779) (xy 298.475251 -54.177957)
			(xy 298.459753 -54.230458) (xy 298.436905 -54.280203) (xy 298.407178 -54.326168) (xy 298.389548 -54.34711)
			(xy 298.383452 -54.354222) (xy 298.380404 -54.362604) (xy 298.378884 -54.366892) (xy 298.377224 -54.375836)
			(xy 298.377102 -54.380384) (xy 298.377102 -54.44744) (xy 298.377223 -54.451988) (xy 298.378879 -54.460934)
			(xy 298.380404 -54.46522) (xy 298.383452 -54.473602) (xy 298.389548 -54.480714) (xy 298.407191 -54.501645)
			(xy 298.43692 -54.54761) (xy 298.459764 -54.597357) (xy 298.475255 -54.649861) (xy 298.483072 -54.704041)
			(xy 298.483528 -54.731412) (xy 298.483042 -54.758663) (xy 298.475286 -54.812611) (xy 298.459931 -54.864906)
			(xy 298.437289 -54.914483) (xy 298.407823 -54.960333) (xy 298.372132 -55.001524) (xy 298.330941 -55.037215)
			(xy 298.285091 -55.066681) (xy 298.235514 -55.089323) (xy 298.183219 -55.104678) (xy 298.129271 -55.112434)
			(xy 298.074769 -55.112434) (xy 298.020821 -55.104678) (xy 297.968526 -55.089323) (xy 297.918949 -55.066681)
			(xy 297.873099 -55.037215) (xy 297.831908 -55.001524) (xy 297.796217 -54.960333) (xy 297.766751 -54.914483)
			(xy 297.744109 -54.864906) (xy 297.728754 -54.812611) (xy 297.720998 -54.758663) (xy 297.720512 -54.731412)
			(xy 297.72099 -54.704044) (xy 297.728825 -54.649872) (xy 297.744322 -54.597376) (xy 297.767163 -54.547634)
			(xy 297.796879 -54.501667) (xy 297.814492 -54.480714) (xy 297.820588 -54.473602) (xy 297.823636 -54.46522)
			(xy 297.825159 -54.460932) (xy 297.826826 -54.451988) (xy 297.826938 -54.44744) (xy 297.826938 -54.380384)
			(xy 297.82681 -54.375837) (xy 297.82514 -54.366897) (xy 297.823636 -54.362604) (xy 297.820588 -54.354222)
			(xy 297.814492 -54.34711) (xy 297.796852 -54.326177) (xy 297.767128 -54.280208) (xy 297.744283 -54.230461)
			(xy 297.728787 -54.177959) (xy 297.720958 -54.12378) (xy 297.720956 -54.069038) (xy 297.728783 -54.014859)
			(xy 297.744277 -53.962356) (xy 297.767119 -53.912608) (xy 297.796841 -53.866638) (xy 297.814492 -53.845714)
			(xy 297.820588 -53.838602) (xy 297.823636 -53.83022) (xy 297.825159 -53.825932) (xy 297.826826 -53.816988)
			(xy 297.826938 -53.81244) (xy 297.826938 -53.745384) (xy 297.82681 -53.740837) (xy 297.82514 -53.731897)
			(xy 297.823636 -53.727604) (xy 297.820588 -53.719222) (xy 297.814492 -53.71211) (xy 297.79685 -53.691179)
			(xy 297.767123 -53.645212) (xy 297.744279 -53.595466) (xy 297.728788 -53.542962) (xy 297.720968 -53.488783)
			(xy 297.720512 -53.461412) (xy 297.720512 -53.461158) (xy 297.720888 -53.436652) (xy 297.727168 -53.388044)
			(xy 297.73963 -53.340643) (xy 297.758071 -53.295233) (xy 297.769788 -53.273706) (xy 297.774614 -53.265324)
			(xy 297.776392 -53.262022) (xy 297.776392 -53.248814) (xy 297.776219 -53.242083) (xy 297.77274 -53.229081)
			(xy 297.769534 -53.22316) (xy 297.725084 -53.147468) (xy 297.720321 -53.14004) (xy 297.706787 -53.12874)
			(xy 297.690212 -53.12273) (xy 297.681396 -53.122322) (xy 291.765482 -53.122322) (xy 291.756916 -53.122697)
			(xy 291.740761 -53.128412) (xy 291.72737 -53.139105) (xy 291.722556 -53.146198) (xy 291.68725 -53.20792)
			(xy 291.677598 -53.224684) (xy 291.674506 -53.230502) (xy 291.671172 -53.243243) (xy 291.670994 -53.24983)
			(xy 291.670994 -53.263546) (xy 291.678106 -53.275484) (xy 291.690659 -53.297592) (xy 291.710436 -53.344426)
			(xy 291.723807 -53.393475) (xy 291.730533 -53.443866) (xy 291.730938 -53.469286) (xy 291.730938 -53.475382)
			(xy 291.730041 -53.502348) (xy 291.721589 -53.555635) (xy 291.705713 -53.6072) (xy 291.682729 -53.656013)
			(xy 291.653098 -53.701102) (xy 291.617409 -53.741565) (xy 291.576376 -53.776597) (xy 291.530815 -53.805497)
			(xy 291.481638 -53.82769) (xy 291.429823 -53.842733) (xy 291.376407 -53.850325) (xy 291.34943 -53.850794)
			(xy 291.322062 -53.850317) (xy 291.267888 -53.842484) (xy 291.215391 -53.826989) (xy 291.165647 -53.804151)
			(xy 291.119677 -53.774437) (xy 291.098732 -53.756814) (xy 291.09162 -53.750718) (xy 291.083238 -53.74767)
			(xy 291.078951 -53.746145) (xy 291.070007 -53.744475) (xy 291.065458 -53.744368) (xy 290.998402 -53.744368)
			(xy 290.993855 -53.744495) (xy 290.984914 -53.746161) (xy 290.980622 -53.74767) (xy 290.97224 -53.750718)
			(xy 290.965128 -53.756814) (xy 290.944197 -53.774457) (xy 290.898231 -53.804185) (xy 290.848484 -53.827031)
			(xy 290.795981 -53.842525) (xy 290.741801 -53.850347) (xy 290.71443 -53.850794) (xy 290.687457 -53.850323)
			(xy 290.634049 -53.842716) (xy 290.582244 -53.827662) (xy 290.533077 -53.805462) (xy 290.487526 -53.776558)
			(xy 290.4465 -53.741527) (xy 290.410816 -53.701068) (xy 290.381187 -53.655985) (xy 290.358203 -53.60718)
			(xy 290.342321 -53.555623) (xy 290.333859 -53.502344) (xy 290.332922 -53.475382) (xy 290.332922 -53.469286)
			(xy 290.333347 -53.443869) (xy 290.340101 -53.393486) (xy 290.353475 -53.344443) (xy 290.373232 -53.297606)
			(xy 290.385754 -53.275484) (xy 290.38931 -53.269642) (xy 290.392866 -53.256434) (xy 290.392866 -53.24983)
			(xy 290.39266 -53.243248) (xy 290.389323 -53.230514) (xy 290.386262 -53.224684) (xy 290.37661 -53.20792)
			(xy 290.341304 -53.146198) (xy 290.33649 -53.1391) (xy 290.323119 -53.128377) (xy 290.306948 -53.122698)
			(xy 290.298378 -53.122322) (xy 286.016446 -53.122322) (xy 286.008089 -53.122705) (xy 285.992279 -53.128146)
			(xy 285.985458 -53.13299) (xy 285.979108 -53.13807) (xy 285.969964 -53.15204) (xy 285.967678 -53.16093)
			(xy 285.959914 -53.190366) (xy 285.93765 -53.247025) (xy 285.908072 -53.300234) (xy 285.871703 -53.349053)
			(xy 285.829184 -53.392621) (xy 285.781266 -53.43017) (xy 285.728795 -53.461036) (xy 285.672695 -53.484675)
			(xy 285.613956 -53.50067) (xy 285.553616 -53.508738) (xy 285.49274 -53.508738) (xy 285.4324 -53.50067)
			(xy 285.373661 -53.484675) (xy 285.317561 -53.461036) (xy 285.26509 -53.43017) (xy 285.217172 -53.392621)
			(xy 285.174653 -53.349053) (xy 285.138284 -53.300234) (xy 285.108706 -53.247025) (xy 285.086442 -53.190366)
			(xy 285.078678 -53.16093) (xy 285.078678 -53.160676) (xy 285.076331 -53.152407) (xy 285.066986 -53.137993)
			(xy 285.06039 -53.132482) (xy 285.054294 -53.127656) (xy 285.038292 -53.122322) (xy 276.984206 -53.122322)
			(xy 276.976312 -53.122657) (xy 276.961305 -53.127574) (xy 276.954742 -53.131974) (xy 276.948392 -53.136292)
			(xy 276.939248 -53.148738) (xy 276.936454 -53.156612) (xy 276.926231 -53.185088) (xy 276.899327 -53.23928)
			(xy 276.865511 -53.28945) (xy 276.825374 -53.334722) (xy 276.779615 -53.374305) (xy 276.75459 -53.391308)
			(xy 276.745446 -53.39715) (xy 276.739858 -53.405786) (xy 276.737177 -53.410113) (xy 276.733455 -53.419584)
			(xy 276.732492 -53.424582) (xy 276.719792 -53.49875) (xy 276.719077 -53.504024) (xy 276.719587 -53.514652)
			(xy 276.720808 -53.519832) (xy 276.723094 -53.52923) (xy 276.729698 -53.537866) (xy 276.744589 -53.55792)
			(xy 276.769592 -53.601161) (xy 276.78874 -53.647295) (xy 276.801707 -53.695531) (xy 276.808272 -53.745048)
			(xy 276.808692 -53.770022) (xy 276.808692 -53.77053) (xy 276.808204 -53.797779) (xy 276.800444 -53.851723)
			(xy 276.785086 -53.904013) (xy 276.762443 -53.953585) (xy 276.732975 -53.999431) (xy 276.697284 -54.040616)
			(xy 276.656094 -54.076303) (xy 276.610245 -54.105765) (xy 276.56067 -54.128402) (xy 276.508378 -54.143753)
			(xy 276.454433 -54.151507) (xy 276.427184 -54.152038) (xy 276.399815 -54.151565) (xy 276.345639 -54.143738)
			(xy 276.293138 -54.128247) (xy 276.24339 -54.105411) (xy 276.197418 -54.075697) (xy 276.176486 -54.058058)
			(xy 276.169374 -54.051962) (xy 276.160992 -54.048914) (xy 276.156704 -54.047394) (xy 276.14776 -54.045734)
			(xy 276.143212 -54.045612) (xy 276.076156 -54.045612) (xy 276.071608 -54.045734) (xy 276.062663 -54.04739)
			(xy 276.058376 -54.048914) (xy 276.049994 -54.051962) (xy 276.042882 -54.058058) (xy 276.021951 -54.075701)
			(xy 275.975985 -54.105428) (xy 275.926238 -54.128271) (xy 275.873735 -54.143761) (xy 275.819555 -54.151578)
			(xy 275.792184 -54.152038) (xy 275.764933 -54.151551) (xy 275.710985 -54.143793) (xy 275.658691 -54.128437)
			(xy 275.609113 -54.105795) (xy 275.563263 -54.076329) (xy 275.522072 -54.040638) (xy 275.48638 -53.999448)
			(xy 275.456912 -53.953599) (xy 275.434268 -53.904023) (xy 275.41891 -53.851729) (xy 275.41115 -53.797781)
			(xy 275.410676 -53.77053) (xy 275.411208 -53.741613) (xy 275.419932 -53.684441) (xy 275.437186 -53.629241)
			(xy 275.462573 -53.577277) (xy 275.495512 -53.52974) (xy 275.535248 -53.487719) (xy 275.557742 -53.46954)
			(xy 275.565126 -53.463257) (xy 275.574919 -53.446541) (xy 275.576792 -53.437028) (xy 275.5773 -53.429408)
			(xy 275.5773 -53.349652) (xy 275.576792 -53.342032) (xy 275.575027 -53.333015) (xy 275.56603 -53.317012)
			(xy 275.559266 -53.31079) (xy 275.557742 -53.30952) (xy 275.538472 -53.294011) (xy 275.503702 -53.258827)
			(xy 275.473765 -53.21945) (xy 275.449162 -53.176537) (xy 275.439378 -53.153818) (xy 275.43506 -53.143404)
			(xy 275.426932 -53.135784) (xy 275.420328 -53.130704) (xy 275.414232 -53.12664) (xy 275.400262 -53.122322)
			(xy 275.080984 -53.122322) (xy 275.080222 -53.122322) (xy 275.070171 -53.122897) (xy 275.051704 -53.130879)
			(xy 275.044408 -53.137816) (xy 275.032724 -53.15077) (xy 275.031708 -53.151786) (xy 275.027087 -53.156706)
			(xy 275.020395 -53.168422) (xy 275.0185 -53.1749) (xy 275.016722 -53.1876) (xy 275.016722 -53.219604)
			(xy 275.016858 -53.224637) (xy 275.018899 -53.234494) (xy 275.020786 -53.239162) (xy 275.039783 -53.257452)
			(xy 275.073104 -53.298326) (xy 275.10054 -53.343362) (xy 275.121578 -53.391719) (xy 275.135826 -53.442492)
			(xy 275.143016 -53.494735) (xy 275.143468 -53.521102) (xy 275.142903 -53.550665) (xy 275.133883 -53.6091)
			(xy 275.116054 -53.665474) (xy 275.089833 -53.718468) (xy 275.055834 -53.766842) (xy 275.035772 -53.788564)
			(xy 275.032978 -53.79593) (xy 275.032978 -53.87213) (xy 275.033099 -53.876678) (xy 275.034755 -53.885624)
			(xy 275.03628 -53.88991) (xy 275.039328 -53.898292) (xy 275.045424 -53.905404) (xy 275.063067 -53.926336)
			(xy 275.092795 -53.972302) (xy 275.115643 -54.022049) (xy 275.131141 -54.074551) (xy 275.13897 -54.12873)
			(xy 275.13897 -54.183473) (xy 275.13114 -54.237652) (xy 275.115642 -54.290154) (xy 275.101848 -54.320186)
			(xy 277.330408 -54.320186) (xy 277.330864 -54.292815) (xy 277.338684 -54.238636) (xy 277.354175 -54.186132)
			(xy 277.377019 -54.136386) (xy 277.406746 -54.090419) (xy 277.424388 -54.069488) (xy 277.424642 -54.069234)
			(xy 277.430226 -54.062146) (xy 277.436473 -54.04523) (xy 277.436834 -54.036214) (xy 277.436834 -53.969158)
			(xy 277.436442 -53.960145) (xy 277.430218 -53.943228) (xy 277.424642 -53.936138) (xy 277.424388 -53.936138)
			(xy 277.424388 -53.935884) (xy 277.406773 -53.914933) (xy 277.377058 -53.868965) (xy 277.354218 -53.819222)
			(xy 277.338721 -53.766726) (xy 277.330886 -53.712554) (xy 277.330408 -53.685186) (xy 277.330894 -53.657935)
			(xy 277.33865 -53.603987) (xy 277.354005 -53.551692) (xy 277.376647 -53.502115) (xy 277.406113 -53.456265)
			(xy 277.441804 -53.415074) (xy 277.482995 -53.379383) (xy 277.528845 -53.349917) (xy 277.578422 -53.327275)
			(xy 277.630717 -53.31192) (xy 277.684665 -53.304164) (xy 277.739167 -53.304164) (xy 277.793115 -53.31192)
			(xy 277.84541 -53.327275) (xy 277.894987 -53.349917) (xy 277.940837 -53.379383) (xy 277.982028 -53.415074)
			(xy 278.017719 -53.456265) (xy 278.047185 -53.502115) (xy 278.069827 -53.551692) (xy 278.085182 -53.603987)
			(xy 278.092938 -53.657935) (xy 278.093424 -53.685186) (xy 278.092968 -53.712557) (xy 278.085151 -53.766737)
			(xy 278.06966 -53.819241) (xy 278.046816 -53.868988) (xy 278.017087 -53.914953) (xy 277.999444 -53.935884)
			(xy 277.99919 -53.936138) (xy 277.993622 -53.943237) (xy 277.987365 -53.960144) (xy 277.986998 -53.969158)
			(xy 277.986998 -54.036214) (xy 277.987349 -54.045231) (xy 277.993601 -54.062148) (xy 277.99919 -54.069234)
			(xy 277.999444 -54.069234) (xy 277.999444 -54.069488) (xy 278.017098 -54.090408) (xy 278.046806 -54.136385)
			(xy 278.069639 -54.186135) (xy 278.085127 -54.238638) (xy 278.092952 -54.292816) (xy 278.093424 -54.320186)
			(xy 278.092938 -54.347437) (xy 278.085182 -54.401385) (xy 278.069827 -54.45368) (xy 278.047185 -54.503257)
			(xy 278.017719 -54.549107) (xy 277.982028 -54.590298) (xy 277.940837 -54.625989) (xy 277.894987 -54.655455)
			(xy 277.84541 -54.678097) (xy 277.793115 -54.693452) (xy 277.739167 -54.701208) (xy 277.684665 -54.701208)
			(xy 277.630717 -54.693452) (xy 277.578422 -54.678097) (xy 277.528845 -54.655455) (xy 277.482995 -54.625989)
			(xy 277.441804 -54.590298) (xy 277.406113 -54.549107) (xy 277.376647 -54.503257) (xy 277.354005 -54.45368)
			(xy 277.33865 -54.401385) (xy 277.330894 -54.347437) (xy 277.330408 -54.320186) (xy 275.101848 -54.320186)
			(xy 275.092793 -54.3399) (xy 275.063065 -54.385867) (xy 275.045424 -54.4068) (xy 275.039328 -54.413912)
			(xy 275.03628 -54.422294) (xy 275.034752 -54.42658) (xy 275.033087 -54.435525) (xy 275.032978 -54.440074)
			(xy 275.032978 -54.50713) (xy 275.033099 -54.511678) (xy 275.034755 -54.520624) (xy 275.03628 -54.52491)
			(xy 275.039328 -54.533292) (xy 275.045424 -54.540404) (xy 275.063065 -54.561336) (xy 275.092788 -54.607303)
			(xy 275.11563 -54.65705) (xy 275.131118 -54.709553) (xy 275.138936 -54.763732) (xy 275.139052 -54.770528)
			(xy 278.27097 -54.770528) (xy 278.271435 -54.743158) (xy 278.279251 -54.688978) (xy 278.294739 -54.636474)
			(xy 278.317581 -54.586727) (xy 278.347308 -54.540761) (xy 278.36495 -54.51983) (xy 278.365204 -54.519576)
			(xy 278.370807 -54.512501) (xy 278.377044 -54.495575) (xy 278.377396 -54.486556) (xy 278.377396 -54.4195)
			(xy 278.37704 -54.410483) (xy 278.370792 -54.393566) (xy 278.365204 -54.38648) (xy 278.36495 -54.38648)
			(xy 278.36495 -54.386226) (xy 278.347317 -54.365289) (xy 278.317603 -54.319318) (xy 278.294765 -54.269572)
			(xy 278.279272 -54.217072) (xy 278.271444 -54.162897) (xy 278.27097 -54.135528) (xy 278.271456 -54.108277)
			(xy 278.279212 -54.054329) (xy 278.294567 -54.002034) (xy 278.317209 -53.952457) (xy 278.346675 -53.906607)
			(xy 278.382366 -53.865416) (xy 278.423557 -53.829725) (xy 278.469407 -53.800259) (xy 278.518984 -53.777617)
			(xy 278.571279 -53.762262) (xy 278.625227 -53.754506) (xy 278.679729 -53.754506) (xy 278.733677 -53.762262)
			(xy 278.785972 -53.777617) (xy 278.835549 -53.800259) (xy 278.881399 -53.829725) (xy 278.92259 -53.865416)
			(xy 278.958281 -53.906607) (xy 278.987747 -53.952457) (xy 279.006509 -53.993538) (xy 282.8968 -53.993538)
			(xy 282.8968 -53.933602) (xy 282.904623 -53.87418) (xy 282.920136 -53.816287) (xy 282.943072 -53.760914)
			(xy 282.973039 -53.709008) (xy 283.009526 -53.661458) (xy 283.051906 -53.619078) (xy 283.099456 -53.582591)
			(xy 283.151362 -53.552624) (xy 283.206735 -53.529688) (xy 283.264628 -53.514175) (xy 283.32405 -53.506352)
			(xy 283.383986 -53.506352) (xy 283.443408 -53.514175) (xy 283.501301 -53.529688) (xy 283.556674 -53.552624)
			(xy 283.60858 -53.582591) (xy 283.65613 -53.619078) (xy 283.69851 -53.661458) (xy 283.734997 -53.709008)
			(xy 283.764964 -53.760914) (xy 283.7879 -53.816287) (xy 283.803413 -53.87418) (xy 283.811236 -53.933602)
			(xy 283.811726 -53.96357) (xy 283.811236 -53.993538) (xy 283.803413 -54.05296) (xy 283.799529 -54.067456)
			(xy 285.14116 -54.067456) (xy 285.145231 -54.011834) (xy 285.157357 -53.957397) (xy 285.17728 -53.905306)
			(xy 285.204576 -53.856671) (xy 285.238662 -53.812528) (xy 285.278811 -53.773819) (xy 285.324169 -53.741368)
			(xy 285.373769 -53.715867) (xy 285.426553 -53.69786) (xy 285.481396 -53.68773) (xy 285.53713 -53.685693)
			(xy 285.592567 -53.691793) (xy 285.646524 -53.705899) (xy 285.697853 -53.727711) (xy 285.745459 -53.756765)
			(xy 285.788327 -53.79244) (xy 285.825544 -53.833977) (xy 285.856317 -53.88049) (xy 285.879989 -53.930987)
			(xy 285.896057 -53.984394) (xy 285.904177 -54.03957) (xy 285.904686 -54.067456) (xy 285.904177 -54.095342)
			(xy 285.896057 -54.150518) (xy 285.879989 -54.203925) (xy 285.863591 -54.238906) (xy 292.5859 -54.238906)
			(xy 292.589971 -54.183284) (xy 292.602097 -54.128847) (xy 292.62202 -54.076756) (xy 292.649316 -54.028121)
			(xy 292.683402 -53.983978) (xy 292.723551 -53.945269) (xy 292.768909 -53.912818) (xy 292.818509 -53.887317)
			(xy 292.871293 -53.86931) (xy 292.926136 -53.85918) (xy 292.98187 -53.857143) (xy 293.037307 -53.863243)
			(xy 293.091264 -53.877349) (xy 293.142593 -53.899161) (xy 293.190199 -53.928215) (xy 293.233067 -53.96389)
			(xy 293.270284 -54.005427) (xy 293.301057 -54.05194) (xy 293.324729 -54.102437) (xy 293.340797 -54.155844)
			(xy 293.348917 -54.21102) (xy 293.349426 -54.238906) (xy 293.348917 -54.266792) (xy 293.340797 -54.321968)
			(xy 293.324729 -54.375375) (xy 293.301057 -54.425872) (xy 293.270284 -54.472385) (xy 293.233067 -54.513922)
			(xy 293.190199 -54.549597) (xy 293.142593 -54.578651) (xy 293.091264 -54.600463) (xy 293.037307 -54.614569)
			(xy 292.98187 -54.620669) (xy 292.926136 -54.618632) (xy 292.871293 -54.608502) (xy 292.818509 -54.590495)
			(xy 292.768909 -54.564994) (xy 292.723551 -54.532543) (xy 292.683402 -54.493834) (xy 292.649316 -54.449691)
			(xy 292.62202 -54.401056) (xy 292.602097 -54.348965) (xy 292.589971 -54.294528) (xy 292.5859 -54.238906)
			(xy 285.863591 -54.238906) (xy 285.856317 -54.254422) (xy 285.825544 -54.300935) (xy 285.788327 -54.342472)
			(xy 285.745459 -54.378147) (xy 285.697853 -54.407201) (xy 285.646524 -54.429013) (xy 285.592567 -54.443119)
			(xy 285.53713 -54.449219) (xy 285.481396 -54.447182) (xy 285.426553 -54.437052) (xy 285.373769 -54.419045)
			(xy 285.324169 -54.393544) (xy 285.278811 -54.361093) (xy 285.238662 -54.322384) (xy 285.204576 -54.278241)
			(xy 285.17728 -54.229606) (xy 285.157357 -54.177515) (xy 285.145231 -54.123078) (xy 285.14116 -54.067456)
			(xy 283.799529 -54.067456) (xy 283.7879 -54.110853) (xy 283.764964 -54.166226) (xy 283.734997 -54.218132)
			(xy 283.69851 -54.265682) (xy 283.65613 -54.308062) (xy 283.60858 -54.344549) (xy 283.556674 -54.374516)
			(xy 283.501301 -54.397452) (xy 283.443408 -54.412965) (xy 283.383986 -54.420788) (xy 283.32405 -54.420788)
			(xy 283.264628 -54.412965) (xy 283.206735 -54.397452) (xy 283.151362 -54.374516) (xy 283.099456 -54.344549)
			(xy 283.051906 -54.308062) (xy 283.009526 -54.265682) (xy 282.973039 -54.218132) (xy 282.943072 -54.166226)
			(xy 282.920136 -54.110853) (xy 282.904623 -54.05296) (xy 282.8968 -53.993538) (xy 279.006509 -53.993538)
			(xy 279.010389 -54.002034) (xy 279.025744 -54.054329) (xy 279.0335 -54.108277) (xy 279.033986 -54.135528)
			(xy 279.03354 -54.162899) (xy 279.025718 -54.217079) (xy 279.010224 -54.269583) (xy 278.987378 -54.319329)
			(xy 278.957649 -54.365295) (xy 278.940006 -54.386226) (xy 278.939752 -54.38648) (xy 278.934162 -54.393564)
			(xy 278.927919 -54.410483) (xy 278.92756 -54.4195) (xy 278.92756 -54.486556) (xy 278.927925 -54.495572)
			(xy 278.934166 -54.51249) (xy 278.939752 -54.519576) (xy 278.940006 -54.519576) (xy 278.940006 -54.51983)
			(xy 278.957627 -54.540777) (xy 278.987341 -54.586746) (xy 279.01018 -54.636489) (xy 279.025676 -54.688987)
			(xy 279.033509 -54.74316) (xy 279.033986 -54.770528) (xy 279.0335 -54.797779) (xy 279.025744 -54.851727)
			(xy 279.010389 -54.904022) (xy 278.987747 -54.953599) (xy 278.958281 -54.999449) (xy 278.92259 -55.04064)
			(xy 278.881399 -55.076331) (xy 278.870312 -55.083456) (xy 285.14116 -55.083456) (xy 285.145231 -55.027834)
			(xy 285.157357 -54.973397) (xy 285.17728 -54.921306) (xy 285.204576 -54.872671) (xy 285.238662 -54.828528)
			(xy 285.278811 -54.789819) (xy 285.324169 -54.757368) (xy 285.373769 -54.731867) (xy 285.426553 -54.71386)
			(xy 285.481396 -54.70373) (xy 285.53713 -54.701693) (xy 285.592567 -54.707793) (xy 285.646524 -54.721899)
			(xy 285.697853 -54.743711) (xy 285.745459 -54.772765) (xy 285.788327 -54.80844) (xy 285.825544 -54.849977)
			(xy 285.856317 -54.89649) (xy 285.879989 -54.946987) (xy 285.892646 -54.989055) (xy 288.100945 -54.989055)
			(xy 288.100945 -54.934545) (xy 288.108703 -54.880591) (xy 288.12406 -54.82829) (xy 288.146705 -54.778707)
			(xy 288.176176 -54.732851) (xy 288.211874 -54.691657) (xy 288.25307 -54.655962) (xy 288.298928 -54.626494)
			(xy 288.348512 -54.603852) (xy 288.400814 -54.588498) (xy 288.454769 -54.580743) (xy 288.482024 -54.580282)
			(xy 288.510116 -54.580758) (xy 288.565694 -54.588988) (xy 288.619464 -54.605283) (xy 288.670261 -54.629289)
			(xy 288.716988 -54.660486) (xy 288.758632 -54.698201) (xy 288.794294 -54.741616) (xy 288.809176 -54.765448)
			(xy 288.81451 -54.774338) (xy 288.831528 -54.78653) (xy 288.924746 -54.80685) (xy 288.94532 -54.802532)
			(xy 288.953956 -54.79669) (xy 288.97803 -54.780705) (xy 289.029958 -54.755359) (xy 289.085113 -54.73813)
			(xy 289.142234 -54.729409) (xy 289.171126 -54.728872) (xy 289.198377 -54.729354) (xy 289.252324 -54.737113)
			(xy 289.304617 -54.752471) (xy 289.354193 -54.775113) (xy 289.400043 -54.80458) (xy 289.441232 -54.840272)
			(xy 289.476923 -54.881462) (xy 289.50639 -54.927312) (xy 289.529032 -54.976888) (xy 289.544388 -55.029182)
			(xy 289.552147 -55.083129) (xy 289.552634 -55.11038) (xy 289.552172 -55.137751) (xy 289.544356 -55.19193)
			(xy 289.528867 -55.244434) (xy 289.506024 -55.294181) (xy 289.476297 -55.340147) (xy 289.458654 -55.361078)
			(xy 289.4584 -55.361332) (xy 289.452836 -55.368434) (xy 289.446576 -55.385339) (xy 289.446208 -55.394352)
			(xy 289.446208 -55.461408) (xy 289.446559 -55.470425) (xy 289.452811 -55.487342) (xy 289.4584 -55.494428)
			(xy 289.458654 -55.494428) (xy 289.458654 -55.494682) (xy 289.476276 -55.51563) (xy 289.506003 -55.561595)
			(xy 289.528851 -55.611338) (xy 289.544349 -55.663838) (xy 289.55218 -55.718015) (xy 289.552182 -55.772755)
			(xy 289.544356 -55.826932) (xy 289.528861 -55.879433) (xy 289.506017 -55.929179) (xy 289.476294 -55.975146)
			(xy 289.458654 -55.996078) (xy 289.4584 -55.996332) (xy 289.452836 -56.003434) (xy 289.446576 -56.020339)
			(xy 289.446208 -56.029352) (xy 289.446208 -56.096408) (xy 289.446559 -56.105425) (xy 289.452811 -56.122342)
			(xy 289.4584 -56.129428) (xy 289.458654 -56.129428) (xy 289.458654 -56.129682) (xy 289.476291 -56.150616)
			(xy 289.506005 -56.196588) (xy 289.528842 -56.246334) (xy 289.544333 -56.298835) (xy 289.552161 -56.353011)
			(xy 289.552634 -56.38038) (xy 289.552148 -56.407631) (xy 289.544392 -56.461579) (xy 289.529037 -56.513874)
			(xy 289.506395 -56.563451) (xy 289.476929 -56.609301) (xy 289.441238 -56.650492) (xy 289.400047 -56.686183)
			(xy 289.354197 -56.715649) (xy 289.30462 -56.738291) (xy 289.252325 -56.753646) (xy 289.198377 -56.761402)
			(xy 289.143875 -56.761402) (xy 289.089927 -56.753646) (xy 289.037632 -56.738291) (xy 288.988055 -56.715649)
			(xy 288.942205 -56.686183) (xy 288.901014 -56.650492) (xy 288.865323 -56.609301) (xy 288.835857 -56.563451)
			(xy 288.813215 -56.513874) (xy 288.79786 -56.461579) (xy 288.790104 -56.407631) (xy 288.789618 -56.38038)
			(xy 288.790068 -56.353009) (xy 288.797889 -56.298829) (xy 288.813382 -56.246326) (xy 288.836227 -56.196579)
			(xy 288.865955 -56.150613) (xy 288.883598 -56.129682) (xy 288.883852 -56.129428) (xy 288.889439 -56.122342)
			(xy 288.895684 -56.105425) (xy 288.896044 -56.096408) (xy 288.896044 -56.029352) (xy 288.895674 -56.020336)
			(xy 288.889437 -56.003418) (xy 288.883852 -55.996332) (xy 288.883598 -55.996332) (xy 288.883598 -55.996078)
			(xy 288.865939 -55.975161) (xy 288.836217 -55.929189) (xy 288.813375 -55.87944) (xy 288.797881 -55.826936)
			(xy 288.790055 -55.772756) (xy 288.790057 -55.718014) (xy 288.797888 -55.663834) (xy 288.813385 -55.611331)
			(xy 288.836232 -55.561584) (xy 288.865957 -55.515615) (xy 288.883598 -55.494682) (xy 288.883852 -55.494428)
			(xy 288.889439 -55.487342) (xy 288.895684 -55.470425) (xy 288.896044 -55.461408) (xy 288.896044 -55.394352)
			(xy 288.895674 -55.385336) (xy 288.889437 -55.368418) (xy 288.883852 -55.361332) (xy 288.883598 -55.360824)
			(xy 288.872654 -55.348089) (xy 288.852813 -55.320998) (xy 288.843974 -55.306722) (xy 288.83864 -55.297832)
			(xy 288.821622 -55.28564) (xy 288.728404 -55.26532) (xy 288.70783 -55.269638) (xy 288.699194 -55.27548)
			(xy 288.675132 -55.291483) (xy 288.6232 -55.316825) (xy 288.568041 -55.33405) (xy 288.510917 -55.342764)
			(xy 288.482024 -55.343298) (xy 288.454769 -55.342857) (xy 288.400814 -55.335102) (xy 288.348512 -55.319748)
			(xy 288.298928 -55.297106) (xy 288.25307 -55.267638) (xy 288.211874 -55.231943) (xy 288.176176 -55.190749)
			(xy 288.146705 -55.144893) (xy 288.12406 -55.09531) (xy 288.108703 -55.043009) (xy 288.100945 -54.989055)
			(xy 285.892646 -54.989055) (xy 285.896057 -55.000394) (xy 285.904177 -55.05557) (xy 285.904686 -55.083456)
			(xy 285.904177 -55.111342) (xy 285.896057 -55.166518) (xy 285.879989 -55.219925) (xy 285.856317 -55.270422)
			(xy 285.825544 -55.316935) (xy 285.788327 -55.358472) (xy 285.745459 -55.394147) (xy 285.701697 -55.420855)
			(xy 286.424545 -55.420855) (xy 286.424545 -55.366345) (xy 286.432303 -55.312391) (xy 286.44766 -55.26009)
			(xy 286.470305 -55.210507) (xy 286.499776 -55.164651) (xy 286.535474 -55.123457) (xy 286.57667 -55.087762)
			(xy 286.622528 -55.058294) (xy 286.672112 -55.035652) (xy 286.724414 -55.020298) (xy 286.778369 -55.012543)
			(xy 286.805624 -55.012082) (xy 286.831938 -55.012539) (xy 286.884067 -55.019777) (xy 286.93471 -55.034098)
			(xy 286.982908 -55.055233) (xy 287.027752 -55.08278) (xy 287.068391 -55.11622) (xy 287.086548 -55.135272)
			(xy 287.094053 -55.142693) (xy 287.113346 -55.151207) (xy 287.123886 -55.151782) (xy 287.198562 -55.151782)
			(xy 287.209112 -55.151251) (xy 287.228407 -55.142718) (xy 287.2359 -55.135272) (xy 287.254057 -55.116218)
			(xy 287.294687 -55.082762) (xy 287.339527 -55.055203) (xy 287.387728 -55.034065) (xy 287.438375 -55.019747)
			(xy 287.490508 -55.012521) (xy 287.516824 -55.012082) (xy 287.544073 -55.01259) (xy 287.598017 -55.020349)
			(xy 287.650307 -55.035706) (xy 287.69988 -55.058348) (xy 287.745726 -55.087814) (xy 287.786913 -55.123504)
			(xy 287.822601 -55.164693) (xy 287.852064 -55.210541) (xy 287.874703 -55.260115) (xy 287.890056 -55.312406)
			(xy 287.897812 -55.366351) (xy 287.897812 -55.420849) (xy 287.890056 -55.474794) (xy 287.874703 -55.527085)
			(xy 287.852064 -55.576659) (xy 287.822601 -55.622507) (xy 287.786913 -55.663696) (xy 287.745726 -55.699386)
			(xy 287.69988 -55.728852) (xy 287.650307 -55.751494) (xy 287.598017 -55.766851) (xy 287.544073 -55.77461)
			(xy 287.516824 -55.775098) (xy 287.490511 -55.774615) (xy 287.438383 -55.767384) (xy 287.38774 -55.753068)
			(xy 287.339541 -55.731938) (xy 287.294697 -55.704395) (xy 287.254057 -55.670958) (xy 287.2359 -55.651908)
			(xy 287.228379 -55.644506) (xy 287.209099 -55.635981) (xy 287.198562 -55.635398) (xy 287.123886 -55.635398)
			(xy 287.113334 -55.635907) (xy 287.094039 -55.644456) (xy 287.086548 -55.651908) (xy 287.068412 -55.670983)
			(xy 287.027778 -55.704438) (xy 286.982934 -55.731995) (xy 286.934729 -55.75313) (xy 286.884078 -55.767443)
			(xy 286.831941 -55.774662) (xy 286.805624 -55.775098) (xy 286.778369 -55.774657) (xy 286.724414 -55.766902)
			(xy 286.672112 -55.751548) (xy 286.622528 -55.728906) (xy 286.57667 -55.699438) (xy 286.535474 -55.663743)
			(xy 286.499776 -55.622549) (xy 286.470305 -55.576693) (xy 286.44766 -55.52711) (xy 286.432303 -55.474809)
			(xy 286.424545 -55.420855) (xy 285.701697 -55.420855) (xy 285.697853 -55.423201) (xy 285.646524 -55.445013)
			(xy 285.592567 -55.459119) (xy 285.53713 -55.465219) (xy 285.481396 -55.463182) (xy 285.426553 -55.453052)
			(xy 285.373769 -55.435045) (xy 285.324169 -55.409544) (xy 285.278811 -55.377093) (xy 285.238662 -55.338384)
			(xy 285.204576 -55.294241) (xy 285.17728 -55.245606) (xy 285.157357 -55.193515) (xy 285.145231 -55.139078)
			(xy 285.14116 -55.083456) (xy 278.870312 -55.083456) (xy 278.835549 -55.105797) (xy 278.785972 -55.128439)
			(xy 278.733677 -55.143794) (xy 278.679729 -55.15155) (xy 278.625227 -55.15155) (xy 278.571279 -55.143794)
			(xy 278.518984 -55.128439) (xy 278.469407 -55.105797) (xy 278.423557 -55.076331) (xy 278.382366 -55.04064)
			(xy 278.346675 -54.999449) (xy 278.317209 -54.953599) (xy 278.294567 -54.904022) (xy 278.279212 -54.851727)
			(xy 278.271456 -54.797779) (xy 278.27097 -54.770528) (xy 275.139052 -54.770528) (xy 275.139404 -54.791102)
			(xy 275.138918 -54.818353) (xy 275.131162 -54.872301) (xy 275.115807 -54.924596) (xy 275.093165 -54.974173)
			(xy 275.063699 -55.020023) (xy 275.028008 -55.061214) (xy 274.986817 -55.096905) (xy 274.940967 -55.126371)
			(xy 274.89139 -55.149013) (xy 274.839095 -55.164368) (xy 274.785147 -55.172124) (xy 274.730645 -55.172124)
			(xy 274.676697 -55.164368) (xy 274.624402 -55.149013) (xy 274.574825 -55.126371) (xy 274.528975 -55.096905)
			(xy 274.487784 -55.061214) (xy 274.452093 -55.020023) (xy 274.422627 -54.974173) (xy 274.399985 -54.924596)
			(xy 274.38463 -54.872301) (xy 274.376874 -54.818353) (xy 274.376388 -54.791102) (xy 274.37686 -54.763732)
			(xy 274.384683 -54.709553) (xy 274.400169 -54.657049) (xy 274.423001 -54.607297) (xy 274.452709 -54.56132)
			(xy 274.470368 -54.540404) (xy 274.476464 -54.533292) (xy 274.479512 -54.52491) (xy 274.481041 -54.520624)
			(xy 274.482707 -54.511679) (xy 274.482814 -54.50713) (xy 274.482814 -54.440074) (xy 274.482694 -54.435526)
			(xy 274.481042 -54.426579) (xy 274.479512 -54.422294) (xy 274.476464 -54.413912) (xy 274.470368 -54.4068)
			(xy 274.452725 -54.385868) (xy 274.422997 -54.339901) (xy 274.400149 -54.290155) (xy 274.384651 -54.237652)
			(xy 274.376821 -54.183473) (xy 274.376821 -54.12873) (xy 274.38465 -54.074551) (xy 274.400148 -54.022048)
			(xy 274.422996 -53.972302) (xy 274.452724 -53.926334) (xy 274.470368 -53.905404) (xy 274.476464 -53.898292)
			(xy 274.479512 -53.88991) (xy 274.481041 -53.885624) (xy 274.482707 -53.876679) (xy 274.482814 -53.87213)
			(xy 274.482814 -53.79593) (xy 274.48002 -53.788564) (xy 274.459948 -53.766853) (xy 274.425969 -53.718468)
			(xy 274.399761 -53.665469) (xy 274.381936 -53.609096) (xy 274.37291 -53.550664) (xy 274.372324 -53.521102)
			(xy 274.372757 -53.494703) (xy 274.379965 -53.4424) (xy 274.394245 -53.39157) (xy 274.41533 -53.343166)
			(xy 274.442826 -53.298093) (xy 274.476218 -53.257196) (xy 274.49526 -53.238908) (xy 274.497016 -53.234341)
			(xy 274.498936 -53.224749) (xy 274.49907 -53.219858) (xy 274.49907 -53.187854) (xy 274.498308 -53.17871)
			(xy 274.497292 -53.1749) (xy 274.495399 -53.168421) (xy 274.488708 -53.156703) (xy 274.484084 -53.151786)
			(xy 274.483068 -53.15077) (xy 274.471384 -53.137816) (xy 274.464095 -53.130862) (xy 274.445628 -53.122856)
			(xy 274.43557 -53.122322) (xy 272.522696 -53.122322) (xy 272.513887 -53.12274) (xy 272.497332 -53.128783)
			(xy 272.483787 -53.140057) (xy 272.479008 -53.147468) (xy 272.434558 -53.22316) (xy 272.431393 -53.229097)
			(xy 272.427922 -53.24209) (xy 272.4277 -53.248814) (xy 272.4277 -53.262022) (xy 272.429478 -53.265324)
			(xy 272.434304 -53.273706) (xy 272.446 -53.295242) (xy 272.464418 -53.340657) (xy 272.476878 -53.388053)
			(xy 272.483175 -53.436655) (xy 272.48358 -53.461158) (xy 272.48358 -53.461412) (xy 272.483107 -53.488782)
			(xy 272.475282 -53.542959) (xy 272.459793 -53.595461) (xy 272.436958 -53.64521) (xy 272.407248 -53.691185)
			(xy 272.3896 -53.71211) (xy 272.383504 -53.719222) (xy 272.380456 -53.727604) (xy 272.378935 -53.731892)
			(xy 272.377273 -53.740836) (xy 272.377154 -53.745384) (xy 272.377154 -53.81244) (xy 272.377275 -53.816988)
			(xy 272.378932 -53.825933) (xy 272.380456 -53.83022) (xy 272.383504 -53.838602) (xy 272.3896 -53.845714)
			(xy 272.407239 -53.866647) (xy 272.43696 -53.912615) (xy 272.459802 -53.962361) (xy 272.475295 -54.014862)
			(xy 272.483122 -54.069039) (xy 272.483121 -54.123779) (xy 272.475291 -54.177955) (xy 272.459795 -54.230456)
			(xy 272.436951 -54.2802) (xy 272.407228 -54.326167) (xy 272.3896 -54.34711) (xy 272.383504 -54.354222)
			(xy 272.380456 -54.362604) (xy 272.378935 -54.366892) (xy 272.377273 -54.375836) (xy 272.377154 -54.380384)
			(xy 272.377154 -54.44744) (xy 272.377275 -54.451988) (xy 272.378932 -54.460933) (xy 272.380456 -54.46522)
			(xy 272.383504 -54.473602) (xy 272.3896 -54.480714) (xy 272.407241 -54.501646) (xy 272.436966 -54.547612)
			(xy 272.459807 -54.597359) (xy 272.475295 -54.649863) (xy 272.483112 -54.704042) (xy 272.48358 -54.731412)
			(xy 272.483094 -54.758663) (xy 272.475338 -54.812611) (xy 272.459983 -54.864906) (xy 272.437341 -54.914483)
			(xy 272.407875 -54.960333) (xy 272.372184 -55.001524) (xy 272.330993 -55.037215) (xy 272.285143 -55.066681)
			(xy 272.235566 -55.089323) (xy 272.183271 -55.104678) (xy 272.129323 -55.112434) (xy 272.074821 -55.112434)
			(xy 272.020873 -55.104678) (xy 271.968578 -55.089323) (xy 271.919001 -55.066681) (xy 271.873151 -55.037215)
			(xy 271.83196 -55.001524) (xy 271.796269 -54.960333) (xy 271.766803 -54.914483) (xy 271.744161 -54.864906)
			(xy 271.728806 -54.812611) (xy 271.72105 -54.758663) (xy 271.720564 -54.731412) (xy 271.721042 -54.704045)
			(xy 271.728878 -54.649873) (xy 271.744377 -54.597378) (xy 271.76722 -54.547638) (xy 271.796939 -54.501673)
			(xy 271.814544 -54.480714) (xy 271.82064 -54.473602) (xy 271.823688 -54.46522) (xy 271.82521 -54.460932)
			(xy 271.826875 -54.451988) (xy 271.82699 -54.44744) (xy 271.82699 -54.380384) (xy 271.826862 -54.375837)
			(xy 271.825194 -54.366896) (xy 271.823688 -54.362604) (xy 271.82064 -54.354222) (xy 271.814544 -54.34711)
			(xy 271.796902 -54.326178) (xy 271.767174 -54.28021) (xy 271.744326 -54.230463) (xy 271.728827 -54.17796)
			(xy 271.720997 -54.12378) (xy 271.720996 -54.069038) (xy 271.728823 -54.014857) (xy 271.74432 -53.962354)
			(xy 271.767165 -53.912606) (xy 271.796891 -53.866637) (xy 271.814544 -53.845714) (xy 271.82064 -53.838602)
			(xy 271.823688 -53.83022) (xy 271.82521 -53.825932) (xy 271.826875 -53.816988) (xy 271.82699 -53.81244)
			(xy 271.82699 -53.745384) (xy 271.826862 -53.740837) (xy 271.825194 -53.731896) (xy 271.823688 -53.727604)
			(xy 271.82064 -53.719222) (xy 271.814544 -53.71211) (xy 271.7969 -53.69118) (xy 271.767169 -53.645214)
			(xy 271.744322 -53.595468) (xy 271.728828 -53.542964) (xy 271.721007 -53.488783) (xy 271.720564 -53.461412)
			(xy 271.720564 -53.461158) (xy 271.72094 -53.436652) (xy 271.727221 -53.388045) (xy 271.739685 -53.340644)
			(xy 271.758127 -53.295235) (xy 271.76984 -53.273706) (xy 271.774666 -53.265324) (xy 271.776444 -53.262022)
			(xy 271.776444 -53.248814) (xy 271.77627 -53.242083) (xy 271.772788 -53.229083) (xy 271.769586 -53.22316)
			(xy 271.725136 -53.147468) (xy 271.720375 -53.140034) (xy 271.706844 -53.12872) (xy 271.690267 -53.122694)
			(xy 271.681448 -53.122322) (xy 265.765534 -53.122322) (xy 265.756972 -53.122704) (xy 265.740828 -53.12843)
			(xy 265.72745 -53.139127) (xy 265.722608 -53.146198) (xy 265.687302 -53.20792) (xy 265.67765 -53.224684)
			(xy 265.674561 -53.230503) (xy 265.67123 -53.243244) (xy 265.671046 -53.24983) (xy 265.671046 -53.263546)
			(xy 265.678158 -53.275484) (xy 265.690712 -53.297591) (xy 265.710492 -53.344425) (xy 265.723865 -53.393474)
			(xy 265.730592 -53.443866) (xy 265.73099 -53.469286) (xy 265.73099 -53.475382) (xy 265.730093 -53.502347)
			(xy 265.72164 -53.555631) (xy 265.705764 -53.607193) (xy 265.68278 -53.656004) (xy 265.653148 -53.701088)
			(xy 265.617458 -53.741548) (xy 265.576424 -53.776575) (xy 265.530863 -53.805471) (xy 265.481686 -53.827658)
			(xy 265.429873 -53.842694) (xy 265.376458 -53.85028) (xy 265.349482 -53.850794) (xy 265.322112 -53.850321)
			(xy 265.267936 -53.842495) (xy 265.215434 -53.827006) (xy 265.165684 -53.804171) (xy 265.119709 -53.774461)
			(xy 265.098784 -53.756814) (xy 265.091672 -53.750718) (xy 265.08329 -53.74767) (xy 265.079004 -53.746143)
			(xy 265.070059 -53.744481) (xy 265.06551 -53.744368) (xy 264.998454 -53.744368) (xy 264.993906 -53.74449)
			(xy 264.984961 -53.746148) (xy 264.980674 -53.74767) (xy 264.972292 -53.750718) (xy 264.96518 -53.756814)
			(xy 264.944248 -53.774454) (xy 264.898281 -53.804177) (xy 264.848534 -53.827017) (xy 264.796031 -53.842503)
			(xy 264.741852 -53.850319) (xy 264.714482 -53.850794) (xy 264.687506 -53.850327) (xy 264.634093 -53.842725)
			(xy 264.582282 -53.827676) (xy 264.533108 -53.805479) (xy 264.487551 -53.776577) (xy 264.446519 -53.741546)
			(xy 264.41083 -53.701085) (xy 264.381196 -53.656) (xy 264.358207 -53.607191) (xy 264.342323 -53.555631)
			(xy 264.333859 -53.502347) (xy 264.332974 -53.475382) (xy 264.332974 -53.469286) (xy 264.333399 -53.443869)
			(xy 264.340152 -53.393486) (xy 264.353524 -53.344442) (xy 264.373279 -53.297604) (xy 264.385806 -53.275484)
			(xy 264.389362 -53.269642) (xy 264.392918 -53.256434) (xy 264.392918 -53.24983) (xy 264.392711 -53.243248)
			(xy 264.389372 -53.230515) (xy 264.386314 -53.224684) (xy 264.376662 -53.20792) (xy 264.341356 -53.146198)
			(xy 264.336544 -53.139094) (xy 264.323176 -53.128358) (xy 264.307003 -53.122662) (xy 264.29843 -53.122322)
			(xy 259.938012 -53.122322) (xy 259.929818 -53.12263) (xy 259.914271 -53.127811) (xy 259.907532 -53.132482)
			(xy 259.900674 -53.137562) (xy 259.891784 -53.15077) (xy 259.889244 -53.158898) (xy 259.881124 -53.184915)
			(xy 259.858486 -53.234493) (xy 259.829023 -53.280344) (xy 259.793334 -53.321536) (xy 259.752146 -53.357228)
			(xy 259.706297 -53.386696) (xy 259.656721 -53.409338) (xy 259.604428 -53.424694) (xy 259.550481 -53.43245)
			(xy 259.495979 -53.43245) (xy 259.442032 -53.424694) (xy 259.389739 -53.409338) (xy 259.340163 -53.386696)
			(xy 259.294314 -53.357228) (xy 259.253126 -53.321536) (xy 259.217437 -53.280344) (xy 259.187974 -53.234493)
			(xy 259.165336 -53.184915) (xy 259.157216 -53.158898) (xy 259.157216 -53.158644) (xy 259.154617 -53.150922)
			(xy 259.145289 -53.137574) (xy 259.138928 -53.132482) (xy 259.132324 -53.127402) (xy 259.11683 -53.122322)
			(xy 250.984258 -53.122322) (xy 250.976361 -53.122649) (xy 250.961345 -53.127554) (xy 250.954794 -53.131974)
			(xy 250.948444 -53.136292) (xy 250.9393 -53.148738) (xy 250.936506 -53.156612) (xy 250.926282 -53.185087)
			(xy 250.899377 -53.239277) (xy 250.865558 -53.289445) (xy 250.825418 -53.334713) (xy 250.779658 -53.374291)
			(xy 250.754642 -53.391308) (xy 250.745498 -53.39715) (xy 250.73991 -53.405786) (xy 250.737232 -53.410114)
			(xy 250.733513 -53.419586) (xy 250.732544 -53.424582) (xy 250.719844 -53.49875) (xy 250.719129 -53.504024)
			(xy 250.719639 -53.514652) (xy 250.72086 -53.519832) (xy 250.723146 -53.52923) (xy 250.72975 -53.537866)
			(xy 250.74464 -53.55792) (xy 250.769639 -53.601163) (xy 250.788784 -53.647296) (xy 250.80175 -53.695533)
			(xy 250.808313 -53.745048) (xy 250.808744 -53.770022) (xy 250.808744 -53.77053) (xy 250.808256 -53.797781)
			(xy 250.800496 -53.851727) (xy 250.785139 -53.90402) (xy 250.762497 -53.953596) (xy 250.73303 -53.999445)
			(xy 250.697339 -54.040635) (xy 250.65615 -54.076327) (xy 250.610301 -54.105794) (xy 250.560726 -54.128437)
			(xy 250.508433 -54.143795) (xy 250.454487 -54.151556) (xy 250.427236 -54.152038) (xy 250.399868 -54.151562)
			(xy 250.345695 -54.143729) (xy 250.293198 -54.128232) (xy 250.243455 -54.105392) (xy 250.197488 -54.075675)
			(xy 250.176538 -54.058058) (xy 250.169426 -54.051962) (xy 250.161044 -54.048914) (xy 250.156755 -54.047399)
			(xy 250.147811 -54.045747) (xy 250.143264 -54.045612) (xy 250.076208 -54.045612) (xy 250.071661 -54.045738)
			(xy 250.062719 -54.047402) (xy 250.058428 -54.048914) (xy 250.050046 -54.051962) (xy 250.042934 -54.058058)
			(xy 250.022004 -54.075704) (xy 249.976039 -54.105437) (xy 249.926293 -54.128287) (xy 249.873789 -54.143784)
			(xy 249.819608 -54.151608) (xy 249.792236 -54.152038) (xy 249.764981 -54.151578) (xy 249.711024 -54.143825)
			(xy 249.65872 -54.128472) (xy 249.609134 -54.105832) (xy 249.563274 -54.076366) (xy 249.522074 -54.040672)
			(xy 249.486374 -53.999479) (xy 249.456899 -53.953624) (xy 249.434251 -53.904042) (xy 249.418889 -53.85174)
			(xy 249.411127 -53.797785) (xy 249.410728 -53.77053) (xy 249.41126 -53.741613) (xy 249.419983 -53.68444)
			(xy 249.437235 -53.629238) (xy 249.46262 -53.577272) (xy 249.495556 -53.529732) (xy 249.53529 -53.487707)
			(xy 249.557794 -53.46954) (xy 249.565172 -53.463253) (xy 249.574955 -53.446537) (xy 249.576844 -53.437028)
			(xy 249.577352 -53.429408) (xy 249.577352 -53.349652) (xy 249.576844 -53.342032) (xy 249.575082 -53.333013)
			(xy 249.56609 -53.317003) (xy 249.559318 -53.31079) (xy 249.557794 -53.30952) (xy 249.538522 -53.294013)
			(xy 249.503748 -53.258832) (xy 249.473807 -53.219455) (xy 249.4492 -53.176543) (xy 249.43943 -53.153818)
			(xy 249.435112 -53.143404) (xy 249.426984 -53.135784) (xy 249.42038 -53.130704) (xy 249.414284 -53.12664)
			(xy 249.400314 -53.122322) (xy 249.081036 -53.122322) (xy 249.080274 -53.122322) (xy 249.070241 -53.122974)
			(xy 249.051813 -53.130958) (xy 249.04446 -53.137816) (xy 249.032776 -53.15077) (xy 249.03176 -53.151786)
			(xy 249.027143 -53.156708) (xy 249.020457 -53.168425) (xy 249.018552 -53.1749) (xy 249.016774 -53.1876)
			(xy 249.016774 -53.219604) (xy 249.01691 -53.224637) (xy 249.018949 -53.234495) (xy 249.020838 -53.239162)
			(xy 249.039837 -53.257451) (xy 249.073162 -53.298323) (xy 249.100601 -53.343359) (xy 249.121642 -53.391716)
			(xy 249.135892 -53.44249) (xy 249.143084 -53.494734) (xy 249.14352 -53.521102) (xy 249.142955 -53.550665)
			(xy 249.133933 -53.609098) (xy 249.116102 -53.665471) (xy 249.089879 -53.718463) (xy 249.055878 -53.766834)
			(xy 249.035824 -53.788564) (xy 249.03303 -53.79593) (xy 249.03303 -53.87213) (xy 249.03315 -53.876678)
			(xy 249.034805 -53.885624) (xy 249.036332 -53.88991) (xy 249.03938 -53.898292) (xy 249.045476 -53.905404)
			(xy 249.063116 -53.926337) (xy 249.092841 -53.972305) (xy 249.115686 -54.022051) (xy 249.131181 -54.074553)
			(xy 249.13901 -54.128731) (xy 249.13901 -54.183472) (xy 249.131181 -54.23765) (xy 249.115685 -54.290152)
			(xy 249.101892 -54.320186) (xy 251.33046 -54.320186) (xy 251.330903 -54.292815) (xy 251.338724 -54.238634)
			(xy 251.354218 -54.18613) (xy 251.377065 -54.136384) (xy 251.406796 -54.090418) (xy 251.42444 -54.069488)
			(xy 251.424694 -54.069234) (xy 251.430272 -54.062141) (xy 251.436524 -54.045229) (xy 251.436886 -54.036214)
			(xy 251.436886 -53.969158) (xy 251.436504 -53.960144) (xy 251.430274 -53.943226) (xy 251.424694 -53.936138)
			(xy 251.42444 -53.936138) (xy 251.42444 -53.935884) (xy 251.406833 -53.914926) (xy 251.377115 -53.868961)
			(xy 251.354272 -53.81922) (xy 251.338774 -53.766725) (xy 251.330938 -53.712553) (xy 251.33046 -53.685186)
			(xy 251.330946 -53.657935) (xy 251.338702 -53.603987) (xy 251.354057 -53.551692) (xy 251.376699 -53.502115)
			(xy 251.406165 -53.456265) (xy 251.441856 -53.415074) (xy 251.483047 -53.379383) (xy 251.528897 -53.349917)
			(xy 251.578474 -53.327275) (xy 251.630769 -53.31192) (xy 251.684717 -53.304164) (xy 251.739219 -53.304164)
			(xy 251.793167 -53.31192) (xy 251.845462 -53.327275) (xy 251.895039 -53.349917) (xy 251.940889 -53.379383)
			(xy 251.98208 -53.415074) (xy 252.017771 -53.456265) (xy 252.047237 -53.502115) (xy 252.069879 -53.551692)
			(xy 252.085234 -53.603987) (xy 252.09299 -53.657935) (xy 252.093476 -53.685186) (xy 252.093008 -53.712556)
			(xy 252.085191 -53.766735) (xy 252.069703 -53.819239) (xy 252.046862 -53.868986) (xy 252.017137 -53.914952)
			(xy 251.999496 -53.935884) (xy 251.999242 -53.936138) (xy 251.993668 -53.943233) (xy 251.987415 -53.960144)
			(xy 251.98705 -53.969158) (xy 251.98705 -54.036214) (xy 251.98739 -54.045233) (xy 251.993648 -54.06215)
			(xy 251.999242 -54.069234) (xy 251.999496 -54.069234) (xy 251.999496 -54.069488) (xy 252.017142 -54.090414)
			(xy 252.046853 -54.136389) (xy 252.069688 -54.186138) (xy 252.085177 -54.23864) (xy 252.093003 -54.292816)
			(xy 252.093476 -54.320186) (xy 252.09299 -54.347437) (xy 252.085234 -54.401385) (xy 252.069879 -54.45368)
			(xy 252.047237 -54.503257) (xy 252.017771 -54.549107) (xy 251.98208 -54.590298) (xy 251.940889 -54.625989)
			(xy 251.895039 -54.655455) (xy 251.845462 -54.678097) (xy 251.793167 -54.693452) (xy 251.739219 -54.701208)
			(xy 251.684717 -54.701208) (xy 251.630769 -54.693452) (xy 251.578474 -54.678097) (xy 251.528897 -54.655455)
			(xy 251.483047 -54.625989) (xy 251.441856 -54.590298) (xy 251.406165 -54.549107) (xy 251.376699 -54.503257)
			(xy 251.354057 -54.45368) (xy 251.338702 -54.401385) (xy 251.330946 -54.347437) (xy 251.33046 -54.320186)
			(xy 249.101892 -54.320186) (xy 249.092839 -54.339898) (xy 249.063115 -54.385866) (xy 249.045476 -54.4068)
			(xy 249.03938 -54.413912) (xy 249.036332 -54.422294) (xy 249.034811 -54.426582) (xy 249.033148 -54.435526)
			(xy 249.03303 -54.440074) (xy 249.03303 -54.50713) (xy 249.03315 -54.511678) (xy 249.034805 -54.520624)
			(xy 249.036332 -54.52491) (xy 249.03938 -54.533292) (xy 249.045476 -54.540404) (xy 249.063119 -54.561335)
			(xy 249.092846 -54.607301) (xy 249.11569 -54.657048) (xy 249.131181 -54.709551) (xy 249.138999 -54.763731)
			(xy 249.139112 -54.770528) (xy 252.271022 -54.770528) (xy 252.271499 -54.743158) (xy 252.279313 -54.688979)
			(xy 252.2948 -54.636476) (xy 252.317639 -54.586729) (xy 252.347362 -54.540762) (xy 252.365002 -54.51983)
			(xy 252.365256 -54.519576) (xy 252.370865 -54.512505) (xy 252.377097 -54.495576) (xy 252.377448 -54.486556)
			(xy 252.377448 -54.4195) (xy 252.377102 -54.410482) (xy 252.370848 -54.393564) (xy 252.365256 -54.38648)
			(xy 252.365002 -54.38648) (xy 252.365002 -54.386226) (xy 252.347362 -54.365295) (xy 252.31765 -54.319322)
			(xy 252.294814 -54.269574) (xy 252.279324 -54.217073) (xy 252.271496 -54.162897) (xy 252.271022 -54.135528)
			(xy 252.271508 -54.108277) (xy 252.279264 -54.054329) (xy 252.294619 -54.002034) (xy 252.317261 -53.952457)
			(xy 252.346727 -53.906607) (xy 252.382418 -53.865416) (xy 252.423609 -53.829725) (xy 252.469459 -53.800259)
			(xy 252.519036 -53.777617) (xy 252.571331 -53.762262) (xy 252.625279 -53.754506) (xy 252.679781 -53.754506)
			(xy 252.733729 -53.762262) (xy 252.786024 -53.777617) (xy 252.835601 -53.800259) (xy 252.881451 -53.829725)
			(xy 252.922642 -53.865416) (xy 252.958333 -53.906607) (xy 252.987799 -53.952457) (xy 253.006561 -53.993538)
			(xy 256.896852 -53.993538) (xy 256.896852 -53.933602) (xy 256.904675 -53.87418) (xy 256.920188 -53.816287)
			(xy 256.943124 -53.760914) (xy 256.973091 -53.709008) (xy 257.009578 -53.661458) (xy 257.051958 -53.619078)
			(xy 257.099508 -53.582591) (xy 257.151414 -53.552624) (xy 257.206787 -53.529688) (xy 257.26468 -53.514175)
			(xy 257.324102 -53.506352) (xy 257.384038 -53.506352) (xy 257.44346 -53.514175) (xy 257.501353 -53.529688)
			(xy 257.556726 -53.552624) (xy 257.608632 -53.582591) (xy 257.656182 -53.619078) (xy 257.698562 -53.661458)
			(xy 257.735049 -53.709008) (xy 257.765016 -53.760914) (xy 257.787952 -53.816287) (xy 257.803465 -53.87418)
			(xy 257.811288 -53.933602) (xy 257.811778 -53.96357) (xy 257.811288 -53.993538) (xy 257.803465 -54.05296)
			(xy 257.799581 -54.067456) (xy 259.141212 -54.067456) (xy 259.145283 -54.011834) (xy 259.157409 -53.957397)
			(xy 259.177332 -53.905306) (xy 259.204628 -53.856671) (xy 259.238714 -53.812528) (xy 259.278863 -53.773819)
			(xy 259.324221 -53.741368) (xy 259.373821 -53.715867) (xy 259.426605 -53.69786) (xy 259.481448 -53.68773)
			(xy 259.537182 -53.685693) (xy 259.592619 -53.691793) (xy 259.646576 -53.705899) (xy 259.697905 -53.727711)
			(xy 259.745511 -53.756765) (xy 259.788379 -53.79244) (xy 259.825596 -53.833977) (xy 259.856369 -53.88049)
			(xy 259.880041 -53.930987) (xy 259.896109 -53.984394) (xy 259.904229 -54.03957) (xy 259.904738 -54.067456)
			(xy 259.904229 -54.095342) (xy 259.896109 -54.150518) (xy 259.880041 -54.203925) (xy 259.863643 -54.238906)
			(xy 266.585952 -54.238906) (xy 266.590023 -54.183284) (xy 266.602149 -54.128847) (xy 266.622072 -54.076756)
			(xy 266.649368 -54.028121) (xy 266.683454 -53.983978) (xy 266.723603 -53.945269) (xy 266.768961 -53.912818)
			(xy 266.818561 -53.887317) (xy 266.871345 -53.86931) (xy 266.926188 -53.85918) (xy 266.981922 -53.857143)
			(xy 267.037359 -53.863243) (xy 267.091316 -53.877349) (xy 267.142645 -53.899161) (xy 267.190251 -53.928215)
			(xy 267.233119 -53.96389) (xy 267.270336 -54.005427) (xy 267.301109 -54.05194) (xy 267.324781 -54.102437)
			(xy 267.340849 -54.155844) (xy 267.348969 -54.21102) (xy 267.349478 -54.238906) (xy 267.348969 -54.266792)
			(xy 267.340849 -54.321968) (xy 267.324781 -54.375375) (xy 267.301109 -54.425872) (xy 267.270336 -54.472385)
			(xy 267.233119 -54.513922) (xy 267.190251 -54.549597) (xy 267.142645 -54.578651) (xy 267.091316 -54.600463)
			(xy 267.037359 -54.614569) (xy 266.981922 -54.620669) (xy 266.926188 -54.618632) (xy 266.871345 -54.608502)
			(xy 266.818561 -54.590495) (xy 266.768961 -54.564994) (xy 266.723603 -54.532543) (xy 266.683454 -54.493834)
			(xy 266.649368 -54.449691) (xy 266.622072 -54.401056) (xy 266.602149 -54.348965) (xy 266.590023 -54.294528)
			(xy 266.585952 -54.238906) (xy 259.863643 -54.238906) (xy 259.856369 -54.254422) (xy 259.825596 -54.300935)
			(xy 259.788379 -54.342472) (xy 259.745511 -54.378147) (xy 259.697905 -54.407201) (xy 259.646576 -54.429013)
			(xy 259.592619 -54.443119) (xy 259.537182 -54.449219) (xy 259.481448 -54.447182) (xy 259.426605 -54.437052)
			(xy 259.373821 -54.419045) (xy 259.324221 -54.393544) (xy 259.278863 -54.361093) (xy 259.238714 -54.322384)
			(xy 259.204628 -54.278241) (xy 259.177332 -54.229606) (xy 259.157409 -54.177515) (xy 259.145283 -54.123078)
			(xy 259.141212 -54.067456) (xy 257.799581 -54.067456) (xy 257.787952 -54.110853) (xy 257.765016 -54.166226)
			(xy 257.735049 -54.218132) (xy 257.698562 -54.265682) (xy 257.656182 -54.308062) (xy 257.608632 -54.344549)
			(xy 257.556726 -54.374516) (xy 257.501353 -54.397452) (xy 257.44346 -54.412965) (xy 257.384038 -54.420788)
			(xy 257.324102 -54.420788) (xy 257.26468 -54.412965) (xy 257.206787 -54.397452) (xy 257.151414 -54.374516)
			(xy 257.099508 -54.344549) (xy 257.051958 -54.308062) (xy 257.009578 -54.265682) (xy 256.973091 -54.218132)
			(xy 256.943124 -54.166226) (xy 256.920188 -54.110853) (xy 256.904675 -54.05296) (xy 256.896852 -53.993538)
			(xy 253.006561 -53.993538) (xy 253.010441 -54.002034) (xy 253.025796 -54.054329) (xy 253.033552 -54.108277)
			(xy 253.034038 -54.135528) (xy 253.033603 -54.1629) (xy 253.02578 -54.217081) (xy 253.010285 -54.269585)
			(xy 252.987436 -54.319331) (xy 252.957703 -54.365296) (xy 252.940058 -54.386226) (xy 252.939804 -54.38648)
			(xy 252.93422 -54.393568) (xy 252.927972 -54.410484) (xy 252.927612 -54.4195) (xy 252.927612 -54.486556)
			(xy 252.927988 -54.495571) (xy 252.934222 -54.512488) (xy 252.939804 -54.519576) (xy 252.940058 -54.519576)
			(xy 252.940058 -54.51983) (xy 252.957671 -54.540783) (xy 252.987388 -54.586749) (xy 253.01023 -54.636492)
			(xy 253.025727 -54.688988) (xy 253.033561 -54.74316) (xy 253.034038 -54.770528) (xy 253.033552 -54.797779)
			(xy 253.025796 -54.851727) (xy 253.010441 -54.904022) (xy 252.987799 -54.953599) (xy 252.958333 -54.999449)
			(xy 252.922642 -55.04064) (xy 252.881451 -55.076331) (xy 252.870364 -55.083456) (xy 259.141212 -55.083456)
			(xy 259.145283 -55.027834) (xy 259.157409 -54.973397) (xy 259.177332 -54.921306) (xy 259.204628 -54.872671)
			(xy 259.238714 -54.828528) (xy 259.278863 -54.789819) (xy 259.324221 -54.757368) (xy 259.373821 -54.731867)
			(xy 259.426605 -54.71386) (xy 259.481448 -54.70373) (xy 259.537182 -54.701693) (xy 259.592619 -54.707793)
			(xy 259.646576 -54.721899) (xy 259.697905 -54.743711) (xy 259.745511 -54.772765) (xy 259.788379 -54.80844)
			(xy 259.825596 -54.849977) (xy 259.856369 -54.89649) (xy 259.880041 -54.946987) (xy 259.892696 -54.989051)
			(xy 262.101068 -54.989051) (xy 262.101068 -54.934549) (xy 262.108824 -54.880602) (xy 262.124178 -54.828308)
			(xy 262.146818 -54.778731) (xy 262.176283 -54.732881) (xy 262.211973 -54.69169) (xy 262.253161 -54.655997)
			(xy 262.29901 -54.62653) (xy 262.348585 -54.603887) (xy 262.400879 -54.588529) (xy 262.454825 -54.580769)
			(xy 262.482076 -54.580282) (xy 262.510167 -54.580796) (xy 262.565743 -54.58902) (xy 262.619512 -54.605307)
			(xy 262.670309 -54.629307) (xy 262.717036 -54.660499) (xy 262.758682 -54.698208) (xy 262.794345 -54.741619)
			(xy 262.809228 -54.765448) (xy 262.814562 -54.774338) (xy 262.83158 -54.78653) (xy 262.924798 -54.80685)
			(xy 262.945372 -54.802532) (xy 262.954008 -54.79669) (xy 262.978068 -54.780683) (xy 263.030001 -54.755342)
			(xy 263.08516 -54.738119) (xy 263.142285 -54.729406) (xy 263.171178 -54.728872) (xy 263.198429 -54.729376)
			(xy 263.252378 -54.737129) (xy 263.304674 -54.752481) (xy 263.354252 -54.77512) (xy 263.400105 -54.804584)
			(xy 263.441297 -54.840273) (xy 263.476991 -54.881462) (xy 263.50646 -54.927311) (xy 263.529104 -54.976887)
			(xy 263.544462 -55.029181) (xy 263.552221 -55.083129) (xy 263.552686 -55.11038) (xy 263.552212 -55.13775)
			(xy 263.544396 -55.191929) (xy 263.528909 -55.244432) (xy 263.506069 -55.294179) (xy 263.476346 -55.340146)
			(xy 263.458706 -55.361078) (xy 263.458452 -55.361332) (xy 263.452882 -55.36843) (xy 263.446627 -55.385338)
			(xy 263.44626 -55.394352) (xy 263.44626 -55.461408) (xy 263.4466 -55.470427) (xy 263.452858 -55.487344)
			(xy 263.458452 -55.494428) (xy 263.458706 -55.494428) (xy 263.458706 -55.494682) (xy 263.476326 -55.515631)
			(xy 263.506049 -55.561597) (xy 263.528893 -55.611341) (xy 263.54439 -55.66384) (xy 263.552219 -55.718016)
			(xy 263.552222 -55.772754) (xy 263.544396 -55.826931) (xy 263.528904 -55.879431) (xy 263.506063 -55.929177)
			(xy 263.476344 -55.975145) (xy 263.458706 -55.996078) (xy 263.458452 -55.996332) (xy 263.452882 -56.00343)
			(xy 263.446627 -56.020338) (xy 263.44626 -56.029352) (xy 263.44626 -56.096408) (xy 263.4466 -56.105427)
			(xy 263.452858 -56.122344) (xy 263.458452 -56.129428) (xy 263.458706 -56.129428) (xy 263.458706 -56.129682)
			(xy 263.476351 -56.150609) (xy 263.506062 -56.196583) (xy 263.528896 -56.246332) (xy 263.544386 -56.298834)
			(xy 263.552213 -56.353011) (xy 263.552686 -56.38038) (xy 263.5522 -56.407631) (xy 263.544444 -56.461579)
			(xy 263.529089 -56.513874) (xy 263.506447 -56.563451) (xy 263.476981 -56.609301) (xy 263.44129 -56.650492)
			(xy 263.400099 -56.686183) (xy 263.354249 -56.715649) (xy 263.304672 -56.738291) (xy 263.252377 -56.753646)
			(xy 263.198429 -56.761402) (xy 263.143927 -56.761402) (xy 263.089979 -56.753646) (xy 263.037684 -56.738291)
			(xy 262.988107 -56.715649) (xy 262.942257 -56.686183) (xy 262.901066 -56.650492) (xy 262.865375 -56.609301)
			(xy 262.835909 -56.563451) (xy 262.813267 -56.513874) (xy 262.797912 -56.461579) (xy 262.790156 -56.407631)
			(xy 262.78967 -56.38038) (xy 262.790107 -56.353009) (xy 262.797929 -56.298828) (xy 262.813424 -56.246323)
			(xy 262.836273 -56.196577) (xy 262.866005 -56.150612) (xy 262.88365 -56.129682) (xy 262.883904 -56.129428)
			(xy 262.889485 -56.122338) (xy 262.895735 -56.105424) (xy 262.896096 -56.096408) (xy 262.896096 -56.029352)
			(xy 262.895715 -56.020338) (xy 262.889484 -56.00342) (xy 262.883904 -55.996332) (xy 262.88365 -55.996332)
			(xy 262.88365 -55.996078) (xy 262.865989 -55.975162) (xy 262.836263 -55.929192) (xy 262.813417 -55.879443)
			(xy 262.797922 -55.826938) (xy 262.790094 -55.772757) (xy 262.790097 -55.718013) (xy 262.797928 -55.663833)
			(xy 262.813428 -55.611329) (xy 262.836278 -55.561582) (xy 262.866007 -55.515614) (xy 262.88365 -55.494682)
			(xy 262.883904 -55.494428) (xy 262.889485 -55.487338) (xy 262.895735 -55.470424) (xy 262.896096 -55.461408)
			(xy 262.896096 -55.394352) (xy 262.895715 -55.385338) (xy 262.889484 -55.36842) (xy 262.883904 -55.361332)
			(xy 262.88365 -55.360824) (xy 262.872704 -55.348092) (xy 262.852864 -55.320999) (xy 262.844026 -55.306722)
			(xy 262.838692 -55.297832) (xy 262.821674 -55.28564) (xy 262.728456 -55.26532) (xy 262.707882 -55.269638)
			(xy 262.699246 -55.27548) (xy 262.67517 -55.29146) (xy 262.623243 -55.316808) (xy 262.568089 -55.334039)
			(xy 262.510967 -55.34276) (xy 262.482076 -55.343298) (xy 262.454825 -55.342831) (xy 262.400879 -55.335071)
			(xy 262.348585 -55.319713) (xy 262.29901 -55.29707) (xy 262.253161 -55.267603) (xy 262.211973 -55.23191)
			(xy 262.176283 -55.190719) (xy 262.146818 -55.144869) (xy 262.124178 -55.095292) (xy 262.108824 -55.042998)
			(xy 262.101068 -54.989051) (xy 259.892696 -54.989051) (xy 259.896109 -55.000394) (xy 259.904229 -55.05557)
			(xy 259.904738 -55.083456) (xy 259.904229 -55.111342) (xy 259.896109 -55.166518) (xy 259.880041 -55.219925)
			(xy 259.856369 -55.270422) (xy 259.825596 -55.316935) (xy 259.788379 -55.358472) (xy 259.745511 -55.394147)
			(xy 259.701756 -55.420851) (xy 260.424668 -55.420851) (xy 260.424668 -55.366349) (xy 260.432424 -55.312402)
			(xy 260.447778 -55.260108) (xy 260.470418 -55.210531) (xy 260.499883 -55.164681) (xy 260.535573 -55.12349)
			(xy 260.576761 -55.087797) (xy 260.62261 -55.05833) (xy 260.672185 -55.035687) (xy 260.724479 -55.020329)
			(xy 260.778425 -55.012569) (xy 260.805676 -55.012082) (xy 260.831989 -55.012571) (xy 260.884116 -55.019802)
			(xy 260.934759 -55.034118) (xy 260.982958 -55.055246) (xy 261.027802 -55.082788) (xy 261.068442 -55.116222)
			(xy 261.0866 -55.135272) (xy 261.094123 -55.142672) (xy 261.113402 -55.151198) (xy 261.123938 -55.151782)
			(xy 261.198614 -55.151782) (xy 261.209167 -55.151279) (xy 261.228462 -55.142726) (xy 261.235952 -55.135272)
			(xy 261.254084 -55.116193) (xy 261.294719 -55.082739) (xy 261.339565 -55.055184) (xy 261.38777 -55.03405)
			(xy 261.438421 -55.019737) (xy 261.490559 -55.012518) (xy 261.516876 -55.012082) (xy 261.544129 -55.012564)
			(xy 261.598081 -55.020318) (xy 261.650381 -55.035671) (xy 261.699963 -55.058312) (xy 261.745817 -55.087778)
			(xy 261.787012 -55.123471) (xy 261.822707 -55.164663) (xy 261.852177 -55.210516) (xy 261.87482 -55.260097)
			(xy 261.890177 -55.312395) (xy 261.897935 -55.366347) (xy 261.897935 -55.420853) (xy 261.890177 -55.474805)
			(xy 261.87482 -55.527103) (xy 261.852177 -55.576684) (xy 261.822707 -55.622537) (xy 261.787012 -55.663729)
			(xy 261.745817 -55.699422) (xy 261.699963 -55.728888) (xy 261.650381 -55.751529) (xy 261.598081 -55.766882)
			(xy 261.544129 -55.774636) (xy 261.516876 -55.775098) (xy 261.490561 -55.774647) (xy 261.438432 -55.767409)
			(xy 261.387789 -55.753087) (xy 261.33959 -55.731951) (xy 261.294747 -55.704402) (xy 261.254108 -55.670961)
			(xy 261.235952 -55.651908) (xy 261.228449 -55.644484) (xy 261.209155 -55.635972) (xy 261.198614 -55.635398)
			(xy 261.123938 -55.635398) (xy 261.113389 -55.635935) (xy 261.094094 -55.644465) (xy 261.0866 -55.651908)
			(xy 261.068439 -55.670958) (xy 261.02781 -55.704415) (xy 260.982971 -55.731975) (xy 260.934771 -55.753114)
			(xy 260.884125 -55.767433) (xy 260.831992 -55.774659) (xy 260.805676 -55.775098) (xy 260.778425 -55.774631)
			(xy 260.724479 -55.766871) (xy 260.672185 -55.751513) (xy 260.62261 -55.72887) (xy 260.576761 -55.699403)
			(xy 260.535573 -55.66371) (xy 260.499883 -55.622519) (xy 260.470418 -55.576669) (xy 260.447778 -55.527092)
			(xy 260.432424 -55.474798) (xy 260.424668 -55.420851) (xy 259.701756 -55.420851) (xy 259.697905 -55.423201)
			(xy 259.646576 -55.445013) (xy 259.592619 -55.459119) (xy 259.537182 -55.465219) (xy 259.481448 -55.463182)
			(xy 259.426605 -55.453052) (xy 259.373821 -55.435045) (xy 259.324221 -55.409544) (xy 259.278863 -55.377093)
			(xy 259.238714 -55.338384) (xy 259.204628 -55.294241) (xy 259.177332 -55.245606) (xy 259.157409 -55.193515)
			(xy 259.145283 -55.139078) (xy 259.141212 -55.083456) (xy 252.870364 -55.083456) (xy 252.835601 -55.105797)
			(xy 252.786024 -55.128439) (xy 252.733729 -55.143794) (xy 252.679781 -55.15155) (xy 252.625279 -55.15155)
			(xy 252.571331 -55.143794) (xy 252.519036 -55.128439) (xy 252.469459 -55.105797) (xy 252.423609 -55.076331)
			(xy 252.382418 -55.04064) (xy 252.346727 -54.999449) (xy 252.317261 -54.953599) (xy 252.294619 -54.904022)
			(xy 252.279264 -54.851727) (xy 252.271508 -54.797779) (xy 252.271022 -54.770528) (xy 249.139112 -54.770528)
			(xy 249.139456 -54.791102) (xy 249.13897 -54.818353) (xy 249.131214 -54.872301) (xy 249.115859 -54.924596)
			(xy 249.093217 -54.974173) (xy 249.063751 -55.020023) (xy 249.02806 -55.061214) (xy 248.986869 -55.096905)
			(xy 248.941019 -55.126371) (xy 248.891442 -55.149013) (xy 248.839147 -55.164368) (xy 248.785199 -55.172124)
			(xy 248.730697 -55.172124) (xy 248.676749 -55.164368) (xy 248.624454 -55.149013) (xy 248.574877 -55.126371)
			(xy 248.529027 -55.096905) (xy 248.487836 -55.061214) (xy 248.452145 -55.020023) (xy 248.422679 -54.974173)
			(xy 248.400037 -54.924596) (xy 248.384682 -54.872301) (xy 248.376926 -54.818353) (xy 248.37644 -54.791102)
			(xy 248.376912 -54.763732) (xy 248.384736 -54.709554) (xy 248.400224 -54.657051) (xy 248.423058 -54.607301)
			(xy 248.452769 -54.561326) (xy 248.47042 -54.540404) (xy 248.476516 -54.533292) (xy 248.479564 -54.52491)
			(xy 248.481086 -54.520622) (xy 248.48275 -54.511678) (xy 248.482866 -54.50713) (xy 248.482866 -54.440074)
			(xy 248.482746 -54.435526) (xy 248.481092 -54.426579) (xy 248.479564 -54.422294) (xy 248.476516 -54.413912)
			(xy 248.47042 -54.4068) (xy 248.452779 -54.385867) (xy 248.423055 -54.339899) (xy 248.40021 -54.290153)
			(xy 248.384713 -54.237651) (xy 248.376885 -54.183472) (xy 248.376885 -54.128731) (xy 248.384713 -54.074552)
			(xy 248.400209 -54.02205) (xy 248.423053 -53.972304) (xy 248.452778 -53.926335) (xy 248.47042 -53.905404)
			(xy 248.476516 -53.898292) (xy 248.479564 -53.88991) (xy 248.481086 -53.885622) (xy 248.48275 -53.876678)
			(xy 248.482866 -53.87213) (xy 248.482866 -53.79593) (xy 248.480072 -53.788564) (xy 248.459998 -53.766854)
			(xy 248.426014 -53.71847) (xy 248.399802 -53.665472) (xy 248.381975 -53.609098) (xy 248.372948 -53.550665)
			(xy 248.372376 -53.521102) (xy 248.372809 -53.494703) (xy 248.380016 -53.442399) (xy 248.394295 -53.391568)
			(xy 248.415378 -53.343162) (xy 248.442872 -53.298087) (xy 248.476261 -53.257187) (xy 248.495312 -53.238908)
			(xy 248.497066 -53.234341) (xy 248.498985 -53.224749) (xy 248.499122 -53.219858) (xy 248.499122 -53.187854)
			(xy 248.49836 -53.17871) (xy 248.497344 -53.1749) (xy 248.495453 -53.16842) (xy 248.488767 -53.156697)
			(xy 248.484136 -53.151786) (xy 248.48312 -53.15077) (xy 248.471436 -53.137816) (xy 248.464145 -53.13087)
			(xy 248.445677 -53.122881) (xy 248.435622 -53.122322) (xy 246.522748 -53.122322) (xy 246.513943 -53.122748)
			(xy 246.497401 -53.128801) (xy 246.483868 -53.140078) (xy 246.47906 -53.147468) (xy 246.43461 -53.22316)
			(xy 246.431447 -53.229097) (xy 246.427979 -53.24209) (xy 246.427752 -53.248814) (xy 246.427752 -53.262022)
			(xy 246.42953 -53.265324) (xy 246.434356 -53.273706) (xy 246.44605 -53.295242) (xy 246.464466 -53.340657)
			(xy 246.476924 -53.388054) (xy 246.483221 -53.436655) (xy 246.483632 -53.461158) (xy 246.483632 -53.461412)
			(xy 246.483159 -53.488781) (xy 246.475333 -53.542958) (xy 246.459842 -53.595459) (xy 246.437006 -53.645207)
			(xy 246.407292 -53.691179) (xy 246.389652 -53.71211) (xy 246.383556 -53.719222) (xy 246.380508 -53.727604)
			(xy 246.378988 -53.731892) (xy 246.377328 -53.740836) (xy 246.377206 -53.745384) (xy 246.377206 -53.81244)
			(xy 246.377327 -53.816988) (xy 246.378983 -53.825934) (xy 246.380508 -53.83022) (xy 246.383556 -53.838602)
			(xy 246.389652 -53.845714) (xy 246.407293 -53.866646) (xy 246.437017 -53.912613) (xy 246.459862 -53.962359)
			(xy 246.475358 -54.014861) (xy 246.483186 -54.069039) (xy 246.483184 -54.123779) (xy 246.475354 -54.177957)
			(xy 246.459856 -54.230458) (xy 246.437009 -54.280202) (xy 246.407282 -54.326168) (xy 246.389652 -54.34711)
			(xy 246.383556 -54.354222) (xy 246.380508 -54.362604) (xy 246.378988 -54.366892) (xy 246.377328 -54.375836)
			(xy 246.377206 -54.380384) (xy 246.377206 -54.44744) (xy 246.377327 -54.451988) (xy 246.378983 -54.460934)
			(xy 246.380508 -54.46522) (xy 246.383556 -54.473602) (xy 246.389652 -54.480714) (xy 246.407295 -54.501645)
			(xy 246.437023 -54.54761) (xy 246.459868 -54.597357) (xy 246.475358 -54.649861) (xy 246.483175 -54.704041)
			(xy 246.483632 -54.731412) (xy 246.483146 -54.758663) (xy 246.47539 -54.812611) (xy 246.460035 -54.864906)
			(xy 246.437393 -54.914483) (xy 246.407927 -54.960333) (xy 246.372236 -55.001524) (xy 246.331045 -55.037215)
			(xy 246.285195 -55.066681) (xy 246.235618 -55.089323) (xy 246.183323 -55.104678) (xy 246.129375 -55.112434)
			(xy 246.074873 -55.112434) (xy 246.020925 -55.104678) (xy 245.96863 -55.089323) (xy 245.919053 -55.066681)
			(xy 245.873203 -55.037215) (xy 245.832012 -55.001524) (xy 245.796321 -54.960333) (xy 245.766855 -54.914483)
			(xy 245.744213 -54.864906) (xy 245.728858 -54.812611) (xy 245.721102 -54.758663) (xy 245.720616 -54.731412)
			(xy 245.721094 -54.704044) (xy 245.728929 -54.649872) (xy 245.744427 -54.597376) (xy 245.767267 -54.547634)
			(xy 245.796983 -54.501667) (xy 245.814596 -54.480714) (xy 245.820692 -54.473602) (xy 245.82374 -54.46522)
			(xy 245.825263 -54.460932) (xy 245.82693 -54.451988) (xy 245.827042 -54.44744) (xy 245.827042 -54.380384)
			(xy 245.826914 -54.375837) (xy 245.825244 -54.366897) (xy 245.82374 -54.362604) (xy 245.820692 -54.354222)
			(xy 245.814596 -54.34711) (xy 245.796956 -54.326177) (xy 245.767232 -54.280208) (xy 245.744386 -54.230461)
			(xy 245.72889 -54.177959) (xy 245.721061 -54.12378) (xy 245.721059 -54.069038) (xy 245.728886 -54.014859)
			(xy 245.74438 -53.962356) (xy 245.767223 -53.912608) (xy 245.796945 -53.866638) (xy 245.814596 -53.845714)
			(xy 245.820692 -53.838602) (xy 245.82374 -53.83022) (xy 245.825263 -53.825932) (xy 245.82693 -53.816988)
			(xy 245.827042 -53.81244) (xy 245.827042 -53.745384) (xy 245.826914 -53.740837) (xy 245.825244 -53.731897)
			(xy 245.82374 -53.727604) (xy 245.820692 -53.719222) (xy 245.814596 -53.71211) (xy 245.796954 -53.691179)
			(xy 245.767227 -53.645212) (xy 245.744382 -53.595466) (xy 245.728891 -53.542962) (xy 245.721071 -53.488783)
			(xy 245.720616 -53.461412) (xy 245.720616 -53.461158) (xy 245.720992 -53.436652) (xy 245.727272 -53.388044)
			(xy 245.739735 -53.340643) (xy 245.758175 -53.295233) (xy 245.769892 -53.273706) (xy 245.774718 -53.265324)
			(xy 245.776496 -53.262022) (xy 245.776496 -53.248814) (xy 245.776323 -53.242083) (xy 245.772844 -53.229081)
			(xy 245.769638 -53.22316) (xy 245.725188 -53.147468) (xy 245.720426 -53.140039) (xy 245.706892 -53.128738)
			(xy 245.690316 -53.122727) (xy 245.6815 -53.122322) (xy 241.60734 -53.122322) (xy 241.595355 -53.122959)
			(xy 241.573991 -53.13382) (xy 241.566446 -53.14315) (xy 241.54979 -53.168547) (xy 241.511078 -53.215349)
			(xy 241.466805 -53.256929) (xy 241.41767 -53.292632) (xy 241.364447 -53.321896) (xy 241.307976 -53.344258)
			(xy 241.249148 -53.359365) (xy 241.188891 -53.366981) (xy 241.158522 -53.367432) (xy 241.126892 -53.36691)
			(xy 241.064173 -53.358647) (xy 241.003069 -53.342272) (xy 240.944623 -53.318065) (xy 240.889835 -53.286439)
			(xy 240.839642 -53.247936) (xy 240.816892 -53.225954) (xy 240.727992 -53.137054) (xy 240.720633 -53.130412)
			(xy 240.702333 -53.122842) (xy 240.692432 -53.122322) (xy 238.534956 -53.122322) (xy 238.52629 -53.12263)
			(xy 238.509934 -53.128353) (xy 238.502952 -53.133498) (xy 238.496348 -53.138832) (xy 238.487458 -53.153564)
			(xy 238.485426 -53.162708) (xy 238.482188 -53.17605) (xy 238.470829 -53.201038) (xy 238.454401 -53.223029)
			(xy 238.444278 -53.232304) (xy 238.44377 -53.232812) (xy 238.430054 -53.245004) (xy 238.42726 -53.250592)
			(xy 238.42726 -53.977794) (xy 238.432086 -53.984906) (xy 238.453052 -54.006419) (xy 238.489741 -54.053986)
			(xy 238.519883 -54.105949) (xy 238.542959 -54.161413) (xy 238.558571 -54.219421) (xy 238.560107 -54.231028)
			(xy 239.886218 -54.231028) (xy 239.886218 -54.171092) (xy 239.894041 -54.11167) (xy 239.909554 -54.053777)
			(xy 239.93249 -53.998404) (xy 239.962457 -53.946498) (xy 239.998944 -53.898948) (xy 240.041324 -53.856568)
			(xy 240.088874 -53.820081) (xy 240.14078 -53.790114) (xy 240.196153 -53.767178) (xy 240.254046 -53.751665)
			(xy 240.313468 -53.743842) (xy 240.373404 -53.743842) (xy 240.432826 -53.751665) (xy 240.490719 -53.767178)
			(xy 240.546092 -53.790114) (xy 240.597998 -53.820081) (xy 240.645548 -53.856568) (xy 240.687928 -53.898948)
			(xy 240.724415 -53.946498) (xy 240.754382 -53.998404) (xy 240.777318 -54.053777) (xy 240.792831 -54.11167)
			(xy 240.800654 -54.171092) (xy 240.801144 -54.20106) (xy 240.800654 -54.231028) (xy 240.792831 -54.29045)
			(xy 240.777318 -54.348343) (xy 240.754382 -54.403716) (xy 240.724415 -54.455622) (xy 240.687928 -54.503172)
			(xy 240.645548 -54.545552) (xy 240.597998 -54.582039) (xy 240.546092 -54.612006) (xy 240.490719 -54.634942)
			(xy 240.432826 -54.650455) (xy 240.373404 -54.658278) (xy 240.313468 -54.658278) (xy 240.254046 -54.650455)
			(xy 240.196153 -54.634942) (xy 240.14078 -54.612006) (xy 240.088874 -54.582039) (xy 240.041324 -54.545552)
			(xy 239.998944 -54.503172) (xy 239.962457 -54.455622) (xy 239.93249 -54.403716) (xy 239.909554 -54.348343)
			(xy 239.894041 -54.29045) (xy 239.886218 -54.231028) (xy 238.560107 -54.231028) (xy 238.566451 -54.278974)
			(xy 238.56696 -54.30901) (xy 238.56696 -54.309518) (xy 238.56647 -54.339486) (xy 238.558647 -54.398908)
			(xy 238.543134 -54.456801) (xy 238.520198 -54.512174) (xy 238.490231 -54.56408) (xy 238.453744 -54.61163)
			(xy 238.411364 -54.65401) (xy 238.363814 -54.690497) (xy 238.311908 -54.720464) (xy 238.256535 -54.7434)
			(xy 238.198642 -54.758913) (xy 238.13922 -54.766736) (xy 238.079284 -54.766736) (xy 238.019862 -54.758913)
			(xy 237.961969 -54.7434) (xy 237.906596 -54.720464) (xy 237.85469 -54.690497) (xy 237.80714 -54.65401)
			(xy 237.76476 -54.61163) (xy 237.728273 -54.56408) (xy 237.698306 -54.512174) (xy 237.67537 -54.456801)
			(xy 237.659857 -54.398908) (xy 237.652034 -54.339486) (xy 237.651544 -54.309518) (xy 237.651544 -54.30901)
			(xy 237.651638 -54.296411) (xy 237.653036 -54.27125) (xy 237.654338 -54.258718) (xy 237.657994 -54.229899)
			(xy 237.671658 -54.173436) (xy 237.692346 -54.119152) (xy 237.719725 -54.067915) (xy 237.753357 -54.020548)
			(xy 237.772702 -53.998876) (xy 237.78591 -53.984652) (xy 237.786164 -53.984144) (xy 237.786164 -53.890926)
			(xy 237.783859 -53.887071) (xy 237.778108 -53.880175) (xy 237.774734 -53.87721) (xy 237.707424 -53.87721)
			(xy 237.70463 -53.878988) (xy 237.691168 -53.903372) (xy 237.676616 -53.928534) (xy 237.641082 -53.974531)
			(xy 237.598986 -54.01461) (xy 237.5513 -54.047842) (xy 237.499127 -54.073462) (xy 237.443673 -54.090876)
			(xy 237.38622 -54.099681) (xy 237.357158 -54.100222) (xy 237.329908 -54.099733) (xy 237.275963 -54.091972)
			(xy 237.223671 -54.076612) (xy 237.174097 -54.053968) (xy 237.12825 -54.024499) (xy 237.087064 -53.988807)
			(xy 237.051375 -53.947616) (xy 237.021912 -53.901766) (xy 236.999273 -53.85219) (xy 236.983919 -53.799896)
			(xy 236.976164 -53.74595) (xy 236.976164 -53.69145) (xy 236.983919 -53.637504) (xy 236.999273 -53.58521)
			(xy 237.021912 -53.535634) (xy 237.051375 -53.489784) (xy 237.087064 -53.448593) (xy 237.12825 -53.412901)
			(xy 237.174097 -53.383432) (xy 237.223671 -53.360788) (xy 237.275963 -53.345428) (xy 237.329908 -53.337667)
			(xy 237.357158 -53.337206) (xy 237.386277 -53.337751) (xy 237.443842 -53.34659) (xy 237.499396 -53.364068)
			(xy 237.551651 -53.389781) (xy 237.599395 -53.423132) (xy 237.62081 -53.44287) (xy 237.621318 -53.443378)
			(xy 237.626652 -53.448458) (xy 237.63986 -53.455062) (xy 237.646718 -53.456332) (xy 237.654051 -53.457373)
			(xy 237.668761 -53.45569) (xy 237.675674 -53.45303) (xy 237.76178 -53.4162) (xy 237.769366 -53.412668)
			(xy 237.781824 -53.40151) (xy 237.786164 -53.394356) (xy 237.786164 -53.250592) (xy 237.78337 -53.245004)
			(xy 237.769654 -53.232812) (xy 237.769146 -53.232304) (xy 237.759006 -53.223045) (xy 237.742574 -53.201054)
			(xy 237.731231 -53.176053) (xy 237.727998 -53.162708) (xy 237.727998 -53.162454) (xy 237.725855 -53.153973)
			(xy 237.71677 -53.139039) (xy 237.710218 -53.133244) (xy 237.703614 -53.128164) (xy 237.687358 -53.122322)
			(xy 221.838012 -53.122322) (xy 221.829818 -53.12263) (xy 221.814271 -53.127811) (xy 221.807532 -53.132482)
			(xy 221.800674 -53.137562) (xy 221.791784 -53.15077) (xy 221.789244 -53.158898) (xy 221.781124 -53.184915)
			(xy 221.758486 -53.234493) (xy 221.729023 -53.280344) (xy 221.693334 -53.321536) (xy 221.652146 -53.357228)
			(xy 221.606297 -53.386696) (xy 221.556721 -53.409338) (xy 221.504428 -53.424694) (xy 221.450481 -53.43245)
			(xy 221.395979 -53.43245) (xy 221.342032 -53.424694) (xy 221.289739 -53.409338) (xy 221.240163 -53.386696)
			(xy 221.194314 -53.357228) (xy 221.153126 -53.321536) (xy 221.117437 -53.280344) (xy 221.087974 -53.234493)
			(xy 221.065336 -53.184915) (xy 221.057216 -53.158898) (xy 221.057216 -53.158644) (xy 221.054617 -53.150922)
			(xy 221.045289 -53.137574) (xy 221.038928 -53.132482) (xy 221.032324 -53.127402) (xy 221.01683 -53.122322)
			(xy 212.884258 -53.122322) (xy 212.876361 -53.122649) (xy 212.861345 -53.127554) (xy 212.854794 -53.131974)
			(xy 212.848444 -53.136292) (xy 212.8393 -53.148738) (xy 212.836506 -53.156612) (xy 212.826282 -53.185087)
			(xy 212.799377 -53.239277) (xy 212.765558 -53.289445) (xy 212.725418 -53.334713) (xy 212.679658 -53.374291)
			(xy 212.654642 -53.391308) (xy 212.645498 -53.39715) (xy 212.63991 -53.405786) (xy 212.637232 -53.410114)
			(xy 212.633513 -53.419586) (xy 212.632544 -53.424582) (xy 212.619844 -53.49875) (xy 212.619129 -53.504024)
			(xy 212.619639 -53.514652) (xy 212.62086 -53.519832) (xy 212.623146 -53.52923) (xy 212.62975 -53.537866)
			(xy 212.64464 -53.55792) (xy 212.669639 -53.601163) (xy 212.688784 -53.647296) (xy 212.70175 -53.695533)
			(xy 212.708313 -53.745048) (xy 212.708744 -53.770022) (xy 212.708744 -53.77053) (xy 212.708256 -53.797781)
			(xy 212.700496 -53.851727) (xy 212.685139 -53.90402) (xy 212.662497 -53.953596) (xy 212.63303 -53.999445)
			(xy 212.597339 -54.040635) (xy 212.55615 -54.076327) (xy 212.510301 -54.105794) (xy 212.460726 -54.128437)
			(xy 212.408433 -54.143795) (xy 212.354487 -54.151556) (xy 212.327236 -54.152038) (xy 212.299868 -54.151562)
			(xy 212.245695 -54.143729) (xy 212.193198 -54.128232) (xy 212.143455 -54.105392) (xy 212.097488 -54.075675)
			(xy 212.076538 -54.058058) (xy 212.069426 -54.051962) (xy 212.061044 -54.048914) (xy 212.056755 -54.047399)
			(xy 212.047811 -54.045747) (xy 212.043264 -54.045612) (xy 211.976208 -54.045612) (xy 211.971661 -54.045738)
			(xy 211.962719 -54.047402) (xy 211.958428 -54.048914) (xy 211.950046 -54.051962) (xy 211.942934 -54.058058)
			(xy 211.922004 -54.075704) (xy 211.876039 -54.105437) (xy 211.826293 -54.128287) (xy 211.773789 -54.143784)
			(xy 211.719608 -54.151608) (xy 211.692236 -54.152038) (xy 211.664981 -54.151578) (xy 211.611024 -54.143825)
			(xy 211.55872 -54.128472) (xy 211.509134 -54.105832) (xy 211.463274 -54.076366) (xy 211.422074 -54.040672)
			(xy 211.386374 -53.999479) (xy 211.356899 -53.953624) (xy 211.334251 -53.904042) (xy 211.318889 -53.85174)
			(xy 211.311127 -53.797785) (xy 211.310728 -53.77053) (xy 211.31126 -53.741613) (xy 211.319983 -53.68444)
			(xy 211.337235 -53.629238) (xy 211.36262 -53.577272) (xy 211.395556 -53.529732) (xy 211.43529 -53.487707)
			(xy 211.457794 -53.46954) (xy 211.465172 -53.463253) (xy 211.474955 -53.446537) (xy 211.476844 -53.437028)
			(xy 211.477352 -53.429408) (xy 211.477352 -53.349652) (xy 211.476844 -53.342032) (xy 211.475082 -53.333013)
			(xy 211.46609 -53.317003) (xy 211.459318 -53.31079) (xy 211.457794 -53.30952) (xy 211.438522 -53.294013)
			(xy 211.403748 -53.258832) (xy 211.373807 -53.219455) (xy 211.3492 -53.176543) (xy 211.33943 -53.153818)
			(xy 211.335112 -53.143404) (xy 211.326984 -53.135784) (xy 211.32038 -53.130704) (xy 211.314284 -53.12664)
			(xy 211.300314 -53.122322) (xy 210.981036 -53.122322) (xy 210.980274 -53.122322) (xy 210.970241 -53.122974)
			(xy 210.951813 -53.130958) (xy 210.94446 -53.137816) (xy 210.932776 -53.15077) (xy 210.93176 -53.151786)
			(xy 210.927143 -53.156708) (xy 210.920457 -53.168425) (xy 210.918552 -53.1749) (xy 210.916774 -53.1876)
			(xy 210.916774 -53.219604) (xy 210.91691 -53.224637) (xy 210.918949 -53.234495) (xy 210.920838 -53.239162)
			(xy 210.939837 -53.257451) (xy 210.973162 -53.298323) (xy 211.000601 -53.343359) (xy 211.021642 -53.391716)
			(xy 211.035892 -53.44249) (xy 211.043084 -53.494734) (xy 211.04352 -53.521102) (xy 211.042955 -53.550665)
			(xy 211.033933 -53.609098) (xy 211.016102 -53.665471) (xy 210.989879 -53.718463) (xy 210.955878 -53.766834)
			(xy 210.935824 -53.788564) (xy 210.93303 -53.79593) (xy 210.93303 -53.87213) (xy 210.93315 -53.876678)
			(xy 210.934805 -53.885624) (xy 210.936332 -53.88991) (xy 210.93938 -53.898292) (xy 210.945476 -53.905404)
			(xy 210.963116 -53.926337) (xy 210.992841 -53.972305) (xy 211.015686 -54.022051) (xy 211.031181 -54.074553)
			(xy 211.03901 -54.128731) (xy 211.03901 -54.183472) (xy 211.031181 -54.23765) (xy 211.015685 -54.290152)
			(xy 211.001892 -54.320186) (xy 213.23046 -54.320186) (xy 213.230903 -54.292815) (xy 213.238724 -54.238634)
			(xy 213.254218 -54.18613) (xy 213.277065 -54.136384) (xy 213.306796 -54.090418) (xy 213.32444 -54.069488)
			(xy 213.324694 -54.069234) (xy 213.330272 -54.062141) (xy 213.336524 -54.045229) (xy 213.336886 -54.036214)
			(xy 213.336886 -53.969158) (xy 213.336504 -53.960144) (xy 213.330274 -53.943226) (xy 213.324694 -53.936138)
			(xy 213.32444 -53.936138) (xy 213.32444 -53.935884) (xy 213.306833 -53.914926) (xy 213.277115 -53.868961)
			(xy 213.254272 -53.81922) (xy 213.238774 -53.766725) (xy 213.230938 -53.712553) (xy 213.23046 -53.685186)
			(xy 213.230946 -53.657935) (xy 213.238702 -53.603987) (xy 213.254057 -53.551692) (xy 213.276699 -53.502115)
			(xy 213.306165 -53.456265) (xy 213.341856 -53.415074) (xy 213.383047 -53.379383) (xy 213.428897 -53.349917)
			(xy 213.478474 -53.327275) (xy 213.530769 -53.31192) (xy 213.584717 -53.304164) (xy 213.639219 -53.304164)
			(xy 213.693167 -53.31192) (xy 213.745462 -53.327275) (xy 213.795039 -53.349917) (xy 213.840889 -53.379383)
			(xy 213.88208 -53.415074) (xy 213.917771 -53.456265) (xy 213.947237 -53.502115) (xy 213.969879 -53.551692)
			(xy 213.985234 -53.603987) (xy 213.99299 -53.657935) (xy 213.993476 -53.685186) (xy 213.993008 -53.712556)
			(xy 213.985191 -53.766735) (xy 213.969703 -53.819239) (xy 213.946862 -53.868986) (xy 213.917137 -53.914952)
			(xy 213.899496 -53.935884) (xy 213.899242 -53.936138) (xy 213.893668 -53.943233) (xy 213.887415 -53.960144)
			(xy 213.88705 -53.969158) (xy 213.88705 -54.036214) (xy 213.88739 -54.045233) (xy 213.893648 -54.06215)
			(xy 213.899242 -54.069234) (xy 213.899496 -54.069234) (xy 213.899496 -54.069488) (xy 213.917142 -54.090414)
			(xy 213.946853 -54.136389) (xy 213.969688 -54.186138) (xy 213.985177 -54.23864) (xy 213.993003 -54.292816)
			(xy 213.993476 -54.320186) (xy 213.99299 -54.347437) (xy 213.985234 -54.401385) (xy 213.969879 -54.45368)
			(xy 213.947237 -54.503257) (xy 213.917771 -54.549107) (xy 213.88208 -54.590298) (xy 213.840889 -54.625989)
			(xy 213.795039 -54.655455) (xy 213.745462 -54.678097) (xy 213.693167 -54.693452) (xy 213.639219 -54.701208)
			(xy 213.584717 -54.701208) (xy 213.530769 -54.693452) (xy 213.478474 -54.678097) (xy 213.428897 -54.655455)
			(xy 213.383047 -54.625989) (xy 213.341856 -54.590298) (xy 213.306165 -54.549107) (xy 213.276699 -54.503257)
			(xy 213.254057 -54.45368) (xy 213.238702 -54.401385) (xy 213.230946 -54.347437) (xy 213.23046 -54.320186)
			(xy 211.001892 -54.320186) (xy 210.992839 -54.339898) (xy 210.963115 -54.385866) (xy 210.945476 -54.4068)
			(xy 210.93938 -54.413912) (xy 210.936332 -54.422294) (xy 210.934811 -54.426582) (xy 210.933148 -54.435526)
			(xy 210.93303 -54.440074) (xy 210.93303 -54.50713) (xy 210.93315 -54.511678) (xy 210.934805 -54.520624)
			(xy 210.936332 -54.52491) (xy 210.93938 -54.533292) (xy 210.945476 -54.540404) (xy 210.963119 -54.561335)
			(xy 210.992846 -54.607301) (xy 211.01569 -54.657048) (xy 211.031181 -54.709551) (xy 211.038999 -54.763731)
			(xy 211.039112 -54.770528) (xy 214.171022 -54.770528) (xy 214.171499 -54.743158) (xy 214.179313 -54.688979)
			(xy 214.1948 -54.636476) (xy 214.217639 -54.586729) (xy 214.247362 -54.540762) (xy 214.265002 -54.51983)
			(xy 214.265256 -54.519576) (xy 214.270865 -54.512505) (xy 214.277097 -54.495576) (xy 214.277448 -54.486556)
			(xy 214.277448 -54.4195) (xy 214.277102 -54.410482) (xy 214.270848 -54.393564) (xy 214.265256 -54.38648)
			(xy 214.265002 -54.38648) (xy 214.265002 -54.386226) (xy 214.247362 -54.365295) (xy 214.21765 -54.319322)
			(xy 214.194814 -54.269574) (xy 214.179324 -54.217073) (xy 214.171496 -54.162897) (xy 214.171022 -54.135528)
			(xy 214.171508 -54.108277) (xy 214.179264 -54.054329) (xy 214.194619 -54.002034) (xy 214.217261 -53.952457)
			(xy 214.246727 -53.906607) (xy 214.282418 -53.865416) (xy 214.323609 -53.829725) (xy 214.369459 -53.800259)
			(xy 214.419036 -53.777617) (xy 214.471331 -53.762262) (xy 214.525279 -53.754506) (xy 214.579781 -53.754506)
			(xy 214.633729 -53.762262) (xy 214.686024 -53.777617) (xy 214.735601 -53.800259) (xy 214.781451 -53.829725)
			(xy 214.822642 -53.865416) (xy 214.858333 -53.906607) (xy 214.887799 -53.952457) (xy 214.906561 -53.993538)
			(xy 218.796852 -53.993538) (xy 218.796852 -53.933602) (xy 218.804675 -53.87418) (xy 218.820188 -53.816287)
			(xy 218.843124 -53.760914) (xy 218.873091 -53.709008) (xy 218.909578 -53.661458) (xy 218.951958 -53.619078)
			(xy 218.999508 -53.582591) (xy 219.051414 -53.552624) (xy 219.106787 -53.529688) (xy 219.16468 -53.514175)
			(xy 219.224102 -53.506352) (xy 219.284038 -53.506352) (xy 219.34346 -53.514175) (xy 219.401353 -53.529688)
			(xy 219.456726 -53.552624) (xy 219.508632 -53.582591) (xy 219.556182 -53.619078) (xy 219.598562 -53.661458)
			(xy 219.635049 -53.709008) (xy 219.665016 -53.760914) (xy 219.687952 -53.816287) (xy 219.703465 -53.87418)
			(xy 219.711288 -53.933602) (xy 219.711778 -53.96357) (xy 219.711288 -53.993538) (xy 219.703465 -54.05296)
			(xy 219.699581 -54.067456) (xy 221.041212 -54.067456) (xy 221.045283 -54.011834) (xy 221.057409 -53.957397)
			(xy 221.077332 -53.905306) (xy 221.104628 -53.856671) (xy 221.138714 -53.812528) (xy 221.178863 -53.773819)
			(xy 221.224221 -53.741368) (xy 221.273821 -53.715867) (xy 221.326605 -53.69786) (xy 221.381448 -53.68773)
			(xy 221.437182 -53.685693) (xy 221.492619 -53.691793) (xy 221.546576 -53.705899) (xy 221.597905 -53.727711)
			(xy 221.645511 -53.756765) (xy 221.688379 -53.79244) (xy 221.725596 -53.833977) (xy 221.756369 -53.88049)
			(xy 221.780041 -53.930987) (xy 221.796109 -53.984394) (xy 221.804229 -54.03957) (xy 221.804738 -54.067456)
			(xy 221.804229 -54.095342) (xy 221.796109 -54.150518) (xy 221.780041 -54.203925) (xy 221.756369 -54.254422)
			(xy 221.725596 -54.300935) (xy 221.688379 -54.342472) (xy 221.645511 -54.378147) (xy 221.597905 -54.407201)
			(xy 221.546576 -54.429013) (xy 221.492619 -54.443119) (xy 221.437182 -54.449219) (xy 221.381448 -54.447182)
			(xy 221.326605 -54.437052) (xy 221.273821 -54.419045) (xy 221.224221 -54.393544) (xy 221.178863 -54.361093)
			(xy 221.138714 -54.322384) (xy 221.104628 -54.278241) (xy 221.077332 -54.229606) (xy 221.057409 -54.177515)
			(xy 221.045283 -54.123078) (xy 221.041212 -54.067456) (xy 219.699581 -54.067456) (xy 219.687952 -54.110853)
			(xy 219.665016 -54.166226) (xy 219.635049 -54.218132) (xy 219.598562 -54.265682) (xy 219.556182 -54.308062)
			(xy 219.508632 -54.344549) (xy 219.456726 -54.374516) (xy 219.401353 -54.397452) (xy 219.34346 -54.412965)
			(xy 219.284038 -54.420788) (xy 219.224102 -54.420788) (xy 219.16468 -54.412965) (xy 219.106787 -54.397452)
			(xy 219.051414 -54.374516) (xy 218.999508 -54.344549) (xy 218.951958 -54.308062) (xy 218.909578 -54.265682)
			(xy 218.873091 -54.218132) (xy 218.843124 -54.166226) (xy 218.820188 -54.110853) (xy 218.804675 -54.05296)
			(xy 218.796852 -53.993538) (xy 214.906561 -53.993538) (xy 214.910441 -54.002034) (xy 214.925796 -54.054329)
			(xy 214.933552 -54.108277) (xy 214.934038 -54.135528) (xy 214.933603 -54.1629) (xy 214.92578 -54.217081)
			(xy 214.910285 -54.269585) (xy 214.887436 -54.319331) (xy 214.857703 -54.365296) (xy 214.840058 -54.386226)
			(xy 214.839804 -54.38648) (xy 214.83422 -54.393568) (xy 214.827972 -54.410484) (xy 214.827612 -54.4195)
			(xy 214.827612 -54.486556) (xy 214.827988 -54.495571) (xy 214.834222 -54.512488) (xy 214.839804 -54.519576)
			(xy 214.840058 -54.519576) (xy 214.840058 -54.51983) (xy 214.857671 -54.540783) (xy 214.887388 -54.586749)
			(xy 214.91023 -54.636492) (xy 214.925727 -54.688988) (xy 214.933561 -54.74316) (xy 214.934038 -54.770528)
			(xy 214.933552 -54.797779) (xy 214.925796 -54.851727) (xy 214.910441 -54.904022) (xy 214.887799 -54.953599)
			(xy 214.858333 -54.999449) (xy 214.822642 -55.04064) (xy 214.781451 -55.076331) (xy 214.770364 -55.083456)
			(xy 221.041212 -55.083456) (xy 221.045283 -55.027834) (xy 221.057409 -54.973397) (xy 221.077332 -54.921306)
			(xy 221.104628 -54.872671) (xy 221.138714 -54.828528) (xy 221.178863 -54.789819) (xy 221.224221 -54.757368)
			(xy 221.273821 -54.731867) (xy 221.326605 -54.71386) (xy 221.381448 -54.70373) (xy 221.437182 -54.701693)
			(xy 221.492619 -54.707793) (xy 221.546576 -54.721899) (xy 221.597905 -54.743711) (xy 221.645511 -54.772765)
			(xy 221.688379 -54.80844) (xy 221.702882 -54.824626) (xy 238.856248 -54.824626) (xy 238.856248 -54.76469)
			(xy 238.864071 -54.705268) (xy 238.879584 -54.647375) (xy 238.90252 -54.592002) (xy 238.932487 -54.540096)
			(xy 238.968974 -54.492546) (xy 239.011354 -54.450166) (xy 239.058904 -54.413679) (xy 239.11081 -54.383712)
			(xy 239.166183 -54.360776) (xy 239.224076 -54.345263) (xy 239.283498 -54.33744) (xy 239.343434 -54.33744)
			(xy 239.402856 -54.345263) (xy 239.460749 -54.360776) (xy 239.516122 -54.383712) (xy 239.568028 -54.413679)
			(xy 239.615578 -54.450166) (xy 239.657958 -54.492546) (xy 239.694445 -54.540096) (xy 239.724412 -54.592002)
			(xy 239.747348 -54.647375) (xy 239.762861 -54.705268) (xy 239.770684 -54.76469) (xy 239.771174 -54.794658)
			(xy 239.770684 -54.824626) (xy 239.770584 -54.825388) (xy 240.88774 -54.825388) (xy 240.88774 -54.765452)
			(xy 240.895563 -54.70603) (xy 240.911076 -54.648137) (xy 240.934012 -54.592764) (xy 240.963979 -54.540858)
			(xy 241.000466 -54.493308) (xy 241.042846 -54.450928) (xy 241.090396 -54.414441) (xy 241.142302 -54.384474)
			(xy 241.197675 -54.361538) (xy 241.255568 -54.346025) (xy 241.31499 -54.338202) (xy 241.374926 -54.338202)
			(xy 241.434348 -54.346025) (xy 241.492241 -54.361538) (xy 241.547614 -54.384474) (xy 241.59952 -54.414441)
			(xy 241.64707 -54.450928) (xy 241.68945 -54.493308) (xy 241.725937 -54.540858) (xy 241.755904 -54.592764)
			(xy 241.77884 -54.648137) (xy 241.794353 -54.70603) (xy 241.802176 -54.765452) (xy 241.802666 -54.79542)
			(xy 241.802176 -54.825388) (xy 241.794353 -54.88481) (xy 241.77884 -54.942703) (xy 241.755904 -54.998076)
			(xy 241.725937 -55.049982) (xy 241.68945 -55.097532) (xy 241.64707 -55.139912) (xy 241.59952 -55.176399)
			(xy 241.547614 -55.206366) (xy 241.492241 -55.229302) (xy 241.434348 -55.244815) (xy 241.374926 -55.252638)
			(xy 241.31499 -55.252638) (xy 241.255568 -55.244815) (xy 241.197675 -55.229302) (xy 241.142302 -55.206366)
			(xy 241.090396 -55.176399) (xy 241.042846 -55.139912) (xy 241.000466 -55.097532) (xy 240.963979 -55.049982)
			(xy 240.934012 -54.998076) (xy 240.911076 -54.942703) (xy 240.895563 -54.88481) (xy 240.88774 -54.825388)
			(xy 239.770584 -54.825388) (xy 239.762861 -54.884048) (xy 239.747348 -54.941941) (xy 239.724412 -54.997314)
			(xy 239.694445 -55.04922) (xy 239.657958 -55.09677) (xy 239.615578 -55.13915) (xy 239.568028 -55.175637)
			(xy 239.516122 -55.205604) (xy 239.460749 -55.22854) (xy 239.402856 -55.244053) (xy 239.343434 -55.251876)
			(xy 239.283498 -55.251876) (xy 239.224076 -55.244053) (xy 239.166183 -55.22854) (xy 239.11081 -55.205604)
			(xy 239.058904 -55.175637) (xy 239.011354 -55.13915) (xy 238.968974 -55.09677) (xy 238.932487 -55.04922)
			(xy 238.90252 -54.997314) (xy 238.879584 -54.941941) (xy 238.864071 -54.884048) (xy 238.856248 -54.824626)
			(xy 221.702882 -54.824626) (xy 221.725596 -54.849977) (xy 221.756369 -54.89649) (xy 221.780041 -54.946987)
			(xy 221.796109 -55.000394) (xy 221.804229 -55.05557) (xy 221.804738 -55.083456) (xy 221.804229 -55.111342)
			(xy 221.796109 -55.166518) (xy 221.780041 -55.219925) (xy 221.756369 -55.270422) (xy 221.725596 -55.316935)
			(xy 221.688379 -55.358472) (xy 221.645511 -55.394147) (xy 221.597905 -55.423201) (xy 221.546576 -55.445013)
			(xy 221.492619 -55.459119) (xy 221.437182 -55.465219) (xy 221.381448 -55.463182) (xy 221.326605 -55.453052)
			(xy 221.273821 -55.435045) (xy 221.224221 -55.409544) (xy 221.178863 -55.377093) (xy 221.138714 -55.338384)
			(xy 221.104628 -55.294241) (xy 221.077332 -55.245606) (xy 221.057409 -55.193515) (xy 221.045283 -55.139078)
			(xy 221.041212 -55.083456) (xy 214.770364 -55.083456) (xy 214.735601 -55.105797) (xy 214.686024 -55.128439)
			(xy 214.633729 -55.143794) (xy 214.579781 -55.15155) (xy 214.525279 -55.15155) (xy 214.471331 -55.143794)
			(xy 214.419036 -55.128439) (xy 214.369459 -55.105797) (xy 214.323609 -55.076331) (xy 214.282418 -55.04064)
			(xy 214.246727 -54.999449) (xy 214.217261 -54.953599) (xy 214.194619 -54.904022) (xy 214.179264 -54.851727)
			(xy 214.171508 -54.797779) (xy 214.171022 -54.770528) (xy 211.039112 -54.770528) (xy 211.039456 -54.791102)
			(xy 211.03897 -54.818353) (xy 211.031214 -54.872301) (xy 211.015859 -54.924596) (xy 210.993217 -54.974173)
			(xy 210.963751 -55.020023) (xy 210.92806 -55.061214) (xy 210.886869 -55.096905) (xy 210.841019 -55.126371)
			(xy 210.791442 -55.149013) (xy 210.739147 -55.164368) (xy 210.685199 -55.172124) (xy 210.630697 -55.172124)
			(xy 210.576749 -55.164368) (xy 210.524454 -55.149013) (xy 210.474877 -55.126371) (xy 210.429027 -55.096905)
			(xy 210.387836 -55.061214) (xy 210.352145 -55.020023) (xy 210.322679 -54.974173) (xy 210.300037 -54.924596)
			(xy 210.284682 -54.872301) (xy 210.276926 -54.818353) (xy 210.27644 -54.791102) (xy 210.276912 -54.763732)
			(xy 210.284736 -54.709554) (xy 210.300224 -54.657051) (xy 210.323058 -54.607301) (xy 210.352769 -54.561326)
			(xy 210.37042 -54.540404) (xy 210.376516 -54.533292) (xy 210.379564 -54.52491) (xy 210.381086 -54.520622)
			(xy 210.38275 -54.511678) (xy 210.382866 -54.50713) (xy 210.382866 -54.440074) (xy 210.382746 -54.435526)
			(xy 210.381092 -54.426579) (xy 210.379564 -54.422294) (xy 210.376516 -54.413912) (xy 210.37042 -54.4068)
			(xy 210.352779 -54.385867) (xy 210.323055 -54.339899) (xy 210.30021 -54.290153) (xy 210.284713 -54.237651)
			(xy 210.276885 -54.183472) (xy 210.276885 -54.128731) (xy 210.284713 -54.074552) (xy 210.300209 -54.02205)
			(xy 210.323053 -53.972304) (xy 210.352778 -53.926335) (xy 210.37042 -53.905404) (xy 210.376516 -53.898292)
			(xy 210.379564 -53.88991) (xy 210.381086 -53.885622) (xy 210.38275 -53.876678) (xy 210.382866 -53.87213)
			(xy 210.382866 -53.79593) (xy 210.380072 -53.788564) (xy 210.359998 -53.766854) (xy 210.326014 -53.71847)
			(xy 210.299802 -53.665472) (xy 210.281975 -53.609098) (xy 210.272948 -53.550665) (xy 210.272376 -53.521102)
			(xy 210.272809 -53.494703) (xy 210.280016 -53.442399) (xy 210.294295 -53.391568) (xy 210.315378 -53.343162)
			(xy 210.342872 -53.298087) (xy 210.376261 -53.257187) (xy 210.395312 -53.238908) (xy 210.397066 -53.234341)
			(xy 210.398985 -53.224749) (xy 210.399122 -53.219858) (xy 210.399122 -53.187854) (xy 210.39836 -53.17871)
			(xy 210.397344 -53.1749) (xy 210.395453 -53.16842) (xy 210.388767 -53.156697) (xy 210.384136 -53.151786)
			(xy 210.38312 -53.15077) (xy 210.371436 -53.137816) (xy 210.364145 -53.13087) (xy 210.345677 -53.122881)
			(xy 210.335622 -53.122322) (xy 208.422748 -53.122322) (xy 208.413943 -53.122748) (xy 208.397401 -53.128801)
			(xy 208.383868 -53.140078) (xy 208.37906 -53.147468) (xy 208.33461 -53.22316) (xy 208.331447 -53.229097)
			(xy 208.327979 -53.24209) (xy 208.327752 -53.248814) (xy 208.327752 -53.262022) (xy 208.32953 -53.265324)
			(xy 208.334356 -53.273706) (xy 208.34605 -53.295242) (xy 208.364466 -53.340657) (xy 208.376924 -53.388054)
			(xy 208.383221 -53.436655) (xy 208.383632 -53.461158) (xy 208.383632 -53.461412) (xy 208.383159 -53.488781)
			(xy 208.375333 -53.542958) (xy 208.359842 -53.595459) (xy 208.337006 -53.645207) (xy 208.307292 -53.691179)
			(xy 208.289652 -53.71211) (xy 208.283556 -53.719222) (xy 208.280508 -53.727604) (xy 208.278988 -53.731892)
			(xy 208.277328 -53.740836) (xy 208.277206 -53.745384) (xy 208.277206 -53.81244) (xy 208.277327 -53.816988)
			(xy 208.278983 -53.825934) (xy 208.280508 -53.83022) (xy 208.283556 -53.838602) (xy 208.289652 -53.845714)
			(xy 208.307293 -53.866646) (xy 208.337017 -53.912613) (xy 208.359862 -53.962359) (xy 208.375358 -54.014861)
			(xy 208.383186 -54.069039) (xy 208.383184 -54.123779) (xy 208.375354 -54.177957) (xy 208.359856 -54.230458)
			(xy 208.337009 -54.280202) (xy 208.307282 -54.326168) (xy 208.289652 -54.34711) (xy 208.283556 -54.354222)
			(xy 208.280508 -54.362604) (xy 208.278988 -54.366892) (xy 208.277328 -54.375836) (xy 208.277206 -54.380384)
			(xy 208.277206 -54.44744) (xy 208.277327 -54.451988) (xy 208.278983 -54.460934) (xy 208.280508 -54.46522)
			(xy 208.283556 -54.473602) (xy 208.289652 -54.480714) (xy 208.307295 -54.501645) (xy 208.337023 -54.54761)
			(xy 208.359868 -54.597357) (xy 208.375358 -54.649861) (xy 208.383175 -54.704041) (xy 208.383632 -54.731412)
			(xy 208.383146 -54.758663) (xy 208.37539 -54.812611) (xy 208.360035 -54.864906) (xy 208.337393 -54.914483)
			(xy 208.307927 -54.960333) (xy 208.272236 -55.001524) (xy 208.231045 -55.037215) (xy 208.185195 -55.066681)
			(xy 208.135618 -55.089323) (xy 208.083323 -55.104678) (xy 208.029375 -55.112434) (xy 207.974873 -55.112434)
			(xy 207.920925 -55.104678) (xy 207.86863 -55.089323) (xy 207.819053 -55.066681) (xy 207.773203 -55.037215)
			(xy 207.732012 -55.001524) (xy 207.696321 -54.960333) (xy 207.666855 -54.914483) (xy 207.644213 -54.864906)
			(xy 207.628858 -54.812611) (xy 207.621102 -54.758663) (xy 207.620616 -54.731412) (xy 207.621094 -54.704044)
			(xy 207.628929 -54.649872) (xy 207.644427 -54.597376) (xy 207.667267 -54.547634) (xy 207.696983 -54.501667)
			(xy 207.714596 -54.480714) (xy 207.720692 -54.473602) (xy 207.72374 -54.46522) (xy 207.725263 -54.460932)
			(xy 207.72693 -54.451988) (xy 207.727042 -54.44744) (xy 207.727042 -54.380384) (xy 207.726914 -54.375837)
			(xy 207.725244 -54.366897) (xy 207.72374 -54.362604) (xy 207.720692 -54.354222) (xy 207.714596 -54.34711)
			(xy 207.696956 -54.326177) (xy 207.667232 -54.280208) (xy 207.644386 -54.230461) (xy 207.62889 -54.177959)
			(xy 207.621061 -54.12378) (xy 207.621059 -54.069038) (xy 207.628886 -54.014859) (xy 207.64438 -53.962356)
			(xy 207.667223 -53.912608) (xy 207.696945 -53.866638) (xy 207.714596 -53.845714) (xy 207.720692 -53.838602)
			(xy 207.72374 -53.83022) (xy 207.725263 -53.825932) (xy 207.72693 -53.816988) (xy 207.727042 -53.81244)
			(xy 207.727042 -53.745384) (xy 207.726914 -53.740837) (xy 207.725244 -53.731897) (xy 207.72374 -53.727604)
			(xy 207.720692 -53.719222) (xy 207.714596 -53.71211) (xy 207.696954 -53.691179) (xy 207.667227 -53.645212)
			(xy 207.644382 -53.595466) (xy 207.628891 -53.542962) (xy 207.621071 -53.488783) (xy 207.620616 -53.461412)
			(xy 207.620616 -53.461158) (xy 207.620992 -53.436652) (xy 207.627272 -53.388044) (xy 207.639735 -53.340643)
			(xy 207.658175 -53.295233) (xy 207.669892 -53.273706) (xy 207.674718 -53.265324) (xy 207.676496 -53.262022)
			(xy 207.676496 -53.248814) (xy 207.676323 -53.242083) (xy 207.672844 -53.229081) (xy 207.669638 -53.22316)
			(xy 207.625188 -53.147468) (xy 207.620426 -53.140039) (xy 207.606892 -53.128738) (xy 207.590316 -53.122727)
			(xy 207.5815 -53.122322) (xy 201.665586 -53.122322) (xy 201.65702 -53.122696) (xy 201.640864 -53.128411)
			(xy 201.627472 -53.139103) (xy 201.62266 -53.146198) (xy 201.587354 -53.20792) (xy 201.577702 -53.224684)
			(xy 201.57461 -53.230502) (xy 201.571276 -53.243243) (xy 201.571098 -53.24983) (xy 201.571098 -53.263546)
			(xy 201.57821 -53.275484) (xy 201.590763 -53.297592) (xy 201.61054 -53.344426) (xy 201.623911 -53.393475)
			(xy 201.630637 -53.443866) (xy 201.631042 -53.469286) (xy 201.631042 -53.475382) (xy 201.630145 -53.502348)
			(xy 201.621693 -53.555635) (xy 201.605817 -53.6072) (xy 201.582834 -53.656014) (xy 201.553202 -53.701103)
			(xy 201.517514 -53.741567) (xy 201.47648 -53.776598) (xy 201.43092 -53.805499) (xy 201.381742 -53.827693)
			(xy 201.329928 -53.842736) (xy 201.276511 -53.850328) (xy 201.249534 -53.850794) (xy 201.222166 -53.850318)
			(xy 201.167992 -53.842485) (xy 201.115494 -53.826991) (xy 201.065749 -53.804152) (xy 201.01978 -53.774439)
			(xy 200.998836 -53.756814) (xy 200.991724 -53.750718) (xy 200.983342 -53.74767) (xy 200.979055 -53.746147)
			(xy 200.97011 -53.744494) (xy 200.965562 -53.744368) (xy 200.898506 -53.744368) (xy 200.893959 -53.744494)
			(xy 200.885017 -53.74616) (xy 200.880726 -53.74767) (xy 200.872344 -53.750718) (xy 200.865232 -53.756814)
			(xy 200.844301 -53.774457) (xy 200.798335 -53.804186) (xy 200.748588 -53.827033) (xy 200.696085 -53.842527)
			(xy 200.641905 -53.850349) (xy 200.614534 -53.850794) (xy 200.58756 -53.850324) (xy 200.534152 -53.842716)
			(xy 200.482347 -53.827663) (xy 200.433179 -53.805463) (xy 200.387628 -53.77656) (xy 200.346601 -53.741529)
			(xy 200.310917 -53.701069) (xy 200.281288 -53.655987) (xy 200.258303 -53.607181) (xy 200.242421 -53.555624)
			(xy 200.233959 -53.502344) (xy 200.233026 -53.475382) (xy 200.233026 -53.469286) (xy 200.233451 -53.443869)
			(xy 200.240203 -53.393485) (xy 200.253574 -53.344441) (xy 200.273326 -53.297601) (xy 200.285858 -53.275484)
			(xy 200.289414 -53.269642) (xy 200.29297 -53.256434) (xy 200.29297 -53.24983) (xy 200.292764 -53.243248)
			(xy 200.289427 -53.230514) (xy 200.286366 -53.224684) (xy 200.276714 -53.20792) (xy 200.241408 -53.146198)
			(xy 200.236594 -53.139099) (xy 200.223224 -53.128376) (xy 200.207052 -53.122695) (xy 200.198482 -53.122322)
			(xy 195.91655 -53.122322) (xy 195.908192 -53.122704) (xy 195.892382 -53.128145) (xy 195.885562 -53.13299)
			(xy 195.879212 -53.13807) (xy 195.870068 -53.15204) (xy 195.867782 -53.16093) (xy 195.860018 -53.190366)
			(xy 195.837754 -53.247025) (xy 195.808176 -53.300234) (xy 195.771807 -53.349053) (xy 195.729288 -53.392621)
			(xy 195.68137 -53.43017) (xy 195.628899 -53.461036) (xy 195.572799 -53.484675) (xy 195.51406 -53.50067)
			(xy 195.45372 -53.508738) (xy 195.392844 -53.508738) (xy 195.332504 -53.50067) (xy 195.273765 -53.484675)
			(xy 195.217665 -53.461036) (xy 195.165194 -53.43017) (xy 195.117276 -53.392621) (xy 195.074757 -53.349053)
			(xy 195.038388 -53.300234) (xy 195.00881 -53.247025) (xy 194.986546 -53.190366) (xy 194.978782 -53.16093)
			(xy 194.978782 -53.160676) (xy 194.976435 -53.152407) (xy 194.96709 -53.137993) (xy 194.960494 -53.132482)
			(xy 194.954398 -53.127656) (xy 194.938396 -53.122322) (xy 186.88431 -53.122322) (xy 186.876415 -53.122656)
			(xy 186.861408 -53.127573) (xy 186.854846 -53.131974) (xy 186.848496 -53.136292) (xy 186.839352 -53.148738)
			(xy 186.836558 -53.156612) (xy 186.826335 -53.185088) (xy 186.799432 -53.23928) (xy 186.765616 -53.289451)
			(xy 186.725478 -53.334723) (xy 186.67972 -53.374306) (xy 186.654694 -53.391308) (xy 186.64555 -53.39715)
			(xy 186.639962 -53.405786) (xy 186.637286 -53.410115) (xy 186.633571 -53.419587) (xy 186.632596 -53.424582)
			(xy 186.619896 -53.49875) (xy 186.619181 -53.504024) (xy 186.619691 -53.514652) (xy 186.620912 -53.519832)
			(xy 186.623198 -53.52923) (xy 186.629802 -53.537866) (xy 186.644693 -53.55792) (xy 186.669695 -53.601161)
			(xy 186.688844 -53.647295) (xy 186.701811 -53.695532) (xy 186.708375 -53.745048) (xy 186.708796 -53.770022)
			(xy 186.708796 -53.77053) (xy 186.708308 -53.797779) (xy 186.700548 -53.851723) (xy 186.68519 -53.904014)
			(xy 186.662547 -53.953586) (xy 186.63308 -53.999432) (xy 186.597388 -54.040618) (xy 186.556198 -54.076305)
			(xy 186.510349 -54.105767) (xy 186.460774 -54.128404) (xy 186.408482 -54.143757) (xy 186.354538 -54.151511)
			(xy 186.327288 -54.152038) (xy 186.299919 -54.151565) (xy 186.245742 -54.143739) (xy 186.193241 -54.128248)
			(xy 186.143493 -54.105412) (xy 186.09752 -54.075699) (xy 186.07659 -54.058058) (xy 186.069478 -54.051962)
			(xy 186.061096 -54.048914) (xy 186.056808 -54.047394) (xy 186.047864 -54.045733) (xy 186.043316 -54.045612)
			(xy 185.97626 -54.045612) (xy 185.971712 -54.045733) (xy 185.962766 -54.047389) (xy 185.95848 -54.048914)
			(xy 185.950098 -54.051962) (xy 185.942986 -54.058058) (xy 185.922055 -54.075701) (xy 185.876089 -54.105428)
			(xy 185.826343 -54.128272) (xy 185.773839 -54.143763) (xy 185.719659 -54.15158) (xy 185.692288 -54.152038)
			(xy 185.665037 -54.151551) (xy 185.611089 -54.143794) (xy 185.558793 -54.128438) (xy 185.509216 -54.105796)
			(xy 185.463365 -54.07633) (xy 185.422174 -54.040639) (xy 185.386481 -53.99945) (xy 185.357012 -53.9536)
			(xy 185.334368 -53.904023) (xy 185.31901 -53.851729) (xy 185.31125 -53.797781) (xy 185.31078 -53.77053)
			(xy 185.311312 -53.741612) (xy 185.320035 -53.684438) (xy 185.337285 -53.629235) (xy 185.362667 -53.577267)
			(xy 185.395601 -53.529724) (xy 185.435332 -53.487695) (xy 185.457846 -53.46954) (xy 185.46523 -53.463256)
			(xy 185.475022 -53.446541) (xy 185.476896 -53.437028) (xy 185.477404 -53.429408) (xy 185.477404 -53.349652)
			(xy 185.476896 -53.342032) (xy 185.475132 -53.333015) (xy 185.466134 -53.317011) (xy 185.45937 -53.31079)
			(xy 185.457846 -53.30952) (xy 185.438576 -53.294011) (xy 185.403805 -53.258828) (xy 185.373868 -53.21945)
			(xy 185.349265 -53.176537) (xy 185.339482 -53.153818) (xy 185.335164 -53.143404) (xy 185.327036 -53.135784)
			(xy 185.320432 -53.130704) (xy 185.314336 -53.12664) (xy 185.300366 -53.122322) (xy 184.981088 -53.122322)
			(xy 184.980326 -53.122322) (xy 184.970274 -53.122896) (xy 184.951807 -53.130878) (xy 184.944512 -53.137816)
			(xy 184.932828 -53.15077) (xy 184.931812 -53.151786) (xy 184.927191 -53.156705) (xy 184.920498 -53.168421)
			(xy 184.918604 -53.1749) (xy 184.916826 -53.1876) (xy 184.916826 -53.21935) (xy 184.917588 -53.228494)
			(xy 184.919189 -53.235899) (xy 184.926168 -53.24934) (xy 184.931304 -53.25491) (xy 184.951478 -53.27641)
			(xy 184.985626 -53.324468) (xy 185.011974 -53.377207) (xy 185.029896 -53.433372) (xy 185.038964 -53.491625)
			(xy 185.039508 -53.521102) (xy 185.039036 -53.548472) (xy 185.031212 -53.60265) (xy 185.015725 -53.655154)
			(xy 184.992893 -53.704905) (xy 184.963185 -53.750882) (xy 184.945528 -53.7718) (xy 184.939432 -53.778912)
			(xy 184.936384 -53.787294) (xy 184.934856 -53.79158) (xy 184.93319 -53.800525) (xy 184.933082 -53.805074)
			(xy 184.933082 -53.87213) (xy 184.933203 -53.876678) (xy 184.934859 -53.885624) (xy 184.936384 -53.88991)
			(xy 184.939432 -53.898292) (xy 184.945528 -53.905404) (xy 184.96317 -53.926336) (xy 184.992898 -53.972303)
			(xy 185.015746 -54.022049) (xy 185.031244 -54.074551) (xy 185.039073 -54.12873) (xy 185.039073 -54.183473)
			(xy 185.031243 -54.237652) (xy 185.015745 -54.290154) (xy 185.001952 -54.320186) (xy 187.230512 -54.320186)
			(xy 187.230967 -54.292815) (xy 187.238787 -54.238636) (xy 187.254279 -54.186132) (xy 187.277123 -54.136386)
			(xy 187.30685 -54.090419) (xy 187.324492 -54.069488) (xy 187.324746 -54.069234) (xy 187.33033 -54.062146)
			(xy 187.336577 -54.04523) (xy 187.336938 -54.036214) (xy 187.336938 -53.969158) (xy 187.336545 -53.960145)
			(xy 187.330322 -53.943228) (xy 187.324746 -53.936138) (xy 187.324492 -53.936138) (xy 187.324492 -53.935884)
			(xy 187.306878 -53.914932) (xy 187.277162 -53.868965) (xy 187.254322 -53.819222) (xy 187.238825 -53.766726)
			(xy 187.23099 -53.712554) (xy 187.230512 -53.685186) (xy 187.230998 -53.657935) (xy 187.238754 -53.603987)
			(xy 187.254109 -53.551692) (xy 187.276751 -53.502115) (xy 187.306217 -53.456265) (xy 187.341908 -53.415074)
			(xy 187.383099 -53.379383) (xy 187.428949 -53.349917) (xy 187.478526 -53.327275) (xy 187.530821 -53.31192)
			(xy 187.584769 -53.304164) (xy 187.639271 -53.304164) (xy 187.693219 -53.31192) (xy 187.745514 -53.327275)
			(xy 187.795091 -53.349917) (xy 187.840941 -53.379383) (xy 187.882132 -53.415074) (xy 187.917823 -53.456265)
			(xy 187.947289 -53.502115) (xy 187.969931 -53.551692) (xy 187.985286 -53.603987) (xy 187.993042 -53.657935)
			(xy 187.993528 -53.685186) (xy 187.993071 -53.712557) (xy 187.985254 -53.766737) (xy 187.969764 -53.819241)
			(xy 187.946919 -53.868988) (xy 187.917191 -53.914953) (xy 187.899548 -53.935884) (xy 187.899294 -53.936138)
			(xy 187.893727 -53.943238) (xy 187.887469 -53.960144) (xy 187.887102 -53.969158) (xy 187.887102 -54.036214)
			(xy 187.887452 -54.045232) (xy 187.893704 -54.062148) (xy 187.899294 -54.069234) (xy 187.899548 -54.069234)
			(xy 187.899548 -54.069488) (xy 187.917187 -54.09042) (xy 187.946901 -54.136392) (xy 187.969737 -54.18614)
			(xy 187.985228 -54.238641) (xy 187.993055 -54.292817) (xy 187.993528 -54.320186) (xy 187.993042 -54.347437)
			(xy 187.985286 -54.401385) (xy 187.969931 -54.45368) (xy 187.947289 -54.503257) (xy 187.917823 -54.549107)
			(xy 187.882132 -54.590298) (xy 187.840941 -54.625989) (xy 187.795091 -54.655455) (xy 187.745514 -54.678097)
			(xy 187.693219 -54.693452) (xy 187.639271 -54.701208) (xy 187.584769 -54.701208) (xy 187.530821 -54.693452)
			(xy 187.478526 -54.678097) (xy 187.428949 -54.655455) (xy 187.383099 -54.625989) (xy 187.341908 -54.590298)
			(xy 187.306217 -54.549107) (xy 187.276751 -54.503257) (xy 187.254109 -54.45368) (xy 187.238754 -54.401385)
			(xy 187.230998 -54.347437) (xy 187.230512 -54.320186) (xy 185.001952 -54.320186) (xy 184.992897 -54.3399)
			(xy 184.963169 -54.385867) (xy 184.945528 -54.4068) (xy 184.939432 -54.413912) (xy 184.936384 -54.422294)
			(xy 184.934856 -54.42658) (xy 184.93319 -54.435525) (xy 184.933082 -54.440074) (xy 184.933082 -54.50713)
			(xy 184.933203 -54.511678) (xy 184.934859 -54.520624) (xy 184.936384 -54.52491) (xy 184.939432 -54.533292)
			(xy 184.945528 -54.540404) (xy 184.963169 -54.561336) (xy 184.992892 -54.607303) (xy 185.015733 -54.65705)
			(xy 185.031221 -54.709553) (xy 185.039039 -54.763732) (xy 185.039155 -54.770528) (xy 188.171074 -54.770528)
			(xy 188.171538 -54.743158) (xy 188.179354 -54.688978) (xy 188.194842 -54.636474) (xy 188.217685 -54.586727)
			(xy 188.247411 -54.540761) (xy 188.265054 -54.51983) (xy 188.265308 -54.519576) (xy 188.270912 -54.512501)
			(xy 188.277148 -54.495575) (xy 188.2775 -54.486556) (xy 188.2775 -54.4195) (xy 188.277143 -54.410483)
			(xy 188.270895 -54.393566) (xy 188.265308 -54.38648) (xy 188.265054 -54.38648) (xy 188.265054 -54.386226)
			(xy 188.247422 -54.365288) (xy 188.217707 -54.319318) (xy 188.194869 -54.269572) (xy 188.179377 -54.217072)
			(xy 188.171548 -54.162897) (xy 188.171074 -54.135528) (xy 188.17156 -54.108277) (xy 188.179316 -54.054329)
			(xy 188.194671 -54.002034) (xy 188.217313 -53.952457) (xy 188.246779 -53.906607) (xy 188.28247 -53.865416)
			(xy 188.323661 -53.829725) (xy 188.369511 -53.800259) (xy 188.419088 -53.777617) (xy 188.471383 -53.762262)
			(xy 188.525331 -53.754506) (xy 188.579833 -53.754506) (xy 188.633781 -53.762262) (xy 188.686076 -53.777617)
			(xy 188.735653 -53.800259) (xy 188.781503 -53.829725) (xy 188.822694 -53.865416) (xy 188.858385 -53.906607)
			(xy 188.887851 -53.952457) (xy 188.906613 -53.993538) (xy 192.796904 -53.993538) (xy 192.796904 -53.933602)
			(xy 192.804727 -53.87418) (xy 192.82024 -53.816287) (xy 192.843176 -53.760914) (xy 192.873143 -53.709008)
			(xy 192.90963 -53.661458) (xy 192.95201 -53.619078) (xy 192.99956 -53.582591) (xy 193.051466 -53.552624)
			(xy 193.106839 -53.529688) (xy 193.164732 -53.514175) (xy 193.224154 -53.506352) (xy 193.28409 -53.506352)
			(xy 193.343512 -53.514175) (xy 193.401405 -53.529688) (xy 193.456778 -53.552624) (xy 193.508684 -53.582591)
			(xy 193.556234 -53.619078) (xy 193.598614 -53.661458) (xy 193.635101 -53.709008) (xy 193.665068 -53.760914)
			(xy 193.688004 -53.816287) (xy 193.703517 -53.87418) (xy 193.71134 -53.933602) (xy 193.71183 -53.96357)
			(xy 193.71134 -53.993538) (xy 193.703517 -54.05296) (xy 193.699633 -54.067456) (xy 195.041264 -54.067456)
			(xy 195.045335 -54.011834) (xy 195.057461 -53.957397) (xy 195.077384 -53.905306) (xy 195.10468 -53.856671)
			(xy 195.138766 -53.812528) (xy 195.178915 -53.773819) (xy 195.224273 -53.741368) (xy 195.273873 -53.715867)
			(xy 195.326657 -53.69786) (xy 195.3815 -53.68773) (xy 195.437234 -53.685693) (xy 195.492671 -53.691793)
			(xy 195.546628 -53.705899) (xy 195.597957 -53.727711) (xy 195.645563 -53.756765) (xy 195.688431 -53.79244)
			(xy 195.725648 -53.833977) (xy 195.756421 -53.88049) (xy 195.780093 -53.930987) (xy 195.796161 -53.984394)
			(xy 195.804281 -54.03957) (xy 195.80479 -54.067456) (xy 195.804281 -54.095342) (xy 195.796161 -54.150518)
			(xy 195.780093 -54.203925) (xy 195.763695 -54.238906) (xy 202.486004 -54.238906) (xy 202.490075 -54.183284)
			(xy 202.502201 -54.128847) (xy 202.522124 -54.076756) (xy 202.54942 -54.028121) (xy 202.583506 -53.983978)
			(xy 202.623655 -53.945269) (xy 202.669013 -53.912818) (xy 202.718613 -53.887317) (xy 202.771397 -53.86931)
			(xy 202.82624 -53.85918) (xy 202.881974 -53.857143) (xy 202.937411 -53.863243) (xy 202.991368 -53.877349)
			(xy 203.042697 -53.899161) (xy 203.090303 -53.928215) (xy 203.133171 -53.96389) (xy 203.170388 -54.005427)
			(xy 203.201161 -54.05194) (xy 203.224833 -54.102437) (xy 203.240901 -54.155844) (xy 203.249021 -54.21102)
			(xy 203.24953 -54.238906) (xy 203.249021 -54.266792) (xy 203.240901 -54.321968) (xy 203.224833 -54.375375)
			(xy 203.201161 -54.425872) (xy 203.170388 -54.472385) (xy 203.133171 -54.513922) (xy 203.090303 -54.549597)
			(xy 203.042697 -54.578651) (xy 202.991368 -54.600463) (xy 202.937411 -54.614569) (xy 202.881974 -54.620669)
			(xy 202.82624 -54.618632) (xy 202.771397 -54.608502) (xy 202.718613 -54.590495) (xy 202.669013 -54.564994)
			(xy 202.623655 -54.532543) (xy 202.583506 -54.493834) (xy 202.54942 -54.449691) (xy 202.522124 -54.401056)
			(xy 202.502201 -54.348965) (xy 202.490075 -54.294528) (xy 202.486004 -54.238906) (xy 195.763695 -54.238906)
			(xy 195.756421 -54.254422) (xy 195.725648 -54.300935) (xy 195.688431 -54.342472) (xy 195.645563 -54.378147)
			(xy 195.597957 -54.407201) (xy 195.546628 -54.429013) (xy 195.492671 -54.443119) (xy 195.437234 -54.449219)
			(xy 195.3815 -54.447182) (xy 195.326657 -54.437052) (xy 195.273873 -54.419045) (xy 195.224273 -54.393544)
			(xy 195.178915 -54.361093) (xy 195.138766 -54.322384) (xy 195.10468 -54.278241) (xy 195.077384 -54.229606)
			(xy 195.057461 -54.177515) (xy 195.045335 -54.123078) (xy 195.041264 -54.067456) (xy 193.699633 -54.067456)
			(xy 193.688004 -54.110853) (xy 193.665068 -54.166226) (xy 193.635101 -54.218132) (xy 193.598614 -54.265682)
			(xy 193.556234 -54.308062) (xy 193.508684 -54.344549) (xy 193.456778 -54.374516) (xy 193.401405 -54.397452)
			(xy 193.343512 -54.412965) (xy 193.28409 -54.420788) (xy 193.224154 -54.420788) (xy 193.164732 -54.412965)
			(xy 193.106839 -54.397452) (xy 193.051466 -54.374516) (xy 192.99956 -54.344549) (xy 192.95201 -54.308062)
			(xy 192.90963 -54.265682) (xy 192.873143 -54.218132) (xy 192.843176 -54.166226) (xy 192.82024 -54.110853)
			(xy 192.804727 -54.05296) (xy 192.796904 -53.993538) (xy 188.906613 -53.993538) (xy 188.910493 -54.002034)
			(xy 188.925848 -54.054329) (xy 188.933604 -54.108277) (xy 188.93409 -54.135528) (xy 188.933643 -54.162899)
			(xy 188.925821 -54.217079) (xy 188.910327 -54.269582) (xy 188.887481 -54.319329) (xy 188.857753 -54.365295)
			(xy 188.84011 -54.386226) (xy 188.839856 -54.38648) (xy 188.834266 -54.393564) (xy 188.828023 -54.410483)
			(xy 188.827664 -54.4195) (xy 188.827664 -54.486556) (xy 188.82805 -54.49557) (xy 188.834278 -54.512487)
			(xy 188.839856 -54.519576) (xy 188.84011 -54.519576) (xy 188.84011 -54.51983) (xy 188.857731 -54.540776)
			(xy 188.887445 -54.586745) (xy 188.910285 -54.636489) (xy 188.92578 -54.688987) (xy 188.933613 -54.74316)
			(xy 188.93409 -54.770528) (xy 188.933604 -54.797779) (xy 188.925848 -54.851727) (xy 188.910493 -54.904022)
			(xy 188.887851 -54.953599) (xy 188.858385 -54.999449) (xy 188.822694 -55.04064) (xy 188.781503 -55.076331)
			(xy 188.770416 -55.083456) (xy 195.041264 -55.083456) (xy 195.045335 -55.027834) (xy 195.057461 -54.973397)
			(xy 195.077384 -54.921306) (xy 195.10468 -54.872671) (xy 195.138766 -54.828528) (xy 195.178915 -54.789819)
			(xy 195.224273 -54.757368) (xy 195.273873 -54.731867) (xy 195.326657 -54.71386) (xy 195.3815 -54.70373)
			(xy 195.437234 -54.701693) (xy 195.492671 -54.707793) (xy 195.546628 -54.721899) (xy 195.597957 -54.743711)
			(xy 195.645563 -54.772765) (xy 195.688431 -54.80844) (xy 195.725648 -54.849977) (xy 195.756421 -54.89649)
			(xy 195.780093 -54.946987) (xy 195.796161 -55.000394) (xy 195.804281 -55.05557) (xy 195.80479 -55.083456)
			(xy 195.804281 -55.111342) (xy 195.796161 -55.166518) (xy 195.780093 -55.219925) (xy 195.756421 -55.270422)
			(xy 195.725648 -55.316935) (xy 195.688431 -55.358472) (xy 195.645563 -55.394147) (xy 195.597957 -55.423201)
			(xy 195.597086 -55.423571) (xy 196.248451 -55.423571) (xy 196.248451 -55.363629) (xy 196.256275 -55.3042)
			(xy 196.27179 -55.246301) (xy 196.29473 -55.190923) (xy 196.324702 -55.139012) (xy 196.361193 -55.091458)
			(xy 196.403579 -55.049074) (xy 196.451136 -55.012586) (xy 196.503048 -54.982617) (xy 196.558428 -54.959681)
			(xy 196.616328 -54.94417) (xy 196.675757 -54.936349) (xy 196.705728 -54.935882) (xy 196.705982 -54.935882)
			(xy 196.737507 -54.936407) (xy 196.799958 -54.945081) (xy 196.860629 -54.962242) (xy 196.918371 -54.987564)
			(xy 196.920798 -54.989055) (xy 198.001045 -54.989055) (xy 198.001045 -54.934545) (xy 198.008803 -54.88059)
			(xy 198.024161 -54.828289) (xy 198.046806 -54.778705) (xy 198.076277 -54.73285) (xy 198.111975 -54.691655)
			(xy 198.153172 -54.655961) (xy 198.19903 -54.626492) (xy 198.248615 -54.603851) (xy 198.300918 -54.588497)
			(xy 198.354873 -54.580743) (xy 198.382128 -54.580282) (xy 198.41022 -54.580755) (xy 198.465799 -54.588986)
			(xy 198.519568 -54.605281) (xy 198.570366 -54.629287) (xy 198.617092 -54.660485) (xy 198.658737 -54.6982)
			(xy 198.694398 -54.741616) (xy 198.70928 -54.765448) (xy 198.714614 -54.774338) (xy 198.731632 -54.78653)
			(xy 198.82485 -54.80685) (xy 198.845424 -54.802532) (xy 198.85406 -54.79669) (xy 198.878132 -54.780704)
			(xy 198.930061 -54.755358) (xy 198.985216 -54.738129) (xy 199.042338 -54.729409) (xy 199.07123 -54.728872)
			(xy 199.098481 -54.72935) (xy 199.152428 -54.73711) (xy 199.204722 -54.752468) (xy 199.254298 -54.775111)
			(xy 199.300147 -54.804579) (xy 199.341336 -54.840271) (xy 199.377027 -54.881461) (xy 199.406494 -54.927311)
			(xy 199.429136 -54.976888) (xy 199.444492 -55.029182) (xy 199.452251 -55.083129) (xy 199.452738 -55.11038)
			(xy 199.452275 -55.137751) (xy 199.444459 -55.19193) (xy 199.42897 -55.244434) (xy 199.406127 -55.294181)
			(xy 199.3764 -55.340147) (xy 199.358758 -55.361078) (xy 199.358504 -55.361332) (xy 199.35294 -55.368434)
			(xy 199.34668 -55.385339) (xy 199.346312 -55.394352) (xy 199.346312 -55.461408) (xy 199.346663 -55.470426)
			(xy 199.352914 -55.487343) (xy 199.358504 -55.494428) (xy 199.358758 -55.494428) (xy 199.358758 -55.494682)
			(xy 199.37638 -55.51563) (xy 199.406106 -55.561595) (xy 199.428954 -55.611339) (xy 199.444452 -55.663838)
			(xy 199.452283 -55.718015) (xy 199.452285 -55.772755) (xy 199.444459 -55.826932) (xy 199.428965 -55.879433)
			(xy 199.406121 -55.929179) (xy 199.376398 -55.975146) (xy 199.358758 -55.996078) (xy 199.358504 -55.996332)
			(xy 199.35294 -56.003434) (xy 199.34668 -56.020339) (xy 199.346312 -56.029352) (xy 199.346312 -56.096408)
			(xy 199.346663 -56.105426) (xy 199.352914 -56.122343) (xy 199.358504 -56.129428) (xy 199.358758 -56.129428)
			(xy 199.358758 -56.129682) (xy 199.376396 -56.150615) (xy 199.406109 -56.196587) (xy 199.428946 -56.246334)
			(xy 199.444437 -56.298835) (xy 199.452265 -56.353011) (xy 199.452738 -56.38038) (xy 199.452252 -56.407631)
			(xy 199.444496 -56.461579) (xy 199.429141 -56.513874) (xy 199.406499 -56.563451) (xy 199.377033 -56.609301)
			(xy 199.341342 -56.650492) (xy 199.300151 -56.686183) (xy 199.254301 -56.715649) (xy 199.204724 -56.738291)
			(xy 199.152429 -56.753646) (xy 199.098481 -56.761402) (xy 199.043979 -56.761402) (xy 198.990031 -56.753646)
			(xy 198.937736 -56.738291) (xy 198.888159 -56.715649) (xy 198.842309 -56.686183) (xy 198.801118 -56.650492)
			(xy 198.765427 -56.609301) (xy 198.735961 -56.563451) (xy 198.713319 -56.513874) (xy 198.697964 -56.461579)
			(xy 198.690208 -56.407631) (xy 198.689722 -56.38038) (xy 198.690171 -56.353009) (xy 198.697992 -56.298829)
			(xy 198.713485 -56.246326) (xy 198.736331 -56.196579) (xy 198.766059 -56.150613) (xy 198.783702 -56.129682)
			(xy 198.783956 -56.129428) (xy 198.789544 -56.122342) (xy 198.795788 -56.105425) (xy 198.796148 -56.096408)
			(xy 198.796148 -56.029352) (xy 198.795777 -56.020336) (xy 198.789541 -56.003419) (xy 198.783956 -55.996332)
			(xy 198.783702 -55.996332) (xy 198.783702 -55.996078) (xy 198.766043 -55.975161) (xy 198.736321 -55.92919)
			(xy 198.713478 -55.879441) (xy 198.697984 -55.826936) (xy 198.690158 -55.772756) (xy 198.69016 -55.718014)
			(xy 198.697991 -55.663834) (xy 198.713489 -55.611331) (xy 198.736335 -55.561584) (xy 198.766061 -55.515615)
			(xy 198.783702 -55.494682) (xy 198.783956 -55.494428) (xy 198.789544 -55.487342) (xy 198.795788 -55.470425)
			(xy 198.796148 -55.461408) (xy 198.796148 -55.394352) (xy 198.795777 -55.385336) (xy 198.789541 -55.368419)
			(xy 198.783956 -55.361332) (xy 198.783702 -55.360824) (xy 198.772759 -55.348089) (xy 198.752917 -55.320998)
			(xy 198.744078 -55.306722) (xy 198.738744 -55.297832) (xy 198.721726 -55.28564) (xy 198.628508 -55.26532)
			(xy 198.607934 -55.269638) (xy 198.599298 -55.27548) (xy 198.575235 -55.291481) (xy 198.523303 -55.316824)
			(xy 198.468145 -55.334049) (xy 198.411021 -55.342764) (xy 198.382128 -55.343298) (xy 198.354873 -55.342857)
			(xy 198.300918 -55.335103) (xy 198.248615 -55.319749) (xy 198.19903 -55.297108) (xy 198.153172 -55.267639)
			(xy 198.111975 -55.231945) (xy 198.076277 -55.19075) (xy 198.046806 -55.144895) (xy 198.024161 -55.095311)
			(xy 198.008803 -55.04301) (xy 198.001045 -54.989055) (xy 196.920798 -54.989055) (xy 196.972094 -55.020568)
			(xy 197.02078 -55.060631) (xy 197.042532 -55.083456) (xy 197.049136 -55.090568) (xy 197.066154 -55.09895)
			(xy 197.14464 -55.1053) (xy 197.154206 -55.105685) (xy 197.17249 -55.100055) (xy 197.1802 -55.094378)
			(xy 197.200506 -55.078872) (xy 197.24445 -55.052808) (xy 197.291477 -55.032838) (xy 197.340748 -55.01932)
			(xy 197.391382 -55.012496) (xy 197.416928 -55.012082) (xy 197.444177 -55.01259) (xy 197.49812 -55.02035)
			(xy 197.55041 -55.035707) (xy 197.599983 -55.058349) (xy 197.645828 -55.087815) (xy 197.687014 -55.123506)
			(xy 197.722702 -55.164694) (xy 197.752164 -55.210542) (xy 197.774803 -55.260116) (xy 197.790156 -55.312407)
			(xy 197.797912 -55.366351) (xy 197.797912 -55.420849) (xy 197.790156 -55.474793) (xy 197.774803 -55.527084)
			(xy 197.752164 -55.576658) (xy 197.722702 -55.622506) (xy 197.687014 -55.663694) (xy 197.645828 -55.699385)
			(xy 197.599983 -55.728851) (xy 197.55041 -55.751493) (xy 197.49812 -55.76685) (xy 197.444177 -55.77461)
			(xy 197.416928 -55.775098) (xy 197.39138 -55.774688) (xy 197.340741 -55.767881) (xy 197.291464 -55.754372)
			(xy 197.244432 -55.734404) (xy 197.200489 -55.708333) (xy 197.1802 -55.692802) (xy 197.172474 -55.687165)
			(xy 197.154199 -55.681564) (xy 197.14464 -55.68188) (xy 197.066154 -55.68823) (xy 197.049136 -55.696612)
			(xy 197.042532 -55.703724) (xy 197.020765 -55.726536) (xy 196.972093 -55.766618) (xy 196.918377 -55.799634)
			(xy 196.860635 -55.824959) (xy 196.799962 -55.842113) (xy 196.737508 -55.850771) (xy 196.705982 -55.851298)
			(xy 196.705728 -55.851298) (xy 196.675757 -55.850851) (xy 196.616328 -55.84303) (xy 196.558428 -55.827519)
			(xy 196.503048 -55.804583) (xy 196.451136 -55.774614) (xy 196.403579 -55.738126) (xy 196.361193 -55.695742)
			(xy 196.324702 -55.648188) (xy 196.29473 -55.596277) (xy 196.27179 -55.540899) (xy 196.256275 -55.483)
			(xy 196.248451 -55.423571) (xy 195.597086 -55.423571) (xy 195.546628 -55.445013) (xy 195.492671 -55.459119)
			(xy 195.437234 -55.465219) (xy 195.3815 -55.463182) (xy 195.326657 -55.453052) (xy 195.273873 -55.435045)
			(xy 195.224273 -55.409544) (xy 195.178915 -55.377093) (xy 195.138766 -55.338384) (xy 195.10468 -55.294241)
			(xy 195.077384 -55.245606) (xy 195.057461 -55.193515) (xy 195.045335 -55.139078) (xy 195.041264 -55.083456)
			(xy 188.770416 -55.083456) (xy 188.735653 -55.105797) (xy 188.686076 -55.128439) (xy 188.633781 -55.143794)
			(xy 188.579833 -55.15155) (xy 188.525331 -55.15155) (xy 188.471383 -55.143794) (xy 188.419088 -55.128439)
			(xy 188.369511 -55.105797) (xy 188.323661 -55.076331) (xy 188.28247 -55.04064) (xy 188.246779 -54.999449)
			(xy 188.217313 -54.953599) (xy 188.194671 -54.904022) (xy 188.179316 -54.851727) (xy 188.17156 -54.797779)
			(xy 188.171074 -54.770528) (xy 185.039155 -54.770528) (xy 185.039508 -54.791102) (xy 185.039022 -54.818353)
			(xy 185.031266 -54.872301) (xy 185.015911 -54.924596) (xy 184.993269 -54.974173) (xy 184.963803 -55.020023)
			(xy 184.928112 -55.061214) (xy 184.886921 -55.096905) (xy 184.841071 -55.126371) (xy 184.791494 -55.149013)
			(xy 184.739199 -55.164368) (xy 184.685251 -55.172124) (xy 184.630749 -55.172124) (xy 184.576801 -55.164368)
			(xy 184.524506 -55.149013) (xy 184.474929 -55.126371) (xy 184.429079 -55.096905) (xy 184.387888 -55.061214)
			(xy 184.352197 -55.020023) (xy 184.322731 -54.974173) (xy 184.300089 -54.924596) (xy 184.284734 -54.872301)
			(xy 184.276978 -54.818353) (xy 184.276492 -54.791102) (xy 184.276964 -54.763732) (xy 184.284787 -54.709553)
			(xy 184.300274 -54.657049) (xy 184.323105 -54.607298) (xy 184.352813 -54.56132) (xy 184.370472 -54.540404)
			(xy 184.376568 -54.533292) (xy 184.379616 -54.52491) (xy 184.381145 -54.520624) (xy 184.382811 -54.511679)
			(xy 184.382918 -54.50713) (xy 184.382918 -54.440074) (xy 184.382798 -54.435526) (xy 184.381142 -54.42658)
			(xy 184.379616 -54.422294) (xy 184.376568 -54.413912) (xy 184.370472 -54.4068) (xy 184.352829 -54.385868)
			(xy 184.323101 -54.339901) (xy 184.300252 -54.290155) (xy 184.284754 -54.237652) (xy 184.276924 -54.183473)
			(xy 184.276924 -54.12873) (xy 184.284753 -54.074551) (xy 184.300251 -54.022048) (xy 184.323099 -53.972301)
			(xy 184.352827 -53.926334) (xy 184.370472 -53.905404) (xy 184.376568 -53.898292) (xy 184.379616 -53.88991)
			(xy 184.381145 -53.885624) (xy 184.382811 -53.876679) (xy 184.382918 -53.87213) (xy 184.382918 -53.805074)
			(xy 184.382798 -53.800526) (xy 184.381142 -53.79158) (xy 184.379616 -53.787294) (xy 184.376568 -53.778912)
			(xy 184.370472 -53.7718) (xy 184.352831 -53.750868) (xy 184.323107 -53.704901) (xy 184.300266 -53.655154)
			(xy 184.284777 -53.602651) (xy 184.276959 -53.548472) (xy 184.276492 -53.521102) (xy 184.27657 -53.508364)
			(xy 184.278224 -53.482943) (xy 184.279794 -53.470302) (xy 184.284432 -53.440168) (xy 184.302043 -53.3818)
			(xy 184.32873 -53.326984) (xy 184.36381 -53.277121) (xy 184.384696 -53.25491) (xy 184.385204 -53.254402)
			(xy 184.390296 -53.248606) (xy 184.397128 -53.234785) (xy 184.398666 -53.227224) (xy 184.399174 -53.21935)
			(xy 184.399174 -53.187854) (xy 184.398412 -53.17871) (xy 184.397396 -53.1749) (xy 184.395503 -53.168421)
			(xy 184.388813 -53.156702) (xy 184.384188 -53.151786) (xy 184.383172 -53.15077) (xy 184.371488 -53.137816)
			(xy 184.3642 -53.130862) (xy 184.345732 -53.122854) (xy 184.335674 -53.122322) (xy 182.4228 -53.122322)
			(xy 182.413991 -53.12274) (xy 182.397435 -53.128782) (xy 182.383888 -53.140055) (xy 182.379112 -53.147468)
			(xy 182.334662 -53.22316) (xy 182.331496 -53.229097) (xy 182.328026 -53.24209) (xy 182.327804 -53.248814)
			(xy 182.327804 -53.262022) (xy 182.329582 -53.265324) (xy 182.334408 -53.273706) (xy 182.346103 -53.295242)
			(xy 182.364522 -53.340657) (xy 182.376982 -53.388054) (xy 182.383279 -53.436655) (xy 182.383684 -53.461158)
			(xy 182.383684 -53.461412) (xy 182.383211 -53.488782) (xy 182.375386 -53.542959) (xy 182.359897 -53.595461)
			(xy 182.337063 -53.645211) (xy 182.307352 -53.691186) (xy 182.289704 -53.71211) (xy 182.283608 -53.719222)
			(xy 182.28056 -53.727604) (xy 182.279039 -53.731892) (xy 182.277376 -53.740836) (xy 182.277258 -53.745384)
			(xy 182.277258 -53.81244) (xy 182.277379 -53.816988) (xy 182.279036 -53.825933) (xy 182.28056 -53.83022)
			(xy 182.283608 -53.838602) (xy 182.289704 -53.845714) (xy 182.307343 -53.866647) (xy 182.337063 -53.912616)
			(xy 182.359905 -53.962361) (xy 182.375398 -54.014862) (xy 182.383225 -54.069039) (xy 182.383224 -54.123779)
			(xy 182.375395 -54.177955) (xy 182.359899 -54.230456) (xy 182.337055 -54.2802) (xy 182.307332 -54.326167)
			(xy 182.289704 -54.34711) (xy 182.283608 -54.354222) (xy 182.28056 -54.362604) (xy 182.279039 -54.366892)
			(xy 182.277376 -54.375836) (xy 182.277258 -54.380384) (xy 182.277258 -54.44744) (xy 182.277379 -54.451988)
			(xy 182.279036 -54.460933) (xy 182.28056 -54.46522) (xy 182.283608 -54.473602) (xy 182.289704 -54.480714)
			(xy 182.307345 -54.501646) (xy 182.337069 -54.547613) (xy 182.35991 -54.597359) (xy 182.375398 -54.649863)
			(xy 182.383215 -54.704042) (xy 182.383684 -54.731412) (xy 182.383198 -54.758663) (xy 182.375442 -54.812611)
			(xy 182.360087 -54.864906) (xy 182.337445 -54.914483) (xy 182.307979 -54.960333) (xy 182.272288 -55.001524)
			(xy 182.231097 -55.037215) (xy 182.185247 -55.066681) (xy 182.13567 -55.089323) (xy 182.083375 -55.104678)
			(xy 182.029427 -55.112434) (xy 181.974925 -55.112434) (xy 181.920977 -55.104678) (xy 181.868682 -55.089323)
			(xy 181.819105 -55.066681) (xy 181.773255 -55.037215) (xy 181.732064 -55.001524) (xy 181.696373 -54.960333)
			(xy 181.666907 -54.914483) (xy 181.644265 -54.864906) (xy 181.62891 -54.812611) (xy 181.621154 -54.758663)
			(xy 181.620668 -54.731412) (xy 181.621146 -54.704045) (xy 181.628982 -54.649873) (xy 181.644481 -54.597379)
			(xy 181.667325 -54.547638) (xy 181.697043 -54.501674) (xy 181.714648 -54.480714) (xy 181.720744 -54.473602)
			(xy 181.723792 -54.46522) (xy 181.725314 -54.460932) (xy 181.726979 -54.451988) (xy 181.727094 -54.44744)
			(xy 181.727094 -54.380384) (xy 181.726966 -54.375837) (xy 181.725298 -54.366896) (xy 181.723792 -54.362604)
			(xy 181.720744 -54.354222) (xy 181.714648 -54.34711) (xy 181.697006 -54.326178) (xy 181.667277 -54.28021)
			(xy 181.644429 -54.230463) (xy 181.62893 -54.17796) (xy 181.6211 -54.12378) (xy 181.621099 -54.069038)
			(xy 181.628927 -54.014857) (xy 181.644423 -53.962354) (xy 181.667269 -53.912606) (xy 181.696995 -53.866637)
			(xy 181.714648 -53.845714) (xy 181.720744 -53.838602) (xy 181.723792 -53.83022) (xy 181.725314 -53.825932)
			(xy 181.726979 -53.816988) (xy 181.727094 -53.81244) (xy 181.727094 -53.745384) (xy 181.726966 -53.740837)
			(xy 181.725298 -53.731896) (xy 181.723792 -53.727604) (xy 181.720744 -53.719222) (xy 181.714648 -53.71211)
			(xy 181.697003 -53.69118) (xy 181.667273 -53.645215) (xy 181.644425 -53.595468) (xy 181.628931 -53.542964)
			(xy 181.62111 -53.488783) (xy 181.620668 -53.461412) (xy 181.620668 -53.461158) (xy 181.621044 -53.436652)
			(xy 181.627325 -53.388045) (xy 181.639789 -53.340645) (xy 181.658232 -53.295235) (xy 181.669944 -53.273706)
			(xy 181.67477 -53.265324) (xy 181.676548 -53.262022) (xy 181.676548 -53.248814) (xy 181.676374 -53.242083)
			(xy 181.672893 -53.229083) (xy 181.66969 -53.22316) (xy 181.62524 -53.147468) (xy 181.62048 -53.140034)
			(xy 181.606948 -53.128718) (xy 181.590371 -53.122691) (xy 181.581552 -53.122322) (xy 175.665638 -53.122322)
			(xy 175.657076 -53.122704) (xy 175.640931 -53.128428) (xy 175.627552 -53.139125) (xy 175.622712 -53.146198)
			(xy 175.587406 -53.20792) (xy 175.577754 -53.224684) (xy 175.574665 -53.230502) (xy 175.571334 -53.243244)
			(xy 175.57115 -53.24983) (xy 175.57115 -53.263546) (xy 175.578262 -53.275484) (xy 175.590816 -53.297591)
			(xy 175.610596 -53.344425) (xy 175.623968 -53.393474) (xy 175.630695 -53.443866) (xy 175.631094 -53.469286)
			(xy 175.631094 -53.475382) (xy 175.630197 -53.502347) (xy 175.621744 -53.555632) (xy 175.605868 -53.607194)
			(xy 175.582884 -53.656004) (xy 175.553252 -53.70109) (xy 175.517563 -53.74155) (xy 175.476528 -53.776577)
			(xy 175.430968 -53.805473) (xy 175.38179 -53.827661) (xy 175.329977 -53.842698) (xy 175.276562 -53.850284)
			(xy 175.249586 -53.850794) (xy 175.222216 -53.850321) (xy 175.168039 -53.842496) (xy 175.115537 -53.827007)
			(xy 175.065787 -53.804173) (xy 175.019812 -53.774463) (xy 174.998888 -53.756814) (xy 174.991776 -53.750718)
			(xy 174.983394 -53.74767) (xy 174.979108 -53.746143) (xy 174.970163 -53.74448) (xy 174.965614 -53.744368)
			(xy 174.898558 -53.744368) (xy 174.89401 -53.74449) (xy 174.885065 -53.746147) (xy 174.880778 -53.74767)
			(xy 174.872396 -53.750718) (xy 174.865284 -53.756814) (xy 174.844352 -53.774455) (xy 174.798385 -53.804178)
			(xy 174.748638 -53.827018) (xy 174.696135 -53.842505) (xy 174.641956 -53.850321) (xy 174.614586 -53.850794)
			(xy 174.58761 -53.850327) (xy 174.534196 -53.842726) (xy 174.482385 -53.827677) (xy 174.433211 -53.80548)
			(xy 174.387653 -53.776578) (xy 174.34662 -53.741547) (xy 174.310931 -53.701086) (xy 174.281296 -53.656002)
			(xy 174.258307 -53.607192) (xy 174.242423 -53.555631) (xy 174.233959 -53.502347) (xy 174.233078 -53.475382)
			(xy 174.233078 -53.469286) (xy 174.233503 -53.443869) (xy 174.240256 -53.393486) (xy 174.253629 -53.344442)
			(xy 174.273384 -53.297604) (xy 174.28591 -53.275484) (xy 174.289466 -53.269642) (xy 174.293022 -53.256434)
			(xy 174.293022 -53.24983) (xy 174.292815 -53.243248) (xy 174.289476 -53.230515) (xy 174.286418 -53.224684)
			(xy 174.276766 -53.20792) (xy 174.24146 -53.146198) (xy 174.236649 -53.139094) (xy 174.22328 -53.128357)
			(xy 174.207107 -53.12266) (xy 174.198534 -53.122322) (xy 169.916602 -53.122322) (xy 169.908247 -53.122711)
			(xy 169.892446 -53.128164) (xy 169.885614 -53.13299) (xy 169.879264 -53.13807) (xy 169.87012 -53.15204)
			(xy 169.867834 -53.16093) (xy 169.86007 -53.190366) (xy 169.837806 -53.247025) (xy 169.808228 -53.300234)
			(xy 169.771859 -53.349053) (xy 169.72934 -53.392621) (xy 169.681422 -53.43017) (xy 169.628951 -53.461036)
			(xy 169.572851 -53.484675) (xy 169.514112 -53.50067) (xy 169.453772 -53.508738) (xy 169.392896 -53.508738)
			(xy 169.332556 -53.50067) (xy 169.273817 -53.484675) (xy 169.217717 -53.461036) (xy 169.165246 -53.43017)
			(xy 169.117328 -53.392621) (xy 169.074809 -53.349053) (xy 169.03844 -53.300234) (xy 169.008862 -53.247025)
			(xy 168.986598 -53.190366) (xy 168.978834 -53.16093) (xy 168.978834 -53.160676) (xy 168.97649 -53.152405)
			(xy 168.967151 -53.137983) (xy 168.960546 -53.132482) (xy 168.95445 -53.127656) (xy 168.938448 -53.122322)
			(xy 160.884362 -53.122322) (xy 160.876465 -53.122649) (xy 160.861448 -53.127552) (xy 160.854898 -53.131974)
			(xy 160.848548 -53.136292) (xy 160.839404 -53.148738) (xy 160.83661 -53.156612) (xy 160.826386 -53.185087)
			(xy 160.799481 -53.239277) (xy 160.765663 -53.289445) (xy 160.725523 -53.334714) (xy 160.679763 -53.374292)
			(xy 160.654746 -53.391308) (xy 160.645602 -53.39715) (xy 160.640014 -53.405786) (xy 160.637336 -53.410114)
			(xy 160.633616 -53.419586) (xy 160.632648 -53.424582) (xy 160.619948 -53.49875) (xy 160.619232 -53.504024)
			(xy 160.619743 -53.514652) (xy 160.620964 -53.519832) (xy 160.62325 -53.52923) (xy 160.629854 -53.537866)
			(xy 160.644743 -53.557921) (xy 160.669742 -53.601163) (xy 160.688888 -53.647296) (xy 160.701853 -53.695533)
			(xy 160.708416 -53.745048) (xy 160.708848 -53.770022) (xy 160.708848 -53.77053) (xy 160.70836 -53.797781)
			(xy 160.7006 -53.851727) (xy 160.685243 -53.904021) (xy 160.662601 -53.953597) (xy 160.633134 -53.999446)
			(xy 160.597443 -54.040636) (xy 160.556254 -54.076328) (xy 160.510406 -54.105796) (xy 160.46083 -54.12844)
			(xy 160.408537 -54.143798) (xy 160.354591 -54.151559) (xy 160.32734 -54.152038) (xy 160.299972 -54.151562)
			(xy 160.245799 -54.143729) (xy 160.193301 -54.128234) (xy 160.143558 -54.105393) (xy 160.097591 -54.075677)
			(xy 160.076642 -54.058058) (xy 160.06953 -54.051962) (xy 160.061148 -54.048914) (xy 160.056859 -54.047398)
			(xy 160.047915 -54.045746) (xy 160.043368 -54.045612) (xy 159.976312 -54.045612) (xy 159.971765 -54.045738)
			(xy 159.962822 -54.047401) (xy 159.958532 -54.048914) (xy 159.95015 -54.051962) (xy 159.943038 -54.058058)
			(xy 159.922106 -54.075698) (xy 159.876139 -54.10542) (xy 159.826392 -54.128258) (xy 159.773889 -54.143741)
			(xy 159.71971 -54.151552) (xy 159.69234 -54.152038) (xy 159.665084 -54.151578) (xy 159.611128 -54.143826)
			(xy 159.558823 -54.128473) (xy 159.509236 -54.105834) (xy 159.463376 -54.076367) (xy 159.422176 -54.040674)
			(xy 159.386475 -53.99948) (xy 159.357 -53.953626) (xy 159.334351 -53.904043) (xy 159.318989 -53.851741)
			(xy 159.311227 -53.797785) (xy 159.310832 -53.77053) (xy 159.311364 -53.741613) (xy 159.320088 -53.68444)
			(xy 159.337339 -53.629238) (xy 159.362724 -53.577272) (xy 159.395661 -53.529733) (xy 159.435395 -53.487708)
			(xy 159.457898 -53.46954) (xy 159.465275 -53.463252) (xy 159.475058 -53.446536) (xy 159.476948 -53.437028)
			(xy 159.477456 -53.429408) (xy 159.477456 -53.349652) (xy 159.476948 -53.342032) (xy 159.475186 -53.333013)
			(xy 159.466195 -53.317003) (xy 159.459422 -53.31079) (xy 159.457898 -53.30952) (xy 159.438626 -53.294013)
			(xy 159.403851 -53.258832) (xy 159.37391 -53.219456) (xy 159.349303 -53.176543) (xy 159.339534 -53.153818)
			(xy 159.335216 -53.143404) (xy 159.327088 -53.135784) (xy 159.320484 -53.130704) (xy 159.314388 -53.12664)
			(xy 159.300418 -53.122322) (xy 158.98114 -53.122322) (xy 158.980378 -53.122322) (xy 158.970345 -53.122973)
			(xy 158.951915 -53.130956) (xy 158.944564 -53.137816) (xy 158.93288 -53.15077) (xy 158.931864 -53.151786)
			(xy 158.927246 -53.156708) (xy 158.92056 -53.168425) (xy 158.918656 -53.1749) (xy 158.916878 -53.1876)
			(xy 158.916878 -53.21935) (xy 158.91764 -53.228494) (xy 158.919239 -53.235901) (xy 158.926213 -53.249345)
			(xy 158.931356 -53.25491) (xy 158.951532 -53.276408) (xy 158.985684 -53.324465) (xy 159.012036 -53.377204)
			(xy 159.02996 -53.43337) (xy 159.03903 -53.491624) (xy 159.03956 -53.521102) (xy 159.039088 -53.548472)
			(xy 159.031263 -53.602649) (xy 159.015775 -53.655152) (xy 158.99294 -53.704901) (xy 158.963229 -53.750876)
			(xy 158.94558 -53.7718) (xy 158.939484 -53.778912) (xy 158.936436 -53.787294) (xy 158.934915 -53.791582)
			(xy 158.933251 -53.800526) (xy 158.933134 -53.805074) (xy 158.933134 -53.87213) (xy 158.933255 -53.876678)
			(xy 158.934909 -53.885624) (xy 158.936436 -53.88991) (xy 158.939484 -53.898292) (xy 158.94558 -53.905404)
			(xy 158.96322 -53.926337) (xy 158.992944 -53.972305) (xy 159.015789 -54.022051) (xy 159.031285 -54.074553)
			(xy 159.039113 -54.128731) (xy 159.039113 -54.183472) (xy 159.031284 -54.23765) (xy 159.015788 -54.290152)
			(xy 159.001995 -54.320186) (xy 161.230564 -54.320186) (xy 161.231006 -54.292815) (xy 161.238827 -54.238634)
			(xy 161.254321 -54.18613) (xy 161.277169 -54.136383) (xy 161.3069 -54.090418) (xy 161.324544 -54.069488)
			(xy 161.324798 -54.069234) (xy 161.330376 -54.062142) (xy 161.336628 -54.045229) (xy 161.33699 -54.036214)
			(xy 161.33699 -53.969158) (xy 161.336607 -53.960144) (xy 161.330378 -53.943226) (xy 161.324798 -53.936138)
			(xy 161.324544 -53.936138) (xy 161.324544 -53.935884) (xy 161.306938 -53.914925) (xy 161.277219 -53.868961)
			(xy 161.254376 -53.81922) (xy 161.238878 -53.766725) (xy 161.231042 -53.712553) (xy 161.230564 -53.685186)
			(xy 161.23105 -53.657935) (xy 161.238806 -53.603987) (xy 161.254161 -53.551692) (xy 161.276803 -53.502115)
			(xy 161.306269 -53.456265) (xy 161.34196 -53.415074) (xy 161.383151 -53.379383) (xy 161.429001 -53.349917)
			(xy 161.478578 -53.327275) (xy 161.530873 -53.31192) (xy 161.584821 -53.304164) (xy 161.639323 -53.304164)
			(xy 161.693271 -53.31192) (xy 161.745566 -53.327275) (xy 161.795143 -53.349917) (xy 161.840993 -53.379383)
			(xy 161.882184 -53.415074) (xy 161.917875 -53.456265) (xy 161.947341 -53.502115) (xy 161.969983 -53.551692)
			(xy 161.985338 -53.603987) (xy 161.993094 -53.657935) (xy 161.99358 -53.685186) (xy 161.993111 -53.712556)
			(xy 161.985294 -53.766735) (xy 161.969806 -53.819239) (xy 161.946965 -53.868986) (xy 161.917241 -53.914952)
			(xy 161.8996 -53.935884) (xy 161.899346 -53.936138) (xy 161.893773 -53.943233) (xy 161.887519 -53.960144)
			(xy 161.887154 -53.969158) (xy 161.887154 -54.036214) (xy 161.887493 -54.045233) (xy 161.893752 -54.06215)
			(xy 161.899346 -54.069234) (xy 161.8996 -54.069234) (xy 161.8996 -54.069488) (xy 161.917247 -54.090414)
			(xy 161.946958 -54.136388) (xy 161.969792 -54.186137) (xy 161.985281 -54.238639) (xy 161.993107 -54.292816)
			(xy 161.99358 -54.320186) (xy 161.993094 -54.347437) (xy 161.985338 -54.401385) (xy 161.969983 -54.45368)
			(xy 161.947341 -54.503257) (xy 161.917875 -54.549107) (xy 161.882184 -54.590298) (xy 161.840993 -54.625989)
			(xy 161.795143 -54.655455) (xy 161.745566 -54.678097) (xy 161.693271 -54.693452) (xy 161.639323 -54.701208)
			(xy 161.584821 -54.701208) (xy 161.530873 -54.693452) (xy 161.478578 -54.678097) (xy 161.429001 -54.655455)
			(xy 161.383151 -54.625989) (xy 161.34196 -54.590298) (xy 161.306269 -54.549107) (xy 161.276803 -54.503257)
			(xy 161.254161 -54.45368) (xy 161.238806 -54.401385) (xy 161.23105 -54.347437) (xy 161.230564 -54.320186)
			(xy 159.001995 -54.320186) (xy 158.992943 -54.339898) (xy 158.963218 -54.385866) (xy 158.94558 -54.4068)
			(xy 158.939484 -54.413912) (xy 158.936436 -54.422294) (xy 158.934915 -54.426582) (xy 158.933251 -54.435526)
			(xy 158.933134 -54.440074) (xy 158.933134 -54.50713) (xy 158.933255 -54.511678) (xy 158.934909 -54.520624)
			(xy 158.936436 -54.52491) (xy 158.939484 -54.533292) (xy 158.94558 -54.540404) (xy 158.963223 -54.561335)
			(xy 158.99295 -54.607301) (xy 159.015794 -54.657048) (xy 159.031284 -54.709552) (xy 159.039103 -54.763731)
			(xy 159.039216 -54.770528) (xy 162.171126 -54.770528) (xy 162.171602 -54.743158) (xy 162.179417 -54.688979)
			(xy 162.194903 -54.636476) (xy 162.217743 -54.586729) (xy 162.247465 -54.540762) (xy 162.265106 -54.51983)
			(xy 162.26536 -54.519576) (xy 162.27097 -54.512506) (xy 162.277201 -54.495576) (xy 162.277552 -54.486556)
			(xy 162.277552 -54.4195) (xy 162.277205 -54.410482) (xy 162.270952 -54.393565) (xy 162.26536 -54.38648)
			(xy 162.265106 -54.38648) (xy 162.265106 -54.386226) (xy 162.247467 -54.365294) (xy 162.217755 -54.319321)
			(xy 162.194919 -54.269574) (xy 162.179428 -54.217073) (xy 162.1716 -54.162897) (xy 162.171126 -54.135528)
			(xy 162.171612 -54.108277) (xy 162.179368 -54.054329) (xy 162.194723 -54.002034) (xy 162.217365 -53.952457)
			(xy 162.246831 -53.906607) (xy 162.282522 -53.865416) (xy 162.323713 -53.829725) (xy 162.369563 -53.800259)
			(xy 162.41914 -53.777617) (xy 162.471435 -53.762262) (xy 162.525383 -53.754506) (xy 162.579885 -53.754506)
			(xy 162.633833 -53.762262) (xy 162.686128 -53.777617) (xy 162.735705 -53.800259) (xy 162.781555 -53.829725)
			(xy 162.822746 -53.865416) (xy 162.858437 -53.906607) (xy 162.887903 -53.952457) (xy 162.906665 -53.993538)
			(xy 166.796956 -53.993538) (xy 166.796956 -53.933602) (xy 166.804779 -53.87418) (xy 166.820292 -53.816287)
			(xy 166.843228 -53.760914) (xy 166.873195 -53.709008) (xy 166.909682 -53.661458) (xy 166.952062 -53.619078)
			(xy 166.999612 -53.582591) (xy 167.051518 -53.552624) (xy 167.106891 -53.529688) (xy 167.164784 -53.514175)
			(xy 167.224206 -53.506352) (xy 167.284142 -53.506352) (xy 167.343564 -53.514175) (xy 167.401457 -53.529688)
			(xy 167.45683 -53.552624) (xy 167.508736 -53.582591) (xy 167.556286 -53.619078) (xy 167.598666 -53.661458)
			(xy 167.635153 -53.709008) (xy 167.66512 -53.760914) (xy 167.688056 -53.816287) (xy 167.703569 -53.87418)
			(xy 167.711392 -53.933602) (xy 167.711882 -53.96357) (xy 167.711392 -53.993538) (xy 167.703569 -54.05296)
			(xy 167.699685 -54.067456) (xy 169.041316 -54.067456) (xy 169.045387 -54.011834) (xy 169.057513 -53.957397)
			(xy 169.077436 -53.905306) (xy 169.104732 -53.856671) (xy 169.138818 -53.812528) (xy 169.178967 -53.773819)
			(xy 169.224325 -53.741368) (xy 169.273925 -53.715867) (xy 169.326709 -53.69786) (xy 169.381552 -53.68773)
			(xy 169.437286 -53.685693) (xy 169.492723 -53.691793) (xy 169.54668 -53.705899) (xy 169.598009 -53.727711)
			(xy 169.645615 -53.756765) (xy 169.688483 -53.79244) (xy 169.7257 -53.833977) (xy 169.756473 -53.88049)
			(xy 169.780145 -53.930987) (xy 169.796213 -53.984394) (xy 169.804333 -54.03957) (xy 169.804842 -54.067456)
			(xy 169.804333 -54.095342) (xy 169.796213 -54.150518) (xy 169.780145 -54.203925) (xy 169.763747 -54.238906)
			(xy 176.486056 -54.238906) (xy 176.490127 -54.183284) (xy 176.502253 -54.128847) (xy 176.522176 -54.076756)
			(xy 176.549472 -54.028121) (xy 176.583558 -53.983978) (xy 176.623707 -53.945269) (xy 176.669065 -53.912818)
			(xy 176.718665 -53.887317) (xy 176.771449 -53.86931) (xy 176.826292 -53.85918) (xy 176.882026 -53.857143)
			(xy 176.937463 -53.863243) (xy 176.99142 -53.877349) (xy 177.042749 -53.899161) (xy 177.090355 -53.928215)
			(xy 177.133223 -53.96389) (xy 177.17044 -54.005427) (xy 177.201213 -54.05194) (xy 177.224885 -54.102437)
			(xy 177.240953 -54.155844) (xy 177.249073 -54.21102) (xy 177.249582 -54.238906) (xy 177.249073 -54.266792)
			(xy 177.240953 -54.321968) (xy 177.224885 -54.375375) (xy 177.201213 -54.425872) (xy 177.17044 -54.472385)
			(xy 177.133223 -54.513922) (xy 177.090355 -54.549597) (xy 177.042749 -54.578651) (xy 176.99142 -54.600463)
			(xy 176.937463 -54.614569) (xy 176.882026 -54.620669) (xy 176.826292 -54.618632) (xy 176.771449 -54.608502)
			(xy 176.718665 -54.590495) (xy 176.669065 -54.564994) (xy 176.623707 -54.532543) (xy 176.583558 -54.493834)
			(xy 176.549472 -54.449691) (xy 176.522176 -54.401056) (xy 176.502253 -54.348965) (xy 176.490127 -54.294528)
			(xy 176.486056 -54.238906) (xy 169.763747 -54.238906) (xy 169.756473 -54.254422) (xy 169.7257 -54.300935)
			(xy 169.688483 -54.342472) (xy 169.645615 -54.378147) (xy 169.598009 -54.407201) (xy 169.54668 -54.429013)
			(xy 169.492723 -54.443119) (xy 169.437286 -54.449219) (xy 169.381552 -54.447182) (xy 169.326709 -54.437052)
			(xy 169.273925 -54.419045) (xy 169.224325 -54.393544) (xy 169.178967 -54.361093) (xy 169.138818 -54.322384)
			(xy 169.104732 -54.278241) (xy 169.077436 -54.229606) (xy 169.057513 -54.177515) (xy 169.045387 -54.123078)
			(xy 169.041316 -54.067456) (xy 167.699685 -54.067456) (xy 167.688056 -54.110853) (xy 167.66512 -54.166226)
			(xy 167.635153 -54.218132) (xy 167.598666 -54.265682) (xy 167.556286 -54.308062) (xy 167.508736 -54.344549)
			(xy 167.45683 -54.374516) (xy 167.401457 -54.397452) (xy 167.343564 -54.412965) (xy 167.284142 -54.420788)
			(xy 167.224206 -54.420788) (xy 167.164784 -54.412965) (xy 167.106891 -54.397452) (xy 167.051518 -54.374516)
			(xy 166.999612 -54.344549) (xy 166.952062 -54.308062) (xy 166.909682 -54.265682) (xy 166.873195 -54.218132)
			(xy 166.843228 -54.166226) (xy 166.820292 -54.110853) (xy 166.804779 -54.05296) (xy 166.796956 -53.993538)
			(xy 162.906665 -53.993538) (xy 162.910545 -54.002034) (xy 162.9259 -54.054329) (xy 162.933656 -54.108277)
			(xy 162.934142 -54.135528) (xy 162.933706 -54.162899) (xy 162.925883 -54.21708) (xy 162.910388 -54.269584)
			(xy 162.887539 -54.319331) (xy 162.857807 -54.365296) (xy 162.840162 -54.386226) (xy 162.839908 -54.38648)
			(xy 162.834325 -54.393569) (xy 162.828076 -54.410484) (xy 162.827716 -54.4195) (xy 162.827716 -54.486556)
			(xy 162.828091 -54.495571) (xy 162.834326 -54.512488) (xy 162.839908 -54.519576) (xy 162.840162 -54.519576)
			(xy 162.840162 -54.51983) (xy 162.857776 -54.540783) (xy 162.887493 -54.586749) (xy 162.910334 -54.636491)
			(xy 162.925831 -54.688988) (xy 162.933665 -54.74316) (xy 162.934142 -54.770528) (xy 162.933656 -54.797779)
			(xy 162.9259 -54.851727) (xy 162.910545 -54.904022) (xy 162.887903 -54.953599) (xy 162.858437 -54.999449)
			(xy 162.822746 -55.04064) (xy 162.781555 -55.076331) (xy 162.770468 -55.083456) (xy 169.041316 -55.083456)
			(xy 169.045387 -55.027834) (xy 169.057513 -54.973397) (xy 169.077436 -54.921306) (xy 169.104732 -54.872671)
			(xy 169.138818 -54.828528) (xy 169.178967 -54.789819) (xy 169.224325 -54.757368) (xy 169.273925 -54.731867)
			(xy 169.326709 -54.71386) (xy 169.381552 -54.70373) (xy 169.437286 -54.701693) (xy 169.492723 -54.707793)
			(xy 169.54668 -54.721899) (xy 169.598009 -54.743711) (xy 169.645615 -54.772765) (xy 169.688483 -54.80844)
			(xy 169.7257 -54.849977) (xy 169.756473 -54.89649) (xy 169.780145 -54.946987) (xy 169.7928 -54.989051)
			(xy 172.001168 -54.989051) (xy 172.001168 -54.934549) (xy 172.008924 -54.880602) (xy 172.024278 -54.828307)
			(xy 172.046919 -54.77873) (xy 172.076384 -54.732879) (xy 172.112074 -54.691688) (xy 172.153263 -54.655996)
			(xy 172.199112 -54.626528) (xy 172.248688 -54.603885) (xy 172.300982 -54.588528) (xy 172.354929 -54.580769)
			(xy 172.38218 -54.580282) (xy 172.410271 -54.580793) (xy 172.465847 -54.589017) (xy 172.519616 -54.605305)
			(xy 172.570413 -54.629305) (xy 172.61714 -54.660498) (xy 172.658786 -54.698208) (xy 172.694449 -54.741619)
			(xy 172.709332 -54.765448) (xy 172.714666 -54.774338) (xy 172.731684 -54.78653) (xy 172.824902 -54.80685)
			(xy 172.845476 -54.802532) (xy 172.854112 -54.79669) (xy 172.87817 -54.780681) (xy 172.930104 -54.755341)
			(xy 172.985264 -54.738118) (xy 173.042389 -54.729405) (xy 173.071282 -54.728872) (xy 173.098532 -54.729395)
			(xy 173.152477 -54.737148) (xy 173.20477 -54.7525) (xy 173.254346 -54.775138) (xy 173.300195 -54.8046)
			(xy 173.341385 -54.840288) (xy 173.377077 -54.881474) (xy 173.406544 -54.927321) (xy 173.429186 -54.976894)
			(xy 173.444543 -55.029186) (xy 173.452302 -55.08313) (xy 173.45279 -55.11038) (xy 173.452315 -55.13775)
			(xy 173.444499 -55.191929) (xy 173.429013 -55.244432) (xy 173.406173 -55.294179) (xy 173.37645 -55.340146)
			(xy 173.35881 -55.361078) (xy 173.358556 -55.361332) (xy 173.352986 -55.36843) (xy 173.346731 -55.385338)
			(xy 173.346364 -55.394352) (xy 173.346364 -55.461408) (xy 173.346725 -55.470424) (xy 173.35297 -55.487341)
			(xy 173.358556 -55.494428) (xy 173.35881 -55.494428) (xy 173.35881 -55.494682) (xy 173.37643 -55.515631)
			(xy 173.406152 -55.561597) (xy 173.428997 -55.611341) (xy 173.444493 -55.66384) (xy 173.452323 -55.718016)
			(xy 173.452325 -55.772754) (xy 173.444499 -55.82693) (xy 173.429007 -55.879431) (xy 173.406167 -55.929176)
			(xy 173.376448 -55.975145) (xy 173.35881 -55.996078) (xy 173.358556 -55.996332) (xy 173.352986 -56.00343)
			(xy 173.346731 -56.020338) (xy 173.346364 -56.029352) (xy 173.346364 -56.096408) (xy 173.346725 -56.105424)
			(xy 173.35297 -56.122341) (xy 173.358556 -56.129428) (xy 173.35881 -56.129428) (xy 173.35881 -56.129682)
			(xy 173.376456 -56.150609) (xy 173.406166 -56.196583) (xy 173.429001 -56.246332) (xy 173.44449 -56.298834)
			(xy 173.452317 -56.35301) (xy 173.45279 -56.38038) (xy 173.452304 -56.407631) (xy 173.444548 -56.461579)
			(xy 173.429193 -56.513874) (xy 173.406551 -56.563451) (xy 173.377085 -56.609301) (xy 173.341394 -56.650492)
			(xy 173.300203 -56.686183) (xy 173.254353 -56.715649) (xy 173.204776 -56.738291) (xy 173.152481 -56.753646)
			(xy 173.098533 -56.761402) (xy 173.044031 -56.761402) (xy 172.990083 -56.753646) (xy 172.937788 -56.738291)
			(xy 172.888211 -56.715649) (xy 172.842361 -56.686183) (xy 172.80117 -56.650492) (xy 172.765479 -56.609301)
			(xy 172.736013 -56.563451) (xy 172.713371 -56.513874) (xy 172.698016 -56.461579) (xy 172.69026 -56.407631)
			(xy 172.689774 -56.38038) (xy 172.69021 -56.353008) (xy 172.698033 -56.298827) (xy 172.713528 -56.246323)
			(xy 172.736376 -56.196577) (xy 172.766109 -56.150612) (xy 172.783754 -56.129682) (xy 172.784008 -56.129428)
			(xy 172.78959 -56.122338) (xy 172.795839 -56.105424) (xy 172.7962 -56.096408) (xy 172.7962 -56.029352)
			(xy 172.795818 -56.020338) (xy 172.789588 -56.003421) (xy 172.784008 -55.996332) (xy 172.783754 -55.996332)
			(xy 172.783754 -55.996078) (xy 172.766093 -55.975162) (xy 172.736367 -55.929192) (xy 172.713521 -55.879443)
			(xy 172.698025 -55.826938) (xy 172.690197 -55.772757) (xy 172.6902 -55.718013) (xy 172.698031 -55.663832)
			(xy 172.713531 -55.611329) (xy 172.736381 -55.561582) (xy 172.766111 -55.515614) (xy 172.783754 -55.494682)
			(xy 172.784008 -55.494428) (xy 172.78959 -55.487338) (xy 172.795839 -55.470424) (xy 172.7962 -55.461408)
			(xy 172.7962 -55.394352) (xy 172.795818 -55.385338) (xy 172.789588 -55.368421) (xy 172.784008 -55.361332)
			(xy 172.783754 -55.360824) (xy 172.772808 -55.348091) (xy 172.752968 -55.320999) (xy 172.74413 -55.306722)
			(xy 172.738796 -55.297832) (xy 172.721778 -55.28564) (xy 172.62856 -55.26532) (xy 172.607986 -55.269638)
			(xy 172.59935 -55.27548) (xy 172.575273 -55.291459) (xy 172.523346 -55.316807) (xy 172.468192 -55.334038)
			(xy 172.411071 -55.34276) (xy 172.38218 -55.343298) (xy 172.354929 -55.342831) (xy 172.300982 -55.335072)
			(xy 172.248688 -55.319715) (xy 172.199112 -55.297072) (xy 172.153263 -55.267604) (xy 172.112074 -55.231912)
			(xy 172.076384 -55.190721) (xy 172.046919 -55.14487) (xy 172.024278 -55.095293) (xy 172.008924 -55.042998)
			(xy 172.001168 -54.989051) (xy 169.7928 -54.989051) (xy 169.796213 -55.000394) (xy 169.804333 -55.05557)
			(xy 169.804842 -55.083456) (xy 169.804333 -55.111342) (xy 169.796213 -55.166518) (xy 169.780145 -55.219925)
			(xy 169.756473 -55.270422) (xy 169.7257 -55.316935) (xy 169.688483 -55.358472) (xy 169.645615 -55.394147)
			(xy 169.60186 -55.420851) (xy 170.324768 -55.420851) (xy 170.324768 -55.366349) (xy 170.332524 -55.312402)
			(xy 170.347878 -55.260107) (xy 170.370519 -55.21053) (xy 170.399984 -55.164679) (xy 170.435674 -55.123488)
			(xy 170.476863 -55.087796) (xy 170.522712 -55.058328) (xy 170.572288 -55.035685) (xy 170.624582 -55.020328)
			(xy 170.678529 -55.012569) (xy 170.70578 -55.012082) (xy 170.732093 -55.012569) (xy 170.784221 -55.0198)
			(xy 170.834863 -55.034116) (xy 170.883062 -55.055245) (xy 170.927906 -55.082787) (xy 170.968547 -55.116222)
			(xy 170.986704 -55.135272) (xy 170.994226 -55.142673) (xy 171.013506 -55.151199) (xy 171.024042 -55.151782)
			(xy 171.098718 -55.151782) (xy 171.109265 -55.151227) (xy 171.128561 -55.142711) (xy 171.136056 -55.135272)
			(xy 171.154186 -55.116191) (xy 171.194822 -55.082737) (xy 171.239668 -55.055182) (xy 171.287873 -55.034048)
			(xy 171.338525 -55.019736) (xy 171.390662 -55.012517) (xy 171.41698 -55.012082) (xy 171.444233 -55.012564)
			(xy 171.498185 -55.020318) (xy 171.550484 -55.035672) (xy 171.600065 -55.058313) (xy 171.645919 -55.08778)
			(xy 171.687113 -55.123472) (xy 171.722808 -55.164665) (xy 171.752277 -55.210517) (xy 171.774921 -55.260098)
			(xy 171.790277 -55.312396) (xy 171.798035 -55.366347) (xy 171.798035 -55.420853) (xy 171.790277 -55.474804)
			(xy 171.774921 -55.527102) (xy 171.752277 -55.576683) (xy 171.722808 -55.622535) (xy 171.687113 -55.663728)
			(xy 171.645919 -55.69942) (xy 171.600065 -55.728887) (xy 171.550484 -55.751528) (xy 171.498185 -55.766882)
			(xy 171.444233 -55.774636) (xy 171.41698 -55.775098) (xy 171.390666 -55.774645) (xy 171.338536 -55.767407)
			(xy 171.287893 -55.753085) (xy 171.239694 -55.73195) (xy 171.194851 -55.704402) (xy 171.154212 -55.670961)
			(xy 171.136056 -55.651908) (xy 171.128552 -55.644486) (xy 171.109259 -55.635973) (xy 171.098718 -55.635398)
			(xy 171.024042 -55.635398) (xy 171.013493 -55.635937) (xy 170.994198 -55.644465) (xy 170.986704 -55.651908)
			(xy 170.968541 -55.670956) (xy 170.927913 -55.704414) (xy 170.883074 -55.731973) (xy 170.834875 -55.753113)
			(xy 170.784229 -55.767432) (xy 170.732096 -55.774658) (xy 170.70578 -55.775098) (xy 170.678529 -55.774631)
			(xy 170.624582 -55.766872) (xy 170.572288 -55.751515) (xy 170.522712 -55.728872) (xy 170.476863 -55.699404)
			(xy 170.435674 -55.663712) (xy 170.399984 -55.622521) (xy 170.370519 -55.57667) (xy 170.347878 -55.527093)
			(xy 170.332524 -55.474798) (xy 170.324768 -55.420851) (xy 169.60186 -55.420851) (xy 169.598009 -55.423201)
			(xy 169.54668 -55.445013) (xy 169.492723 -55.459119) (xy 169.437286 -55.465219) (xy 169.381552 -55.463182)
			(xy 169.326709 -55.453052) (xy 169.273925 -55.435045) (xy 169.224325 -55.409544) (xy 169.178967 -55.377093)
			(xy 169.138818 -55.338384) (xy 169.104732 -55.294241) (xy 169.077436 -55.245606) (xy 169.057513 -55.193515)
			(xy 169.045387 -55.139078) (xy 169.041316 -55.083456) (xy 162.770468 -55.083456) (xy 162.735705 -55.105797)
			(xy 162.686128 -55.128439) (xy 162.633833 -55.143794) (xy 162.579885 -55.15155) (xy 162.525383 -55.15155)
			(xy 162.471435 -55.143794) (xy 162.41914 -55.128439) (xy 162.369563 -55.105797) (xy 162.323713 -55.076331)
			(xy 162.282522 -55.04064) (xy 162.246831 -54.999449) (xy 162.217365 -54.953599) (xy 162.194723 -54.904022)
			(xy 162.179368 -54.851727) (xy 162.171612 -54.797779) (xy 162.171126 -54.770528) (xy 159.039216 -54.770528)
			(xy 159.03956 -54.791102) (xy 159.039074 -54.818353) (xy 159.031318 -54.872301) (xy 159.015963 -54.924596)
			(xy 158.993321 -54.974173) (xy 158.963855 -55.020023) (xy 158.928164 -55.061214) (xy 158.886973 -55.096905)
			(xy 158.841123 -55.126371) (xy 158.791546 -55.149013) (xy 158.739251 -55.164368) (xy 158.685303 -55.172124)
			(xy 158.630801 -55.172124) (xy 158.576853 -55.164368) (xy 158.524558 -55.149013) (xy 158.474981 -55.126371)
			(xy 158.429131 -55.096905) (xy 158.38794 -55.061214) (xy 158.352249 -55.020023) (xy 158.322783 -54.974173)
			(xy 158.300141 -54.924596) (xy 158.284786 -54.872301) (xy 158.27703 -54.818353) (xy 158.276544 -54.791102)
			(xy 158.277016 -54.763732) (xy 158.28484 -54.709554) (xy 158.300328 -54.657052) (xy 158.323162 -54.607302)
			(xy 158.352873 -54.561327) (xy 158.370524 -54.540404) (xy 158.37662 -54.533292) (xy 158.379668 -54.52491)
			(xy 158.38119 -54.520622) (xy 158.382853 -54.511678) (xy 158.38297 -54.50713) (xy 158.38297 -54.440074)
			(xy 158.38285 -54.435526) (xy 158.381196 -54.426579) (xy 158.379668 -54.422294) (xy 158.37662 -54.413912)
			(xy 158.370524 -54.4068) (xy 158.352883 -54.385867) (xy 158.323158 -54.339899) (xy 158.300313 -54.290153)
			(xy 158.284817 -54.237651) (xy 158.276988 -54.183472) (xy 158.276988 -54.128731) (xy 158.284816 -54.074552)
			(xy 158.300312 -54.02205) (xy 158.323157 -53.972303) (xy 158.352881 -53.926335) (xy 158.370524 -53.905404)
			(xy 158.37662 -53.898292) (xy 158.379668 -53.88991) (xy 158.38119 -53.885622) (xy 158.382853 -53.876678)
			(xy 158.38297 -53.87213) (xy 158.38297 -53.805074) (xy 158.38285 -53.800526) (xy 158.381196 -53.791579)
			(xy 158.379668 -53.787294) (xy 158.37662 -53.778912) (xy 158.370524 -53.7718) (xy 158.352881 -53.750869)
			(xy 158.323153 -53.704903) (xy 158.300308 -53.655156) (xy 158.284817 -53.602653) (xy 158.276998 -53.548473)
			(xy 158.276544 -53.521102) (xy 158.276622 -53.508364) (xy 158.278276 -53.482943) (xy 158.279846 -53.470302)
			(xy 158.284485 -53.440168) (xy 158.302098 -53.381802) (xy 158.328787 -53.326988) (xy 158.36387 -53.277128)
			(xy 158.384748 -53.25491) (xy 158.385256 -53.254402) (xy 158.390351 -53.248608) (xy 158.39719 -53.234787)
			(xy 158.398718 -53.227224) (xy 158.399226 -53.21935) (xy 158.399226 -53.187854) (xy 158.398464 -53.17871)
			(xy 158.397448 -53.1749) (xy 158.395557 -53.168419) (xy 158.388872 -53.156696) (xy 158.38424 -53.151786)
			(xy 158.383224 -53.15077) (xy 158.37154 -53.137816) (xy 158.364249 -53.130869) (xy 158.345781 -53.122878)
			(xy 158.335726 -53.122322) (xy 156.422852 -53.122322) (xy 156.414047 -53.122747) (xy 156.397503 -53.1288)
			(xy 156.38397 -53.140076) (xy 156.379164 -53.147468) (xy 156.334714 -53.22316) (xy 156.331551 -53.229097)
			(xy 156.328083 -53.24209) (xy 156.327856 -53.248814) (xy 156.327856 -53.262022) (xy 156.329634 -53.265324)
			(xy 156.33446 -53.273706) (xy 156.346154 -53.295243) (xy 156.36457 -53.340658) (xy 156.377028 -53.388054)
			(xy 156.383324 -53.436655) (xy 156.383736 -53.461158) (xy 156.383736 -53.461412) (xy 156.383263 -53.488781)
			(xy 156.375437 -53.542958) (xy 156.359946 -53.595459) (xy 156.33711 -53.645207) (xy 156.307397 -53.691179)
			(xy 156.289756 -53.71211) (xy 156.28366 -53.719222) (xy 156.280612 -53.727604) (xy 156.279092 -53.731892)
			(xy 156.277431 -53.740836) (xy 156.27731 -53.745384) (xy 156.27731 -53.81244) (xy 156.277431 -53.816988)
			(xy 156.279087 -53.825934) (xy 156.280612 -53.83022) (xy 156.28366 -53.838602) (xy 156.289756 -53.845714)
			(xy 156.307397 -53.866646) (xy 156.337121 -53.912614) (xy 156.359966 -53.962359) (xy 156.375461 -54.014861)
			(xy 156.383289 -54.069039) (xy 156.383287 -54.123779) (xy 156.375457 -54.177957) (xy 156.359959 -54.230458)
			(xy 156.337112 -54.280202) (xy 156.307386 -54.326168) (xy 156.289756 -54.34711) (xy 156.28366 -54.354222)
			(xy 156.280612 -54.362604) (xy 156.279092 -54.366892) (xy 156.277431 -54.375836) (xy 156.27731 -54.380384)
			(xy 156.27731 -54.44744) (xy 156.277431 -54.451988) (xy 156.279087 -54.460934) (xy 156.280612 -54.46522)
			(xy 156.28366 -54.473602) (xy 156.289756 -54.480714) (xy 156.307399 -54.501645) (xy 156.337127 -54.547611)
			(xy 156.359971 -54.597357) (xy 156.375461 -54.649861) (xy 156.383279 -54.704041) (xy 156.383736 -54.731412)
			(xy 156.38325 -54.758663) (xy 156.375494 -54.812611) (xy 156.360139 -54.864906) (xy 156.337497 -54.914483)
			(xy 156.308031 -54.960333) (xy 156.27234 -55.001524) (xy 156.231149 -55.037215) (xy 156.185299 -55.066681)
			(xy 156.135722 -55.089323) (xy 156.083427 -55.104678) (xy 156.029479 -55.112434) (xy 155.974977 -55.112434)
			(xy 155.921029 -55.104678) (xy 155.868734 -55.089323) (xy 155.819157 -55.066681) (xy 155.773307 -55.037215)
			(xy 155.732116 -55.001524) (xy 155.696425 -54.960333) (xy 155.666959 -54.914483) (xy 155.644317 -54.864906)
			(xy 155.628962 -54.812611) (xy 155.621206 -54.758663) (xy 155.62072 -54.731412) (xy 155.621198 -54.704044)
			(xy 155.629033 -54.649872) (xy 155.644531 -54.597377) (xy 155.667372 -54.547635) (xy 155.697088 -54.501668)
			(xy 155.7147 -54.480714) (xy 155.720796 -54.473602) (xy 155.723844 -54.46522) (xy 155.725367 -54.460932)
			(xy 155.727034 -54.451988) (xy 155.727146 -54.44744) (xy 155.727146 -54.380384) (xy 155.727018 -54.375837)
			(xy 155.725349 -54.366897) (xy 155.723844 -54.362604) (xy 155.720796 -54.354222) (xy 155.7147 -54.34711)
			(xy 155.69706 -54.326177) (xy 155.667335 -54.280208) (xy 155.64449 -54.230461) (xy 155.628993 -54.177959)
			(xy 155.621164 -54.12378) (xy 155.621162 -54.069038) (xy 155.628989 -54.014859) (xy 155.644483 -53.962356)
			(xy 155.667326 -53.912608) (xy 155.697049 -53.866638) (xy 155.7147 -53.845714) (xy 155.720796 -53.838602)
			(xy 155.723844 -53.83022) (xy 155.725367 -53.825932) (xy 155.727034 -53.816988) (xy 155.727146 -53.81244)
			(xy 155.727146 -53.745384) (xy 155.727018 -53.740837) (xy 155.725349 -53.731897) (xy 155.723844 -53.727604)
			(xy 155.720796 -53.719222) (xy 155.7147 -53.71211) (xy 155.697057 -53.691179) (xy 155.66733 -53.645213)
			(xy 155.644486 -53.595466) (xy 155.628994 -53.542963) (xy 155.621174 -53.488783) (xy 155.62072 -53.461412)
			(xy 155.62072 -53.461158) (xy 155.621096 -53.436652) (xy 155.627376 -53.388044) (xy 155.639839 -53.340643)
			(xy 155.658279 -53.295233) (xy 155.669996 -53.273706) (xy 155.674822 -53.265324) (xy 155.6766 -53.262022)
			(xy 155.6766 -53.248814) (xy 155.676427 -53.242083) (xy 155.672949 -53.229081) (xy 155.669742 -53.22316)
			(xy 155.625292 -53.147468) (xy 155.62053 -53.140039) (xy 155.606996 -53.128737) (xy 155.59042 -53.122725)
			(xy 155.581604 -53.122322) (xy 149.66569 -53.122322) (xy 149.657123 -53.122696) (xy 149.640967 -53.128409)
			(xy 149.627574 -53.139101) (xy 149.622764 -53.146198) (xy 149.587458 -53.20792) (xy 149.577806 -53.224684)
			(xy 149.574714 -53.230502) (xy 149.571379 -53.243243) (xy 149.571202 -53.24983) (xy 149.571202 -53.263546)
			(xy 149.578314 -53.275484) (xy 149.590866 -53.297592) (xy 149.610644 -53.344426) (xy 149.624014 -53.393475)
			(xy 149.63074 -53.443866) (xy 149.631146 -53.469286) (xy 149.631146 -53.475382) (xy 149.630249 -53.502348)
			(xy 149.621797 -53.555636) (xy 149.605921 -53.607201) (xy 149.582938 -53.656015) (xy 149.553306 -53.701104)
			(xy 149.517618 -53.741568) (xy 149.476584 -53.7766) (xy 149.431024 -53.805502) (xy 149.381846 -53.827695)
			(xy 149.330032 -53.842739) (xy 149.276615 -53.850332) (xy 149.249638 -53.850794) (xy 149.22227 -53.850318)
			(xy 149.168096 -53.842486) (xy 149.115597 -53.826992) (xy 149.065852 -53.804154) (xy 149.019882 -53.774441)
			(xy 148.99894 -53.756814) (xy 148.991828 -53.750718) (xy 148.983446 -53.74767) (xy 148.979159 -53.746147)
			(xy 148.970214 -53.744493) (xy 148.965666 -53.744368) (xy 148.89861 -53.744368) (xy 148.894063 -53.744494)
			(xy 148.885121 -53.746159) (xy 148.88083 -53.74767) (xy 148.872448 -53.750718) (xy 148.865336 -53.756814)
			(xy 148.844403 -53.774452) (xy 148.798435 -53.804169) (xy 148.748687 -53.827003) (xy 148.696185 -53.842484)
			(xy 148.642007 -53.850293) (xy 148.614638 -53.850794) (xy 148.587664 -53.850324) (xy 148.534255 -53.842717)
			(xy 148.48245 -53.827664) (xy 148.433282 -53.805464) (xy 148.38773 -53.776561) (xy 148.346703 -53.74153)
			(xy 148.311018 -53.70107) (xy 148.281388 -53.655988) (xy 148.258403 -53.607181) (xy 148.242521 -53.555624)
			(xy 148.234059 -53.502344) (xy 148.23313 -53.475382) (xy 148.23313 -53.469286) (xy 148.233555 -53.443869)
			(xy 148.240307 -53.393485) (xy 148.253678 -53.344441) (xy 148.273431 -53.297601) (xy 148.285962 -53.275484)
			(xy 148.289518 -53.269642) (xy 148.293074 -53.256434) (xy 148.293074 -53.24983) (xy 148.292868 -53.243248)
			(xy 148.289532 -53.230514) (xy 148.28647 -53.224684) (xy 148.276818 -53.20792) (xy 148.241512 -53.146198)
			(xy 148.236699 -53.139099) (xy 148.223328 -53.128374) (xy 148.207156 -53.122692) (xy 148.198586 -53.122322)
			(xy 143.916654 -53.122322) (xy 143.908296 -53.122703) (xy 143.892485 -53.128143) (xy 143.885666 -53.13299)
			(xy 143.879316 -53.13807) (xy 143.870172 -53.15204) (xy 143.867886 -53.16093) (xy 143.860122 -53.190366)
			(xy 143.837858 -53.247025) (xy 143.80828 -53.300234) (xy 143.771911 -53.349053) (xy 143.729392 -53.392621)
			(xy 143.681474 -53.43017) (xy 143.629003 -53.461036) (xy 143.572903 -53.484675) (xy 143.514164 -53.50067)
			(xy 143.453824 -53.508738) (xy 143.392948 -53.508738) (xy 143.332608 -53.50067) (xy 143.273869 -53.484675)
			(xy 143.217769 -53.461036) (xy 143.165298 -53.43017) (xy 143.11738 -53.392621) (xy 143.074861 -53.349053)
			(xy 143.038492 -53.300234) (xy 143.008914 -53.247025) (xy 142.98665 -53.190366) (xy 142.978886 -53.16093)
			(xy 142.978886 -53.160676) (xy 142.97654 -53.152407) (xy 142.967195 -53.137992) (xy 142.960598 -53.132482)
			(xy 142.954502 -53.127656) (xy 142.9385 -53.122322) (xy 134.884414 -53.122322) (xy 134.876519 -53.122656)
			(xy 134.861511 -53.127571) (xy 134.85495 -53.131974) (xy 134.8486 -53.136292) (xy 134.839456 -53.148738)
			(xy 134.836662 -53.156612) (xy 134.826439 -53.185088) (xy 134.799536 -53.239281) (xy 134.76572 -53.289451)
			(xy 134.725583 -53.334724) (xy 134.679825 -53.374307) (xy 134.654798 -53.391308) (xy 134.645654 -53.39715)
			(xy 134.640066 -53.405786) (xy 134.63739 -53.410115) (xy 134.633674 -53.419587) (xy 134.6327 -53.424582)
			(xy 134.62 -53.49875) (xy 134.619285 -53.504024) (xy 134.619795 -53.514652) (xy 134.621016 -53.519832)
			(xy 134.623302 -53.52923) (xy 134.629906 -53.537866) (xy 134.644797 -53.55792) (xy 134.669799 -53.601161)
			(xy 134.688947 -53.647295) (xy 134.701914 -53.695532) (xy 134.708478 -53.745048) (xy 134.7089 -53.770022)
			(xy 134.7089 -53.77053) (xy 134.708412 -53.79778) (xy 134.700652 -53.851724) (xy 134.685294 -53.904014)
			(xy 134.662651 -53.953587) (xy 134.633184 -53.999433) (xy 134.597493 -54.040619) (xy 134.556303 -54.076307)
			(xy 134.510454 -54.10577) (xy 134.460879 -54.128408) (xy 134.408587 -54.14376) (xy 134.354642 -54.151515)
			(xy 134.327392 -54.152038) (xy 134.300022 -54.151566) (xy 134.245846 -54.14374) (xy 134.193344 -54.12825)
			(xy 134.143596 -54.105414) (xy 134.097623 -54.075701) (xy 134.076694 -54.058058) (xy 134.069582 -54.051962)
			(xy 134.0612 -54.048914) (xy 134.056912 -54.047394) (xy 134.047968 -54.045732) (xy 134.04342 -54.045612)
			(xy 133.976364 -54.045612) (xy 133.971816 -54.045733) (xy 133.96287 -54.047388) (xy 133.958584 -54.048914)
			(xy 133.950202 -54.051962) (xy 133.94309 -54.058058) (xy 133.922159 -54.075701) (xy 133.876193 -54.105429)
			(xy 133.826447 -54.128274) (xy 133.773943 -54.143764) (xy 133.719763 -54.151582) (xy 133.692392 -54.152038)
			(xy 133.66514 -54.151552) (xy 133.611192 -54.143794) (xy 133.558896 -54.128439) (xy 133.509318 -54.105798)
			(xy 133.463467 -54.076332) (xy 133.422275 -54.040641) (xy 133.386582 -53.999451) (xy 133.357113 -53.953601)
			(xy 133.334469 -53.904024) (xy 133.31911 -53.85173) (xy 133.31135 -53.797782) (xy 133.310884 -53.77053)
			(xy 133.311416 -53.741612) (xy 133.320139 -53.684438) (xy 133.337389 -53.629235) (xy 133.362772 -53.577267)
			(xy 133.395706 -53.529724) (xy 133.435437 -53.487696) (xy 133.45795 -53.46954) (xy 133.465333 -53.463256)
			(xy 133.475125 -53.44654) (xy 133.477 -53.437028) (xy 133.477508 -53.429408) (xy 133.477508 -53.349652)
			(xy 133.477 -53.342032) (xy 133.475236 -53.333015) (xy 133.466239 -53.31701) (xy 133.459474 -53.31079)
			(xy 133.45795 -53.30952) (xy 133.438679 -53.294012) (xy 133.403909 -53.258828) (xy 133.373971 -53.21945)
			(xy 133.349368 -53.176538) (xy 133.339586 -53.153818) (xy 133.335268 -53.143404) (xy 133.32714 -53.135784)
			(xy 133.320536 -53.130704) (xy 133.31444 -53.12664) (xy 133.30047 -53.122322) (xy 132.981192 -53.122322)
			(xy 132.98043 -53.122322) (xy 132.970378 -53.122895) (xy 132.951909 -53.130876) (xy 132.944616 -53.137816)
			(xy 132.932932 -53.15077) (xy 132.931916 -53.151786) (xy 132.927294 -53.156705) (xy 132.920601 -53.168421)
			(xy 132.918708 -53.1749) (xy 132.91693 -53.1876) (xy 132.91693 -53.21935) (xy 132.917692 -53.228494)
			(xy 132.919293 -53.235899) (xy 132.926273 -53.249339) (xy 132.931408 -53.25491) (xy 132.951582 -53.27641)
			(xy 132.985729 -53.324468) (xy 133.012077 -53.377207) (xy 133.029999 -53.433372) (xy 133.039067 -53.491625)
			(xy 133.039612 -53.521102) (xy 133.03914 -53.548472) (xy 133.031316 -53.60265) (xy 133.015829 -53.655154)
			(xy 132.992998 -53.704905) (xy 132.96329 -53.750883) (xy 132.945632 -53.7718) (xy 132.939536 -53.778912)
			(xy 132.936488 -53.787294) (xy 132.934959 -53.79158) (xy 132.933294 -53.800525) (xy 132.933186 -53.805074)
			(xy 132.933186 -53.87213) (xy 132.933306 -53.876678) (xy 132.934959 -53.885625) (xy 132.936488 -53.88991)
			(xy 132.939536 -53.898292) (xy 132.945632 -53.905404) (xy 132.963274 -53.926336) (xy 132.993002 -53.972303)
			(xy 133.015849 -54.022049) (xy 133.031347 -54.074551) (xy 133.039177 -54.128731) (xy 133.039176 -54.183472)
			(xy 133.031347 -54.237652) (xy 133.015848 -54.290154) (xy 133.002055 -54.320186) (xy 135.230616 -54.320186)
			(xy 135.23107 -54.292815) (xy 135.23889 -54.238636) (xy 135.254382 -54.186132) (xy 135.277226 -54.136385)
			(xy 135.306954 -54.090419) (xy 135.324596 -54.069488) (xy 135.32485 -54.069234) (xy 135.330434 -54.062146)
			(xy 135.336681 -54.04523) (xy 135.337042 -54.036214) (xy 135.337042 -53.969158) (xy 135.33667 -53.960142)
			(xy 135.330434 -53.943225) (xy 135.32485 -53.936138) (xy 135.324596 -53.936138) (xy 135.324596 -53.935884)
			(xy 135.306982 -53.914932) (xy 135.277267 -53.868964) (xy 135.254426 -53.819222) (xy 135.238929 -53.766726)
			(xy 135.231094 -53.712554) (xy 135.230616 -53.685186) (xy 135.231102 -53.657935) (xy 135.238858 -53.603987)
			(xy 135.254213 -53.551692) (xy 135.276855 -53.502115) (xy 135.306321 -53.456265) (xy 135.342012 -53.415074)
			(xy 135.383203 -53.379383) (xy 135.429053 -53.349917) (xy 135.47863 -53.327275) (xy 135.530925 -53.31192)
			(xy 135.584873 -53.304164) (xy 135.639375 -53.304164) (xy 135.693323 -53.31192) (xy 135.745618 -53.327275)
			(xy 135.795195 -53.349917) (xy 135.841045 -53.379383) (xy 135.882236 -53.415074) (xy 135.917927 -53.456265)
			(xy 135.947393 -53.502115) (xy 135.970035 -53.551692) (xy 135.98539 -53.603987) (xy 135.993146 -53.657935)
			(xy 135.993632 -53.685186) (xy 135.993174 -53.712557) (xy 135.985357 -53.766737) (xy 135.969867 -53.819241)
			(xy 135.947023 -53.868987) (xy 135.917295 -53.914953) (xy 135.899652 -53.935884) (xy 135.899398 -53.936138)
			(xy 135.893831 -53.943238) (xy 135.887573 -53.960144) (xy 135.887206 -53.969158) (xy 135.887206 -54.036214)
			(xy 135.887555 -54.045232) (xy 135.893808 -54.062149) (xy 135.899398 -54.069234) (xy 135.899652 -54.069234)
			(xy 135.899652 -54.069488) (xy 135.917291 -54.09042) (xy 135.947005 -54.136392) (xy 135.969842 -54.186139)
			(xy 135.985332 -54.23864) (xy 135.993159 -54.292817) (xy 135.993632 -54.320186) (xy 135.993146 -54.347437)
			(xy 135.98539 -54.401385) (xy 135.970035 -54.45368) (xy 135.947393 -54.503257) (xy 135.917927 -54.549107)
			(xy 135.882236 -54.590298) (xy 135.841045 -54.625989) (xy 135.795195 -54.655455) (xy 135.745618 -54.678097)
			(xy 135.693323 -54.693452) (xy 135.639375 -54.701208) (xy 135.584873 -54.701208) (xy 135.530925 -54.693452)
			(xy 135.47863 -54.678097) (xy 135.429053 -54.655455) (xy 135.383203 -54.625989) (xy 135.342012 -54.590298)
			(xy 135.306321 -54.549107) (xy 135.276855 -54.503257) (xy 135.254213 -54.45368) (xy 135.238858 -54.401385)
			(xy 135.231102 -54.347437) (xy 135.230616 -54.320186) (xy 133.002055 -54.320186) (xy 132.993 -54.3399)
			(xy 132.963272 -54.385866) (xy 132.945632 -54.4068) (xy 132.939536 -54.413912) (xy 132.936488 -54.422294)
			(xy 132.934959 -54.42658) (xy 132.933294 -54.435525) (xy 132.933186 -54.440074) (xy 132.933186 -54.50713)
			(xy 132.933306 -54.511678) (xy 132.934959 -54.520625) (xy 132.936488 -54.52491) (xy 132.939536 -54.533292)
			(xy 132.945632 -54.540404) (xy 132.963272 -54.561336) (xy 132.992996 -54.607303) (xy 133.015836 -54.65705)
			(xy 133.031325 -54.709553) (xy 133.039142 -54.763732) (xy 133.039259 -54.770528) (xy 136.171178 -54.770528)
			(xy 136.171641 -54.743157) (xy 136.179457 -54.688977) (xy 136.194946 -54.636474) (xy 136.217788 -54.586727)
			(xy 136.247515 -54.540761) (xy 136.265158 -54.51983) (xy 136.265412 -54.519576) (xy 136.271016 -54.512501)
			(xy 136.277252 -54.495575) (xy 136.277604 -54.486556) (xy 136.277604 -54.4195) (xy 136.277246 -54.410483)
			(xy 136.270999 -54.393566) (xy 136.265412 -54.38648) (xy 136.265158 -54.38648) (xy 136.265158 -54.386226)
			(xy 136.247511 -54.365301) (xy 136.217801 -54.319325) (xy 136.194968 -54.269576) (xy 136.179478 -54.217074)
			(xy 136.171651 -54.162898) (xy 136.171178 -54.135528) (xy 136.171664 -54.108277) (xy 136.17942 -54.054329)
			(xy 136.194775 -54.002034) (xy 136.217417 -53.952457) (xy 136.246883 -53.906607) (xy 136.282574 -53.865416)
			(xy 136.323765 -53.829725) (xy 136.369615 -53.800259) (xy 136.419192 -53.777617) (xy 136.471487 -53.762262)
			(xy 136.525435 -53.754506) (xy 136.579937 -53.754506) (xy 136.633885 -53.762262) (xy 136.68618 -53.777617)
			(xy 136.735757 -53.800259) (xy 136.781607 -53.829725) (xy 136.822798 -53.865416) (xy 136.858489 -53.906607)
			(xy 136.887955 -53.952457) (xy 136.906717 -53.993538) (xy 140.797008 -53.993538) (xy 140.797008 -53.933602)
			(xy 140.804831 -53.87418) (xy 140.820344 -53.816287) (xy 140.84328 -53.760914) (xy 140.873247 -53.709008)
			(xy 140.909734 -53.661458) (xy 140.952114 -53.619078) (xy 140.999664 -53.582591) (xy 141.05157 -53.552624)
			(xy 141.106943 -53.529688) (xy 141.164836 -53.514175) (xy 141.224258 -53.506352) (xy 141.284194 -53.506352)
			(xy 141.343616 -53.514175) (xy 141.401509 -53.529688) (xy 141.456882 -53.552624) (xy 141.508788 -53.582591)
			(xy 141.556338 -53.619078) (xy 141.598718 -53.661458) (xy 141.635205 -53.709008) (xy 141.665172 -53.760914)
			(xy 141.688108 -53.816287) (xy 141.703621 -53.87418) (xy 141.711444 -53.933602) (xy 141.711934 -53.96357)
			(xy 141.711444 -53.993538) (xy 141.703621 -54.05296) (xy 141.699737 -54.067456) (xy 143.041368 -54.067456)
			(xy 143.045439 -54.011834) (xy 143.057565 -53.957397) (xy 143.077488 -53.905306) (xy 143.104784 -53.856671)
			(xy 143.13887 -53.812528) (xy 143.179019 -53.773819) (xy 143.224377 -53.741368) (xy 143.273977 -53.715867)
			(xy 143.326761 -53.69786) (xy 143.381604 -53.68773) (xy 143.437338 -53.685693) (xy 143.492775 -53.691793)
			(xy 143.546732 -53.705899) (xy 143.598061 -53.727711) (xy 143.645667 -53.756765) (xy 143.688535 -53.79244)
			(xy 143.725752 -53.833977) (xy 143.756525 -53.88049) (xy 143.780197 -53.930987) (xy 143.796265 -53.984394)
			(xy 143.804385 -54.03957) (xy 143.804894 -54.067456) (xy 143.804385 -54.095342) (xy 143.796265 -54.150518)
			(xy 143.780197 -54.203925) (xy 143.763799 -54.238906) (xy 150.486108 -54.238906) (xy 150.490179 -54.183284)
			(xy 150.502305 -54.128847) (xy 150.522228 -54.076756) (xy 150.549524 -54.028121) (xy 150.58361 -53.983978)
			(xy 150.623759 -53.945269) (xy 150.669117 -53.912818) (xy 150.718717 -53.887317) (xy 150.771501 -53.86931)
			(xy 150.826344 -53.85918) (xy 150.882078 -53.857143) (xy 150.937515 -53.863243) (xy 150.991472 -53.877349)
			(xy 151.042801 -53.899161) (xy 151.090407 -53.928215) (xy 151.133275 -53.96389) (xy 151.170492 -54.005427)
			(xy 151.201265 -54.05194) (xy 151.224937 -54.102437) (xy 151.241005 -54.155844) (xy 151.249125 -54.21102)
			(xy 151.249634 -54.238906) (xy 151.249125 -54.266792) (xy 151.241005 -54.321968) (xy 151.224937 -54.375375)
			(xy 151.201265 -54.425872) (xy 151.170492 -54.472385) (xy 151.133275 -54.513922) (xy 151.090407 -54.549597)
			(xy 151.042801 -54.578651) (xy 150.991472 -54.600463) (xy 150.937515 -54.614569) (xy 150.882078 -54.620669)
			(xy 150.826344 -54.618632) (xy 150.771501 -54.608502) (xy 150.718717 -54.590495) (xy 150.669117 -54.564994)
			(xy 150.623759 -54.532543) (xy 150.58361 -54.493834) (xy 150.549524 -54.449691) (xy 150.522228 -54.401056)
			(xy 150.502305 -54.348965) (xy 150.490179 -54.294528) (xy 150.486108 -54.238906) (xy 143.763799 -54.238906)
			(xy 143.756525 -54.254422) (xy 143.725752 -54.300935) (xy 143.688535 -54.342472) (xy 143.645667 -54.378147)
			(xy 143.598061 -54.407201) (xy 143.546732 -54.429013) (xy 143.492775 -54.443119) (xy 143.437338 -54.449219)
			(xy 143.381604 -54.447182) (xy 143.326761 -54.437052) (xy 143.273977 -54.419045) (xy 143.224377 -54.393544)
			(xy 143.179019 -54.361093) (xy 143.13887 -54.322384) (xy 143.104784 -54.278241) (xy 143.077488 -54.229606)
			(xy 143.057565 -54.177515) (xy 143.045439 -54.123078) (xy 143.041368 -54.067456) (xy 141.699737 -54.067456)
			(xy 141.688108 -54.110853) (xy 141.665172 -54.166226) (xy 141.635205 -54.218132) (xy 141.598718 -54.265682)
			(xy 141.556338 -54.308062) (xy 141.508788 -54.344549) (xy 141.456882 -54.374516) (xy 141.401509 -54.397452)
			(xy 141.343616 -54.412965) (xy 141.284194 -54.420788) (xy 141.224258 -54.420788) (xy 141.164836 -54.412965)
			(xy 141.106943 -54.397452) (xy 141.05157 -54.374516) (xy 140.999664 -54.344549) (xy 140.952114 -54.308062)
			(xy 140.909734 -54.265682) (xy 140.873247 -54.218132) (xy 140.84328 -54.166226) (xy 140.820344 -54.110853)
			(xy 140.804831 -54.05296) (xy 140.797008 -53.993538) (xy 136.906717 -53.993538) (xy 136.910597 -54.002034)
			(xy 136.925952 -54.054329) (xy 136.933708 -54.108277) (xy 136.934194 -54.135528) (xy 136.933746 -54.162899)
			(xy 136.925924 -54.217079) (xy 136.910431 -54.269582) (xy 136.887585 -54.319329) (xy 136.857857 -54.365295)
			(xy 136.840214 -54.386226) (xy 136.83996 -54.38648) (xy 136.834371 -54.393565) (xy 136.828127 -54.410483)
			(xy 136.827768 -54.4195) (xy 136.827768 -54.486556) (xy 136.828153 -54.49557) (xy 136.834382 -54.512487)
			(xy 136.83996 -54.519576) (xy 136.840214 -54.519576) (xy 136.840214 -54.51983) (xy 136.857836 -54.540776)
			(xy 136.88755 -54.586745) (xy 136.910389 -54.636489) (xy 136.925884 -54.688987) (xy 136.933717 -54.74316)
			(xy 136.934194 -54.770528) (xy 136.933708 -54.797779) (xy 136.925952 -54.851727) (xy 136.910597 -54.904022)
			(xy 136.887955 -54.953599) (xy 136.858489 -54.999449) (xy 136.822798 -55.04064) (xy 136.781607 -55.076331)
			(xy 136.77052 -55.083456) (xy 143.041368 -55.083456) (xy 143.045439 -55.027834) (xy 143.057565 -54.973397)
			(xy 143.077488 -54.921306) (xy 143.104784 -54.872671) (xy 143.13887 -54.828528) (xy 143.179019 -54.789819)
			(xy 143.224377 -54.757368) (xy 143.273977 -54.731867) (xy 143.326761 -54.71386) (xy 143.381604 -54.70373)
			(xy 143.437338 -54.701693) (xy 143.492775 -54.707793) (xy 143.546732 -54.721899) (xy 143.598061 -54.743711)
			(xy 143.645667 -54.772765) (xy 143.688535 -54.80844) (xy 143.725752 -54.849977) (xy 143.756525 -54.89649)
			(xy 143.780197 -54.946987) (xy 143.792854 -54.989055) (xy 146.001145 -54.989055) (xy 146.001145 -54.934545)
			(xy 146.008903 -54.88059) (xy 146.024261 -54.828288) (xy 146.046906 -54.778704) (xy 146.076378 -54.732848)
			(xy 146.112076 -54.691654) (xy 146.153274 -54.655959) (xy 146.199132 -54.626491) (xy 146.248718 -54.60385)
			(xy 146.301021 -54.588496) (xy 146.354977 -54.580743) (xy 146.382232 -54.580282) (xy 146.410324 -54.580751)
			(xy 146.465903 -54.588983) (xy 146.519672 -54.605279) (xy 146.57047 -54.629286) (xy 146.617196 -54.660484)
			(xy 146.658841 -54.6982) (xy 146.694502 -54.741616) (xy 146.709384 -54.765448) (xy 146.714718 -54.774338)
			(xy 146.731736 -54.78653) (xy 146.824954 -54.80685) (xy 146.845528 -54.802532) (xy 146.854164 -54.79669)
			(xy 146.878235 -54.780702) (xy 146.930164 -54.755357) (xy 146.98532 -54.738128) (xy 147.042442 -54.729409)
			(xy 147.071334 -54.728872) (xy 147.098585 -54.729346) (xy 147.152532 -54.737107) (xy 147.204826 -54.752465)
			(xy 147.254402 -54.775109) (xy 147.300251 -54.804577) (xy 147.341441 -54.840269) (xy 147.377132 -54.88146)
			(xy 147.406598 -54.92731) (xy 147.42924 -54.976887) (xy 147.444596 -55.029181) (xy 147.452355 -55.083129)
			(xy 147.452842 -55.11038) (xy 147.452378 -55.13775) (xy 147.444562 -55.19193) (xy 147.429073 -55.244434)
			(xy 147.406231 -55.294181) (xy 147.376504 -55.340147) (xy 147.358862 -55.361078) (xy 147.358608 -55.361332)
			(xy 147.353045 -55.368435) (xy 147.346784 -55.385339) (xy 147.346416 -55.394352) (xy 147.346416 -55.461408)
			(xy 147.346766 -55.470426) (xy 147.353018 -55.487343) (xy 147.358608 -55.494428) (xy 147.358862 -55.494428)
			(xy 147.358862 -55.494682) (xy 147.376484 -55.51563) (xy 147.40621 -55.561595) (xy 147.429057 -55.611339)
			(xy 147.444555 -55.663839) (xy 147.452386 -55.718015) (xy 147.452388 -55.772755) (xy 147.444562 -55.826932)
			(xy 147.429068 -55.879433) (xy 147.406225 -55.929178) (xy 147.376502 -55.975146) (xy 147.358862 -55.996078)
			(xy 147.358608 -55.996332) (xy 147.353045 -56.003435) (xy 147.346784 -56.020339) (xy 147.346416 -56.029352)
			(xy 147.346416 -56.096408) (xy 147.346766 -56.105426) (xy 147.353018 -56.122343) (xy 147.358608 -56.129428)
			(xy 147.358862 -56.129428) (xy 147.358862 -56.129682) (xy 147.3765 -56.150615) (xy 147.406213 -56.196587)
			(xy 147.42905 -56.246334) (xy 147.444541 -56.298835) (xy 147.452369 -56.353011) (xy 147.452842 -56.38038)
			(xy 147.452356 -56.407631) (xy 147.4446 -56.461579) (xy 147.429245 -56.513874) (xy 147.406603 -56.563451)
			(xy 147.377137 -56.609301) (xy 147.341446 -56.650492) (xy 147.300255 -56.686183) (xy 147.254405 -56.715649)
			(xy 147.204828 -56.738291) (xy 147.152533 -56.753646) (xy 147.098585 -56.761402) (xy 147.044083 -56.761402)
			(xy 146.990135 -56.753646) (xy 146.93784 -56.738291) (xy 146.888263 -56.715649) (xy 146.842413 -56.686183)
			(xy 146.801222 -56.650492) (xy 146.765531 -56.609301) (xy 146.736065 -56.563451) (xy 146.713423 -56.513874)
			(xy 146.698068 -56.461579) (xy 146.690312 -56.407631) (xy 146.689826 -56.38038) (xy 146.690274 -56.353009)
			(xy 146.698095 -56.298829) (xy 146.713588 -56.246325) (xy 146.736434 -56.196579) (xy 146.766163 -56.150613)
			(xy 146.783806 -56.129682) (xy 146.78406 -56.129428) (xy 146.789648 -56.122343) (xy 146.795892 -56.105425)
			(xy 146.796252 -56.096408) (xy 146.796252 -56.029352) (xy 146.795881 -56.020336) (xy 146.789644 -56.003419)
			(xy 146.78406 -55.996332) (xy 146.783806 -55.996332) (xy 146.783806 -55.996078) (xy 146.766147 -55.975161)
			(xy 146.736424 -55.92919) (xy 146.713581 -55.879441) (xy 146.698087 -55.826937) (xy 146.690261 -55.772756)
			(xy 146.690263 -55.718014) (xy 146.698094 -55.663834) (xy 146.713592 -55.611331) (xy 146.736439 -55.561584)
			(xy 146.766165 -55.515615) (xy 146.783806 -55.494682) (xy 146.78406 -55.494428) (xy 146.789648 -55.487343)
			(xy 146.795892 -55.470425) (xy 146.796252 -55.461408) (xy 146.796252 -55.394352) (xy 146.795881 -55.385336)
			(xy 146.789644 -55.368419) (xy 146.78406 -55.361332) (xy 146.783806 -55.360824) (xy 146.772863 -55.348089)
			(xy 146.753021 -55.320998) (xy 146.744182 -55.306722) (xy 146.738848 -55.297832) (xy 146.72183 -55.28564)
			(xy 146.628612 -55.26532) (xy 146.608038 -55.269638) (xy 146.599402 -55.27548) (xy 146.575338 -55.291479)
			(xy 146.523407 -55.316823) (xy 146.468249 -55.334049) (xy 146.411125 -55.342764) (xy 146.382232 -55.343298)
			(xy 146.354977 -55.342857) (xy 146.301021 -55.335104) (xy 146.248718 -55.31975) (xy 146.199132 -55.297109)
			(xy 146.153274 -55.267641) (xy 146.112076 -55.231946) (xy 146.076378 -55.190752) (xy 146.046906 -55.144896)
			(xy 146.024261 -55.095312) (xy 146.008903 -55.04301) (xy 146.001145 -54.989055) (xy 143.792854 -54.989055)
			(xy 143.796265 -55.000394) (xy 143.804385 -55.05557) (xy 143.804894 -55.083456) (xy 143.804385 -55.111342)
			(xy 143.796265 -55.166518) (xy 143.780197 -55.219925) (xy 143.756525 -55.270422) (xy 143.725752 -55.316935)
			(xy 143.688535 -55.358472) (xy 143.645667 -55.394147) (xy 143.601905 -55.420855) (xy 144.324745 -55.420855)
			(xy 144.324745 -55.366345) (xy 144.332503 -55.31239) (xy 144.347861 -55.260088) (xy 144.370506 -55.210504)
			(xy 144.399978 -55.164648) (xy 144.435676 -55.123454) (xy 144.476874 -55.087759) (xy 144.522732 -55.058291)
			(xy 144.572318 -55.03565) (xy 144.624621 -55.020296) (xy 144.678577 -55.012543) (xy 144.705832 -55.012082)
			(xy 144.732146 -55.012534) (xy 144.784275 -55.019773) (xy 144.834918 -55.034095) (xy 144.883117 -55.055231)
			(xy 144.92796 -55.082779) (xy 144.968599 -55.11622) (xy 144.986756 -55.135272) (xy 144.994296 -55.142652)
			(xy 145.013562 -55.15119) (xy 145.024094 -55.151782) (xy 145.09877 -55.151782) (xy 145.10932 -55.151256)
			(xy 145.128616 -55.142719) (xy 145.136108 -55.135272) (xy 145.154261 -55.116214) (xy 145.194892 -55.082758)
			(xy 145.239733 -55.0552) (xy 145.287934 -55.034062) (xy 145.338582 -55.019745) (xy 145.390716 -55.012521)
			(xy 145.417032 -55.012082) (xy 145.444281 -55.01259) (xy 145.498224 -55.02035) (xy 145.550513 -55.035708)
			(xy 145.600085 -55.05835) (xy 145.64593 -55.087817) (xy 145.687116 -55.123507) (xy 145.722803 -55.164695)
			(xy 145.752265 -55.210543) (xy 145.774903 -55.260117) (xy 145.790256 -55.312408) (xy 145.798012 -55.366351)
			(xy 145.798012 -55.420849) (xy 145.790256 -55.474792) (xy 145.774903 -55.527083) (xy 145.752265 -55.576657)
			(xy 145.722803 -55.622505) (xy 145.687116 -55.663693) (xy 145.64593 -55.699383) (xy 145.600085 -55.72885)
			(xy 145.550513 -55.751492) (xy 145.498224 -55.76685) (xy 145.444281 -55.77461) (xy 145.417032 -55.775098)
			(xy 145.390716 -55.774677) (xy 145.338586 -55.767432) (xy 145.287942 -55.753104) (xy 145.239744 -55.731963)
			(xy 145.194901 -55.704409) (xy 145.154263 -55.670963) (xy 145.136108 -55.651908) (xy 145.128584 -55.644509)
			(xy 145.109306 -55.635983) (xy 145.09877 -55.635398) (xy 145.024094 -55.635398) (xy 145.013542 -55.635911)
			(xy 144.994247 -55.644457) (xy 144.986756 -55.651908) (xy 144.968616 -55.670979) (xy 144.927983 -55.704435)
			(xy 144.883139 -55.731992) (xy 144.834936 -55.753127) (xy 144.784285 -55.767441) (xy 144.732149 -55.774662)
			(xy 144.705832 -55.775098) (xy 144.678577 -55.774657) (xy 144.624621 -55.766904) (xy 144.572318 -55.75155)
			(xy 144.522732 -55.728909) (xy 144.476874 -55.699441) (xy 144.435676 -55.663746) (xy 144.399978 -55.622552)
			(xy 144.370506 -55.576696) (xy 144.347861 -55.527112) (xy 144.332503 -55.47481) (xy 144.324745 -55.420855)
			(xy 143.601905 -55.420855) (xy 143.598061 -55.423201) (xy 143.546732 -55.445013) (xy 143.492775 -55.459119)
			(xy 143.437338 -55.465219) (xy 143.381604 -55.463182) (xy 143.326761 -55.453052) (xy 143.273977 -55.435045)
			(xy 143.224377 -55.409544) (xy 143.179019 -55.377093) (xy 143.13887 -55.338384) (xy 143.104784 -55.294241)
			(xy 143.077488 -55.245606) (xy 143.057565 -55.193515) (xy 143.045439 -55.139078) (xy 143.041368 -55.083456)
			(xy 136.77052 -55.083456) (xy 136.735757 -55.105797) (xy 136.68618 -55.128439) (xy 136.633885 -55.143794)
			(xy 136.579937 -55.15155) (xy 136.525435 -55.15155) (xy 136.471487 -55.143794) (xy 136.419192 -55.128439)
			(xy 136.369615 -55.105797) (xy 136.323765 -55.076331) (xy 136.282574 -55.04064) (xy 136.246883 -54.999449)
			(xy 136.217417 -54.953599) (xy 136.194775 -54.904022) (xy 136.17942 -54.851727) (xy 136.171664 -54.797779)
			(xy 136.171178 -54.770528) (xy 133.039259 -54.770528) (xy 133.039612 -54.791102) (xy 133.039126 -54.818353)
			(xy 133.03137 -54.872301) (xy 133.016015 -54.924596) (xy 132.993373 -54.974173) (xy 132.963907 -55.020023)
			(xy 132.928216 -55.061214) (xy 132.887025 -55.096905) (xy 132.841175 -55.126371) (xy 132.791598 -55.149013)
			(xy 132.739303 -55.164368) (xy 132.685355 -55.172124) (xy 132.630853 -55.172124) (xy 132.576905 -55.164368)
			(xy 132.52461 -55.149013) (xy 132.475033 -55.126371) (xy 132.429183 -55.096905) (xy 132.387992 -55.061214)
			(xy 132.352301 -55.020023) (xy 132.322835 -54.974173) (xy 132.300193 -54.924596) (xy 132.284838 -54.872301)
			(xy 132.277082 -54.818353) (xy 132.276596 -54.791102) (xy 132.277068 -54.763732) (xy 132.284891 -54.709553)
			(xy 132.300378 -54.65705) (xy 132.32321 -54.607298) (xy 132.352918 -54.561321) (xy 132.370576 -54.540404)
			(xy 132.376672 -54.533292) (xy 132.37972 -54.52491) (xy 132.381249 -54.520624) (xy 132.382914 -54.511679)
			(xy 132.383022 -54.50713) (xy 132.383022 -54.440074) (xy 132.382902 -54.435526) (xy 132.381246 -54.42658)
			(xy 132.37972 -54.422294) (xy 132.376672 -54.413912) (xy 132.370576 -54.4068) (xy 132.352933 -54.385868)
			(xy 132.323204 -54.339901) (xy 132.300356 -54.290155) (xy 132.284857 -54.237652) (xy 132.277027 -54.183473)
			(xy 132.277027 -54.12873) (xy 132.284856 -54.07455) (xy 132.300355 -54.022048) (xy 132.323203 -53.972301)
			(xy 132.352931 -53.926334) (xy 132.370576 -53.905404) (xy 132.376672 -53.898292) (xy 132.37972 -53.88991)
			(xy 132.381249 -53.885624) (xy 132.382914 -53.876679) (xy 132.383022 -53.87213) (xy 132.383022 -53.805074)
			(xy 132.382902 -53.800526) (xy 132.381246 -53.79158) (xy 132.37972 -53.787294) (xy 132.376672 -53.778912)
			(xy 132.370576 -53.7718) (xy 132.352935 -53.750868) (xy 132.323211 -53.704901) (xy 132.300369 -53.655154)
			(xy 132.28488 -53.602651) (xy 132.277062 -53.548472) (xy 132.276596 -53.521102) (xy 132.276674 -53.508364)
			(xy 132.278328 -53.482943) (xy 132.279898 -53.470302) (xy 132.284536 -53.440168) (xy 132.302147 -53.3818)
			(xy 132.328834 -53.326984) (xy 132.363914 -53.277121) (xy 132.3848 -53.25491) (xy 132.385308 -53.254402)
			(xy 132.390399 -53.248606) (xy 132.397231 -53.234784) (xy 132.39877 -53.227224) (xy 132.399278 -53.21935)
			(xy 132.399278 -53.187854) (xy 132.398516 -53.17871) (xy 132.3975 -53.1749) (xy 132.395607 -53.168421)
			(xy 132.388917 -53.156702) (xy 132.384292 -53.151786) (xy 132.383276 -53.15077) (xy 132.371592 -53.137816)
			(xy 132.364304 -53.130861) (xy 132.345837 -53.122851) (xy 132.335778 -53.122322) (xy 130.422904 -53.122322)
			(xy 130.414094 -53.122739) (xy 130.397538 -53.12878) (xy 130.38399 -53.140053) (xy 130.379216 -53.147468)
			(xy 130.334766 -53.22316) (xy 130.3316 -53.229097) (xy 130.328129 -53.24209) (xy 130.327908 -53.248814)
			(xy 130.327908 -53.262022) (xy 130.329686 -53.265324) (xy 130.334512 -53.273706) (xy 130.346207 -53.295242)
			(xy 130.364625 -53.340657) (xy 130.377085 -53.388054) (xy 130.383382 -53.436655) (xy 130.383788 -53.461158)
			(xy 130.383788 -53.461412) (xy 130.383315 -53.488782) (xy 130.37549 -53.542959) (xy 130.360001 -53.595461)
			(xy 130.337167 -53.645211) (xy 130.307457 -53.691186) (xy 130.289808 -53.71211) (xy 130.283712 -53.719222)
			(xy 130.280664 -53.727604) (xy 130.279143 -53.731892) (xy 130.27748 -53.740836) (xy 130.277362 -53.745384)
			(xy 130.277362 -53.81244) (xy 130.277484 -53.816988) (xy 130.279141 -53.825933) (xy 130.280664 -53.83022)
			(xy 130.283712 -53.838602) (xy 130.289808 -53.845714) (xy 130.307446 -53.866647) (xy 130.337167 -53.912616)
			(xy 130.360008 -53.962362) (xy 130.375502 -54.014863) (xy 130.383328 -54.069039) (xy 130.383327 -54.123779)
			(xy 130.375498 -54.177955) (xy 130.360002 -54.230455) (xy 130.337158 -54.2802) (xy 130.307435 -54.326167)
			(xy 130.289808 -54.34711) (xy 130.283712 -54.354222) (xy 130.280664 -54.362604) (xy 130.279143 -54.366892)
			(xy 130.27748 -54.375836) (xy 130.277362 -54.380384) (xy 130.277362 -54.44744) (xy 130.277484 -54.451988)
			(xy 130.279141 -54.460933) (xy 130.280664 -54.46522) (xy 130.283712 -54.473602) (xy 130.289808 -54.480714)
			(xy 130.307449 -54.501646) (xy 130.337173 -54.547613) (xy 130.360013 -54.59736) (xy 130.375501 -54.649863)
			(xy 130.383318 -54.704042) (xy 130.383788 -54.731412) (xy 130.383302 -54.758663) (xy 130.375546 -54.812611)
			(xy 130.360191 -54.864906) (xy 130.337549 -54.914483) (xy 130.308083 -54.960333) (xy 130.272392 -55.001524)
			(xy 130.231201 -55.037215) (xy 130.185351 -55.066681) (xy 130.135774 -55.089323) (xy 130.083479 -55.104678)
			(xy 130.029531 -55.112434) (xy 129.975029 -55.112434) (xy 129.921081 -55.104678) (xy 129.868786 -55.089323)
			(xy 129.819209 -55.066681) (xy 129.773359 -55.037215) (xy 129.732168 -55.001524) (xy 129.696477 -54.960333)
			(xy 129.667011 -54.914483) (xy 129.644369 -54.864906) (xy 129.629014 -54.812611) (xy 129.621258 -54.758663)
			(xy 129.620772 -54.731412) (xy 129.62125 -54.704045) (xy 129.629086 -54.649874) (xy 129.644585 -54.597379)
			(xy 129.667429 -54.547639) (xy 129.697148 -54.501674) (xy 129.714752 -54.480714) (xy 129.720848 -54.473602)
			(xy 129.723896 -54.46522) (xy 129.725418 -54.460932) (xy 129.727082 -54.451988) (xy 129.727198 -54.44744)
			(xy 129.727198 -54.380384) (xy 129.72707 -54.375837) (xy 129.725402 -54.366896) (xy 129.723896 -54.362604)
			(xy 129.720848 -54.354222) (xy 129.714752 -54.34711) (xy 129.697109 -54.326178) (xy 129.667381 -54.28021)
			(xy 129.644532 -54.230464) (xy 129.629034 -54.17796) (xy 129.621203 -54.12378) (xy 129.621202 -54.069038)
			(xy 129.62903 -54.014857) (xy 129.644526 -53.962353) (xy 129.667372 -53.912606) (xy 129.697099 -53.866637)
			(xy 129.714752 -53.845714) (xy 129.720848 -53.838602) (xy 129.723896 -53.83022) (xy 129.725418 -53.825932)
			(xy 129.727082 -53.816988) (xy 129.727198 -53.81244) (xy 129.727198 -53.745384) (xy 129.72707 -53.740837)
			(xy 129.725402 -53.731896) (xy 129.723896 -53.727604) (xy 129.720848 -53.719222) (xy 129.714752 -53.71211)
			(xy 129.697107 -53.69118) (xy 129.667376 -53.645215) (xy 129.644528 -53.595468) (xy 129.629035 -53.542964)
			(xy 129.621213 -53.488783) (xy 129.620772 -53.461412) (xy 129.620772 -53.461158) (xy 129.621148 -53.436652)
			(xy 129.627429 -53.388045) (xy 129.639893 -53.340645) (xy 129.658336 -53.295235) (xy 129.670048 -53.273706)
			(xy 129.674874 -53.265324) (xy 129.676652 -53.262022) (xy 129.676652 -53.248814) (xy 129.676479 -53.242083)
			(xy 129.672997 -53.229082) (xy 129.669794 -53.22316) (xy 129.625344 -53.147468) (xy 129.620584 -53.140033)
			(xy 129.607053 -53.128717) (xy 129.590475 -53.122688) (xy 129.581656 -53.122322) (xy 123.665742 -53.122322)
			(xy 123.657179 -53.122703) (xy 123.641034 -53.128427) (xy 123.627654 -53.139123) (xy 123.622816 -53.146198)
			(xy 123.58751 -53.20792) (xy 123.577858 -53.224684) (xy 123.574769 -53.230502) (xy 123.571437 -53.243244)
			(xy 123.571254 -53.24983) (xy 123.571254 -53.263546) (xy 123.578366 -53.275484) (xy 123.59092 -53.297591)
			(xy 123.6107 -53.344425) (xy 123.624072 -53.393474) (xy 123.630799 -53.443866) (xy 123.631198 -53.469286)
			(xy 123.631198 -53.475382) (xy 123.630301 -53.502347) (xy 123.621848 -53.555632) (xy 123.605972 -53.607194)
			(xy 123.582988 -53.656005) (xy 123.553356 -53.701091) (xy 123.517667 -53.741551) (xy 123.476633 -53.776579)
			(xy 123.431072 -53.805475) (xy 123.381895 -53.827663) (xy 123.330081 -53.842701) (xy 123.276666 -53.850287)
			(xy 123.24969 -53.850794) (xy 123.22232 -53.850322) (xy 123.168143 -53.842496) (xy 123.11564 -53.827008)
			(xy 123.06589 -53.804175) (xy 123.019914 -53.774465) (xy 122.998992 -53.756814) (xy 122.99188 -53.750718)
			(xy 122.983498 -53.74767) (xy 122.979212 -53.746143) (xy 122.970267 -53.744479) (xy 122.965718 -53.744368)
			(xy 122.898662 -53.744368) (xy 122.894114 -53.744489) (xy 122.885169 -53.746146) (xy 122.880882 -53.74767)
			(xy 122.8725 -53.750718) (xy 122.865388 -53.756814) (xy 122.844456 -53.774455) (xy 122.798489 -53.804178)
			(xy 122.748742 -53.827019) (xy 122.696239 -53.842507) (xy 122.64206 -53.850324) (xy 122.61469 -53.850794)
			(xy 122.587714 -53.850327) (xy 122.534299 -53.842726) (xy 122.482488 -53.827678) (xy 122.433313 -53.805481)
			(xy 122.387755 -53.776579) (xy 122.346722 -53.741549) (xy 122.311032 -53.701088) (xy 122.281397 -53.656003)
			(xy 122.258408 -53.607193) (xy 122.242523 -53.555632) (xy 122.234059 -53.502348) (xy 122.233182 -53.475382)
			(xy 122.233182 -53.469286) (xy 122.233607 -53.443869) (xy 122.24036 -53.393486) (xy 122.253733 -53.344442)
			(xy 122.273488 -53.297604) (xy 122.286014 -53.275484) (xy 122.28957 -53.269642) (xy 122.293126 -53.256434)
			(xy 122.293126 -53.24983) (xy 122.292919 -53.243248) (xy 122.289581 -53.230515) (xy 122.286522 -53.224684)
			(xy 122.27687 -53.20792) (xy 122.241564 -53.146198) (xy 122.236753 -53.139094) (xy 122.223384 -53.128355)
			(xy 122.207211 -53.122657) (xy 122.198638 -53.122322) (xy 105.8164 -53.122322) (xy 105.808039 -53.122696)
			(xy 105.79222 -53.128125) (xy 105.785412 -53.13299) (xy 105.779062 -53.13807) (xy 105.769918 -53.15204)
			(xy 105.767632 -53.16093) (xy 105.759868 -53.190366) (xy 105.737604 -53.247025) (xy 105.708026 -53.300234)
			(xy 105.671657 -53.349053) (xy 105.629138 -53.392621) (xy 105.58122 -53.43017) (xy 105.528749 -53.461036)
			(xy 105.472649 -53.484675) (xy 105.41391 -53.50067) (xy 105.35357 -53.508738) (xy 105.292694 -53.508738)
			(xy 105.232354 -53.50067) (xy 105.173615 -53.484675) (xy 105.117515 -53.461036) (xy 105.065044 -53.43017)
			(xy 105.017126 -53.392621) (xy 104.974607 -53.349053) (xy 104.938238 -53.300234) (xy 104.90866 -53.247025)
			(xy 104.886396 -53.190366) (xy 104.878632 -53.16093) (xy 104.878632 -53.160676) (xy 104.876288 -53.152405)
			(xy 104.866949 -53.137984) (xy 104.860344 -53.132482) (xy 104.854248 -53.127656) (xy 104.838246 -53.122322)
			(xy 96.78416 -53.122322) (xy 96.776263 -53.122649) (xy 96.761247 -53.127553) (xy 96.754696 -53.131974)
			(xy 96.748346 -53.136292) (xy 96.739202 -53.148738) (xy 96.736408 -53.156612) (xy 96.726184 -53.185087)
			(xy 96.699279 -53.239277) (xy 96.665461 -53.289445) (xy 96.625321 -53.334713) (xy 96.57956 -53.374292)
			(xy 96.554544 -53.391308) (xy 96.5454 -53.39715) (xy 96.539812 -53.405786) (xy 96.537134 -53.410114)
			(xy 96.533415 -53.419586) (xy 96.532446 -53.424582) (xy 96.519746 -53.49875) (xy 96.519031 -53.504024)
			(xy 96.519541 -53.514652) (xy 96.520762 -53.519832) (xy 96.523048 -53.52923) (xy 96.529652 -53.537866)
			(xy 96.544541 -53.55792) (xy 96.56954 -53.601163) (xy 96.588686 -53.647296) (xy 96.601651 -53.695533)
			(xy 96.608215 -53.745048) (xy 96.608646 -53.770022) (xy 96.608646 -53.77053) (xy 96.608158 -53.797781)
			(xy 96.600398 -53.851727) (xy 96.585041 -53.904021) (xy 96.562399 -53.953597) (xy 96.532932 -53.999446)
			(xy 96.497241 -54.040636) (xy 96.456052 -54.076327) (xy 96.410204 -54.105795) (xy 96.360628 -54.128438)
			(xy 96.308335 -54.143797) (xy 96.254389 -54.151558) (xy 96.227138 -54.152038) (xy 96.19977 -54.151562)
			(xy 96.145597 -54.143729) (xy 96.0931 -54.128233) (xy 96.043357 -54.105392) (xy 95.997389 -54.075676)
			(xy 95.97644 -54.058058) (xy 95.969328 -54.051962) (xy 95.960946 -54.048914) (xy 95.956657 -54.047398)
			(xy 95.947713 -54.045746) (xy 95.943166 -54.045612) (xy 95.87611 -54.045612) (xy 95.871563 -54.045738)
			(xy 95.86262 -54.047401) (xy 95.85833 -54.048914) (xy 95.849948 -54.051962) (xy 95.842836 -54.058058)
			(xy 95.821904 -54.075698) (xy 95.775937 -54.10542) (xy 95.72619 -54.128257) (xy 95.673686 -54.14374)
			(xy 95.619508 -54.151551) (xy 95.592138 -54.152038) (xy 95.564883 -54.151578) (xy 95.510926 -54.143825)
			(xy 95.458622 -54.128473) (xy 95.409035 -54.105833) (xy 95.363175 -54.076366) (xy 95.321975 -54.040673)
			(xy 95.286274 -53.99948) (xy 95.2568 -53.953625) (xy 95.234151 -53.904042) (xy 95.218789 -53.851741)
			(xy 95.211027 -53.797785) (xy 95.21063 -53.77053) (xy 95.211162 -53.741613) (xy 95.219885 -53.68444)
			(xy 95.237137 -53.629238) (xy 95.262522 -53.577272) (xy 95.295459 -53.529732) (xy 95.335193 -53.487707)
			(xy 95.357696 -53.46954) (xy 95.365074 -53.463253) (xy 95.374856 -53.446536) (xy 95.376746 -53.437028)
			(xy 95.377254 -53.429408) (xy 95.377254 -53.349652) (xy 95.376746 -53.342032) (xy 95.374984 -53.333013)
			(xy 95.365992 -53.317003) (xy 95.35922 -53.31079) (xy 95.357696 -53.30952) (xy 95.338424 -53.294013)
			(xy 95.30365 -53.258832) (xy 95.273709 -53.219455) (xy 95.249102 -53.176543) (xy 95.239332 -53.153818)
			(xy 95.235014 -53.143404) (xy 95.226886 -53.135784) (xy 95.220282 -53.130704) (xy 95.214186 -53.12664)
			(xy 95.200216 -53.122322) (xy 94.880938 -53.122322) (xy 94.880176 -53.122322) (xy 94.870143 -53.122974)
			(xy 94.851714 -53.130957) (xy 94.844362 -53.137816) (xy 94.832678 -53.15077) (xy 94.831662 -53.151786)
			(xy 94.827044 -53.156708) (xy 94.820359 -53.168425) (xy 94.818454 -53.1749) (xy 94.816676 -53.1876)
			(xy 94.816676 -53.21935) (xy 94.817438 -53.228494) (xy 94.819037 -53.235901) (xy 94.826011 -53.249346)
			(xy 94.831154 -53.25491) (xy 94.85133 -53.276408) (xy 94.885482 -53.324465) (xy 94.911834 -53.377204)
			(xy 94.929758 -53.43337) (xy 94.938828 -53.491624) (xy 94.939358 -53.521102) (xy 94.938886 -53.548472)
			(xy 94.931061 -53.602649) (xy 94.915573 -53.655152) (xy 94.892738 -53.704901) (xy 94.863027 -53.750876)
			(xy 94.845378 -53.7718) (xy 94.839282 -53.778912) (xy 94.836234 -53.787294) (xy 94.834713 -53.791582)
			(xy 94.833049 -53.800526) (xy 94.832932 -53.805074) (xy 94.832932 -53.87213) (xy 94.833053 -53.876678)
			(xy 94.834707 -53.885624) (xy 94.836234 -53.88991) (xy 94.839282 -53.898292) (xy 94.845378 -53.905404)
			(xy 94.863018 -53.926337) (xy 94.892742 -53.972305) (xy 94.915587 -54.022051) (xy 94.931083 -54.074553)
			(xy 94.938911 -54.128731) (xy 94.938911 -54.183472) (xy 94.931082 -54.23765) (xy 94.915586 -54.290152)
			(xy 94.901793 -54.320186) (xy 97.130362 -54.320186) (xy 97.130805 -54.292815) (xy 97.138626 -54.238634)
			(xy 97.15412 -54.18613) (xy 97.176967 -54.136384) (xy 97.206698 -54.090418) (xy 97.224342 -54.069488)
			(xy 97.224596 -54.069234) (xy 97.230174 -54.062142) (xy 97.236426 -54.045229) (xy 97.236788 -54.036214)
			(xy 97.236788 -53.969158) (xy 97.236406 -53.960144) (xy 97.230176 -53.943226) (xy 97.224596 -53.936138)
			(xy 97.224342 -53.936138) (xy 97.224342 -53.935884) (xy 97.206735 -53.914926) (xy 97.177017 -53.868961)
			(xy 97.154174 -53.81922) (xy 97.138676 -53.766725) (xy 97.13084 -53.712553) (xy 97.130362 -53.685186)
			(xy 97.130848 -53.657935) (xy 97.138604 -53.603987) (xy 97.153959 -53.551692) (xy 97.176601 -53.502115)
			(xy 97.206067 -53.456265) (xy 97.241758 -53.415074) (xy 97.282949 -53.379383) (xy 97.328799 -53.349917)
			(xy 97.378376 -53.327275) (xy 97.430671 -53.31192) (xy 97.484619 -53.304164) (xy 97.539121 -53.304164)
			(xy 97.593069 -53.31192) (xy 97.645364 -53.327275) (xy 97.694941 -53.349917) (xy 97.740791 -53.379383)
			(xy 97.781982 -53.415074) (xy 97.817673 -53.456265) (xy 97.847139 -53.502115) (xy 97.869781 -53.551692)
			(xy 97.885136 -53.603987) (xy 97.892892 -53.657935) (xy 97.893378 -53.685186) (xy 97.892909 -53.712556)
			(xy 97.885093 -53.766735) (xy 97.869605 -53.819239) (xy 97.846763 -53.868986) (xy 97.817039 -53.914952)
			(xy 97.799398 -53.935884) (xy 97.799144 -53.936138) (xy 97.793571 -53.943233) (xy 97.787317 -53.960144)
			(xy 97.786952 -53.969158) (xy 97.786952 -54.036214) (xy 97.787291 -54.045233) (xy 97.79355 -54.06215)
			(xy 97.799144 -54.069234) (xy 97.799398 -54.069234) (xy 97.799398 -54.069488) (xy 97.817045 -54.090414)
			(xy 97.846755 -54.136388) (xy 97.86959 -54.186137) (xy 97.885079 -54.23864) (xy 97.892905 -54.292816)
			(xy 97.893378 -54.320186) (xy 97.892892 -54.347437) (xy 97.885136 -54.401385) (xy 97.869781 -54.45368)
			(xy 97.847139 -54.503257) (xy 97.817673 -54.549107) (xy 97.781982 -54.590298) (xy 97.740791 -54.625989)
			(xy 97.694941 -54.655455) (xy 97.645364 -54.678097) (xy 97.593069 -54.693452) (xy 97.539121 -54.701208)
			(xy 97.484619 -54.701208) (xy 97.430671 -54.693452) (xy 97.378376 -54.678097) (xy 97.328799 -54.655455)
			(xy 97.282949 -54.625989) (xy 97.241758 -54.590298) (xy 97.206067 -54.549107) (xy 97.176601 -54.503257)
			(xy 97.153959 -54.45368) (xy 97.138604 -54.401385) (xy 97.130848 -54.347437) (xy 97.130362 -54.320186)
			(xy 94.901793 -54.320186) (xy 94.892741 -54.339898) (xy 94.863017 -54.385866) (xy 94.845378 -54.4068)
			(xy 94.839282 -54.413912) (xy 94.836234 -54.422294) (xy 94.834713 -54.426582) (xy 94.833049 -54.435526)
			(xy 94.832932 -54.440074) (xy 94.832932 -54.50713) (xy 94.833053 -54.511678) (xy 94.834707 -54.520624)
			(xy 94.836234 -54.52491) (xy 94.839282 -54.533292) (xy 94.845378 -54.540404) (xy 94.863021 -54.561335)
			(xy 94.892748 -54.607301) (xy 94.915592 -54.657048) (xy 94.931083 -54.709551) (xy 94.938901 -54.763731)
			(xy 94.939014 -54.770528) (xy 98.070924 -54.770528) (xy 98.071401 -54.743158) (xy 98.079215 -54.688979)
			(xy 98.094701 -54.636476) (xy 98.117541 -54.586729) (xy 98.147264 -54.540762) (xy 98.164904 -54.51983)
			(xy 98.165158 -54.519576) (xy 98.170768 -54.512505) (xy 98.176999 -54.495576) (xy 98.17735 -54.486556)
			(xy 98.17735 -54.4195) (xy 98.177004 -54.410482) (xy 98.17075 -54.393564) (xy 98.165158 -54.38648)
			(xy 98.164904 -54.38648) (xy 98.164904 -54.386226) (xy 98.147264 -54.365294) (xy 98.117552 -54.319322)
			(xy 98.094716 -54.269574) (xy 98.079226 -54.217073) (xy 98.071398 -54.162897) (xy 98.070924 -54.135528)
			(xy 98.07141 -54.108277) (xy 98.079166 -54.054329) (xy 98.094521 -54.002034) (xy 98.117163 -53.952457)
			(xy 98.146629 -53.906607) (xy 98.18232 -53.865416) (xy 98.223511 -53.829725) (xy 98.269361 -53.800259)
			(xy 98.318938 -53.777617) (xy 98.371233 -53.762262) (xy 98.425181 -53.754506) (xy 98.479683 -53.754506)
			(xy 98.533631 -53.762262) (xy 98.585926 -53.777617) (xy 98.635503 -53.800259) (xy 98.681353 -53.829725)
			(xy 98.722544 -53.865416) (xy 98.758235 -53.906607) (xy 98.787701 -53.952457) (xy 98.806463 -53.993538)
			(xy 102.696754 -53.993538) (xy 102.696754 -53.933602) (xy 102.704577 -53.87418) (xy 102.72009 -53.816287)
			(xy 102.743026 -53.760914) (xy 102.772993 -53.709008) (xy 102.80948 -53.661458) (xy 102.85186 -53.619078)
			(xy 102.89941 -53.582591) (xy 102.951316 -53.552624) (xy 103.006689 -53.529688) (xy 103.064582 -53.514175)
			(xy 103.124004 -53.506352) (xy 103.18394 -53.506352) (xy 103.243362 -53.514175) (xy 103.301255 -53.529688)
			(xy 103.356628 -53.552624) (xy 103.408534 -53.582591) (xy 103.456084 -53.619078) (xy 103.498464 -53.661458)
			(xy 103.534951 -53.709008) (xy 103.564918 -53.760914) (xy 103.587854 -53.816287) (xy 103.603367 -53.87418)
			(xy 103.61119 -53.933602) (xy 103.61168 -53.96357) (xy 103.61119 -53.993538) (xy 103.603367 -54.05296)
			(xy 103.599483 -54.067456) (xy 104.941114 -54.067456) (xy 104.945185 -54.011834) (xy 104.957311 -53.957397)
			(xy 104.977234 -53.905306) (xy 105.00453 -53.856671) (xy 105.038616 -53.812528) (xy 105.078765 -53.773819)
			(xy 105.124123 -53.741368) (xy 105.173723 -53.715867) (xy 105.226507 -53.69786) (xy 105.28135 -53.68773)
			(xy 105.337084 -53.685693) (xy 105.392521 -53.691793) (xy 105.446478 -53.705899) (xy 105.497807 -53.727711)
			(xy 105.545413 -53.756765) (xy 105.588281 -53.79244) (xy 105.625498 -53.833977) (xy 105.656271 -53.88049)
			(xy 105.679943 -53.930987) (xy 105.696011 -53.984394) (xy 105.704131 -54.03957) (xy 105.70464 -54.067456)
			(xy 105.704131 -54.095342) (xy 105.696011 -54.150518) (xy 105.679943 -54.203925) (xy 105.663545 -54.238906)
			(xy 124.48616 -54.238906) (xy 124.490231 -54.183284) (xy 124.502357 -54.128847) (xy 124.52228 -54.076756)
			(xy 124.549576 -54.028121) (xy 124.583662 -53.983978) (xy 124.623811 -53.945269) (xy 124.669169 -53.912818)
			(xy 124.718769 -53.887317) (xy 124.771553 -53.86931) (xy 124.826396 -53.85918) (xy 124.88213 -53.857143)
			(xy 124.937567 -53.863243) (xy 124.991524 -53.877349) (xy 125.042853 -53.899161) (xy 125.090459 -53.928215)
			(xy 125.133327 -53.96389) (xy 125.170544 -54.005427) (xy 125.201317 -54.05194) (xy 125.224989 -54.102437)
			(xy 125.241057 -54.155844) (xy 125.249177 -54.21102) (xy 125.249686 -54.238906) (xy 125.249177 -54.266792)
			(xy 125.241057 -54.321968) (xy 125.224989 -54.375375) (xy 125.201317 -54.425872) (xy 125.170544 -54.472385)
			(xy 125.133327 -54.513922) (xy 125.090459 -54.549597) (xy 125.042853 -54.578651) (xy 124.991524 -54.600463)
			(xy 124.937567 -54.614569) (xy 124.88213 -54.620669) (xy 124.826396 -54.618632) (xy 124.771553 -54.608502)
			(xy 124.718769 -54.590495) (xy 124.669169 -54.564994) (xy 124.623811 -54.532543) (xy 124.583662 -54.493834)
			(xy 124.549576 -54.449691) (xy 124.52228 -54.401056) (xy 124.502357 -54.348965) (xy 124.490231 -54.294528)
			(xy 124.48616 -54.238906) (xy 105.663545 -54.238906) (xy 105.656271 -54.254422) (xy 105.625498 -54.300935)
			(xy 105.588281 -54.342472) (xy 105.545413 -54.378147) (xy 105.497807 -54.407201) (xy 105.446478 -54.429013)
			(xy 105.392521 -54.443119) (xy 105.337084 -54.449219) (xy 105.28135 -54.447182) (xy 105.226507 -54.437052)
			(xy 105.173723 -54.419045) (xy 105.124123 -54.393544) (xy 105.078765 -54.361093) (xy 105.038616 -54.322384)
			(xy 105.00453 -54.278241) (xy 104.977234 -54.229606) (xy 104.957311 -54.177515) (xy 104.945185 -54.123078)
			(xy 104.941114 -54.067456) (xy 103.599483 -54.067456) (xy 103.587854 -54.110853) (xy 103.564918 -54.166226)
			(xy 103.534951 -54.218132) (xy 103.498464 -54.265682) (xy 103.456084 -54.308062) (xy 103.408534 -54.344549)
			(xy 103.356628 -54.374516) (xy 103.301255 -54.397452) (xy 103.243362 -54.412965) (xy 103.18394 -54.420788)
			(xy 103.124004 -54.420788) (xy 103.064582 -54.412965) (xy 103.006689 -54.397452) (xy 102.951316 -54.374516)
			(xy 102.89941 -54.344549) (xy 102.85186 -54.308062) (xy 102.80948 -54.265682) (xy 102.772993 -54.218132)
			(xy 102.743026 -54.166226) (xy 102.72009 -54.110853) (xy 102.704577 -54.05296) (xy 102.696754 -53.993538)
			(xy 98.806463 -53.993538) (xy 98.810343 -54.002034) (xy 98.825698 -54.054329) (xy 98.833454 -54.108277)
			(xy 98.83394 -54.135528) (xy 98.833505 -54.1629) (xy 98.825682 -54.217081) (xy 98.810186 -54.269585)
			(xy 98.787337 -54.319331) (xy 98.757605 -54.365296) (xy 98.73996 -54.386226) (xy 98.739706 -54.38648)
			(xy 98.734122 -54.393569) (xy 98.727874 -54.410484) (xy 98.727514 -54.4195) (xy 98.727514 -54.486556)
			(xy 98.727889 -54.495571) (xy 98.734124 -54.512488) (xy 98.739706 -54.519576) (xy 98.73996 -54.519576)
			(xy 98.73996 -54.51983) (xy 98.757574 -54.540783) (xy 98.787291 -54.586749) (xy 98.810132 -54.636491)
			(xy 98.825629 -54.688988) (xy 98.833463 -54.74316) (xy 98.83394 -54.770528) (xy 98.833454 -54.797779)
			(xy 98.825698 -54.851727) (xy 98.810343 -54.904022) (xy 98.787701 -54.953599) (xy 98.758235 -54.999449)
			(xy 98.722544 -55.04064) (xy 98.681353 -55.076331) (xy 98.670266 -55.083456) (xy 104.941114 -55.083456)
			(xy 104.945185 -55.027834) (xy 104.957311 -54.973397) (xy 104.977234 -54.921306) (xy 105.00453 -54.872671)
			(xy 105.038616 -54.828528) (xy 105.078765 -54.789819) (xy 105.124123 -54.757368) (xy 105.173723 -54.731867)
			(xy 105.226507 -54.71386) (xy 105.28135 -54.70373) (xy 105.337084 -54.701693) (xy 105.392521 -54.707793)
			(xy 105.446478 -54.721899) (xy 105.497807 -54.743711) (xy 105.545413 -54.772765) (xy 105.588281 -54.80844)
			(xy 105.625498 -54.849977) (xy 105.656271 -54.89649) (xy 105.679943 -54.946987) (xy 105.692598 -54.989051)
			(xy 120.001268 -54.989051) (xy 120.001268 -54.934549) (xy 120.009024 -54.880601) (xy 120.024379 -54.828306)
			(xy 120.047019 -54.778729) (xy 120.076485 -54.732878) (xy 120.112176 -54.691687) (xy 120.153365 -54.655995)
			(xy 120.199215 -54.626527) (xy 120.248791 -54.603884) (xy 120.301085 -54.588527) (xy 120.355033 -54.580769)
			(xy 120.382284 -54.580282) (xy 120.410375 -54.58079) (xy 120.465952 -54.589014) (xy 120.51972 -54.605303)
			(xy 120.570518 -54.629304) (xy 120.617245 -54.660497) (xy 120.65889 -54.698207) (xy 120.694553 -54.741618)
			(xy 120.709436 -54.765448) (xy 120.71477 -54.774338) (xy 120.731788 -54.78653) (xy 120.825006 -54.80685)
			(xy 120.84558 -54.802532) (xy 120.854216 -54.79669) (xy 120.878273 -54.78068) (xy 120.930207 -54.75534)
			(xy 120.985367 -54.738117) (xy 121.042493 -54.729405) (xy 121.071386 -54.728872) (xy 121.098636 -54.729391)
			(xy 121.152581 -54.737145) (xy 121.204874 -54.752498) (xy 121.25445 -54.775136) (xy 121.300299 -54.804599)
			(xy 121.341489 -54.840287) (xy 121.377181 -54.881473) (xy 121.406648 -54.92732) (xy 121.42929 -54.976894)
			(xy 121.444647 -55.029185) (xy 121.452406 -55.08313) (xy 121.452894 -55.11038) (xy 121.452418 -55.13775)
			(xy 121.444603 -55.191929) (xy 121.429116 -55.244432) (xy 121.406276 -55.294179) (xy 121.376554 -55.340146)
			(xy 121.358914 -55.361078) (xy 121.35866 -55.361332) (xy 121.353091 -55.36843) (xy 121.346835 -55.385338)
			(xy 121.346468 -55.394352) (xy 121.346468 -55.461408) (xy 121.346828 -55.470424) (xy 121.353074 -55.487341)
			(xy 121.35866 -55.494428) (xy 121.358914 -55.494428) (xy 121.358914 -55.494682) (xy 121.376533 -55.515631)
			(xy 121.406256 -55.561597) (xy 121.4291 -55.611341) (xy 121.444596 -55.66384) (xy 121.452426 -55.718016)
			(xy 121.452428 -55.772754) (xy 121.444602 -55.82693) (xy 121.42911 -55.879431) (xy 121.40627 -55.929176)
			(xy 121.376552 -55.975144) (xy 121.358914 -55.996078) (xy 121.35866 -55.996332) (xy 121.353091 -56.00343)
			(xy 121.346835 -56.020338) (xy 121.346468 -56.029352) (xy 121.346468 -56.096408) (xy 121.346828 -56.105424)
			(xy 121.353074 -56.122341) (xy 121.35866 -56.129428) (xy 121.358914 -56.129428) (xy 121.358914 -56.129682)
			(xy 121.37656 -56.150608) (xy 121.406271 -56.196583) (xy 121.429105 -56.246332) (xy 121.444594 -56.298834)
			(xy 121.452421 -56.35301) (xy 121.452894 -56.38038) (xy 121.452408 -56.407631) (xy 121.444652 -56.461579)
			(xy 121.429297 -56.513874) (xy 121.406655 -56.563451) (xy 121.377189 -56.609301) (xy 121.341498 -56.650492)
			(xy 121.300307 -56.686183) (xy 121.254457 -56.715649) (xy 121.20488 -56.738291) (xy 121.152585 -56.753646)
			(xy 121.098637 -56.761402) (xy 121.044135 -56.761402) (xy 120.990187 -56.753646) (xy 120.937892 -56.738291)
			(xy 120.888315 -56.715649) (xy 120.842465 -56.686183) (xy 120.801274 -56.650492) (xy 120.765583 -56.609301)
			(xy 120.736117 -56.563451) (xy 120.713475 -56.513874) (xy 120.69812 -56.461579) (xy 120.690364 -56.407631)
			(xy 120.689878 -56.38038) (xy 120.690313 -56.353008) (xy 120.698136 -56.298827) (xy 120.713631 -56.246323)
			(xy 120.73648 -56.196577) (xy 120.766213 -56.150612) (xy 120.783858 -56.129682) (xy 120.784112 -56.129428)
			(xy 120.789694 -56.122339) (xy 120.795943 -56.105424) (xy 120.796304 -56.096408) (xy 120.796304 -56.029352)
			(xy 120.795921 -56.020338) (xy 120.789691 -56.003421) (xy 120.784112 -55.996332) (xy 120.783858 -55.996332)
			(xy 120.783858 -55.996078) (xy 120.766196 -55.975162) (xy 120.73647 -55.929192) (xy 120.713624 -55.879443)
			(xy 120.698128 -55.826938) (xy 120.690301 -55.772757) (xy 120.690303 -55.718013) (xy 120.698134 -55.663832)
			(xy 120.713635 -55.611329) (xy 120.736485 -55.561582) (xy 120.766215 -55.515614) (xy 120.783858 -55.494682)
			(xy 120.784112 -55.494428) (xy 120.789694 -55.487339) (xy 120.795943 -55.470424) (xy 120.796304 -55.461408)
			(xy 120.796304 -55.394352) (xy 120.795921 -55.385338) (xy 120.789691 -55.368421) (xy 120.784112 -55.361332)
			(xy 120.783858 -55.360824) (xy 120.772912 -55.348091) (xy 120.753072 -55.320999) (xy 120.744234 -55.306722)
			(xy 120.7389 -55.297832) (xy 120.721882 -55.28564) (xy 120.628664 -55.26532) (xy 120.60809 -55.269638)
			(xy 120.599454 -55.27548) (xy 120.575403 -55.2915) (xy 120.523467 -55.316838) (xy 120.468305 -55.334059)
			(xy 120.411178 -55.342767) (xy 120.382284 -55.343298) (xy 120.355033 -55.342831) (xy 120.301085 -55.335073)
			(xy 120.248791 -55.319716) (xy 120.199215 -55.297073) (xy 120.153365 -55.267605) (xy 120.112176 -55.231913)
			(xy 120.076485 -55.190722) (xy 120.047019 -55.144871) (xy 120.024379 -55.095294) (xy 120.009024 -55.042999)
			(xy 120.001268 -54.989051) (xy 105.692598 -54.989051) (xy 105.696011 -55.000394) (xy 105.704131 -55.05557)
			(xy 105.70464 -55.083456) (xy 105.704131 -55.111342) (xy 105.696011 -55.166518) (xy 105.679943 -55.219925)
			(xy 105.656271 -55.270422) (xy 105.625498 -55.316935) (xy 105.588281 -55.358472) (xy 105.545413 -55.394147)
			(xy 105.501658 -55.420851) (xy 118.324868 -55.420851) (xy 118.324868 -55.366349) (xy 118.332624 -55.312401)
			(xy 118.347979 -55.260106) (xy 118.370619 -55.210529) (xy 118.400085 -55.164678) (xy 118.435776 -55.123487)
			(xy 118.476965 -55.087795) (xy 118.522815 -55.058327) (xy 118.572391 -55.035684) (xy 118.624685 -55.020327)
			(xy 118.678633 -55.012569) (xy 118.705884 -55.012082) (xy 118.732197 -55.012566) (xy 118.784325 -55.019798)
			(xy 118.834967 -55.034114) (xy 118.883166 -55.055244) (xy 118.92801 -55.082787) (xy 118.968651 -55.116222)
			(xy 118.986808 -55.135272) (xy 118.994328 -55.142675) (xy 119.013609 -55.1512) (xy 119.024146 -55.151782)
			(xy 119.098822 -55.151782) (xy 119.109369 -55.15123) (xy 119.128665 -55.142711) (xy 119.13616 -55.135272)
			(xy 119.154288 -55.116189) (xy 119.194924 -55.082735) (xy 119.23977 -55.055181) (xy 119.287977 -55.034047)
			(xy 119.338629 -55.019736) (xy 119.390766 -55.012517) (xy 119.417084 -55.012082) (xy 119.444337 -55.012564)
			(xy 119.498288 -55.020319) (xy 119.550587 -55.035673) (xy 119.600167 -55.058314) (xy 119.646021 -55.087781)
			(xy 119.687215 -55.123474) (xy 119.722909 -55.164666) (xy 119.752378 -55.210519) (xy 119.775021 -55.260098)
			(xy 119.790377 -55.312396) (xy 119.798135 -55.366347) (xy 119.798135 -55.420853) (xy 119.790377 -55.474804)
			(xy 119.775021 -55.527102) (xy 119.752378 -55.576681) (xy 119.722909 -55.622534) (xy 119.687215 -55.663726)
			(xy 119.646021 -55.699419) (xy 119.600167 -55.728886) (xy 119.550587 -55.751527) (xy 119.498288 -55.766881)
			(xy 119.444337 -55.774636) (xy 119.417084 -55.775098) (xy 119.39077 -55.774642) (xy 119.338641 -55.767405)
			(xy 119.287998 -55.753084) (xy 119.239799 -55.731949) (xy 119.194955 -55.704401) (xy 119.154316 -55.67096)
			(xy 119.13616 -55.651908) (xy 119.128654 -55.644488) (xy 119.109362 -55.635974) (xy 119.098822 -55.635398)
			(xy 119.024146 -55.635398) (xy 119.013598 -55.635939) (xy 118.994302 -55.644466) (xy 118.986808 -55.651908)
			(xy 118.968643 -55.670954) (xy 118.928015 -55.704412) (xy 118.883177 -55.731972) (xy 118.834978 -55.753112)
			(xy 118.784332 -55.767431) (xy 118.7322 -55.774658) (xy 118.705884 -55.775098) (xy 118.678633 -55.774631)
			(xy 118.624685 -55.766873) (xy 118.572391 -55.751516) (xy 118.522815 -55.728873) (xy 118.476965 -55.699405)
			(xy 118.435776 -55.663713) (xy 118.400085 -55.622522) (xy 118.370619 -55.576671) (xy 118.347979 -55.527094)
			(xy 118.332624 -55.474799) (xy 118.324868 -55.420851) (xy 105.501658 -55.420851) (xy 105.497807 -55.423201)
			(xy 105.446478 -55.445013) (xy 105.392521 -55.459119) (xy 105.337084 -55.465219) (xy 105.28135 -55.463182)
			(xy 105.226507 -55.453052) (xy 105.173723 -55.435045) (xy 105.124123 -55.409544) (xy 105.078765 -55.377093)
			(xy 105.038616 -55.338384) (xy 105.00453 -55.294241) (xy 104.977234 -55.245606) (xy 104.957311 -55.193515)
			(xy 104.945185 -55.139078) (xy 104.941114 -55.083456) (xy 98.670266 -55.083456) (xy 98.635503 -55.105797)
			(xy 98.585926 -55.128439) (xy 98.533631 -55.143794) (xy 98.479683 -55.15155) (xy 98.425181 -55.15155)
			(xy 98.371233 -55.143794) (xy 98.318938 -55.128439) (xy 98.269361 -55.105797) (xy 98.223511 -55.076331)
			(xy 98.18232 -55.04064) (xy 98.146629 -54.999449) (xy 98.117163 -54.953599) (xy 98.094521 -54.904022)
			(xy 98.079166 -54.851727) (xy 98.07141 -54.797779) (xy 98.070924 -54.770528) (xy 94.939014 -54.770528)
			(xy 94.939358 -54.791102) (xy 94.938872 -54.818353) (xy 94.931116 -54.872301) (xy 94.915761 -54.924596)
			(xy 94.893119 -54.974173) (xy 94.863653 -55.020023) (xy 94.827962 -55.061214) (xy 94.786771 -55.096905)
			(xy 94.740921 -55.126371) (xy 94.691344 -55.149013) (xy 94.639049 -55.164368) (xy 94.585101 -55.172124)
			(xy 94.530599 -55.172124) (xy 94.476651 -55.164368) (xy 94.424356 -55.149013) (xy 94.374779 -55.126371)
			(xy 94.328929 -55.096905) (xy 94.287738 -55.061214) (xy 94.252047 -55.020023) (xy 94.222581 -54.974173)
			(xy 94.199939 -54.924596) (xy 94.184584 -54.872301) (xy 94.176828 -54.818353) (xy 94.176342 -54.791102)
			(xy 94.176814 -54.763732) (xy 94.184638 -54.709554) (xy 94.200126 -54.657052) (xy 94.22296 -54.607302)
			(xy 94.252671 -54.561327) (xy 94.270322 -54.540404) (xy 94.276418 -54.533292) (xy 94.279466 -54.52491)
			(xy 94.280988 -54.520622) (xy 94.282652 -54.511678) (xy 94.282768 -54.50713) (xy 94.282768 -54.440074)
			(xy 94.282648 -54.435526) (xy 94.280994 -54.426579) (xy 94.279466 -54.422294) (xy 94.276418 -54.413912)
			(xy 94.270322 -54.4068) (xy 94.252681 -54.385867) (xy 94.222957 -54.339899) (xy 94.200111 -54.290153)
			(xy 94.184615 -54.237651) (xy 94.176786 -54.183472) (xy 94.176786 -54.128731) (xy 94.184614 -54.074552)
			(xy 94.20011 -54.02205) (xy 94.222955 -53.972303) (xy 94.25268 -53.926335) (xy 94.270322 -53.905404)
			(xy 94.276418 -53.898292) (xy 94.279466 -53.88991) (xy 94.280988 -53.885622) (xy 94.282652 -53.876678)
			(xy 94.282768 -53.87213) (xy 94.282768 -53.805074) (xy 94.282648 -53.800526) (xy 94.280994 -53.791579)
			(xy 94.279466 -53.787294) (xy 94.276418 -53.778912) (xy 94.270322 -53.7718) (xy 94.252679 -53.750869)
			(xy 94.222951 -53.704903) (xy 94.200107 -53.655156) (xy 94.184616 -53.602653) (xy 94.176797 -53.548473)
			(xy 94.176342 -53.521102) (xy 94.17642 -53.508364) (xy 94.178074 -53.482943) (xy 94.179644 -53.470302)
			(xy 94.184283 -53.440168) (xy 94.201896 -53.381802) (xy 94.228585 -53.326988) (xy 94.263668 -53.277128)
			(xy 94.284546 -53.25491) (xy 94.285054 -53.254402) (xy 94.290149 -53.248608) (xy 94.296989 -53.234787)
			(xy 94.298516 -53.227224) (xy 94.299024 -53.21935) (xy 94.299024 -53.187854) (xy 94.298262 -53.17871)
			(xy 94.297246 -53.1749) (xy 94.295355 -53.16842) (xy 94.288669 -53.156697) (xy 94.284038 -53.151786)
			(xy 94.283022 -53.15077) (xy 94.271338 -53.137816) (xy 94.264047 -53.13087) (xy 94.245579 -53.122879)
			(xy 94.235524 -53.122322) (xy 92.32265 -53.122322) (xy 92.313845 -53.122748) (xy 92.297302 -53.128801)
			(xy 92.283769 -53.140077) (xy 92.278962 -53.147468) (xy 92.234512 -53.22316) (xy 92.231349 -53.229097)
			(xy 92.227881 -53.24209) (xy 92.227654 -53.248814) (xy 92.227654 -53.262022) (xy 92.229432 -53.265324)
			(xy 92.234258 -53.273706) (xy 92.245952 -53.295242) (xy 92.264368 -53.340657) (xy 92.276826 -53.388054)
			(xy 92.283122 -53.436655) (xy 92.283534 -53.461158) (xy 92.283534 -53.461412) (xy 92.283061 -53.488781)
			(xy 92.275235 -53.542958) (xy 92.259744 -53.595459) (xy 92.236908 -53.645207) (xy 92.207195 -53.691179)
			(xy 92.189554 -53.71211) (xy 92.183458 -53.719222) (xy 92.18041 -53.727604) (xy 92.17889 -53.731892)
			(xy 92.177229 -53.740836) (xy 92.177108 -53.745384) (xy 92.177108 -53.81244) (xy 92.177229 -53.816988)
			(xy 92.178885 -53.825934) (xy 92.18041 -53.83022) (xy 92.183458 -53.838602) (xy 92.189554 -53.845714)
			(xy 92.207195 -53.866646) (xy 92.236919 -53.912613) (xy 92.259764 -53.962359) (xy 92.27526 -54.014861)
			(xy 92.283087 -54.069039) (xy 92.283086 -54.123779) (xy 92.275256 -54.177957) (xy 92.259758 -54.230458)
			(xy 92.23691 -54.280202) (xy 92.207184 -54.326168) (xy 92.189554 -54.34711) (xy 92.183458 -54.354222)
			(xy 92.18041 -54.362604) (xy 92.17889 -54.366892) (xy 92.177229 -54.375836) (xy 92.177108 -54.380384)
			(xy 92.177108 -54.44744) (xy 92.177229 -54.451988) (xy 92.178885 -54.460934) (xy 92.18041 -54.46522)
			(xy 92.183458 -54.473602) (xy 92.189554 -54.480714) (xy 92.207197 -54.501645) (xy 92.236925 -54.547611)
			(xy 92.259769 -54.597357) (xy 92.275259 -54.649861) (xy 92.283077 -54.704041) (xy 92.283534 -54.731412)
			(xy 92.283048 -54.758663) (xy 92.275292 -54.812611) (xy 92.259937 -54.864906) (xy 92.237295 -54.914483)
			(xy 92.207829 -54.960333) (xy 92.172138 -55.001524) (xy 92.130947 -55.037215) (xy 92.085097 -55.066681)
			(xy 92.03552 -55.089323) (xy 91.983225 -55.104678) (xy 91.929277 -55.112434) (xy 91.874775 -55.112434)
			(xy 91.820827 -55.104678) (xy 91.768532 -55.089323) (xy 91.718955 -55.066681) (xy 91.673105 -55.037215)
			(xy 91.631914 -55.001524) (xy 91.596223 -54.960333) (xy 91.566757 -54.914483) (xy 91.544115 -54.864906)
			(xy 91.52876 -54.812611) (xy 91.521004 -54.758663) (xy 91.520518 -54.731412) (xy 91.520996 -54.704044)
			(xy 91.528831 -54.649872) (xy 91.544329 -54.597376) (xy 91.56717 -54.547634) (xy 91.596885 -54.501667)
			(xy 91.614498 -54.480714) (xy 91.620594 -54.473602) (xy 91.623642 -54.46522) (xy 91.625165 -54.460932)
			(xy 91.626832 -54.451988) (xy 91.626944 -54.44744) (xy 91.626944 -54.380384) (xy 91.626816 -54.375837)
			(xy 91.625146 -54.366897) (xy 91.623642 -54.362604) (xy 91.620594 -54.354222) (xy 91.614498 -54.34711)
			(xy 91.596858 -54.326177) (xy 91.567133 -54.280208) (xy 91.544288 -54.230461) (xy 91.528792 -54.177959)
			(xy 91.520962 -54.12378) (xy 91.520961 -54.069038) (xy 91.528788 -54.014859) (xy 91.544282 -53.962356)
			(xy 91.567125 -53.912608) (xy 91.596847 -53.866638) (xy 91.614498 -53.845714) (xy 91.620594 -53.838602)
			(xy 91.623642 -53.83022) (xy 91.625165 -53.825932) (xy 91.626832 -53.816988) (xy 91.626944 -53.81244)
			(xy 91.626944 -53.745384) (xy 91.626816 -53.740837) (xy 91.625146 -53.731897) (xy 91.623642 -53.727604)
			(xy 91.620594 -53.719222) (xy 91.614498 -53.71211) (xy 91.596856 -53.691179) (xy 91.567128 -53.645213)
			(xy 91.544284 -53.595466) (xy 91.528793 -53.542962) (xy 91.520973 -53.488783) (xy 91.520518 -53.461412)
			(xy 91.520518 -53.461158) (xy 91.520894 -53.436652) (xy 91.527174 -53.388044) (xy 91.539637 -53.340643)
			(xy 91.558077 -53.295233) (xy 91.569794 -53.273706) (xy 91.57462 -53.265324) (xy 91.576398 -53.262022)
			(xy 91.576398 -53.248814) (xy 91.576225 -53.242083) (xy 91.572747 -53.229081) (xy 91.56954 -53.22316)
			(xy 91.52509 -53.147468) (xy 91.520328 -53.140039) (xy 91.506794 -53.128737) (xy 91.490218 -53.122726)
			(xy 91.481402 -53.122322) (xy 85.565488 -53.122322) (xy 85.556922 -53.122696) (xy 85.540765 -53.12841)
			(xy 85.527373 -53.139102) (xy 85.522562 -53.146198) (xy 85.487256 -53.20792) (xy 85.477604 -53.224684)
			(xy 85.474512 -53.230502) (xy 85.471178 -53.243243) (xy 85.471 -53.24983) (xy 85.471 -53.263546)
			(xy 85.478112 -53.275484) (xy 85.490665 -53.297592) (xy 85.510442 -53.344426) (xy 85.523812 -53.393475)
			(xy 85.530538 -53.443866) (xy 85.530944 -53.469286) (xy 85.530944 -53.475382) (xy 85.530047 -53.502348)
			(xy 85.521595 -53.555636) (xy 85.505719 -53.607201) (xy 85.482736 -53.656015) (xy 85.453104 -53.701103)
			(xy 85.417416 -53.741567) (xy 85.376382 -53.776599) (xy 85.330822 -53.8055) (xy 85.281644 -53.827694)
			(xy 85.22983 -53.842737) (xy 85.176413 -53.85033) (xy 85.149436 -53.850794) (xy 85.122068 -53.850318)
			(xy 85.067894 -53.842486) (xy 85.015396 -53.826991) (xy 84.965651 -53.804153) (xy 84.919681 -53.77444)
			(xy 84.898738 -53.756814) (xy 84.891626 -53.750718) (xy 84.883244 -53.74767) (xy 84.878957 -53.746147)
			(xy 84.870012 -53.744493) (xy 84.865464 -53.744368) (xy 84.798408 -53.744368) (xy 84.793861 -53.744494)
			(xy 84.784919 -53.74616) (xy 84.780628 -53.74767) (xy 84.772246 -53.750718) (xy 84.765134 -53.756814)
			(xy 84.744203 -53.774457) (xy 84.698237 -53.804186) (xy 84.648491 -53.827033) (xy 84.595987 -53.842527)
			(xy 84.541807 -53.85035) (xy 84.514436 -53.850794) (xy 84.487462 -53.850324) (xy 84.434054 -53.842717)
			(xy 84.382249 -53.827663) (xy 84.33308 -53.805464) (xy 84.287529 -53.77656) (xy 84.246502 -53.741529)
			(xy 84.210818 -53.70107) (xy 84.181188 -53.655987) (xy 84.158203 -53.607181) (xy 84.142321 -53.555624)
			(xy 84.133859 -53.502344) (xy 84.132928 -53.475382) (xy 84.132928 -53.469286) (xy 84.133353 -53.443869)
			(xy 84.140105 -53.393485) (xy 84.153476 -53.344441) (xy 84.173229 -53.297601) (xy 84.18576 -53.275484)
			(xy 84.189316 -53.269642) (xy 84.192872 -53.256434) (xy 84.192872 -53.24983) (xy 84.192666 -53.243248)
			(xy 84.18933 -53.230514) (xy 84.186268 -53.224684) (xy 84.176616 -53.20792) (xy 84.14131 -53.146198)
			(xy 84.136497 -53.139099) (xy 84.123126 -53.128375) (xy 84.106954 -53.122694) (xy 84.098384 -53.122322)
			(xy 79.816452 -53.122322) (xy 79.808094 -53.122704) (xy 79.792284 -53.128144) (xy 79.785464 -53.13299)
			(xy 79.779114 -53.13807) (xy 79.76997 -53.15204) (xy 79.767684 -53.16093) (xy 79.75992 -53.190366)
			(xy 79.737656 -53.247025) (xy 79.708078 -53.300234) (xy 79.671709 -53.349053) (xy 79.62919 -53.392621)
			(xy 79.581272 -53.43017) (xy 79.528801 -53.461036) (xy 79.472701 -53.484675) (xy 79.413962 -53.50067)
			(xy 79.353622 -53.508738) (xy 79.292746 -53.508738) (xy 79.232406 -53.50067) (xy 79.173667 -53.484675)
			(xy 79.117567 -53.461036) (xy 79.065096 -53.43017) (xy 79.017178 -53.392621) (xy 78.974659 -53.349053)
			(xy 78.93829 -53.300234) (xy 78.908712 -53.247025) (xy 78.886448 -53.190366) (xy 78.878684 -53.16093)
			(xy 78.878684 -53.160676) (xy 78.876338 -53.152407) (xy 78.866993 -53.137992) (xy 78.860396 -53.132482)
			(xy 78.8543 -53.127656) (xy 78.838298 -53.122322) (xy 70.784212 -53.122322) (xy 70.776317 -53.122656)
			(xy 70.76131 -53.127572) (xy 70.754748 -53.131974) (xy 70.748398 -53.136292) (xy 70.739254 -53.148738)
			(xy 70.73646 -53.156612) (xy 70.726237 -53.185088) (xy 70.699334 -53.23928) (xy 70.665518 -53.289451)
			(xy 70.625381 -53.334723) (xy 70.579623 -53.374306) (xy 70.554596 -53.391308) (xy 70.545452 -53.39715)
			(xy 70.539864 -53.405786) (xy 70.537188 -53.410115) (xy 70.533472 -53.419587) (xy 70.532498 -53.424582)
			(xy 70.519798 -53.49875) (xy 70.519083 -53.504024) (xy 70.519593 -53.514652) (xy 70.520814 -53.519832)
			(xy 70.5231 -53.52923) (xy 70.529704 -53.537866) (xy 70.544595 -53.55792) (xy 70.569597 -53.601161)
			(xy 70.588745 -53.647295) (xy 70.601712 -53.695532) (xy 70.608277 -53.745048) (xy 70.608698 -53.770022)
			(xy 70.608698 -53.77053) (xy 70.60821 -53.79778) (xy 70.60045 -53.851723) (xy 70.585092 -53.904014)
			(xy 70.562449 -53.953587) (xy 70.532982 -53.999433) (xy 70.49729 -54.040618) (xy 70.456101 -54.076306)
			(xy 70.410252 -54.105768) (xy 70.360676 -54.128406) (xy 70.308384 -54.143758) (xy 70.25444 -54.151513)
			(xy 70.22719 -54.152038) (xy 70.199821 -54.151565) (xy 70.145644 -54.143739) (xy 70.093142 -54.128249)
			(xy 70.043394 -54.105413) (xy 69.997422 -54.0757) (xy 69.976492 -54.058058) (xy 69.96938 -54.051962)
			(xy 69.960998 -54.048914) (xy 69.95671 -54.047394) (xy 69.947766 -54.045733) (xy 69.943218 -54.045612)
			(xy 69.876162 -54.045612) (xy 69.871614 -54.045733) (xy 69.862668 -54.047388) (xy 69.858382 -54.048914)
			(xy 69.85 -54.051962) (xy 69.842888 -54.058058) (xy 69.821957 -54.075701) (xy 69.775991 -54.105429)
			(xy 69.726245 -54.128273) (xy 69.673741 -54.143763) (xy 69.619561 -54.151581) (xy 69.59219 -54.152038)
			(xy 69.564938 -54.151552) (xy 69.51099 -54.143794) (xy 69.458695 -54.128438) (xy 69.409117 -54.105797)
			(xy 69.363266 -54.076331) (xy 69.322074 -54.04064) (xy 69.286381 -53.99945) (xy 69.256913 -53.953601)
			(xy 69.234269 -53.904024) (xy 69.21891 -53.851729) (xy 69.21115 -53.797782) (xy 69.210682 -53.77053)
			(xy 69.211214 -53.741612) (xy 69.219937 -53.684438) (xy 69.237187 -53.629235) (xy 69.26257 -53.577267)
			(xy 69.295504 -53.529724) (xy 69.335235 -53.487695) (xy 69.357748 -53.46954) (xy 69.365131 -53.463256)
			(xy 69.374923 -53.446541) (xy 69.376798 -53.437028) (xy 69.377306 -53.429408) (xy 69.377306 -53.349652)
			(xy 69.376798 -53.342032) (xy 69.375034 -53.333015) (xy 69.366036 -53.317011) (xy 69.359272 -53.31079)
			(xy 69.357748 -53.30952) (xy 69.338478 -53.294011) (xy 69.303707 -53.258828) (xy 69.27377 -53.21945)
			(xy 69.249166 -53.176537) (xy 69.239384 -53.153818) (xy 69.235066 -53.143404) (xy 69.226938 -53.135784)
			(xy 69.220334 -53.130704) (xy 69.214238 -53.12664) (xy 69.200268 -53.122322) (xy 68.88099 -53.122322)
			(xy 68.880228 -53.122322) (xy 68.870176 -53.122896) (xy 68.851708 -53.130877) (xy 68.844414 -53.137816)
			(xy 68.83273 -53.15077) (xy 68.831714 -53.151786) (xy 68.827092 -53.156705) (xy 68.8204 -53.168421)
			(xy 68.818506 -53.1749) (xy 68.816728 -53.1876) (xy 68.816728 -53.21935) (xy 68.81749 -53.228494)
			(xy 68.819091 -53.235899) (xy 68.826071 -53.249339) (xy 68.831206 -53.25491) (xy 68.85138 -53.27641)
			(xy 68.885527 -53.324468) (xy 68.911875 -53.377207) (xy 68.929797 -53.433372) (xy 68.938866 -53.491625)
			(xy 68.93941 -53.521102) (xy 68.938938 -53.548472) (xy 68.931114 -53.60265) (xy 68.915627 -53.655154)
			(xy 68.892795 -53.704905) (xy 68.863087 -53.750883) (xy 68.84543 -53.7718) (xy 68.839334 -53.778912)
			(xy 68.836286 -53.787294) (xy 68.834758 -53.79158) (xy 68.833092 -53.800525) (xy 68.832984 -53.805074)
			(xy 68.832984 -53.87213) (xy 68.833104 -53.876678) (xy 68.834757 -53.885625) (xy 68.836286 -53.88991)
			(xy 68.839334 -53.898292) (xy 68.84543 -53.905404) (xy 68.863072 -53.926336) (xy 68.8928 -53.972303)
			(xy 68.915648 -54.022049) (xy 68.931146 -54.074551) (xy 68.938975 -54.12873) (xy 68.938975 -54.183473)
			(xy 68.931145 -54.237652) (xy 68.915647 -54.290154) (xy 68.901854 -54.320186) (xy 71.130414 -54.320186)
			(xy 71.130868 -54.292815) (xy 71.138689 -54.238636) (xy 71.15418 -54.186132) (xy 71.177025 -54.136386)
			(xy 71.206752 -54.090419) (xy 71.224394 -54.069488) (xy 71.224648 -54.069234) (xy 71.230232 -54.062146)
			(xy 71.236479 -54.04523) (xy 71.23684 -54.036214) (xy 71.23684 -53.969158) (xy 71.236468 -53.960142)
			(xy 71.230232 -53.943225) (xy 71.224648 -53.936138) (xy 71.224394 -53.936138) (xy 71.224394 -53.935884)
			(xy 71.20678 -53.914932) (xy 71.177065 -53.868964) (xy 71.154224 -53.819222) (xy 71.138727 -53.766726)
			(xy 71.130892 -53.712554) (xy 71.130414 -53.685186) (xy 71.1309 -53.657935) (xy 71.138656 -53.603987)
			(xy 71.154011 -53.551692) (xy 71.176653 -53.502115) (xy 71.206119 -53.456265) (xy 71.24181 -53.415074)
			(xy 71.283001 -53.379383) (xy 71.328851 -53.349917) (xy 71.378428 -53.327275) (xy 71.430723 -53.31192)
			(xy 71.484671 -53.304164) (xy 71.539173 -53.304164) (xy 71.593121 -53.31192) (xy 71.645416 -53.327275)
			(xy 71.694993 -53.349917) (xy 71.740843 -53.379383) (xy 71.782034 -53.415074) (xy 71.817725 -53.456265)
			(xy 71.847191 -53.502115) (xy 71.869833 -53.551692) (xy 71.885188 -53.603987) (xy 71.892944 -53.657935)
			(xy 71.89343 -53.685186) (xy 71.892973 -53.712557) (xy 71.885155 -53.766737) (xy 71.869665 -53.819241)
			(xy 71.846821 -53.868988) (xy 71.817093 -53.914953) (xy 71.79945 -53.935884) (xy 71.799196 -53.936138)
			(xy 71.793629 -53.943238) (xy 71.787371 -53.960144) (xy 71.787004 -53.969158) (xy 71.787004 -54.036214)
			(xy 71.787354 -54.045232) (xy 71.793606 -54.062149) (xy 71.799196 -54.069234) (xy 71.79945 -54.069234)
			(xy 71.79945 -54.069488) (xy 71.817089 -54.09042) (xy 71.846803 -54.136392) (xy 71.869639 -54.18614)
			(xy 71.88513 -54.238641) (xy 71.892957 -54.292817) (xy 71.89343 -54.320186) (xy 71.892944 -54.347437)
			(xy 71.885188 -54.401385) (xy 71.869833 -54.45368) (xy 71.847191 -54.503257) (xy 71.817725 -54.549107)
			(xy 71.782034 -54.590298) (xy 71.740843 -54.625989) (xy 71.694993 -54.655455) (xy 71.645416 -54.678097)
			(xy 71.593121 -54.693452) (xy 71.539173 -54.701208) (xy 71.484671 -54.701208) (xy 71.430723 -54.693452)
			(xy 71.378428 -54.678097) (xy 71.328851 -54.655455) (xy 71.283001 -54.625989) (xy 71.24181 -54.590298)
			(xy 71.206119 -54.549107) (xy 71.176653 -54.503257) (xy 71.154011 -54.45368) (xy 71.138656 -54.401385)
			(xy 71.1309 -54.347437) (xy 71.130414 -54.320186) (xy 68.901854 -54.320186) (xy 68.892799 -54.3399)
			(xy 68.863071 -54.385867) (xy 68.84543 -54.4068) (xy 68.839334 -54.413912) (xy 68.836286 -54.422294)
			(xy 68.834758 -54.42658) (xy 68.833092 -54.435525) (xy 68.832984 -54.440074) (xy 68.832984 -54.50713)
			(xy 68.833104 -54.511678) (xy 68.834757 -54.520625) (xy 68.836286 -54.52491) (xy 68.839334 -54.533292)
			(xy 68.84543 -54.540404) (xy 68.863071 -54.561336) (xy 68.892794 -54.607303) (xy 68.915635 -54.65705)
			(xy 68.931123 -54.709553) (xy 68.93894 -54.763732) (xy 68.939057 -54.770528) (xy 72.070976 -54.770528)
			(xy 72.07144 -54.743157) (xy 72.079255 -54.688978) (xy 72.094744 -54.636474) (xy 72.117587 -54.586727)
			(xy 72.147313 -54.540761) (xy 72.164956 -54.51983) (xy 72.16521 -54.519576) (xy 72.170814 -54.512501)
			(xy 72.17705 -54.495575) (xy 72.177402 -54.486556) (xy 72.177402 -54.4195) (xy 72.177045 -54.410483)
			(xy 72.170797 -54.393566) (xy 72.16521 -54.38648) (xy 72.164956 -54.38648) (xy 72.164956 -54.386226)
			(xy 72.147308 -54.365301) (xy 72.117599 -54.319326) (xy 72.094766 -54.269576) (xy 72.079276 -54.217074)
			(xy 72.071449 -54.162898) (xy 72.070976 -54.135528) (xy 72.071462 -54.108277) (xy 72.079218 -54.054329)
			(xy 72.094573 -54.002034) (xy 72.117215 -53.952457) (xy 72.146681 -53.906607) (xy 72.182372 -53.865416)
			(xy 72.223563 -53.829725) (xy 72.269413 -53.800259) (xy 72.31899 -53.777617) (xy 72.371285 -53.762262)
			(xy 72.425233 -53.754506) (xy 72.479735 -53.754506) (xy 72.533683 -53.762262) (xy 72.585978 -53.777617)
			(xy 72.635555 -53.800259) (xy 72.681405 -53.829725) (xy 72.722596 -53.865416) (xy 72.758287 -53.906607)
			(xy 72.787753 -53.952457) (xy 72.806515 -53.993538) (xy 76.696806 -53.993538) (xy 76.696806 -53.933602)
			(xy 76.704629 -53.87418) (xy 76.720142 -53.816287) (xy 76.743078 -53.760914) (xy 76.773045 -53.709008)
			(xy 76.809532 -53.661458) (xy 76.851912 -53.619078) (xy 76.899462 -53.582591) (xy 76.951368 -53.552624)
			(xy 77.006741 -53.529688) (xy 77.064634 -53.514175) (xy 77.124056 -53.506352) (xy 77.183992 -53.506352)
			(xy 77.243414 -53.514175) (xy 77.301307 -53.529688) (xy 77.35668 -53.552624) (xy 77.408586 -53.582591)
			(xy 77.456136 -53.619078) (xy 77.498516 -53.661458) (xy 77.535003 -53.709008) (xy 77.56497 -53.760914)
			(xy 77.587906 -53.816287) (xy 77.603419 -53.87418) (xy 77.611242 -53.933602) (xy 77.611732 -53.96357)
			(xy 77.611242 -53.993538) (xy 77.603419 -54.05296) (xy 77.599535 -54.067456) (xy 78.941166 -54.067456)
			(xy 78.945237 -54.011834) (xy 78.957363 -53.957397) (xy 78.977286 -53.905306) (xy 79.004582 -53.856671)
			(xy 79.038668 -53.812528) (xy 79.078817 -53.773819) (xy 79.124175 -53.741368) (xy 79.173775 -53.715867)
			(xy 79.226559 -53.69786) (xy 79.281402 -53.68773) (xy 79.337136 -53.685693) (xy 79.392573 -53.691793)
			(xy 79.44653 -53.705899) (xy 79.497859 -53.727711) (xy 79.545465 -53.756765) (xy 79.588333 -53.79244)
			(xy 79.62555 -53.833977) (xy 79.656323 -53.88049) (xy 79.679995 -53.930987) (xy 79.696063 -53.984394)
			(xy 79.704183 -54.03957) (xy 79.704692 -54.067456) (xy 79.704183 -54.095342) (xy 79.696063 -54.150518)
			(xy 79.679995 -54.203925) (xy 79.663597 -54.238906) (xy 86.385906 -54.238906) (xy 86.389977 -54.183284)
			(xy 86.402103 -54.128847) (xy 86.422026 -54.076756) (xy 86.449322 -54.028121) (xy 86.483408 -53.983978)
			(xy 86.523557 -53.945269) (xy 86.568915 -53.912818) (xy 86.618515 -53.887317) (xy 86.671299 -53.86931)
			(xy 86.726142 -53.85918) (xy 86.781876 -53.857143) (xy 86.837313 -53.863243) (xy 86.89127 -53.877349)
			(xy 86.942599 -53.899161) (xy 86.990205 -53.928215) (xy 87.033073 -53.96389) (xy 87.07029 -54.005427)
			(xy 87.101063 -54.05194) (xy 87.124735 -54.102437) (xy 87.140803 -54.155844) (xy 87.148923 -54.21102)
			(xy 87.149432 -54.238906) (xy 87.148923 -54.266792) (xy 87.140803 -54.321968) (xy 87.124735 -54.375375)
			(xy 87.101063 -54.425872) (xy 87.07029 -54.472385) (xy 87.033073 -54.513922) (xy 86.990205 -54.549597)
			(xy 86.942599 -54.578651) (xy 86.89127 -54.600463) (xy 86.837313 -54.614569) (xy 86.781876 -54.620669)
			(xy 86.726142 -54.618632) (xy 86.671299 -54.608502) (xy 86.618515 -54.590495) (xy 86.568915 -54.564994)
			(xy 86.523557 -54.532543) (xy 86.483408 -54.493834) (xy 86.449322 -54.449691) (xy 86.422026 -54.401056)
			(xy 86.402103 -54.348965) (xy 86.389977 -54.294528) (xy 86.385906 -54.238906) (xy 79.663597 -54.238906)
			(xy 79.656323 -54.254422) (xy 79.62555 -54.300935) (xy 79.588333 -54.342472) (xy 79.545465 -54.378147)
			(xy 79.497859 -54.407201) (xy 79.44653 -54.429013) (xy 79.392573 -54.443119) (xy 79.337136 -54.449219)
			(xy 79.281402 -54.447182) (xy 79.226559 -54.437052) (xy 79.173775 -54.419045) (xy 79.124175 -54.393544)
			(xy 79.078817 -54.361093) (xy 79.038668 -54.322384) (xy 79.004582 -54.278241) (xy 78.977286 -54.229606)
			(xy 78.957363 -54.177515) (xy 78.945237 -54.123078) (xy 78.941166 -54.067456) (xy 77.599535 -54.067456)
			(xy 77.587906 -54.110853) (xy 77.56497 -54.166226) (xy 77.535003 -54.218132) (xy 77.498516 -54.265682)
			(xy 77.456136 -54.308062) (xy 77.408586 -54.344549) (xy 77.35668 -54.374516) (xy 77.301307 -54.397452)
			(xy 77.243414 -54.412965) (xy 77.183992 -54.420788) (xy 77.124056 -54.420788) (xy 77.064634 -54.412965)
			(xy 77.006741 -54.397452) (xy 76.951368 -54.374516) (xy 76.899462 -54.344549) (xy 76.851912 -54.308062)
			(xy 76.809532 -54.265682) (xy 76.773045 -54.218132) (xy 76.743078 -54.166226) (xy 76.720142 -54.110853)
			(xy 76.704629 -54.05296) (xy 76.696806 -53.993538) (xy 72.806515 -53.993538) (xy 72.810395 -54.002034)
			(xy 72.82575 -54.054329) (xy 72.833506 -54.108277) (xy 72.833992 -54.135528) (xy 72.833544 -54.162899)
			(xy 72.825722 -54.217079) (xy 72.810229 -54.269582) (xy 72.787383 -54.319329) (xy 72.757655 -54.365295)
			(xy 72.740012 -54.386226) (xy 72.739758 -54.38648) (xy 72.734169 -54.393564) (xy 72.727925 -54.410483)
			(xy 72.727566 -54.4195) (xy 72.727566 -54.486556) (xy 72.727951 -54.49557) (xy 72.73418 -54.512487)
			(xy 72.739758 -54.519576) (xy 72.740012 -54.519576) (xy 72.740012 -54.51983) (xy 72.757634 -54.540776)
			(xy 72.787348 -54.586745) (xy 72.810187 -54.636489) (xy 72.825682 -54.688987) (xy 72.833515 -54.74316)
			(xy 72.833992 -54.770528) (xy 72.833506 -54.797779) (xy 72.82575 -54.851727) (xy 72.810395 -54.904022)
			(xy 72.787753 -54.953599) (xy 72.758287 -54.999449) (xy 72.722596 -55.04064) (xy 72.681405 -55.076331)
			(xy 72.670318 -55.083456) (xy 78.941166 -55.083456) (xy 78.945237 -55.027834) (xy 78.957363 -54.973397)
			(xy 78.977286 -54.921306) (xy 79.004582 -54.872671) (xy 79.038668 -54.828528) (xy 79.078817 -54.789819)
			(xy 79.124175 -54.757368) (xy 79.173775 -54.731867) (xy 79.226559 -54.71386) (xy 79.281402 -54.70373)
			(xy 79.337136 -54.701693) (xy 79.392573 -54.707793) (xy 79.44653 -54.721899) (xy 79.497859 -54.743711)
			(xy 79.545465 -54.772765) (xy 79.588333 -54.80844) (xy 79.62555 -54.849977) (xy 79.656323 -54.89649)
			(xy 79.679995 -54.946987) (xy 79.692652 -54.989055) (xy 81.900945 -54.989055) (xy 81.900945 -54.934545)
			(xy 81.908703 -54.88059) (xy 81.924061 -54.828288) (xy 81.946706 -54.778705) (xy 81.976178 -54.732849)
			(xy 82.011876 -54.691654) (xy 82.053073 -54.65596) (xy 82.098931 -54.626492) (xy 82.148516 -54.60385)
			(xy 82.200819 -54.588497) (xy 82.254775 -54.580743) (xy 82.28203 -54.580282) (xy 82.310122 -54.580753)
			(xy 82.365701 -54.588985) (xy 82.41947 -54.60528) (xy 82.470268 -54.629286) (xy 82.516994 -54.660485)
			(xy 82.558639 -54.6982) (xy 82.5943 -54.741616) (xy 82.609182 -54.765448) (xy 82.614516 -54.774338)
			(xy 82.631534 -54.78653) (xy 82.724752 -54.80685) (xy 82.745326 -54.802532) (xy 82.753962 -54.79669)
			(xy 82.778034 -54.780703) (xy 82.829963 -54.755357) (xy 82.885118 -54.738128) (xy 82.94224 -54.729409)
			(xy 82.971132 -54.728872) (xy 82.998383 -54.729348) (xy 83.05233 -54.737108) (xy 83.104624 -54.752467)
			(xy 83.1542 -54.77511) (xy 83.200049 -54.804578) (xy 83.241238 -54.84027) (xy 83.27693 -54.88146)
			(xy 83.306396 -54.927311) (xy 83.329038 -54.976887) (xy 83.344394 -55.029182) (xy 83.352153 -55.083129)
			(xy 83.35264 -55.11038) (xy 83.352177 -55.137751) (xy 83.344361 -55.19193) (xy 83.328872 -55.244434)
			(xy 83.306029 -55.294181) (xy 83.276302 -55.340147) (xy 83.25866 -55.361078) (xy 83.258406 -55.361332)
			(xy 83.252842 -55.368434) (xy 83.246582 -55.385339) (xy 83.246214 -55.394352) (xy 83.246214 -55.461408)
			(xy 83.246564 -55.470426) (xy 83.252816 -55.487343) (xy 83.258406 -55.494428) (xy 83.25866 -55.494428)
			(xy 83.25866 -55.494682) (xy 83.276282 -55.51563) (xy 83.306008 -55.561595) (xy 83.328856 -55.611339)
			(xy 83.344354 -55.663839) (xy 83.352185 -55.718015) (xy 83.352187 -55.772755) (xy 83.34436 -55.826932)
			(xy 83.328866 -55.879433) (xy 83.306023 -55.929178) (xy 83.2763 -55.975146) (xy 83.25866 -55.996078)
			(xy 83.258406 -55.996332) (xy 83.252842 -56.003434) (xy 83.246582 -56.020339) (xy 83.246214 -56.029352)
			(xy 83.246214 -56.096408) (xy 83.246564 -56.105426) (xy 83.252816 -56.122343) (xy 83.258406 -56.129428)
			(xy 83.25866 -56.129428) (xy 83.25866 -56.129682) (xy 83.276298 -56.150615) (xy 83.306011 -56.196587)
			(xy 83.328848 -56.246334) (xy 83.344339 -56.298835) (xy 83.352167 -56.353011) (xy 83.35264 -56.38038)
			(xy 83.352154 -56.407631) (xy 83.344398 -56.461579) (xy 83.329043 -56.513874) (xy 83.306401 -56.563451)
			(xy 83.276935 -56.609301) (xy 83.241244 -56.650492) (xy 83.200053 -56.686183) (xy 83.154203 -56.715649)
			(xy 83.104626 -56.738291) (xy 83.052331 -56.753646) (xy 82.998383 -56.761402) (xy 82.943881 -56.761402)
			(xy 82.889933 -56.753646) (xy 82.837638 -56.738291) (xy 82.788061 -56.715649) (xy 82.742211 -56.686183)
			(xy 82.70102 -56.650492) (xy 82.665329 -56.609301) (xy 82.635863 -56.563451) (xy 82.613221 -56.513874)
			(xy 82.597866 -56.461579) (xy 82.59011 -56.407631) (xy 82.589624 -56.38038) (xy 82.590072 -56.353009)
			(xy 82.597894 -56.298829) (xy 82.613387 -56.246325) (xy 82.636232 -56.196579) (xy 82.665961 -56.150613)
			(xy 82.683604 -56.129682) (xy 82.683858 -56.129428) (xy 82.689446 -56.122343) (xy 82.69569 -56.105425)
			(xy 82.69605 -56.096408) (xy 82.69605 -56.029352) (xy 82.695679 -56.020336) (xy 82.689442 -56.003419)
			(xy 82.683858 -55.996332) (xy 82.683604 -55.996332) (xy 82.683604 -55.996078) (xy 82.665945 -55.975161)
			(xy 82.636222 -55.92919) (xy 82.61338 -55.879441) (xy 82.597886 -55.826936) (xy 82.59006 -55.772756)
			(xy 82.590062 -55.718014) (xy 82.597892 -55.663834) (xy 82.61339 -55.611331) (xy 82.636237 -55.561584)
			(xy 82.665963 -55.515615) (xy 82.683604 -55.494682) (xy 82.683858 -55.494428) (xy 82.689446 -55.487343)
			(xy 82.69569 -55.470425) (xy 82.69605 -55.461408) (xy 82.69605 -55.394352) (xy 82.695679 -55.385336)
			(xy 82.689442 -55.368419) (xy 82.683858 -55.361332) (xy 82.683604 -55.360824) (xy 82.672661 -55.348089)
			(xy 82.652819 -55.320998) (xy 82.64398 -55.306722) (xy 82.638646 -55.297832) (xy 82.621628 -55.28564)
			(xy 82.52841 -55.26532) (xy 82.507836 -55.269638) (xy 82.4992 -55.27548) (xy 82.475136 -55.29148)
			(xy 82.423205 -55.316823) (xy 82.368047 -55.334049) (xy 82.310923 -55.342764) (xy 82.28203 -55.343298)
			(xy 82.254775 -55.342857) (xy 82.200819 -55.335103) (xy 82.148516 -55.31975) (xy 82.098931 -55.297108)
			(xy 82.053073 -55.26764) (xy 82.011876 -55.231946) (xy 81.976178 -55.190751) (xy 81.946706 -55.144895)
			(xy 81.924061 -55.095312) (xy 81.908703 -55.04301) (xy 81.900945 -54.989055) (xy 79.692652 -54.989055)
			(xy 79.696063 -55.000394) (xy 79.704183 -55.05557) (xy 79.704692 -55.083456) (xy 79.704183 -55.111342)
			(xy 79.696063 -55.166518) (xy 79.679995 -55.219925) (xy 79.656323 -55.270422) (xy 79.62555 -55.316935)
			(xy 79.588333 -55.358472) (xy 79.545465 -55.394147) (xy 79.501703 -55.420855) (xy 80.224545 -55.420855)
			(xy 80.224545 -55.366345) (xy 80.232303 -55.31239) (xy 80.247661 -55.260088) (xy 80.270306 -55.210505)
			(xy 80.299778 -55.164649) (xy 80.335476 -55.123454) (xy 80.376673 -55.08776) (xy 80.422531 -55.058292)
			(xy 80.472116 -55.03565) (xy 80.524419 -55.020297) (xy 80.578375 -55.012543) (xy 80.60563 -55.012082)
			(xy 80.631944 -55.012535) (xy 80.684073 -55.019774) (xy 80.734716 -55.034096) (xy 80.782915 -55.055231)
			(xy 80.827758 -55.082779) (xy 80.868397 -55.11622) (xy 80.886554 -55.135272) (xy 80.894057 -55.142695)
			(xy 80.913351 -55.151208) (xy 80.923892 -55.151782) (xy 80.998568 -55.151782) (xy 81.009118 -55.151255)
			(xy 81.028414 -55.142719) (xy 81.035906 -55.135272) (xy 81.05406 -55.116215) (xy 81.094691 -55.082759)
			(xy 81.139532 -55.055201) (xy 81.187733 -55.034063) (xy 81.23838 -55.019746) (xy 81.290514 -55.012521)
			(xy 81.31683 -55.012082) (xy 81.344079 -55.01259) (xy 81.398022 -55.02035) (xy 81.450312 -55.035707)
			(xy 81.499884 -55.05835) (xy 81.545729 -55.087816) (xy 81.586915 -55.123506) (xy 81.622602 -55.164695)
			(xy 81.652065 -55.210542) (xy 81.674703 -55.260116) (xy 81.690056 -55.312407) (xy 81.697812 -55.366351)
			(xy 81.697812 -55.420849) (xy 81.690056 -55.474793) (xy 81.674703 -55.527084) (xy 81.652065 -55.576658)
			(xy 81.622602 -55.622505) (xy 81.586915 -55.663694) (xy 81.545729 -55.699384) (xy 81.499884 -55.72885)
			(xy 81.450312 -55.751493) (xy 81.398022 -55.76685) (xy 81.344079 -55.77461) (xy 81.31683 -55.775098)
			(xy 81.290514 -55.774678) (xy 81.238384 -55.767433) (xy 81.18774 -55.753105) (xy 81.139541 -55.731964)
			(xy 81.094699 -55.704409) (xy 81.054061 -55.670963) (xy 81.035906 -55.651908) (xy 81.028383 -55.644508)
			(xy 81.009104 -55.635983) (xy 80.998568 -55.635398) (xy 80.923892 -55.635398) (xy 80.91334 -55.63591)
			(xy 80.894045 -55.644457) (xy 80.886554 -55.651908) (xy 80.868415 -55.67098) (xy 80.827782 -55.704436)
			(xy 80.782938 -55.731992) (xy 80.734734 -55.753128) (xy 80.684084 -55.767441) (xy 80.631947 -55.774662)
			(xy 80.60563 -55.775098) (xy 80.578375 -55.774657) (xy 80.524419 -55.766903) (xy 80.472116 -55.75155)
			(xy 80.422531 -55.728908) (xy 80.376673 -55.69944) (xy 80.335476 -55.663746) (xy 80.299778 -55.622551)
			(xy 80.270306 -55.576695) (xy 80.247661 -55.527112) (xy 80.232303 -55.47481) (xy 80.224545 -55.420855)
			(xy 79.501703 -55.420855) (xy 79.497859 -55.423201) (xy 79.44653 -55.445013) (xy 79.392573 -55.459119)
			(xy 79.337136 -55.465219) (xy 79.281402 -55.463182) (xy 79.226559 -55.453052) (xy 79.173775 -55.435045)
			(xy 79.124175 -55.409544) (xy 79.078817 -55.377093) (xy 79.038668 -55.338384) (xy 79.004582 -55.294241)
			(xy 78.977286 -55.245606) (xy 78.957363 -55.193515) (xy 78.945237 -55.139078) (xy 78.941166 -55.083456)
			(xy 72.670318 -55.083456) (xy 72.635555 -55.105797) (xy 72.585978 -55.128439) (xy 72.533683 -55.143794)
			(xy 72.479735 -55.15155) (xy 72.425233 -55.15155) (xy 72.371285 -55.143794) (xy 72.31899 -55.128439)
			(xy 72.269413 -55.105797) (xy 72.223563 -55.076331) (xy 72.182372 -55.04064) (xy 72.146681 -54.999449)
			(xy 72.117215 -54.953599) (xy 72.094573 -54.904022) (xy 72.079218 -54.851727) (xy 72.071462 -54.797779)
			(xy 72.070976 -54.770528) (xy 68.939057 -54.770528) (xy 68.93941 -54.791102) (xy 68.938924 -54.818353)
			(xy 68.931168 -54.872301) (xy 68.915813 -54.924596) (xy 68.893171 -54.974173) (xy 68.863705 -55.020023)
			(xy 68.828014 -55.061214) (xy 68.786823 -55.096905) (xy 68.740973 -55.126371) (xy 68.691396 -55.149013)
			(xy 68.639101 -55.164368) (xy 68.585153 -55.172124) (xy 68.530651 -55.172124) (xy 68.476703 -55.164368)
			(xy 68.424408 -55.149013) (xy 68.374831 -55.126371) (xy 68.328981 -55.096905) (xy 68.28779 -55.061214)
			(xy 68.252099 -55.020023) (xy 68.222633 -54.974173) (xy 68.199991 -54.924596) (xy 68.184636 -54.872301)
			(xy 68.17688 -54.818353) (xy 68.176394 -54.791102) (xy 68.176866 -54.763732) (xy 68.184689 -54.709553)
			(xy 68.200176 -54.657049) (xy 68.223007 -54.607298) (xy 68.252716 -54.56132) (xy 68.270374 -54.540404)
			(xy 68.27647 -54.533292) (xy 68.279518 -54.52491) (xy 68.281047 -54.520624) (xy 68.282713 -54.511679)
			(xy 68.28282 -54.50713) (xy 68.28282 -54.440074) (xy 68.2827 -54.435526) (xy 68.281044 -54.42658)
			(xy 68.279518 -54.422294) (xy 68.27647 -54.413912) (xy 68.270374 -54.4068) (xy 68.252731 -54.385868)
			(xy 68.223003 -54.339901) (xy 68.200154 -54.290155) (xy 68.184655 -54.237652) (xy 68.176826 -54.183473)
			(xy 68.176825 -54.12873) (xy 68.184655 -54.074551) (xy 68.200153 -54.022048) (xy 68.223001 -53.972301)
			(xy 68.252729 -53.926334) (xy 68.270374 -53.905404) (xy 68.27647 -53.898292) (xy 68.279518 -53.88991)
			(xy 68.281047 -53.885624) (xy 68.282713 -53.876679) (xy 68.28282 -53.87213) (xy 68.28282 -53.805074)
			(xy 68.2827 -53.800526) (xy 68.281044 -53.79158) (xy 68.279518 -53.787294) (xy 68.27647 -53.778912)
			(xy 68.270374 -53.7718) (xy 68.252733 -53.750868) (xy 68.223009 -53.704901) (xy 68.200167 -53.655154)
			(xy 68.184678 -53.602651) (xy 68.17686 -53.548472) (xy 68.176394 -53.521102) (xy 68.176472 -53.508364)
			(xy 68.178126 -53.482943) (xy 68.179696 -53.470302) (xy 68.184334 -53.440168) (xy 68.201945 -53.3818)
			(xy 68.228632 -53.326984) (xy 68.263712 -53.277121) (xy 68.284598 -53.25491) (xy 68.285106 -53.254402)
			(xy 68.290197 -53.248606) (xy 68.29703 -53.234785) (xy 68.298568 -53.227224) (xy 68.299076 -53.21935)
			(xy 68.299076 -53.187854) (xy 68.298314 -53.17871) (xy 68.297298 -53.1749) (xy 68.295405 -53.168421)
			(xy 68.288715 -53.156702) (xy 68.28409 -53.151786) (xy 68.283074 -53.15077) (xy 68.27139 -53.137816)
			(xy 68.264102 -53.130861) (xy 68.245634 -53.122853) (xy 68.235576 -53.122322) (xy 66.322702 -53.122322)
			(xy 66.313892 -53.122739) (xy 66.297336 -53.128781) (xy 66.283789 -53.140054) (xy 66.279014 -53.147468)
			(xy 66.234564 -53.22316) (xy 66.231398 -53.229097) (xy 66.227927 -53.24209) (xy 66.227706 -53.248814)
			(xy 66.227706 -53.262022) (xy 66.229484 -53.265324) (xy 66.23431 -53.273706) (xy 66.246005 -53.295242)
			(xy 66.264423 -53.340657) (xy 66.276883 -53.388054) (xy 66.283181 -53.436655) (xy 66.283586 -53.461158)
			(xy 66.283586 -53.461412) (xy 66.283113 -53.488782) (xy 66.275288 -53.542959) (xy 66.259799 -53.595461)
			(xy 66.236965 -53.645211) (xy 66.207255 -53.691186) (xy 66.189606 -53.71211) (xy 66.18351 -53.719222)
			(xy 66.180462 -53.727604) (xy 66.178941 -53.731892) (xy 66.177278 -53.740836) (xy 66.17716 -53.745384)
			(xy 66.17716 -53.81244) (xy 66.177282 -53.816988) (xy 66.178939 -53.825933) (xy 66.180462 -53.83022)
			(xy 66.18351 -53.838602) (xy 66.189606 -53.845714) (xy 66.207244 -53.866647) (xy 66.236965 -53.912616)
			(xy 66.259807 -53.962361) (xy 66.2753 -54.014862) (xy 66.283126 -54.069039) (xy 66.283125 -54.123779)
			(xy 66.275296 -54.177955) (xy 66.2598 -54.230455) (xy 66.236956 -54.2802) (xy 66.207234 -54.326167)
			(xy 66.189606 -54.34711) (xy 66.18351 -54.354222) (xy 66.180462 -54.362604) (xy 66.178941 -54.366892)
			(xy 66.177278 -54.375836) (xy 66.17716 -54.380384) (xy 66.17716 -54.44744) (xy 66.177282 -54.451988)
			(xy 66.178939 -54.460933) (xy 66.180462 -54.46522) (xy 66.18351 -54.473602) (xy 66.189606 -54.480714)
			(xy 66.207247 -54.501646) (xy 66.236971 -54.547613) (xy 66.259812 -54.59736) (xy 66.2753 -54.649863)
			(xy 66.283116 -54.704042) (xy 66.283586 -54.731412) (xy 66.2831 -54.758663) (xy 66.275344 -54.812611)
			(xy 66.259989 -54.864906) (xy 66.237347 -54.914483) (xy 66.207881 -54.960333) (xy 66.17219 -55.001524)
			(xy 66.130999 -55.037215) (xy 66.085149 -55.066681) (xy 66.035572 -55.089323) (xy 65.983277 -55.104678)
			(xy 65.929329 -55.112434) (xy 65.874827 -55.112434) (xy 65.820879 -55.104678) (xy 65.768584 -55.089323)
			(xy 65.719007 -55.066681) (xy 65.673157 -55.037215) (xy 65.631966 -55.001524) (xy 65.596275 -54.960333)
			(xy 65.566809 -54.914483) (xy 65.544167 -54.864906) (xy 65.528812 -54.812611) (xy 65.521056 -54.758663)
			(xy 65.52057 -54.731412) (xy 65.521048 -54.704045) (xy 65.528884 -54.649873) (xy 65.544383 -54.597379)
			(xy 65.567227 -54.547638) (xy 65.596946 -54.501674) (xy 65.61455 -54.480714) (xy 65.620646 -54.473602)
			(xy 65.623694 -54.46522) (xy 65.625216 -54.460932) (xy 65.626881 -54.451988) (xy 65.626996 -54.44744)
			(xy 65.626996 -54.380384) (xy 65.626868 -54.375837) (xy 65.6252 -54.366896) (xy 65.623694 -54.362604)
			(xy 65.620646 -54.354222) (xy 65.61455 -54.34711) (xy 65.596908 -54.326178) (xy 65.567179 -54.28021)
			(xy 65.544331 -54.230463) (xy 65.528832 -54.17796) (xy 65.521001 -54.12378) (xy 65.521 -54.069038)
			(xy 65.528828 -54.014857) (xy 65.544324 -53.962353) (xy 65.567171 -53.912606) (xy 65.596897 -53.866637)
			(xy 65.61455 -53.845714) (xy 65.620646 -53.838602) (xy 65.623694 -53.83022) (xy 65.625216 -53.825932)
			(xy 65.626881 -53.816988) (xy 65.626996 -53.81244) (xy 65.626996 -53.745384) (xy 65.626868 -53.740837)
			(xy 65.6252 -53.731896) (xy 65.623694 -53.727604) (xy 65.620646 -53.719222) (xy 65.61455 -53.71211)
			(xy 65.596905 -53.69118) (xy 65.567174 -53.645215) (xy 65.544327 -53.595468) (xy 65.528833 -53.542964)
			(xy 65.521012 -53.488783) (xy 65.52057 -53.461412) (xy 65.52057 -53.461158) (xy 65.520946 -53.436652)
			(xy 65.527227 -53.388045) (xy 65.539691 -53.340645) (xy 65.558134 -53.295235) (xy 65.569846 -53.273706)
			(xy 65.574672 -53.265324) (xy 65.57645 -53.262022) (xy 65.57645 -53.248814) (xy 65.576276 -53.242083)
			(xy 65.572795 -53.229083) (xy 65.569592 -53.22316) (xy 65.525142 -53.147468) (xy 65.520382 -53.140033)
			(xy 65.506851 -53.128718) (xy 65.490273 -53.12269) (xy 65.481454 -53.122322) (xy 59.56554 -53.122322)
			(xy 59.556978 -53.122703) (xy 59.540833 -53.128428) (xy 59.527453 -53.139124) (xy 59.522614 -53.146198)
			(xy 59.487308 -53.20792) (xy 59.477656 -53.224684) (xy 59.474567 -53.230502) (xy 59.471236 -53.243244)
			(xy 59.471052 -53.24983) (xy 59.471052 -53.263546) (xy 59.478164 -53.275484) (xy 59.490718 -53.297591)
			(xy 59.510498 -53.344425) (xy 59.52387 -53.393474) (xy 59.530597 -53.443866) (xy 59.530996 -53.469286)
			(xy 59.530996 -53.475382) (xy 59.530099 -53.502347) (xy 59.521646 -53.555632) (xy 59.50577 -53.607194)
			(xy 59.482786 -53.656005) (xy 59.453154 -53.70109) (xy 59.417465 -53.74155) (xy 59.37643 -53.776578)
			(xy 59.33087 -53.805474) (xy 59.281692 -53.827662) (xy 59.229879 -53.842699) (xy 59.176464 -53.850286)
			(xy 59.149488 -53.850794) (xy 59.122118 -53.850321) (xy 59.067941 -53.842496) (xy 59.015438 -53.827007)
			(xy 58.965689 -53.804174) (xy 58.919713 -53.774464) (xy 58.89879 -53.756814) (xy 58.891678 -53.750718)
			(xy 58.883296 -53.74767) (xy 58.87901 -53.746143) (xy 58.870065 -53.74448) (xy 58.865516 -53.744368)
			(xy 58.79846 -53.744368) (xy 58.793912 -53.74449) (xy 58.784967 -53.746147) (xy 58.78068 -53.74767)
			(xy 58.772298 -53.750718) (xy 58.765186 -53.756814) (xy 58.744254 -53.774455) (xy 58.698287 -53.804178)
			(xy 58.64854 -53.827018) (xy 58.596037 -53.842506) (xy 58.541858 -53.850322) (xy 58.514488 -53.850794)
			(xy 58.487512 -53.850327) (xy 58.434098 -53.842726) (xy 58.382287 -53.827677) (xy 58.333112 -53.805481)
			(xy 58.287554 -53.776579) (xy 58.246521 -53.741548) (xy 58.210831 -53.701087) (xy 58.181196 -53.656002)
			(xy 58.158208 -53.607193) (xy 58.142323 -53.555632) (xy 58.133859 -53.502347) (xy 58.13298 -53.475382)
			(xy 58.13298 -53.469286) (xy 58.133405 -53.443869) (xy 58.140158 -53.393486) (xy 58.153531 -53.344442)
			(xy 58.173286 -53.297604) (xy 58.185812 -53.275484) (xy 58.189368 -53.269642) (xy 58.192924 -53.256434)
			(xy 58.192924 -53.24983) (xy 58.192717 -53.243248) (xy 58.189378 -53.230515) (xy 58.18632 -53.224684)
			(xy 58.176668 -53.20792) (xy 58.141362 -53.146198) (xy 58.136551 -53.139094) (xy 58.123182 -53.128356)
			(xy 58.107009 -53.122658) (xy 58.098436 -53.122322) (xy 53.816504 -53.122322) (xy 53.808149 -53.122711)
			(xy 53.792348 -53.128163) (xy 53.785516 -53.13299) (xy 53.779166 -53.13807) (xy 53.770022 -53.15204)
			(xy 53.767736 -53.16093) (xy 53.759972 -53.190366) (xy 53.737708 -53.247025) (xy 53.70813 -53.300234)
			(xy 53.671761 -53.349053) (xy 53.629242 -53.392621) (xy 53.581324 -53.43017) (xy 53.528853 -53.461036)
			(xy 53.472753 -53.484675) (xy 53.414014 -53.50067) (xy 53.353674 -53.508738) (xy 53.292798 -53.508738)
			(xy 53.232458 -53.50067) (xy 53.173719 -53.484675) (xy 53.117619 -53.461036) (xy 53.065148 -53.43017)
			(xy 53.01723 -53.392621) (xy 52.974711 -53.349053) (xy 52.938342 -53.300234) (xy 52.908764 -53.247025)
			(xy 52.8865 -53.190366) (xy 52.878736 -53.16093) (xy 52.878736 -53.160676) (xy 52.876392 -53.152405)
			(xy 52.867053 -53.137983) (xy 52.860448 -53.132482) (xy 52.854352 -53.127656) (xy 52.83835 -53.122322)
			(xy 44.784264 -53.122322) (xy 44.776366 -53.122648) (xy 44.76135 -53.127551) (xy 44.7548 -53.131974)
			(xy 44.74845 -53.136292) (xy 44.739306 -53.148738) (xy 44.736512 -53.156612) (xy 44.726288 -53.185087)
			(xy 44.699383 -53.239277) (xy 44.665565 -53.289445) (xy 44.625425 -53.334714) (xy 44.579665 -53.374293)
			(xy 44.554648 -53.391308) (xy 44.545504 -53.39715) (xy 44.539916 -53.405786) (xy 44.537237 -53.410114)
			(xy 44.533518 -53.419586) (xy 44.53255 -53.424582) (xy 44.51985 -53.49875) (xy 44.519134 -53.504024)
			(xy 44.519645 -53.514652) (xy 44.520866 -53.519832) (xy 44.523152 -53.52923) (xy 44.529756 -53.537866)
			(xy 44.544645 -53.557921) (xy 44.569644 -53.601163) (xy 44.588789 -53.647296) (xy 44.601755 -53.695533)
			(xy 44.608318 -53.745048) (xy 44.60875 -53.770022) (xy 44.60875 -53.77053) (xy 44.608262 -53.797781)
			(xy 44.600502 -53.851728) (xy 44.585145 -53.904021) (xy 44.562503 -53.953597) (xy 44.533036 -53.999447)
			(xy 44.497346 -54.040637) (xy 44.456157 -54.076329) (xy 44.410308 -54.105797) (xy 44.360732 -54.128441)
			(xy 44.308439 -54.1438) (xy 44.254493 -54.151561) (xy 44.227242 -54.152038) (xy 44.199874 -54.151562)
			(xy 44.1457 -54.14373) (xy 44.093203 -54.128234) (xy 44.04346 -54.105394) (xy 43.997492 -54.075678)
			(xy 43.976544 -54.058058) (xy 43.969432 -54.051962) (xy 43.96105 -54.048914) (xy 43.956761 -54.047398)
			(xy 43.947817 -54.045745) (xy 43.94327 -54.045612) (xy 43.876214 -54.045612) (xy 43.871667 -54.045737)
			(xy 43.862724 -54.0474) (xy 43.858434 -54.048914) (xy 43.850052 -54.051962) (xy 43.84294 -54.058058)
			(xy 43.822008 -54.075698) (xy 43.776041 -54.10542) (xy 43.726294 -54.128258) (xy 43.673791 -54.143742)
			(xy 43.619612 -54.151553) (xy 43.592242 -54.152038) (xy 43.564986 -54.151578) (xy 43.511029 -54.143826)
			(xy 43.458725 -54.128474) (xy 43.409137 -54.105834) (xy 43.363277 -54.076368) (xy 43.322076 -54.040675)
			(xy 43.286375 -53.999481) (xy 43.2569 -53.953626) (xy 43.234251 -53.904043) (xy 43.218889 -53.851741)
			(xy 43.211127 -53.797786) (xy 43.210734 -53.77053) (xy 43.211266 -53.741613) (xy 43.21999 -53.68444)
			(xy 43.237242 -53.629238) (xy 43.262627 -53.577272) (xy 43.295563 -53.529733) (xy 43.335297 -53.487708)
			(xy 43.3578 -53.46954) (xy 43.365177 -53.463252) (xy 43.374959 -53.446536) (xy 43.37685 -53.437028)
			(xy 43.377358 -53.429408) (xy 43.377358 -53.349652) (xy 43.37685 -53.342032) (xy 43.375088 -53.333013)
			(xy 43.366097 -53.317002) (xy 43.359324 -53.31079) (xy 43.3578 -53.30952) (xy 43.338531 -53.29401)
			(xy 43.303765 -53.258824) (xy 43.273831 -53.219445) (xy 43.24923 -53.176532) (xy 43.239436 -53.153818)
			(xy 43.235118 -53.143404) (xy 43.22699 -53.135784) (xy 43.220386 -53.130704) (xy 43.21429 -53.12664)
			(xy 43.20032 -53.122322) (xy 42.881042 -53.122322) (xy 42.88028 -53.122322) (xy 42.870247 -53.122973)
			(xy 42.851817 -53.130955) (xy 42.844466 -53.137816) (xy 42.832782 -53.15077) (xy 42.831766 -53.151786)
			(xy 42.827148 -53.156707) (xy 42.820462 -53.168425) (xy 42.818558 -53.1749) (xy 42.81678 -53.1876)
			(xy 42.81678 -53.21935) (xy 42.817542 -53.228494) (xy 42.819141 -53.235901) (xy 42.826116 -53.249345)
			(xy 42.831258 -53.25491) (xy 42.851434 -53.276408) (xy 42.885586 -53.324465) (xy 42.911937 -53.377204)
			(xy 42.929861 -53.43337) (xy 42.938931 -53.491624) (xy 42.939462 -53.521102) (xy 42.93899 -53.548472)
			(xy 42.931165 -53.602649) (xy 42.915677 -53.655152) (xy 42.892843 -53.704902) (xy 42.863132 -53.750876)
			(xy 42.845482 -53.7718) (xy 42.839386 -53.778912) (xy 42.836338 -53.787294) (xy 42.834817 -53.791582)
			(xy 42.833153 -53.800526) (xy 42.833036 -53.805074) (xy 42.833036 -53.87213) (xy 42.833157 -53.876678)
			(xy 42.834811 -53.885624) (xy 42.836338 -53.88991) (xy 42.839386 -53.898292) (xy 42.845482 -53.905404)
			(xy 42.863122 -53.926337) (xy 42.892846 -53.972305) (xy 42.915691 -54.022051) (xy 42.931186 -54.074553)
			(xy 42.939014 -54.128731) (xy 42.939014 -54.183472) (xy 42.931186 -54.23765) (xy 42.915689 -54.290152)
			(xy 42.901897 -54.320186) (xy 45.130466 -54.320186) (xy 45.130908 -54.292815) (xy 45.138729 -54.238634)
			(xy 45.154223 -54.18613) (xy 45.17707 -54.136383) (xy 45.206801 -54.090418) (xy 45.224446 -54.069488)
			(xy 45.2247 -54.069234) (xy 45.230278 -54.062142) (xy 45.23653 -54.045229) (xy 45.236892 -54.036214)
			(xy 45.236892 -53.969158) (xy 45.236509 -53.960144) (xy 45.23028 -53.943227) (xy 45.2247 -53.936138)
			(xy 45.224446 -53.936138) (xy 45.224446 -53.935884) (xy 45.20684 -53.914925) (xy 45.177122 -53.86896)
			(xy 45.154279 -53.81922) (xy 45.13878 -53.766725) (xy 45.130944 -53.712553) (xy 45.130466 -53.685186)
			(xy 45.130952 -53.657935) (xy 45.138708 -53.603987) (xy 45.154063 -53.551692) (xy 45.176705 -53.502115)
			(xy 45.206171 -53.456265) (xy 45.241862 -53.415074) (xy 45.283053 -53.379383) (xy 45.328903 -53.349917)
			(xy 45.37848 -53.327275) (xy 45.430775 -53.31192) (xy 45.484723 -53.304164) (xy 45.539225 -53.304164)
			(xy 45.593173 -53.31192) (xy 45.645468 -53.327275) (xy 45.695045 -53.349917) (xy 45.740895 -53.379383)
			(xy 45.782086 -53.415074) (xy 45.817777 -53.456265) (xy 45.847243 -53.502115) (xy 45.869885 -53.551692)
			(xy 45.88524 -53.603987) (xy 45.892996 -53.657935) (xy 45.893482 -53.685186) (xy 45.893012 -53.712556)
			(xy 45.885196 -53.766735) (xy 45.869708 -53.819238) (xy 45.846867 -53.868985) (xy 45.817143 -53.914952)
			(xy 45.799502 -53.935884) (xy 45.799248 -53.936138) (xy 45.793675 -53.943234) (xy 45.787421 -53.960144)
			(xy 45.787056 -53.969158) (xy 45.787056 -54.036214) (xy 45.787394 -54.045233) (xy 45.793654 -54.06215)
			(xy 45.799248 -54.069234) (xy 45.799502 -54.069234) (xy 45.799502 -54.069488) (xy 45.817149 -54.090414)
			(xy 45.84686 -54.136388) (xy 45.869694 -54.186137) (xy 45.885183 -54.238639) (xy 45.893009 -54.292816)
			(xy 45.893482 -54.320186) (xy 45.892996 -54.347437) (xy 45.88524 -54.401385) (xy 45.869885 -54.45368)
			(xy 45.847243 -54.503257) (xy 45.817777 -54.549107) (xy 45.782086 -54.590298) (xy 45.740895 -54.625989)
			(xy 45.695045 -54.655455) (xy 45.645468 -54.678097) (xy 45.593173 -54.693452) (xy 45.539225 -54.701208)
			(xy 45.484723 -54.701208) (xy 45.430775 -54.693452) (xy 45.37848 -54.678097) (xy 45.328903 -54.655455)
			(xy 45.283053 -54.625989) (xy 45.241862 -54.590298) (xy 45.206171 -54.549107) (xy 45.176705 -54.503257)
			(xy 45.154063 -54.45368) (xy 45.138708 -54.401385) (xy 45.130952 -54.347437) (xy 45.130466 -54.320186)
			(xy 42.901897 -54.320186) (xy 42.892845 -54.339898) (xy 42.86312 -54.385865) (xy 42.845482 -54.4068)
			(xy 42.839386 -54.413912) (xy 42.836338 -54.422294) (xy 42.834817 -54.426582) (xy 42.833153 -54.435526)
			(xy 42.833036 -54.440074) (xy 42.833036 -54.50713) (xy 42.833157 -54.511678) (xy 42.834811 -54.520624)
			(xy 42.836338 -54.52491) (xy 42.839386 -54.533292) (xy 42.845482 -54.540404) (xy 42.863125 -54.561335)
			(xy 42.892851 -54.607301) (xy 42.915695 -54.657048) (xy 42.931186 -54.709552) (xy 42.939004 -54.763731)
			(xy 42.939118 -54.770528) (xy 46.071028 -54.770528) (xy 46.071504 -54.743158) (xy 46.079318 -54.688979)
			(xy 46.094805 -54.636476) (xy 46.117644 -54.586729) (xy 46.147367 -54.540762) (xy 46.165008 -54.51983)
			(xy 46.165262 -54.519576) (xy 46.170872 -54.512506) (xy 46.177103 -54.495576) (xy 46.177454 -54.486556)
			(xy 46.177454 -54.4195) (xy 46.177107 -54.410482) (xy 46.170853 -54.393565) (xy 46.165262 -54.38648)
			(xy 46.165008 -54.38648) (xy 46.165008 -54.386226) (xy 46.147369 -54.365294) (xy 46.117657 -54.319321)
			(xy 46.094821 -54.269574) (xy 46.07933 -54.217073) (xy 46.071502 -54.162897) (xy 46.071028 -54.135528)
			(xy 46.071514 -54.108277) (xy 46.07927 -54.054329) (xy 46.094625 -54.002034) (xy 46.117267 -53.952457)
			(xy 46.146733 -53.906607) (xy 46.182424 -53.865416) (xy 46.223615 -53.829725) (xy 46.269465 -53.800259)
			(xy 46.319042 -53.777617) (xy 46.371337 -53.762262) (xy 46.425285 -53.754506) (xy 46.479787 -53.754506)
			(xy 46.533735 -53.762262) (xy 46.58603 -53.777617) (xy 46.635607 -53.800259) (xy 46.681457 -53.829725)
			(xy 46.722648 -53.865416) (xy 46.758339 -53.906607) (xy 46.787805 -53.952457) (xy 46.806567 -53.993538)
			(xy 50.696858 -53.993538) (xy 50.696858 -53.933602) (xy 50.704681 -53.87418) (xy 50.720194 -53.816287)
			(xy 50.74313 -53.760914) (xy 50.773097 -53.709008) (xy 50.809584 -53.661458) (xy 50.851964 -53.619078)
			(xy 50.899514 -53.582591) (xy 50.95142 -53.552624) (xy 51.006793 -53.529688) (xy 51.064686 -53.514175)
			(xy 51.124108 -53.506352) (xy 51.184044 -53.506352) (xy 51.243466 -53.514175) (xy 51.301359 -53.529688)
			(xy 51.356732 -53.552624) (xy 51.408638 -53.582591) (xy 51.456188 -53.619078) (xy 51.498568 -53.661458)
			(xy 51.535055 -53.709008) (xy 51.565022 -53.760914) (xy 51.587958 -53.816287) (xy 51.603471 -53.87418)
			(xy 51.611294 -53.933602) (xy 51.611784 -53.96357) (xy 51.611294 -53.993538) (xy 51.603471 -54.05296)
			(xy 51.599587 -54.067456) (xy 52.941218 -54.067456) (xy 52.945289 -54.011834) (xy 52.957415 -53.957397)
			(xy 52.977338 -53.905306) (xy 53.004634 -53.856671) (xy 53.03872 -53.812528) (xy 53.078869 -53.773819)
			(xy 53.124227 -53.741368) (xy 53.173827 -53.715867) (xy 53.226611 -53.69786) (xy 53.281454 -53.68773)
			(xy 53.337188 -53.685693) (xy 53.392625 -53.691793) (xy 53.446582 -53.705899) (xy 53.497911 -53.727711)
			(xy 53.545517 -53.756765) (xy 53.588385 -53.79244) (xy 53.625602 -53.833977) (xy 53.656375 -53.88049)
			(xy 53.680047 -53.930987) (xy 53.696115 -53.984394) (xy 53.704235 -54.03957) (xy 53.704744 -54.067456)
			(xy 53.704235 -54.095342) (xy 53.696115 -54.150518) (xy 53.680047 -54.203925) (xy 53.663649 -54.238906)
			(xy 60.385958 -54.238906) (xy 60.390029 -54.183284) (xy 60.402155 -54.128847) (xy 60.422078 -54.076756)
			(xy 60.449374 -54.028121) (xy 60.48346 -53.983978) (xy 60.523609 -53.945269) (xy 60.568967 -53.912818)
			(xy 60.618567 -53.887317) (xy 60.671351 -53.86931) (xy 60.726194 -53.85918) (xy 60.781928 -53.857143)
			(xy 60.837365 -53.863243) (xy 60.891322 -53.877349) (xy 60.942651 -53.899161) (xy 60.990257 -53.928215)
			(xy 61.033125 -53.96389) (xy 61.070342 -54.005427) (xy 61.101115 -54.05194) (xy 61.124787 -54.102437)
			(xy 61.140855 -54.155844) (xy 61.148975 -54.21102) (xy 61.149484 -54.238906) (xy 61.148975 -54.266792)
			(xy 61.140855 -54.321968) (xy 61.124787 -54.375375) (xy 61.101115 -54.425872) (xy 61.070342 -54.472385)
			(xy 61.033125 -54.513922) (xy 60.990257 -54.549597) (xy 60.942651 -54.578651) (xy 60.891322 -54.600463)
			(xy 60.837365 -54.614569) (xy 60.781928 -54.620669) (xy 60.726194 -54.618632) (xy 60.671351 -54.608502)
			(xy 60.618567 -54.590495) (xy 60.568967 -54.564994) (xy 60.523609 -54.532543) (xy 60.48346 -54.493834)
			(xy 60.449374 -54.449691) (xy 60.422078 -54.401056) (xy 60.402155 -54.348965) (xy 60.390029 -54.294528)
			(xy 60.385958 -54.238906) (xy 53.663649 -54.238906) (xy 53.656375 -54.254422) (xy 53.625602 -54.300935)
			(xy 53.588385 -54.342472) (xy 53.545517 -54.378147) (xy 53.497911 -54.407201) (xy 53.446582 -54.429013)
			(xy 53.392625 -54.443119) (xy 53.337188 -54.449219) (xy 53.281454 -54.447182) (xy 53.226611 -54.437052)
			(xy 53.173827 -54.419045) (xy 53.124227 -54.393544) (xy 53.078869 -54.361093) (xy 53.03872 -54.322384)
			(xy 53.004634 -54.278241) (xy 52.977338 -54.229606) (xy 52.957415 -54.177515) (xy 52.945289 -54.123078)
			(xy 52.941218 -54.067456) (xy 51.599587 -54.067456) (xy 51.587958 -54.110853) (xy 51.565022 -54.166226)
			(xy 51.535055 -54.218132) (xy 51.498568 -54.265682) (xy 51.456188 -54.308062) (xy 51.408638 -54.344549)
			(xy 51.356732 -54.374516) (xy 51.301359 -54.397452) (xy 51.243466 -54.412965) (xy 51.184044 -54.420788)
			(xy 51.124108 -54.420788) (xy 51.064686 -54.412965) (xy 51.006793 -54.397452) (xy 50.95142 -54.374516)
			(xy 50.899514 -54.344549) (xy 50.851964 -54.308062) (xy 50.809584 -54.265682) (xy 50.773097 -54.218132)
			(xy 50.74313 -54.166226) (xy 50.720194 -54.110853) (xy 50.704681 -54.05296) (xy 50.696858 -53.993538)
			(xy 46.806567 -53.993538) (xy 46.810447 -54.002034) (xy 46.825802 -54.054329) (xy 46.833558 -54.108277)
			(xy 46.834044 -54.135528) (xy 46.833608 -54.162899) (xy 46.825785 -54.21708) (xy 46.81029 -54.269584)
			(xy 46.787441 -54.319331) (xy 46.757709 -54.365296) (xy 46.740064 -54.386226) (xy 46.73981 -54.38648)
			(xy 46.734227 -54.393569) (xy 46.727978 -54.410484) (xy 46.727618 -54.4195) (xy 46.727618 -54.486556)
			(xy 46.727992 -54.495571) (xy 46.734228 -54.512488) (xy 46.73981 -54.519576) (xy 46.740064 -54.519576)
			(xy 46.740064 -54.51983) (xy 46.757678 -54.540782) (xy 46.787395 -54.586749) (xy 46.810236 -54.636491)
			(xy 46.825733 -54.688988) (xy 46.833567 -54.74316) (xy 46.834044 -54.770528) (xy 46.833558 -54.797779)
			(xy 46.825802 -54.851727) (xy 46.810447 -54.904022) (xy 46.787805 -54.953599) (xy 46.758339 -54.999449)
			(xy 46.722648 -55.04064) (xy 46.681457 -55.076331) (xy 46.67037 -55.083456) (xy 52.941218 -55.083456)
			(xy 52.945289 -55.027834) (xy 52.957415 -54.973397) (xy 52.977338 -54.921306) (xy 53.004634 -54.872671)
			(xy 53.03872 -54.828528) (xy 53.078869 -54.789819) (xy 53.124227 -54.757368) (xy 53.173827 -54.731867)
			(xy 53.226611 -54.71386) (xy 53.281454 -54.70373) (xy 53.337188 -54.701693) (xy 53.392625 -54.707793)
			(xy 53.446582 -54.721899) (xy 53.497911 -54.743711) (xy 53.545517 -54.772765) (xy 53.588385 -54.80844)
			(xy 53.625602 -54.849977) (xy 53.656375 -54.89649) (xy 53.680047 -54.946987) (xy 53.696115 -55.000394)
			(xy 53.704235 -55.05557) (xy 53.704744 -55.083456) (xy 53.704235 -55.111342) (xy 53.696115 -55.166518)
			(xy 53.680047 -55.219925) (xy 53.656375 -55.270422) (xy 53.625602 -55.316935) (xy 53.588385 -55.358472)
			(xy 53.545517 -55.394147) (xy 53.497911 -55.423201) (xy 53.497047 -55.423568) (xy 54.148472 -55.423568)
			(xy 54.148472 -55.363632) (xy 54.156295 -55.30421) (xy 54.171807 -55.246317) (xy 54.194743 -55.190944)
			(xy 54.224709 -55.139038) (xy 54.261195 -55.091488) (xy 54.303574 -55.049107) (xy 54.351123 -55.012619)
			(xy 54.403028 -54.98265) (xy 54.4584 -54.959713) (xy 54.516292 -54.944198) (xy 54.575714 -54.936373)
			(xy 54.605682 -54.935882) (xy 54.605936 -54.935882) (xy 54.63746 -54.936437) (xy 54.69991 -54.945106)
			(xy 54.76058 -54.96226) (xy 54.818322 -54.987577) (xy 54.820722 -54.989051) (xy 55.901068 -54.989051)
			(xy 55.901068 -54.934549) (xy 55.908824 -54.880601) (xy 55.924179 -54.828307) (xy 55.946819 -54.778729)
			(xy 55.976284 -54.732879) (xy 56.011975 -54.691688) (xy 56.053164 -54.655995) (xy 56.099013 -54.626528)
			(xy 56.14859 -54.603885) (xy 56.200884 -54.588528) (xy 56.254831 -54.580769) (xy 56.282082 -54.580282)
			(xy 56.310173 -54.580791) (xy 56.36575 -54.589016) (xy 56.419518 -54.605304) (xy 56.470316 -54.629305)
			(xy 56.517043 -54.660497) (xy 56.558688 -54.698207) (xy 56.594351 -54.741619) (xy 56.609234 -54.765448)
			(xy 56.614568 -54.774338) (xy 56.631586 -54.78653) (xy 56.724804 -54.80685) (xy 56.745378 -54.802532)
			(xy 56.754014 -54.79669) (xy 56.778072 -54.780681) (xy 56.830006 -54.75534) (xy 56.885165 -54.738117)
			(xy 56.942291 -54.729405) (xy 56.971184 -54.728872) (xy 56.998434 -54.729393) (xy 57.052379 -54.737147)
			(xy 57.104672 -54.752499) (xy 57.154248 -54.775137) (xy 57.200097 -54.804599) (xy 57.241287 -54.840287)
			(xy 57.276979 -54.881474) (xy 57.306446 -54.92732) (xy 57.329088 -54.976894) (xy 57.344445 -55.029185)
			(xy 57.352204 -55.08313) (xy 57.352692 -55.11038) (xy 57.352216 -55.13775) (xy 57.344401 -55.191929)
			(xy 57.328914 -55.244432) (xy 57.306075 -55.294179) (xy 57.276352 -55.340146) (xy 57.258712 -55.361078)
			(xy 57.258458 -55.361332) (xy 57.252889 -55.36843) (xy 57.246633 -55.385338) (xy 57.246266 -55.394352)
			(xy 57.246266 -55.461408) (xy 57.246626 -55.470424) (xy 57.252872 -55.487341) (xy 57.258458 -55.494428)
			(xy 57.258712 -55.494428) (xy 57.258712 -55.494682) (xy 57.276331 -55.515631) (xy 57.306054 -55.561597)
			(xy 57.328898 -55.611341) (xy 57.344394 -55.66384) (xy 57.352224 -55.718016) (xy 57.352226 -55.772754)
			(xy 57.344401 -55.82693) (xy 57.328909 -55.879431) (xy 57.306069 -55.929176) (xy 57.27635 -55.975145)
			(xy 57.258712 -55.996078) (xy 57.258458 -55.996332) (xy 57.252889 -56.00343) (xy 57.246633 -56.020338)
			(xy 57.246266 -56.029352) (xy 57.246266 -56.096408) (xy 57.246626 -56.105424) (xy 57.252872 -56.122341)
			(xy 57.258458 -56.129428) (xy 57.258712 -56.129428) (xy 57.258712 -56.129682) (xy 57.276358 -56.150608)
			(xy 57.306068 -56.196583) (xy 57.328903 -56.246332) (xy 57.344392 -56.298834) (xy 57.352219 -56.35301)
			(xy 57.352692 -56.38038) (xy 57.352206 -56.407631) (xy 57.34445 -56.461579) (xy 57.329095 -56.513874)
			(xy 57.306453 -56.563451) (xy 57.276987 -56.609301) (xy 57.241296 -56.650492) (xy 57.200105 -56.686183)
			(xy 57.154255 -56.715649) (xy 57.104678 -56.738291) (xy 57.052383 -56.753646) (xy 56.998435 -56.761402)
			(xy 56.943933 -56.761402) (xy 56.889985 -56.753646) (xy 56.83769 -56.738291) (xy 56.788113 -56.715649)
			(xy 56.742263 -56.686183) (xy 56.701072 -56.650492) (xy 56.665381 -56.609301) (xy 56.635915 -56.563451)
			(xy 56.613273 -56.513874) (xy 56.597918 -56.461579) (xy 56.590162 -56.407631) (xy 56.589676 -56.38038)
			(xy 56.590112 -56.353008) (xy 56.597934 -56.298827) (xy 56.613429 -56.246323) (xy 56.636278 -56.196577)
			(xy 56.666011 -56.150612) (xy 56.683656 -56.129682) (xy 56.68391 -56.129428) (xy 56.689492 -56.122338)
			(xy 56.695741 -56.105424) (xy 56.696102 -56.096408) (xy 56.696102 -56.029352) (xy 56.695719 -56.020338)
			(xy 56.689489 -56.003421) (xy 56.68391 -55.996332) (xy 56.683656 -55.996332) (xy 56.683656 -55.996078)
			(xy 56.665995 -55.975162) (xy 56.636268 -55.929192) (xy 56.613422 -55.879443) (xy 56.597926 -55.826938)
			(xy 56.590099 -55.772757) (xy 56.590101 -55.718013) (xy 56.597933 -55.663832) (xy 56.613433 -55.611329)
			(xy 56.636283 -55.561582) (xy 56.666013 -55.515614) (xy 56.683656 -55.494682) (xy 56.68391 -55.494428)
			(xy 56.689492 -55.487338) (xy 56.695741 -55.470424) (xy 56.696102 -55.461408) (xy 56.696102 -55.394352)
			(xy 56.695719 -55.385338) (xy 56.689489 -55.368421) (xy 56.68391 -55.361332) (xy 56.683656 -55.360824)
			(xy 56.67271 -55.348091) (xy 56.65287 -55.320999) (xy 56.644032 -55.306722) (xy 56.638698 -55.297832)
			(xy 56.62168 -55.28564) (xy 56.528462 -55.26532) (xy 56.507888 -55.269638) (xy 56.499252 -55.27548)
			(xy 56.475174 -55.291458) (xy 56.423248 -55.316806) (xy 56.368094 -55.334038) (xy 56.310973 -55.34276)
			(xy 56.282082 -55.343298) (xy 56.254831 -55.342831) (xy 56.200884 -55.335072) (xy 56.14859 -55.319715)
			(xy 56.099013 -55.297072) (xy 56.053164 -55.267605) (xy 56.011975 -55.231912) (xy 55.976284 -55.190721)
			(xy 55.946819 -55.144871) (xy 55.924179 -55.095293) (xy 55.908824 -55.042999) (xy 55.901068 -54.989051)
			(xy 54.820722 -54.989051) (xy 54.872046 -55.020576) (xy 54.920733 -55.060633) (xy 54.942486 -55.083456)
			(xy 54.94909 -55.090568) (xy 54.966108 -55.09895) (xy 55.044594 -55.1053) (xy 55.054159 -55.105661)
			(xy 55.072442 -55.100047) (xy 55.080154 -55.094378) (xy 55.100442 -55.078847) (xy 55.144391 -55.052787)
			(xy 55.191423 -55.032822) (xy 55.240698 -55.01931) (xy 55.291335 -55.012492) (xy 55.316882 -55.012082)
			(xy 55.344135 -55.012564) (xy 55.398086 -55.020319) (xy 55.450385 -55.035673) (xy 55.499966 -55.058314)
			(xy 55.54582 -55.08778) (xy 55.587014 -55.123473) (xy 55.622709 -55.164665) (xy 55.652178 -55.210518)
			(xy 55.674821 -55.260098) (xy 55.690177 -55.312396) (xy 55.697935 -55.366347) (xy 55.697935 -55.420853)
			(xy 55.690177 -55.474804) (xy 55.674821 -55.527102) (xy 55.652178 -55.576682) (xy 55.622709 -55.622535)
			(xy 55.587014 -55.663727) (xy 55.54582 -55.69942) (xy 55.499966 -55.728886) (xy 55.450385 -55.751527)
			(xy 55.398086 -55.766881) (xy 55.344135 -55.774636) (xy 55.316882 -55.775098) (xy 55.291333 -55.774713)
			(xy 55.240693 -55.7679) (xy 55.191415 -55.754386) (xy 55.144384 -55.734412) (xy 55.100442 -55.708336)
			(xy 55.080154 -55.692802) (xy 55.072413 -55.68719) (xy 55.05415 -55.681574) (xy 55.044594 -55.68188)
			(xy 54.966108 -55.68823) (xy 54.94909 -55.696612) (xy 54.942486 -55.703724) (xy 54.920742 -55.726559)
			(xy 54.872065 -55.766638) (xy 54.818344 -55.799651) (xy 54.760598 -55.824973) (xy 54.699921 -55.842122)
			(xy 54.637463 -55.850774) (xy 54.605936 -55.851298) (xy 54.605682 -55.851298) (xy 54.575714 -55.850827)
			(xy 54.516292 -55.843002) (xy 54.4584 -55.827487) (xy 54.403028 -55.80455) (xy 54.351123 -55.774581)
			(xy 54.303574 -55.738093) (xy 54.261195 -55.695712) (xy 54.224709 -55.648162) (xy 54.194743 -55.596256)
			(xy 54.171807 -55.540883) (xy 54.156295 -55.48299) (xy 54.148472 -55.423568) (xy 53.497047 -55.423568)
			(xy 53.446582 -55.445013) (xy 53.392625 -55.459119) (xy 53.337188 -55.465219) (xy 53.281454 -55.463182)
			(xy 53.226611 -55.453052) (xy 53.173827 -55.435045) (xy 53.124227 -55.409544) (xy 53.078869 -55.377093)
			(xy 53.03872 -55.338384) (xy 53.004634 -55.294241) (xy 52.977338 -55.245606) (xy 52.957415 -55.193515)
			(xy 52.945289 -55.139078) (xy 52.941218 -55.083456) (xy 46.67037 -55.083456) (xy 46.635607 -55.105797)
			(xy 46.58603 -55.128439) (xy 46.533735 -55.143794) (xy 46.479787 -55.15155) (xy 46.425285 -55.15155)
			(xy 46.371337 -55.143794) (xy 46.319042 -55.128439) (xy 46.269465 -55.105797) (xy 46.223615 -55.076331)
			(xy 46.182424 -55.04064) (xy 46.146733 -54.999449) (xy 46.117267 -54.953599) (xy 46.094625 -54.904022)
			(xy 46.07927 -54.851727) (xy 46.071514 -54.797779) (xy 46.071028 -54.770528) (xy 42.939118 -54.770528)
			(xy 42.939462 -54.791102) (xy 42.938976 -54.818353) (xy 42.93122 -54.872301) (xy 42.915865 -54.924596)
			(xy 42.893223 -54.974173) (xy 42.863757 -55.020023) (xy 42.828066 -55.061214) (xy 42.786875 -55.096905)
			(xy 42.741025 -55.126371) (xy 42.691448 -55.149013) (xy 42.639153 -55.164368) (xy 42.585205 -55.172124)
			(xy 42.530703 -55.172124) (xy 42.476755 -55.164368) (xy 42.42446 -55.149013) (xy 42.374883 -55.126371)
			(xy 42.329033 -55.096905) (xy 42.287842 -55.061214) (xy 42.252151 -55.020023) (xy 42.222685 -54.974173)
			(xy 42.200043 -54.924596) (xy 42.184688 -54.872301) (xy 42.176932 -54.818353) (xy 42.176446 -54.791102)
			(xy 42.176918 -54.763732) (xy 42.184742 -54.709555) (xy 42.20023 -54.657052) (xy 42.223065 -54.607302)
			(xy 42.252776 -54.561327) (xy 42.270426 -54.540404) (xy 42.276522 -54.533292) (xy 42.27957 -54.52491)
			(xy 42.281092 -54.520622) (xy 42.282755 -54.511678) (xy 42.282872 -54.50713) (xy 42.282872 -54.440074)
			(xy 42.282752 -54.435526) (xy 42.281098 -54.426579) (xy 42.27957 -54.422294) (xy 42.276522 -54.413912)
			(xy 42.270426 -54.4068) (xy 42.252785 -54.385867) (xy 42.22306 -54.339899) (xy 42.200215 -54.290153)
			(xy 42.184718 -54.237651) (xy 42.176889 -54.183472) (xy 42.176889 -54.128731) (xy 42.184717 -54.074552)
			(xy 42.200214 -54.02205) (xy 42.223059 -53.972303) (xy 42.252783 -53.926335) (xy 42.270426 -53.905404)
			(xy 42.276522 -53.898292) (xy 42.27957 -53.88991) (xy 42.281092 -53.885622) (xy 42.282755 -53.876678)
			(xy 42.282872 -53.87213) (xy 42.282872 -53.805074) (xy 42.282752 -53.800526) (xy 42.281098 -53.791579)
			(xy 42.27957 -53.787294) (xy 42.276522 -53.778912) (xy 42.270426 -53.7718) (xy 42.252783 -53.750869)
			(xy 42.223055 -53.704903) (xy 42.20021 -53.655157) (xy 42.184719 -53.602653) (xy 42.1769 -53.548473)
			(xy 42.176446 -53.521102) (xy 42.176524 -53.508364) (xy 42.178178 -53.482943) (xy 42.179748 -53.470302)
			(xy 42.184387 -53.440168) (xy 42.202 -53.381802) (xy 42.228689 -53.326988) (xy 42.263773 -53.277129)
			(xy 42.28465 -53.25491) (xy 42.285158 -53.254402) (xy 42.290253 -53.248608) (xy 42.297092 -53.234787)
			(xy 42.29862 -53.227224) (xy 42.299128 -53.21935) (xy 42.299128 -53.187854) (xy 42.298366 -53.17871)
			(xy 42.29735 -53.1749) (xy 42.295459 -53.168419) (xy 42.288774 -53.156696) (xy 42.284142 -53.151786)
			(xy 42.283126 -53.15077) (xy 42.271442 -53.137816) (xy 42.264151 -53.130869) (xy 42.245683 -53.122877)
			(xy 42.235628 -53.122322) (xy 40.322754 -53.122322) (xy 40.313949 -53.122747) (xy 40.297405 -53.128799)
			(xy 40.28387 -53.140075) (xy 40.279066 -53.147468) (xy 40.234616 -53.22316) (xy 40.231452 -53.229097)
			(xy 40.227985 -53.24209) (xy 40.227758 -53.248814) (xy 40.227758 -53.262022) (xy 40.229536 -53.265324)
			(xy 40.234362 -53.273706) (xy 40.246056 -53.295243) (xy 40.264471 -53.340658) (xy 40.27693 -53.388054)
			(xy 40.283226 -53.436655) (xy 40.283638 -53.461158) (xy 40.283638 -53.461412) (xy 40.283165 -53.488781)
			(xy 40.275339 -53.542958) (xy 40.259848 -53.595459) (xy 40.237012 -53.645207) (xy 40.207299 -53.69118)
			(xy 40.189658 -53.71211) (xy 40.183562 -53.719222) (xy 40.180514 -53.727604) (xy 40.178994 -53.731892)
			(xy 40.177333 -53.740836) (xy 40.177212 -53.745384) (xy 40.177212 -53.81244) (xy 40.177333 -53.816988)
			(xy 40.178989 -53.825934) (xy 40.180514 -53.83022) (xy 40.183562 -53.838602) (xy 40.189658 -53.845714)
			(xy 40.207298 -53.866646) (xy 40.237023 -53.912614) (xy 40.259867 -53.962359) (xy 40.275363 -54.014861)
			(xy 40.28319 -54.069039) (xy 40.283189 -54.123779) (xy 40.275359 -54.177957) (xy 40.259861 -54.230458)
			(xy 40.237014 -54.280202) (xy 40.207288 -54.326168) (xy 40.189658 -54.34711) (xy 40.183562 -54.354222)
			(xy 40.180514 -54.362604) (xy 40.178994 -54.366892) (xy 40.177333 -54.375836) (xy 40.177212 -54.380384)
			(xy 40.177212 -54.44744) (xy 40.177333 -54.451988) (xy 40.178989 -54.460934) (xy 40.180514 -54.46522)
			(xy 40.183562 -54.473602) (xy 40.189658 -54.480714) (xy 40.207301 -54.501645) (xy 40.237028 -54.547611)
			(xy 40.259872 -54.597357) (xy 40.275363 -54.649861) (xy 40.28318 -54.704041) (xy 40.283638 -54.731412)
			(xy 40.283152 -54.758663) (xy 40.275396 -54.812611) (xy 40.260041 -54.864906) (xy 40.237399 -54.914483)
			(xy 40.207933 -54.960333) (xy 40.172242 -55.001524) (xy 40.131051 -55.037215) (xy 40.085201 -55.066681)
			(xy 40.035624 -55.089323) (xy 39.983329 -55.104678) (xy 39.929381 -55.112434) (xy 39.874879 -55.112434)
			(xy 39.820931 -55.104678) (xy 39.768636 -55.089323) (xy 39.719059 -55.066681) (xy 39.673209 -55.037215)
			(xy 39.632018 -55.001524) (xy 39.596327 -54.960333) (xy 39.566861 -54.914483) (xy 39.544219 -54.864906)
			(xy 39.528864 -54.812611) (xy 39.521108 -54.758663) (xy 39.520622 -54.731412) (xy 39.5211 -54.704044)
			(xy 39.528935 -54.649872) (xy 39.544433 -54.597377) (xy 39.567274 -54.547635) (xy 39.59699 -54.501668)
			(xy 39.614602 -54.480714) (xy 39.620698 -54.473602) (xy 39.623746 -54.46522) (xy 39.625269 -54.460932)
			(xy 39.626935 -54.451988) (xy 39.627048 -54.44744) (xy 39.627048 -54.380384) (xy 39.62692 -54.375837)
			(xy 39.625251 -54.366897) (xy 39.623746 -54.362604) (xy 39.620698 -54.354222) (xy 39.614602 -54.34711)
			(xy 39.596962 -54.326177) (xy 39.567237 -54.280208) (xy 39.544391 -54.230461) (xy 39.528895 -54.177959)
			(xy 39.521065 -54.12378) (xy 39.521064 -54.069038) (xy 39.528891 -54.014859) (xy 39.544385 -53.962356)
			(xy 39.567228 -53.912608) (xy 39.596951 -53.866638) (xy 39.614602 -53.845714) (xy 39.620698 -53.838602)
			(xy 39.623746 -53.83022) (xy 39.625269 -53.825932) (xy 39.626935 -53.816988) (xy 39.627048 -53.81244)
			(xy 39.627048 -53.745384) (xy 39.62692 -53.740837) (xy 39.625251 -53.731897) (xy 39.623746 -53.727604)
			(xy 39.620698 -53.719222) (xy 39.614602 -53.71211) (xy 39.596959 -53.691179) (xy 39.567232 -53.645213)
			(xy 39.544387 -53.595466) (xy 39.528896 -53.542963) (xy 39.521076 -53.488783) (xy 39.520622 -53.461412)
			(xy 39.520622 -53.461158) (xy 39.520998 -53.436652) (xy 39.527278 -53.388044) (xy 39.539741 -53.340643)
			(xy 39.558182 -53.295233) (xy 39.569898 -53.273706) (xy 39.574724 -53.265324) (xy 39.576502 -53.262022)
			(xy 39.576502 -53.248814) (xy 39.576328 -53.242084) (xy 39.572843 -53.229084) (xy 39.569644 -53.22316)
			(xy 39.525194 -53.147468) (xy 39.520432 -53.140039) (xy 39.506898 -53.128736) (xy 39.490322 -53.122723)
			(xy 39.481506 -53.122322) (xy 33.565592 -53.122322) (xy 33.557025 -53.122695) (xy 33.540868 -53.128408)
			(xy 33.527474 -53.1391) (xy 33.522666 -53.146198) (xy 33.48736 -53.20792) (xy 33.477708 -53.224684)
			(xy 33.474616 -53.230502) (xy 33.471281 -53.243243) (xy 33.471104 -53.24983) (xy 33.471104 -53.263546)
			(xy 33.478216 -53.275484) (xy 33.490768 -53.297592) (xy 33.510545 -53.344426) (xy 33.523916 -53.393475)
			(xy 33.530642 -53.443866) (xy 33.531048 -53.469286) (xy 33.531048 -53.475382) (xy 33.530151 -53.502348)
			(xy 33.521699 -53.555636) (xy 33.505823 -53.607201) (xy 33.48284 -53.656015) (xy 33.453208 -53.701104)
			(xy 33.41752 -53.741569) (xy 33.376486 -53.776601) (xy 33.330926 -53.805503) (xy 33.281748 -53.827697)
			(xy 33.229934 -53.842741) (xy 33.176517 -53.850334) (xy 33.14954 -53.850794) (xy 33.122172 -53.850318)
			(xy 33.067998 -53.842486) (xy 33.015499 -53.826993) (xy 32.965754 -53.804155) (xy 32.919783 -53.774442)
			(xy 32.898842 -53.756814) (xy 32.89173 -53.750718) (xy 32.883348 -53.74767) (xy 32.879061 -53.746147)
			(xy 32.870116 -53.744492) (xy 32.865568 -53.744368) (xy 32.798512 -53.744368) (xy 32.793965 -53.744494)
			(xy 32.785023 -53.746159) (xy 32.780732 -53.74767) (xy 32.77235 -53.750718) (xy 32.765238 -53.756814)
			(xy 32.744305 -53.774452) (xy 32.698337 -53.804169) (xy 32.64859 -53.827004) (xy 32.596087 -53.842485)
			(xy 32.541909 -53.850294) (xy 32.51454 -53.850794) (xy 32.487566 -53.850324) (xy 32.434157 -53.842717)
			(xy 32.382352 -53.827664) (xy 32.333183 -53.805465) (xy 32.287631 -53.776562) (xy 32.246603 -53.741531)
			(xy 32.210919 -53.701071) (xy 32.181289 -53.655988) (xy 32.158303 -53.607182) (xy 32.142421 -53.555625)
			(xy 32.133959 -53.502345) (xy 32.133032 -53.475382) (xy 32.133032 -53.469286) (xy 32.133457 -53.443869)
			(xy 32.140209 -53.393485) (xy 32.15358 -53.344441) (xy 32.173333 -53.297601) (xy 32.185864 -53.275484)
			(xy 32.18942 -53.269642) (xy 32.192976 -53.256434) (xy 32.192976 -53.24983) (xy 32.19277 -53.243248)
			(xy 32.189434 -53.230513) (xy 32.186372 -53.224684) (xy 32.17672 -53.20792) (xy 32.141414 -53.146198)
			(xy 32.136601 -53.139099) (xy 32.12323 -53.128374) (xy 32.107059 -53.122691) (xy 32.098488 -53.122322)
			(xy 27.816556 -53.122322) (xy 27.808198 -53.122703) (xy 27.792387 -53.128142) (xy 27.785568 -53.13299)
			(xy 27.779218 -53.13807) (xy 27.770074 -53.15204) (xy 27.767788 -53.16093) (xy 27.760024 -53.190366)
			(xy 27.73776 -53.247025) (xy 27.708182 -53.300234) (xy 27.671813 -53.349053) (xy 27.629294 -53.392621)
			(xy 27.581376 -53.43017) (xy 27.528905 -53.461036) (xy 27.472805 -53.484675) (xy 27.414066 -53.50067)
			(xy 27.353726 -53.508738) (xy 27.29285 -53.508738) (xy 27.23251 -53.50067) (xy 27.173771 -53.484675)
			(xy 27.117671 -53.461036) (xy 27.0652 -53.43017) (xy 27.017282 -53.392621) (xy 26.974763 -53.349053)
			(xy 26.938394 -53.300234) (xy 26.908816 -53.247025) (xy 26.886552 -53.190366) (xy 26.878788 -53.16093)
			(xy 26.878788 -53.160676) (xy 26.876442 -53.152407) (xy 26.867097 -53.137992) (xy 26.8605 -53.132482)
			(xy 26.854404 -53.127656) (xy 26.838402 -53.122322) (xy 18.784316 -53.122322) (xy 18.776421 -53.122656)
			(xy 18.761413 -53.12757) (xy 18.754852 -53.131974) (xy 18.748502 -53.136292) (xy 18.739358 -53.148738)
			(xy 18.736564 -53.156612) (xy 18.726341 -53.185088) (xy 18.699438 -53.239281) (xy 18.665622 -53.289452)
			(xy 18.625485 -53.334724) (xy 18.579727 -53.374308) (xy 18.5547 -53.391308) (xy 18.545556 -53.39715)
			(xy 18.539968 -53.405786) (xy 18.537292 -53.410115) (xy 18.533576 -53.419587) (xy 18.532602 -53.424582)
			(xy 18.519902 -53.49875) (xy 18.519187 -53.504024) (xy 18.519697 -53.514652) (xy 18.520918 -53.519832)
			(xy 18.523204 -53.52923) (xy 18.529808 -53.537866) (xy 18.544699 -53.55792) (xy 18.569701 -53.601161)
			(xy 18.588849 -53.647295) (xy 18.601816 -53.695532) (xy 18.60838 -53.745048) (xy 18.608802 -53.770022)
			(xy 18.608802 -53.77053) (xy 18.608314 -53.79778) (xy 18.600554 -53.851724) (xy 18.585196 -53.904015)
			(xy 18.562553 -53.953588) (xy 18.533086 -53.999434) (xy 18.497395 -54.04062) (xy 18.456205 -54.076308)
			(xy 18.410356 -54.105771) (xy 18.360781 -54.128409) (xy 18.308489 -54.143762) (xy 18.254544 -54.151517)
			(xy 18.227294 -54.152038) (xy 18.199924 -54.151566) (xy 18.145748 -54.14374) (xy 18.093246 -54.12825)
			(xy 18.043497 -54.105415) (xy 17.997524 -54.075702) (xy 17.976596 -54.058058) (xy 17.969484 -54.051962)
			(xy 17.961102 -54.048914) (xy 17.956814 -54.047394) (xy 17.94787 -54.045732) (xy 17.943322 -54.045612)
			(xy 17.876266 -54.045612) (xy 17.871718 -54.045733) (xy 17.862772 -54.047387) (xy 17.858486 -54.048914)
			(xy 17.850104 -54.051962) (xy 17.842992 -54.058058) (xy 17.822061 -54.075701) (xy 17.776096 -54.10543)
			(xy 17.726349 -54.128274) (xy 17.673845 -54.143765) (xy 17.619665 -54.151584) (xy 17.592294 -54.152038)
			(xy 17.565042 -54.151552) (xy 17.511094 -54.143795) (xy 17.458798 -54.128439) (xy 17.409219 -54.105798)
			(xy 17.363368 -54.076332) (xy 17.322176 -54.040641) (xy 17.286482 -53.999452) (xy 17.257013 -53.953602)
			(xy 17.234369 -53.904025) (xy 17.21901 -53.85173) (xy 17.21125 -53.797782) (xy 17.210786 -53.77053)
			(xy 17.211318 -53.741612) (xy 17.220041 -53.684438) (xy 17.237291 -53.629235) (xy 17.262674 -53.577267)
			(xy 17.295608 -53.529725) (xy 17.335339 -53.487696) (xy 17.357852 -53.46954) (xy 17.365235 -53.463256)
			(xy 17.375026 -53.44654) (xy 17.376902 -53.437028) (xy 17.37741 -53.429408) (xy 17.37741 -53.349652)
			(xy 17.376902 -53.342032) (xy 17.375138 -53.333015) (xy 17.366141 -53.31701) (xy 17.359376 -53.31079)
			(xy 17.357852 -53.30952) (xy 17.338581 -53.294012) (xy 17.303811 -53.258828) (xy 17.273873 -53.219451)
			(xy 17.249269 -53.176538) (xy 17.239488 -53.153818) (xy 17.23517 -53.143404) (xy 17.227042 -53.135784)
			(xy 17.220438 -53.130704) (xy 17.214342 -53.12664) (xy 17.200372 -53.122322) (xy 16.881094 -53.122322)
			(xy 16.880332 -53.122322) (xy 16.87028 -53.122895) (xy 16.851811 -53.130875) (xy 16.844518 -53.137816)
			(xy 16.832834 -53.15077) (xy 16.831818 -53.151786) (xy 16.827196 -53.156705) (xy 16.820503 -53.168421)
			(xy 16.81861 -53.1749) (xy 16.816832 -53.1876) (xy 16.816832 -53.21935) (xy 16.817594 -53.228494)
			(xy 16.819195 -53.235899) (xy 16.826175 -53.249339) (xy 16.83131 -53.25491) (xy 16.851484 -53.27641)
			(xy 16.885631 -53.324468) (xy 16.911979 -53.377207) (xy 16.9299 -53.433372) (xy 16.938969 -53.491625)
			(xy 16.939514 -53.521102) (xy 16.939042 -53.548472) (xy 16.931218 -53.60265) (xy 16.915731 -53.655154)
			(xy 16.8929 -53.704906) (xy 16.863192 -53.750883) (xy 16.845534 -53.7718) (xy 16.839438 -53.778912)
			(xy 16.83639 -53.787294) (xy 16.834861 -53.79158) (xy 16.833196 -53.800525) (xy 16.833088 -53.805074)
			(xy 16.833088 -53.87213) (xy 16.833208 -53.876678) (xy 16.834862 -53.885625) (xy 16.83639 -53.88991)
			(xy 16.839438 -53.898292) (xy 16.845534 -53.905404) (xy 16.863176 -53.926336) (xy 16.892904 -53.972303)
			(xy 16.915751 -54.022049) (xy 16.931249 -54.074551) (xy 16.939078 -54.128731) (xy 16.939078 -54.183472)
			(xy 16.931248 -54.237652) (xy 16.91575 -54.290154) (xy 16.901957 -54.320186) (xy 19.130518 -54.320186)
			(xy 19.130971 -54.292815) (xy 19.138792 -54.238635) (xy 19.154283 -54.186132) (xy 19.177128 -54.136385)
			(xy 19.206855 -54.090419) (xy 19.224498 -54.069488) (xy 19.224752 -54.069234) (xy 19.230337 -54.062146)
			(xy 19.236583 -54.04523) (xy 19.236944 -54.036214) (xy 19.236944 -53.969158) (xy 19.236572 -53.960142)
			(xy 19.230336 -53.943225) (xy 19.224752 -53.936138) (xy 19.224498 -53.936138) (xy 19.224498 -53.935884)
			(xy 19.206885 -53.914931) (xy 19.177169 -53.868964) (xy 19.154328 -53.819222) (xy 19.138831 -53.766726)
			(xy 19.130996 -53.712554) (xy 19.130518 -53.685186) (xy 19.131004 -53.657935) (xy 19.13876 -53.603987)
			(xy 19.154115 -53.551692) (xy 19.176757 -53.502115) (xy 19.206223 -53.456265) (xy 19.241914 -53.415074)
			(xy 19.283105 -53.379383) (xy 19.328955 -53.349917) (xy 19.378532 -53.327275) (xy 19.430827 -53.31192)
			(xy 19.484775 -53.304164) (xy 19.539277 -53.304164) (xy 19.593225 -53.31192) (xy 19.64552 -53.327275)
			(xy 19.695097 -53.349917) (xy 19.740947 -53.379383) (xy 19.782138 -53.415074) (xy 19.817829 -53.456265)
			(xy 19.847295 -53.502115) (xy 19.869937 -53.551692) (xy 19.885292 -53.603987) (xy 19.893048 -53.657935)
			(xy 19.893534 -53.685186) (xy 19.893076 -53.712557) (xy 19.885259 -53.766737) (xy 19.869769 -53.819241)
			(xy 19.846925 -53.868987) (xy 19.817197 -53.914953) (xy 19.799554 -53.935884) (xy 19.7993 -53.936138)
			(xy 19.793733 -53.943238) (xy 19.787475 -53.960145) (xy 19.787108 -53.969158) (xy 19.787108 -54.036214)
			(xy 19.787457 -54.045232) (xy 19.79371 -54.062149) (xy 19.7993 -54.069234) (xy 19.799554 -54.069234)
			(xy 19.799554 -54.069488) (xy 19.817194 -54.09042) (xy 19.846907 -54.136392) (xy 19.869744 -54.186139)
			(xy 19.885234 -54.23864) (xy 19.893061 -54.292817) (xy 19.893534 -54.320186) (xy 19.893048 -54.347437)
			(xy 19.885292 -54.401385) (xy 19.869937 -54.45368) (xy 19.847295 -54.503257) (xy 19.817829 -54.549107)
			(xy 19.782138 -54.590298) (xy 19.740947 -54.625989) (xy 19.695097 -54.655455) (xy 19.64552 -54.678097)
			(xy 19.593225 -54.693452) (xy 19.539277 -54.701208) (xy 19.484775 -54.701208) (xy 19.430827 -54.693452)
			(xy 19.378532 -54.678097) (xy 19.328955 -54.655455) (xy 19.283105 -54.625989) (xy 19.241914 -54.590298)
			(xy 19.206223 -54.549107) (xy 19.176757 -54.503257) (xy 19.154115 -54.45368) (xy 19.13876 -54.401385)
			(xy 19.131004 -54.347437) (xy 19.130518 -54.320186) (xy 16.901957 -54.320186) (xy 16.892902 -54.3399)
			(xy 16.863174 -54.385866) (xy 16.845534 -54.4068) (xy 16.839438 -54.413912) (xy 16.83639 -54.422294)
			(xy 16.834861 -54.42658) (xy 16.833196 -54.435525) (xy 16.833088 -54.440074) (xy 16.833088 -54.50713)
			(xy 16.833208 -54.511678) (xy 16.834862 -54.520625) (xy 16.83639 -54.52491) (xy 16.839438 -54.533292)
			(xy 16.845534 -54.540404) (xy 16.863174 -54.561336) (xy 16.892897 -54.607303) (xy 16.915738 -54.65705)
			(xy 16.931226 -54.709553) (xy 16.939043 -54.763732) (xy 16.93916 -54.770528) (xy 20.07108 -54.770528)
			(xy 20.071543 -54.743157) (xy 20.079359 -54.688977) (xy 20.094847 -54.636474) (xy 20.11769 -54.586727)
			(xy 20.147417 -54.540761) (xy 20.16506 -54.51983) (xy 20.165314 -54.519576) (xy 20.170918 -54.512502)
			(xy 20.177154 -54.495575) (xy 20.177506 -54.486556) (xy 20.177506 -54.4195) (xy 20.177148 -54.410483)
			(xy 20.170901 -54.393566) (xy 20.165314 -54.38648) (xy 20.16506 -54.38648) (xy 20.16506 -54.386226)
			(xy 20.147413 -54.3653) (xy 20.117704 -54.319325) (xy 20.09487 -54.269576) (xy 20.07938 -54.217074)
			(xy 20.071553 -54.162898) (xy 20.07108 -54.135528) (xy 20.071566 -54.108277) (xy 20.079322 -54.054329)
			(xy 20.094677 -54.002034) (xy 20.117319 -53.952457) (xy 20.146785 -53.906607) (xy 20.182476 -53.865416)
			(xy 20.223667 -53.829725) (xy 20.269517 -53.800259) (xy 20.319094 -53.777617) (xy 20.371389 -53.762262)
			(xy 20.425337 -53.754506) (xy 20.479839 -53.754506) (xy 20.533787 -53.762262) (xy 20.586082 -53.777617)
			(xy 20.635659 -53.800259) (xy 20.681509 -53.829725) (xy 20.7227 -53.865416) (xy 20.758391 -53.906607)
			(xy 20.787857 -53.952457) (xy 20.806619 -53.993538) (xy 24.69691 -53.993538) (xy 24.69691 -53.933602)
			(xy 24.704733 -53.87418) (xy 24.720246 -53.816287) (xy 24.743182 -53.760914) (xy 24.773149 -53.709008)
			(xy 24.809636 -53.661458) (xy 24.852016 -53.619078) (xy 24.899566 -53.582591) (xy 24.951472 -53.552624)
			(xy 25.006845 -53.529688) (xy 25.064738 -53.514175) (xy 25.12416 -53.506352) (xy 25.184096 -53.506352)
			(xy 25.243518 -53.514175) (xy 25.301411 -53.529688) (xy 25.356784 -53.552624) (xy 25.40869 -53.582591)
			(xy 25.45624 -53.619078) (xy 25.49862 -53.661458) (xy 25.535107 -53.709008) (xy 25.565074 -53.760914)
			(xy 25.58801 -53.816287) (xy 25.603523 -53.87418) (xy 25.611346 -53.933602) (xy 25.611836 -53.96357)
			(xy 25.611346 -53.993538) (xy 25.603523 -54.05296) (xy 25.599639 -54.067456) (xy 26.94127 -54.067456)
			(xy 26.945341 -54.011834) (xy 26.957467 -53.957397) (xy 26.97739 -53.905306) (xy 27.004686 -53.856671)
			(xy 27.038772 -53.812528) (xy 27.078921 -53.773819) (xy 27.124279 -53.741368) (xy 27.173879 -53.715867)
			(xy 27.226663 -53.69786) (xy 27.281506 -53.68773) (xy 27.33724 -53.685693) (xy 27.392677 -53.691793)
			(xy 27.446634 -53.705899) (xy 27.497963 -53.727711) (xy 27.545569 -53.756765) (xy 27.588437 -53.79244)
			(xy 27.625654 -53.833977) (xy 27.656427 -53.88049) (xy 27.680099 -53.930987) (xy 27.696167 -53.984394)
			(xy 27.704287 -54.03957) (xy 27.704796 -54.067456) (xy 27.704287 -54.095342) (xy 27.696167 -54.150518)
			(xy 27.680099 -54.203925) (xy 27.663701 -54.238906) (xy 34.38601 -54.238906) (xy 34.390081 -54.183284)
			(xy 34.402207 -54.128847) (xy 34.42213 -54.076756) (xy 34.449426 -54.028121) (xy 34.483512 -53.983978)
			(xy 34.523661 -53.945269) (xy 34.569019 -53.912818) (xy 34.618619 -53.887317) (xy 34.671403 -53.86931)
			(xy 34.726246 -53.85918) (xy 34.78198 -53.857143) (xy 34.837417 -53.863243) (xy 34.891374 -53.877349)
			(xy 34.942703 -53.899161) (xy 34.990309 -53.928215) (xy 35.033177 -53.96389) (xy 35.070394 -54.005427)
			(xy 35.101167 -54.05194) (xy 35.124839 -54.102437) (xy 35.140907 -54.155844) (xy 35.149027 -54.21102)
			(xy 35.149536 -54.238906) (xy 35.149027 -54.266792) (xy 35.140907 -54.321968) (xy 35.124839 -54.375375)
			(xy 35.101167 -54.425872) (xy 35.070394 -54.472385) (xy 35.033177 -54.513922) (xy 34.990309 -54.549597)
			(xy 34.942703 -54.578651) (xy 34.891374 -54.600463) (xy 34.837417 -54.614569) (xy 34.78198 -54.620669)
			(xy 34.726246 -54.618632) (xy 34.671403 -54.608502) (xy 34.618619 -54.590495) (xy 34.569019 -54.564994)
			(xy 34.523661 -54.532543) (xy 34.483512 -54.493834) (xy 34.449426 -54.449691) (xy 34.42213 -54.401056)
			(xy 34.402207 -54.348965) (xy 34.390081 -54.294528) (xy 34.38601 -54.238906) (xy 27.663701 -54.238906)
			(xy 27.656427 -54.254422) (xy 27.625654 -54.300935) (xy 27.588437 -54.342472) (xy 27.545569 -54.378147)
			(xy 27.497963 -54.407201) (xy 27.446634 -54.429013) (xy 27.392677 -54.443119) (xy 27.33724 -54.449219)
			(xy 27.281506 -54.447182) (xy 27.226663 -54.437052) (xy 27.173879 -54.419045) (xy 27.124279 -54.393544)
			(xy 27.078921 -54.361093) (xy 27.038772 -54.322384) (xy 27.004686 -54.278241) (xy 26.97739 -54.229606)
			(xy 26.957467 -54.177515) (xy 26.945341 -54.123078) (xy 26.94127 -54.067456) (xy 25.599639 -54.067456)
			(xy 25.58801 -54.110853) (xy 25.565074 -54.166226) (xy 25.535107 -54.218132) (xy 25.49862 -54.265682)
			(xy 25.45624 -54.308062) (xy 25.40869 -54.344549) (xy 25.356784 -54.374516) (xy 25.301411 -54.397452)
			(xy 25.243518 -54.412965) (xy 25.184096 -54.420788) (xy 25.12416 -54.420788) (xy 25.064738 -54.412965)
			(xy 25.006845 -54.397452) (xy 24.951472 -54.374516) (xy 24.899566 -54.344549) (xy 24.852016 -54.308062)
			(xy 24.809636 -54.265682) (xy 24.773149 -54.218132) (xy 24.743182 -54.166226) (xy 24.720246 -54.110853)
			(xy 24.704733 -54.05296) (xy 24.69691 -53.993538) (xy 20.806619 -53.993538) (xy 20.810499 -54.002034)
			(xy 20.825854 -54.054329) (xy 20.83361 -54.108277) (xy 20.834096 -54.135528) (xy 20.833647 -54.162899)
			(xy 20.825825 -54.217079) (xy 20.810332 -54.269582) (xy 20.787487 -54.319329) (xy 20.757759 -54.365295)
			(xy 20.740116 -54.386226) (xy 20.739862 -54.38648) (xy 20.734273 -54.393565) (xy 20.728029 -54.410483)
			(xy 20.72767 -54.4195) (xy 20.72767 -54.486556) (xy 20.728055 -54.49557) (xy 20.734284 -54.512487)
			(xy 20.739862 -54.519576) (xy 20.740116 -54.519576) (xy 20.740116 -54.51983) (xy 20.757738 -54.540776)
			(xy 20.787452 -54.586745) (xy 20.810291 -54.636489) (xy 20.825786 -54.688987) (xy 20.833619 -54.74316)
			(xy 20.834096 -54.770528) (xy 20.83361 -54.797779) (xy 20.825854 -54.851727) (xy 20.810499 -54.904022)
			(xy 20.787857 -54.953599) (xy 20.758391 -54.999449) (xy 20.7227 -55.04064) (xy 20.681509 -55.076331)
			(xy 20.670422 -55.083456) (xy 26.94127 -55.083456) (xy 26.945341 -55.027834) (xy 26.957467 -54.973397)
			(xy 26.97739 -54.921306) (xy 27.004686 -54.872671) (xy 27.038772 -54.828528) (xy 27.078921 -54.789819)
			(xy 27.124279 -54.757368) (xy 27.173879 -54.731867) (xy 27.226663 -54.71386) (xy 27.281506 -54.70373)
			(xy 27.33724 -54.701693) (xy 27.392677 -54.707793) (xy 27.446634 -54.721899) (xy 27.497963 -54.743711)
			(xy 27.545569 -54.772765) (xy 27.588437 -54.80844) (xy 27.625654 -54.849977) (xy 27.656427 -54.89649)
			(xy 27.680099 -54.946987) (xy 27.692756 -54.989055) (xy 29.901045 -54.989055) (xy 29.901045 -54.934545)
			(xy 29.908803 -54.880589) (xy 29.924161 -54.828287) (xy 29.946807 -54.778704) (xy 29.976279 -54.732848)
			(xy 30.011977 -54.691653) (xy 30.053175 -54.655958) (xy 30.099034 -54.62649) (xy 30.148619 -54.603849)
			(xy 30.200923 -54.588496) (xy 30.254879 -54.580743) (xy 30.282134 -54.580282) (xy 30.310226 -54.58075)
			(xy 30.365805 -54.588982) (xy 30.419575 -54.605278) (xy 30.470372 -54.629285) (xy 30.517098 -54.660484)
			(xy 30.558743 -54.698199) (xy 30.594404 -54.741616) (xy 30.609286 -54.765448) (xy 30.61462 -54.774338)
			(xy 30.631638 -54.78653) (xy 30.724856 -54.80685) (xy 30.74543 -54.802532) (xy 30.754066 -54.79669)
			(xy 30.778137 -54.780701) (xy 30.830066 -54.755356) (xy 30.885222 -54.738127) (xy 30.942344 -54.729409)
			(xy 30.971236 -54.728872) (xy 30.998487 -54.729344) (xy 31.052434 -54.737105) (xy 31.104728 -54.752464)
			(xy 31.154304 -54.775108) (xy 31.200153 -54.804576) (xy 31.241343 -54.840269) (xy 31.277034 -54.881459)
			(xy 31.3065 -54.92731) (xy 31.329142 -54.976887) (xy 31.344498 -55.029181) (xy 31.352257 -55.083129)
			(xy 31.352744 -55.11038) (xy 31.35228 -55.13775) (xy 31.344464 -55.19193) (xy 31.328975 -55.244434)
			(xy 31.306132 -55.294181) (xy 31.276406 -55.340147) (xy 31.258764 -55.361078) (xy 31.25851 -55.361332)
			(xy 31.252947 -55.368435) (xy 31.246686 -55.385339) (xy 31.246318 -55.394352) (xy 31.246318 -55.461408)
			(xy 31.246667 -55.470426) (xy 31.25292 -55.487343) (xy 31.25851 -55.494428) (xy 31.258764 -55.494428)
			(xy 31.258764 -55.494682) (xy 31.276385 -55.51563) (xy 31.306112 -55.561595) (xy 31.328959 -55.611339)
			(xy 31.344457 -55.663839) (xy 31.352288 -55.718015) (xy 31.35229 -55.772755) (xy 31.344463 -55.826932)
			(xy 31.328969 -55.879433) (xy 31.306126 -55.929178) (xy 31.276404 -55.975145) (xy 31.258764 -55.996078)
			(xy 31.25851 -55.996332) (xy 31.252947 -56.003435) (xy 31.246686 -56.020339) (xy 31.246318 -56.029352)
			(xy 31.246318 -56.096408) (xy 31.246667 -56.105426) (xy 31.25292 -56.122343) (xy 31.25851 -56.129428)
			(xy 31.258764 -56.129428) (xy 31.258764 -56.129682) (xy 31.276403 -56.150615) (xy 31.306116 -56.196587)
			(xy 31.328952 -56.246334) (xy 31.344443 -56.298835) (xy 31.352271 -56.353011) (xy 31.352744 -56.38038)
			(xy 31.352258 -56.407631) (xy 31.344502 -56.461579) (xy 31.329147 -56.513874) (xy 31.306505 -56.563451)
			(xy 31.277039 -56.609301) (xy 31.241348 -56.650492) (xy 31.200157 -56.686183) (xy 31.154307 -56.715649)
			(xy 31.10473 -56.738291) (xy 31.052435 -56.753646) (xy 30.998487 -56.761402) (xy 30.943985 -56.761402)
			(xy 30.890037 -56.753646) (xy 30.837742 -56.738291) (xy 30.788165 -56.715649) (xy 30.742315 -56.686183)
			(xy 30.701124 -56.650492) (xy 30.665433 -56.609301) (xy 30.635967 -56.563451) (xy 30.613325 -56.513874)
			(xy 30.59797 -56.461579) (xy 30.590214 -56.407631) (xy 30.589728 -56.38038) (xy 30.590176 -56.353009)
			(xy 30.597997 -56.298829) (xy 30.61349 -56.246325) (xy 30.636336 -56.196579) (xy 30.666065 -56.150613)
			(xy 30.683708 -56.129682) (xy 30.683962 -56.129428) (xy 30.68955 -56.122343) (xy 30.695794 -56.105425)
			(xy 30.696154 -56.096408) (xy 30.696154 -56.029352) (xy 30.695782 -56.020336) (xy 30.689546 -56.003419)
			(xy 30.683962 -55.996332) (xy 30.683708 -55.996332) (xy 30.683708 -55.996078) (xy 30.666049 -55.975161)
			(xy 30.636326 -55.92919) (xy 30.613483 -55.879441) (xy 30.597989 -55.826937) (xy 30.590163 -55.772756)
			(xy 30.590165 -55.718014) (xy 30.597995 -55.663834) (xy 30.613494 -55.611331) (xy 30.63634 -55.561584)
			(xy 30.666067 -55.515615) (xy 30.683708 -55.494682) (xy 30.683962 -55.494428) (xy 30.68955 -55.487343)
			(xy 30.695794 -55.470425) (xy 30.696154 -55.461408) (xy 30.696154 -55.394352) (xy 30.695782 -55.385336)
			(xy 30.689546 -55.368419) (xy 30.683962 -55.361332) (xy 30.683708 -55.360824) (xy 30.672765 -55.348089)
			(xy 30.652923 -55.320998) (xy 30.644084 -55.306722) (xy 30.63875 -55.297832) (xy 30.621732 -55.28564)
			(xy 30.528514 -55.26532) (xy 30.50794 -55.269638) (xy 30.499304 -55.27548) (xy 30.475239 -55.291478)
			(xy 30.423308 -55.316822) (xy 30.368151 -55.334048) (xy 30.311026 -55.342763) (xy 30.282134 -55.343298)
			(xy 30.254879 -55.342857) (xy 30.200923 -55.335104) (xy 30.148619 -55.319751) (xy 30.099034 -55.29711)
			(xy 30.053175 -55.267642) (xy 30.011977 -55.231947) (xy 29.976279 -55.190752) (xy 29.946807 -55.144896)
			(xy 29.924161 -55.095313) (xy 29.908803 -55.043011) (xy 29.901045 -54.989055) (xy 27.692756 -54.989055)
			(xy 27.696167 -55.000394) (xy 27.704287 -55.05557) (xy 27.704796 -55.083456) (xy 27.704287 -55.111342)
			(xy 27.696167 -55.166518) (xy 27.680099 -55.219925) (xy 27.656427 -55.270422) (xy 27.625654 -55.316935)
			(xy 27.588437 -55.358472) (xy 27.545569 -55.394147) (xy 27.501807 -55.420855) (xy 28.224645 -55.420855)
			(xy 28.224645 -55.366345) (xy 28.232403 -55.312389) (xy 28.247761 -55.260087) (xy 28.270407 -55.210504)
			(xy 28.299879 -55.164648) (xy 28.335577 -55.123453) (xy 28.376775 -55.087758) (xy 28.422634 -55.05829)
			(xy 28.472219 -55.035649) (xy 28.524523 -55.020296) (xy 28.578479 -55.012543) (xy 28.605734 -55.012082)
			(xy 28.632048 -55.012533) (xy 28.684177 -55.019772) (xy 28.73482 -55.034094) (xy 28.783019 -55.05523)
			(xy 28.827862 -55.082779) (xy 28.868502 -55.11622) (xy 28.886658 -55.135272) (xy 28.894197 -55.142653)
			(xy 28.913464 -55.15119) (xy 28.923996 -55.151782) (xy 28.998672 -55.151782) (xy 29.009222 -55.151257)
			(xy 29.028518 -55.142719) (xy 29.03601 -55.135272) (xy 29.054162 -55.116213) (xy 29.094793 -55.082757)
			(xy 29.139634 -55.0552) (xy 29.187836 -55.034062) (xy 29.238484 -55.019745) (xy 29.290618 -55.012521)
			(xy 29.316934 -55.012082) (xy 29.344183 -55.012591) (xy 29.398125 -55.020351) (xy 29.450415 -55.035708)
			(xy 29.499986 -55.058351) (xy 29.545831 -55.087817) (xy 29.587016 -55.123508) (xy 29.622703 -55.164696)
			(xy 29.652165 -55.210544) (xy 29.674803 -55.260117) (xy 29.690156 -55.312408) (xy 29.697912 -55.366351)
			(xy 29.697912 -55.420849) (xy 29.690156 -55.474792) (xy 29.674803 -55.527083) (xy 29.652165 -55.576656)
			(xy 29.622703 -55.622504) (xy 29.587016 -55.663692) (xy 29.545831 -55.699383) (xy 29.499986 -55.728849)
			(xy 29.450415 -55.751492) (xy 29.398125 -55.766849) (xy 29.344183 -55.774609) (xy 29.316934 -55.775098)
			(xy 29.290619 -55.774675) (xy 29.238488 -55.767431) (xy 29.187844 -55.753104) (xy 29.139646 -55.731963)
			(xy 29.094803 -55.704409) (xy 29.054165 -55.670963) (xy 29.03601 -55.651908) (xy 29.028485 -55.64451)
			(xy 29.009208 -55.635983) (xy 28.998672 -55.635398) (xy 28.923996 -55.635398) (xy 28.913445 -55.635912)
			(xy 28.894149 -55.644458) (xy 28.886658 -55.651908) (xy 28.868517 -55.670978) (xy 28.827884 -55.704434)
			(xy 28.783041 -55.731991) (xy 28.734837 -55.753127) (xy 28.684187 -55.767441) (xy 28.632051 -55.774662)
			(xy 28.605734 -55.775098) (xy 28.578479 -55.774657) (xy 28.524523 -55.766904) (xy 28.472219 -55.751551)
			(xy 28.422634 -55.72891) (xy 28.376775 -55.699442) (xy 28.335577 -55.663747) (xy 28.299879 -55.622552)
			(xy 28.270407 -55.576696) (xy 28.247761 -55.527113) (xy 28.232403 -55.474811) (xy 28.224645 -55.420855)
			(xy 27.501807 -55.420855) (xy 27.497963 -55.423201) (xy 27.446634 -55.445013) (xy 27.392677 -55.459119)
			(xy 27.33724 -55.465219) (xy 27.281506 -55.463182) (xy 27.226663 -55.453052) (xy 27.173879 -55.435045)
			(xy 27.124279 -55.409544) (xy 27.078921 -55.377093) (xy 27.038772 -55.338384) (xy 27.004686 -55.294241)
			(xy 26.97739 -55.245606) (xy 26.957467 -55.193515) (xy 26.945341 -55.139078) (xy 26.94127 -55.083456)
			(xy 20.670422 -55.083456) (xy 20.635659 -55.105797) (xy 20.586082 -55.128439) (xy 20.533787 -55.143794)
			(xy 20.479839 -55.15155) (xy 20.425337 -55.15155) (xy 20.371389 -55.143794) (xy 20.319094 -55.128439)
			(xy 20.269517 -55.105797) (xy 20.223667 -55.076331) (xy 20.182476 -55.04064) (xy 20.146785 -54.999449)
			(xy 20.117319 -54.953599) (xy 20.094677 -54.904022) (xy 20.079322 -54.851727) (xy 20.071566 -54.797779)
			(xy 20.07108 -54.770528) (xy 16.93916 -54.770528) (xy 16.939514 -54.791102) (xy 16.939028 -54.818353)
			(xy 16.931272 -54.872301) (xy 16.915917 -54.924596) (xy 16.893275 -54.974173) (xy 16.863809 -55.020023)
			(xy 16.828118 -55.061214) (xy 16.786927 -55.096905) (xy 16.741077 -55.126371) (xy 16.6915 -55.149013)
			(xy 16.639205 -55.164368) (xy 16.585257 -55.172124) (xy 16.530755 -55.172124) (xy 16.476807 -55.164368)
			(xy 16.424512 -55.149013) (xy 16.374935 -55.126371) (xy 16.329085 -55.096905) (xy 16.287894 -55.061214)
			(xy 16.252203 -55.020023) (xy 16.222737 -54.974173) (xy 16.200095 -54.924596) (xy 16.18474 -54.872301)
			(xy 16.176984 -54.818353) (xy 16.176498 -54.791102) (xy 16.17697 -54.763732) (xy 16.184793 -54.709554)
			(xy 16.20028 -54.65705) (xy 16.223112 -54.607298) (xy 16.25282 -54.561321) (xy 16.270478 -54.540404)
			(xy 16.276574 -54.533292) (xy 16.279622 -54.52491) (xy 16.281151 -54.520624) (xy 16.282816 -54.511679)
			(xy 16.282924 -54.50713) (xy 16.282924 -54.440074) (xy 16.282804 -54.435526) (xy 16.281148 -54.42658)
			(xy 16.279622 -54.422294) (xy 16.276574 -54.413912) (xy 16.270478 -54.4068) (xy 16.252839 -54.385866)
			(xy 16.223118 -54.339897) (xy 16.200275 -54.290151) (xy 16.184781 -54.237649) (xy 16.176953 -54.183472)
			(xy 16.176953 -54.128731) (xy 16.18478 -54.074554) (xy 16.200274 -54.022052) (xy 16.223116 -53.972305)
			(xy 16.252837 -53.926336) (xy 16.270478 -53.905404) (xy 16.276574 -53.898292) (xy 16.279622 -53.88991)
			(xy 16.281151 -53.885624) (xy 16.282816 -53.876679) (xy 16.282924 -53.87213) (xy 16.282924 -53.805074)
			(xy 16.282804 -53.800526) (xy 16.281148 -53.79158) (xy 16.279622 -53.787294) (xy 16.276574 -53.778912)
			(xy 16.270478 -53.7718) (xy 16.252837 -53.750868) (xy 16.223113 -53.704901) (xy 16.200271 -53.655154)
			(xy 16.184781 -53.602651) (xy 16.176963 -53.548472) (xy 16.176498 -53.521102) (xy 16.176576 -53.508364)
			(xy 16.17823 -53.482943) (xy 16.1798 -53.470302) (xy 16.184438 -53.440168) (xy 16.202049 -53.3818)
			(xy 16.228736 -53.326984) (xy 16.263817 -53.277122) (xy 16.284702 -53.25491) (xy 16.28521 -53.254402)
			(xy 16.290301 -53.248606) (xy 16.297133 -53.234784) (xy 16.298672 -53.227224) (xy 16.29918 -53.21935)
			(xy 16.29918 -53.187854) (xy 16.298418 -53.17871) (xy 16.297402 -53.1749) (xy 16.295509 -53.168421)
			(xy 16.28882 -53.156702) (xy 16.284194 -53.151786) (xy 16.283178 -53.15077) (xy 16.271494 -53.137816)
			(xy 16.264206 -53.130861) (xy 16.245739 -53.12285) (xy 16.23568 -53.122322) (xy 14.322806 -53.122322)
			(xy 14.313996 -53.122739) (xy 14.297439 -53.12878) (xy 14.283891 -53.140052) (xy 14.279118 -53.147468)
			(xy 14.234668 -53.22316) (xy 14.231502 -53.229096) (xy 14.228031 -53.24209) (xy 14.22781 -53.248814)
			(xy 14.22781 -53.262022) (xy 14.229588 -53.265324) (xy 14.234414 -53.273706) (xy 14.246109 -53.295242)
			(xy 14.264527 -53.340657) (xy 14.276987 -53.388054) (xy 14.283284 -53.436655) (xy 14.28369 -53.461158)
			(xy 14.28369 -53.461412) (xy 14.283217 -53.488782) (xy 14.275392 -53.542959) (xy 14.259903 -53.595461)
			(xy 14.237069 -53.645211) (xy 14.207359 -53.691186) (xy 14.18971 -53.71211) (xy 14.183614 -53.719222)
			(xy 14.180566 -53.727604) (xy 14.179039 -53.73189) (xy 14.177376 -53.740835) (xy 14.177264 -53.745384)
			(xy 14.177264 -53.81244) (xy 14.177386 -53.816988) (xy 14.179043 -53.825933) (xy 14.180566 -53.83022)
			(xy 14.183614 -53.838602) (xy 14.18971 -53.845714) (xy 14.207348 -53.866647) (xy 14.237069 -53.912616)
			(xy 14.25991 -53.962362) (xy 14.275403 -54.014863) (xy 14.283229 -54.069039) (xy 14.283228 -54.123779)
			(xy 14.275399 -54.177955) (xy 14.259904 -54.230455) (xy 14.23706 -54.2802) (xy 14.207337 -54.326167)
			(xy 14.18971 -54.34711) (xy 14.183614 -54.354222) (xy 14.180566 -54.362604) (xy 14.179039 -54.36689)
			(xy 14.177376 -54.375835) (xy 14.177264 -54.380384) (xy 14.177264 -54.44744) (xy 14.177386 -54.451988)
			(xy 14.179043 -54.460933) (xy 14.180566 -54.46522) (xy 14.183614 -54.473602) (xy 14.18971 -54.480714)
			(xy 14.207351 -54.501646) (xy 14.237074 -54.547613) (xy 14.259915 -54.59736) (xy 14.275403 -54.649863)
			(xy 14.283219 -54.704042) (xy 14.28369 -54.731412) (xy 14.283204 -54.758663) (xy 14.275448 -54.812611)
			(xy 14.260093 -54.864906) (xy 14.237451 -54.914483) (xy 14.207985 -54.960333) (xy 14.172294 -55.001524)
			(xy 14.131103 -55.037215) (xy 14.085253 -55.066681) (xy 14.035676 -55.089323) (xy 13.983381 -55.104678)
			(xy 13.929433 -55.112434) (xy 13.874931 -55.112434) (xy 13.820983 -55.104678) (xy 13.768688 -55.089323)
			(xy 13.719111 -55.066681) (xy 13.673261 -55.037215) (xy 13.63207 -55.001524) (xy 13.596379 -54.960333)
			(xy 13.566913 -54.914483) (xy 13.544271 -54.864906) (xy 13.528916 -54.812611) (xy 13.52116 -54.758663)
			(xy 13.520674 -54.731412) (xy 13.521152 -54.704045) (xy 13.528988 -54.649874) (xy 13.544488 -54.597379)
			(xy 13.567331 -54.547639) (xy 13.59705 -54.501675) (xy 13.614654 -54.480714) (xy 13.62075 -54.473602)
			(xy 13.623798 -54.46522) (xy 13.62532 -54.460932) (xy 13.626984 -54.451988) (xy 13.6271 -54.44744)
			(xy 13.6271 -54.380384) (xy 13.626972 -54.375837) (xy 13.625304 -54.366896) (xy 13.623798 -54.362604)
			(xy 13.62075 -54.354222) (xy 13.614654 -54.34711) (xy 13.597011 -54.326178) (xy 13.567283 -54.28021)
			(xy 13.544434 -54.230464) (xy 13.528935 -54.177961) (xy 13.521104 -54.123781) (xy 13.521103 -54.069038)
			(xy 13.528931 -54.014857) (xy 13.544428 -53.962353) (xy 13.567274 -53.912606) (xy 13.597 -53.866637)
			(xy 13.614654 -53.845714) (xy 13.62075 -53.838602) (xy 13.623798 -53.83022) (xy 13.62532 -53.825932)
			(xy 13.626984 -53.816988) (xy 13.6271 -53.81244) (xy 13.6271 -53.745384) (xy 13.626972 -53.740837)
			(xy 13.625304 -53.731896) (xy 13.623798 -53.727604) (xy 13.62075 -53.719222) (xy 13.614654 -53.71211)
			(xy 13.597009 -53.69118) (xy 13.567278 -53.645215) (xy 13.54443 -53.595468) (xy 13.528936 -53.542964)
			(xy 13.521115 -53.488783) (xy 13.520674 -53.461412) (xy 13.520674 -53.461158) (xy 13.52105 -53.436652)
			(xy 13.527331 -53.388045) (xy 13.539795 -53.340645) (xy 13.558238 -53.295236) (xy 13.56995 -53.273706)
			(xy 13.574776 -53.265324) (xy 13.576554 -53.262022) (xy 13.576554 -53.248814) (xy 13.576381 -53.242083)
			(xy 13.5729 -53.229082) (xy 13.569696 -53.22316) (xy 13.525246 -53.147468) (xy 13.520486 -53.140033)
			(xy 13.506955 -53.128716) (xy 13.490378 -53.122687) (xy 13.481558 -53.122322) (xy 7.565644 -53.122322)
			(xy 7.557081 -53.122703) (xy 7.540935 -53.128426) (xy 7.527555 -53.139122) (xy 7.522718 -53.146198)
			(xy 7.487412 -53.20792) (xy 7.47776 -53.224684) (xy 7.47467 -53.230502) (xy 7.471339 -53.243244)
			(xy 7.471156 -53.24983) (xy 7.471156 -53.263546) (xy 7.478268 -53.275484) (xy 7.490822 -53.297591)
			(xy 7.510601 -53.344425) (xy 7.523974 -53.393474) (xy 7.5307 -53.443866) (xy 7.5311 -53.469286) (xy 7.5311 -53.475382)
			(xy 7.530203 -53.502347) (xy 7.52175 -53.555632) (xy 7.505874 -53.607195) (xy 7.48289 -53.656006)
			(xy 7.453258 -53.701091) (xy 7.417569 -53.741552) (xy 7.376535 -53.77658) (xy 7.330974 -53.805476)
			(xy 7.281797 -53.827665) (xy 7.229983 -53.842702) (xy 7.176568 -53.850289) (xy 7.149592 -53.850794)
			(xy 7.122222 -53.850322) (xy 7.068045 -53.842497) (xy 7.015542 -53.827009) (xy 6.965792 -53.804175)
			(xy 6.919816 -53.774466) (xy 6.898894 -53.756814) (xy 6.891782 -53.750718) (xy 6.8834 -53.74767)
			(xy 6.879114 -53.746142) (xy 6.870169 -53.744479) (xy 6.86562 -53.744368) (xy 6.798564 -53.744368)
			(xy 6.794016 -53.744489) (xy 6.785071 -53.746146) (xy 6.780784 -53.74767) (xy 6.772402 -53.750718)
			(xy 6.76529 -53.756814) (xy 6.744358 -53.774455) (xy 6.698391 -53.804179) (xy 6.648644 -53.82702)
			(xy 6.596141 -53.842508) (xy 6.541962 -53.850325) (xy 6.514592 -53.850794) (xy 6.487616 -53.850327)
			(xy 6.434201 -53.842727) (xy 6.38239 -53.827678) (xy 6.333214 -53.805482) (xy 6.287656 -53.77658)
			(xy 6.246622 -53.741549) (xy 6.210932 -53.701088) (xy 6.181297 -53.656003) (xy 6.158308 -53.607194)
			(xy 6.142423 -53.555632) (xy 6.133959 -53.502348) (xy 6.133084 -53.475382) (xy 6.133084 -53.469286)
			(xy 6.133509 -53.443869) (xy 6.140263 -53.393486) (xy 6.153635 -53.344442) (xy 6.17339 -53.297604)
			(xy 6.185916 -53.275484) (xy 6.189472 -53.269642) (xy 6.193028 -53.256434) (xy 6.193028 -53.24983)
			(xy 6.192821 -53.243248) (xy 6.189483 -53.230515) (xy 6.186424 -53.224684) (xy 6.176772 -53.20792)
			(xy 6.141466 -53.146198) (xy 6.136655 -53.139093) (xy 6.123286 -53.128354) (xy 6.107114 -53.122656)
			(xy 6.09854 -53.122322) (xy 2.926588 -53.122322) (xy 2.91657 -53.122744) (xy 2.898061 -53.130417)
			(xy 2.883898 -53.14459) (xy 2.876237 -53.163104) (xy 2.875788 -53.173122) (xy 2.875788 -54.238906)
			(xy 8.386062 -54.238906) (xy 8.390133 -54.183284) (xy 8.402259 -54.128847) (xy 8.422182 -54.076756)
			(xy 8.449478 -54.028121) (xy 8.483564 -53.983978) (xy 8.523713 -53.945269) (xy 8.569071 -53.912818)
			(xy 8.618671 -53.887317) (xy 8.671455 -53.86931) (xy 8.726298 -53.85918) (xy 8.782032 -53.857143)
			(xy 8.837469 -53.863243) (xy 8.891426 -53.877349) (xy 8.942755 -53.899161) (xy 8.990361 -53.928215)
			(xy 9.033229 -53.96389) (xy 9.070446 -54.005427) (xy 9.101219 -54.05194) (xy 9.124891 -54.102437)
			(xy 9.140959 -54.155844) (xy 9.149079 -54.21102) (xy 9.149588 -54.238906) (xy 9.149079 -54.266792)
			(xy 9.140959 -54.321968) (xy 9.124891 -54.375375) (xy 9.101219 -54.425872) (xy 9.070446 -54.472385)
			(xy 9.033229 -54.513922) (xy 8.990361 -54.549597) (xy 8.942755 -54.578651) (xy 8.891426 -54.600463)
			(xy 8.837469 -54.614569) (xy 8.782032 -54.620669) (xy 8.726298 -54.618632) (xy 8.671455 -54.608502)
			(xy 8.618671 -54.590495) (xy 8.569071 -54.564994) (xy 8.523713 -54.532543) (xy 8.483564 -54.493834)
			(xy 8.449478 -54.449691) (xy 8.422182 -54.401056) (xy 8.402259 -54.348965) (xy 8.390133 -54.294528)
			(xy 8.386062 -54.238906) (xy 2.875788 -54.238906) (xy 2.875788 -54.989041) (xy 3.901168 -54.989041)
			(xy 3.901168 -54.934539) (xy 3.908924 -54.880592) (xy 3.924279 -54.828297) (xy 3.94692 -54.77872)
			(xy 3.976386 -54.73287) (xy 4.012077 -54.69168) (xy 4.053267 -54.655988) (xy 4.099117 -54.626522)
			(xy 4.148693 -54.603881) (xy 4.200988 -54.588525) (xy 4.254935 -54.580768) (xy 4.282186 -54.580282)
			(xy 4.310277 -54.580788) (xy 4.365854 -54.589013) (xy 4.419622 -54.605302) (xy 4.47042 -54.629303)
			(xy 4.517147 -54.660496) (xy 4.558792 -54.698207) (xy 4.594455 -54.741618) (xy 4.609338 -54.765448)
			(xy 4.614672 -54.774338) (xy 4.63169 -54.78653) (xy 4.724908 -54.80685) (xy 4.745482 -54.802532)
			(xy 4.754118 -54.79669) (xy 4.778175 -54.780679) (xy 4.830109 -54.755339) (xy 4.885269 -54.738117)
			(xy 4.942395 -54.729405) (xy 4.971288 -54.728872) (xy 4.998541 -54.729337) (xy 5.052492 -54.737094)
			(xy 5.104789 -54.75245) (xy 5.15437 -54.775092) (xy 5.200223 -54.80456) (xy 5.241415 -54.840253)
			(xy 5.277109 -54.881446) (xy 5.306577 -54.927299) (xy 5.32922 -54.976879) (xy 5.344576 -55.029176)
			(xy 5.352333 -55.083127) (xy 5.352796 -55.11038) (xy 5.352319 -55.13775) (xy 5.344504 -55.191929)
			(xy 5.329018 -55.244432) (xy 5.306178 -55.294179) (xy 5.276456 -55.340146) (xy 5.258816 -55.361078)
			(xy 5.258562 -55.361332) (xy 5.252994 -55.368431) (xy 5.246737 -55.385338) (xy 5.24637 -55.394352)
			(xy 5.24637 -55.461408) (xy 5.24673 -55.470424) (xy 5.252976 -55.487341) (xy 5.258562 -55.494428)
			(xy 5.258816 -55.494428) (xy 5.258816 -55.494682) (xy 5.276457 -55.515615) (xy 5.306181 -55.561583)
			(xy 5.329026 -55.611329) (xy 5.344522 -55.663831) (xy 5.352351 -55.718009) (xy 5.352351 -55.772751)
			(xy 5.344522 -55.826929) (xy 5.329026 -55.879431) (xy 5.306181 -55.929177) (xy 5.276457 -55.975145)
			(xy 5.258816 -55.996078) (xy 5.258562 -55.996332) (xy 5.252994 -56.003431) (xy 5.246737 -56.020338)
			(xy 5.24637 -56.029352) (xy 5.24637 -56.096408) (xy 5.24673 -56.105424) (xy 5.252976 -56.122341)
			(xy 5.258562 -56.129428) (xy 5.258816 -56.129428) (xy 5.258816 -56.129682) (xy 5.276463 -56.150608)
			(xy 5.306173 -56.196583) (xy 5.329007 -56.246332) (xy 5.344496 -56.298834) (xy 5.352323 -56.35301)
			(xy 5.352796 -56.38038) (xy 5.35231 -56.407631) (xy 5.344554 -56.461579) (xy 5.329199 -56.513874)
			(xy 5.306557 -56.563451) (xy 5.277091 -56.609301) (xy 5.2414 -56.650492) (xy 5.200209 -56.686183)
			(xy 5.154359 -56.715649) (xy 5.104782 -56.738291) (xy 5.052487 -56.753646) (xy 4.998539 -56.761402)
			(xy 4.944037 -56.761402) (xy 4.890089 -56.753646) (xy 4.837794 -56.738291) (xy 4.788217 -56.715649)
			(xy 4.742367 -56.686183) (xy 4.701176 -56.650492) (xy 4.665485 -56.609301) (xy 4.636019 -56.563451)
			(xy 4.613377 -56.513874) (xy 4.598022 -56.461579) (xy 4.590266 -56.407631) (xy 4.58978 -56.38038)
			(xy 4.590215 -56.353008) (xy 4.598037 -56.298827) (xy 4.613533 -56.246323) (xy 4.636382 -56.196577)
			(xy 4.666114 -56.150612) (xy 4.68376 -56.129682) (xy 4.684014 -56.129428) (xy 4.689597 -56.122339)
			(xy 4.695845 -56.105424) (xy 4.696206 -56.096408) (xy 4.696206 -56.029352) (xy 4.695823 -56.020338)
			(xy 4.689593 -56.003421) (xy 4.684014 -55.996332) (xy 4.68376 -55.996332) (xy 4.68376 -55.996078)
			(xy 4.666119 -55.975145) (xy 4.636394 -55.929178) (xy 4.613549 -55.879431) (xy 4.598052 -55.826929)
			(xy 4.590224 -55.772751) (xy 4.590224 -55.718009) (xy 4.598052 -55.663831) (xy 4.613549 -55.611329)
			(xy 4.636394 -55.561582) (xy 4.666119 -55.515615) (xy 4.68376 -55.494682) (xy 4.684014 -55.494428)
			(xy 4.689597 -55.487339) (xy 4.695845 -55.470424) (xy 4.696206 -55.461408) (xy 4.696206 -55.394352)
			(xy 4.695823 -55.385338) (xy 4.689593 -55.368421) (xy 4.684014 -55.361332) (xy 4.68376 -55.360824)
			(xy 4.672814 -55.348091) (xy 4.652974 -55.320999) (xy 4.644136 -55.306722) (xy 4.638802 -55.297832)
			(xy 4.621784 -55.28564) (xy 4.528566 -55.26532) (xy 4.507992 -55.269638) (xy 4.499356 -55.27548)
			(xy 4.475304 -55.291499) (xy 4.423368 -55.316838) (xy 4.368207 -55.334058) (xy 4.31108 -55.342767)
			(xy 4.282186 -55.343298) (xy 4.254935 -55.342812) (xy 4.200988 -55.335055) (xy 4.148693 -55.319699)
			(xy 4.099117 -55.297058) (xy 4.053267 -55.267592) (xy 4.012077 -55.2319) (xy 3.976386 -55.19071)
			(xy 3.94692 -55.14486) (xy 3.924279 -55.095283) (xy 3.908924 -55.042988) (xy 3.901168 -54.989041)
			(xy 2.875788 -54.989041) (xy 2.875788 -54.999128) (xy 2.875788 -55.001414) (xy 2.876743 -55.011731)
			(xy 2.885806 -55.030338) (xy 2.893314 -55.037482) (xy 2.906367 -55.048163) (xy 2.931031 -55.071173)
			(xy 2.94259 -55.083456) (xy 2.949448 -55.090822) (xy 2.957576 -55.094886) (xy 2.961864 -55.096805)
			(xy 2.970936 -55.099239) (xy 2.97561 -55.099712) (xy 3.0226 -55.103522) (xy 3.044698 -55.1053) (xy 3.049587 -55.105554)
			(xy 3.059307 -55.1044) (xy 3.064002 -55.103014) (xy 3.072384 -55.100474) (xy 3.080258 -55.094378)
			(xy 3.100546 -55.078845) (xy 3.144489 -55.052771) (xy 3.19152 -55.032798) (xy 3.240797 -55.019285)
			(xy 3.291438 -55.012473) (xy 3.316986 -55.012082) (xy 3.344239 -55.012545) (xy 3.39819 -55.020302)
			(xy 3.450489 -55.035657) (xy 3.500069 -55.0583) (xy 3.545923 -55.087767) (xy 3.587116 -55.123461)
			(xy 3.62281 -55.164654) (xy 3.652279 -55.210507) (xy 3.674921 -55.260088) (xy 3.690278 -55.312386)
			(xy 3.698035 -55.366337) (xy 3.698035 -55.420843) (xy 3.690278 -55.474794) (xy 3.674921 -55.527092)
			(xy 3.652279 -55.576673) (xy 3.62281 -55.622526) (xy 3.587116 -55.663719) (xy 3.545923 -55.699413)
			(xy 3.500069 -55.72888) (xy 3.450489 -55.751523) (xy 3.39819 -55.766878) (xy 3.344239 -55.774635)
			(xy 3.316986 -55.775098) (xy 3.316478 -55.775098) (xy 3.290959 -55.77465) (xy 3.240382 -55.767806)
			(xy 3.191167 -55.754282) (xy 3.144194 -55.734321) (xy 3.100301 -55.708277) (xy 3.080004 -55.692802)
			(xy 3.07213 -55.686452) (xy 3.054604 -55.681118) (xy 3.04165 -55.682134) (xy 2.97561 -55.687468)
			(xy 2.970931 -55.687917) (xy 2.961853 -55.690346) (xy 2.957576 -55.692294) (xy 2.949448 -55.696358)
			(xy 2.94259 -55.703724) (xy 2.931021 -55.715997) (xy 2.906356 -55.739004) (xy 2.893314 -55.749698)
			(xy 2.885831 -55.756852) (xy 2.87681 -55.775463) (xy 2.875788 -55.785766) (xy 2.875788 -57.48528)
			(xy 4.606034 -57.48528) (xy 4.610105 -57.429658) (xy 4.622231 -57.375221) (xy 4.642154 -57.32313)
			(xy 4.66945 -57.274495) (xy 4.703536 -57.230352) (xy 4.743685 -57.191643) (xy 4.789043 -57.159192)
			(xy 4.838643 -57.133691) (xy 4.891427 -57.115684) (xy 4.94627 -57.105554) (xy 5.002004 -57.103517)
			(xy 5.057441 -57.109617) (xy 5.111398 -57.123723) (xy 5.162727 -57.145535) (xy 5.210333 -57.174589)
			(xy 5.253201 -57.210264) (xy 5.290418 -57.251801) (xy 5.321191 -57.298314) (xy 5.344863 -57.348811)
			(xy 5.360931 -57.402218) (xy 5.369051 -57.457394) (xy 5.36956 -57.48528) (xy 5.369051 -57.513166)
			(xy 5.360931 -57.568342) (xy 5.344863 -57.621749) (xy 5.321191 -57.672246) (xy 5.290418 -57.718759)
			(xy 5.253201 -57.760296) (xy 5.210333 -57.795971) (xy 5.162727 -57.825025) (xy 5.111398 -57.846837)
			(xy 5.057441 -57.860943) (xy 5.002004 -57.867043) (xy 4.94627 -57.865006) (xy 4.891427 -57.854876)
			(xy 4.838643 -57.836869) (xy 4.789043 -57.811368) (xy 4.743685 -57.778917) (xy 4.703536 -57.740208)
			(xy 4.66945 -57.696065) (xy 4.642154 -57.64743) (xy 4.622231 -57.595339) (xy 4.610105 -57.540902)
			(xy 4.606034 -57.48528) (xy 2.875788 -57.48528) (xy 2.875788 -58.106052) (xy 5.282928 -58.106052)
			(xy 5.282928 -58.046116) (xy 5.290751 -57.986694) (xy 5.306264 -57.928801) (xy 5.3292 -57.873428)
			(xy 5.359167 -57.821522) (xy 5.395654 -57.773972) (xy 5.438034 -57.731592) (xy 5.485584 -57.695105)
			(xy 5.53749 -57.665138) (xy 5.592863 -57.642202) (xy 5.650756 -57.626689) (xy 5.710178 -57.618866)
			(xy 5.770114 -57.618866) (xy 5.829536 -57.626689) (xy 5.887429 -57.642202) (xy 5.942802 -57.665138)
			(xy 5.994708 -57.695105) (xy 6.042258 -57.731592) (xy 6.084638 -57.773972) (xy 6.121125 -57.821522)
			(xy 6.151092 -57.873428) (xy 6.160965 -57.897264) (xy 7.567912 -57.897264) (xy 7.567912 -57.837328)
			(xy 7.575735 -57.777906) (xy 7.591248 -57.720013) (xy 7.614184 -57.66464) (xy 7.644151 -57.612734)
			(xy 7.680638 -57.565184) (xy 7.723018 -57.522804) (xy 7.770568 -57.486317) (xy 7.822474 -57.45635)
			(xy 7.877847 -57.433414) (xy 7.93574 -57.417901) (xy 7.995162 -57.410078) (xy 8.055098 -57.410078)
			(xy 8.11452 -57.417901) (xy 8.172413 -57.433414) (xy 8.227786 -57.45635) (xy 8.279692 -57.486317)
			(xy 8.327242 -57.522804) (xy 8.369622 -57.565184) (xy 8.406109 -57.612734) (xy 8.436076 -57.66464)
			(xy 8.459012 -57.720013) (xy 8.474525 -57.777906) (xy 8.482348 -57.837328) (xy 8.482838 -57.867296)
			(xy 8.482348 -57.897264) (xy 8.474525 -57.956686) (xy 8.459012 -58.014579) (xy 8.436076 -58.069952)
			(xy 8.406109 -58.121858) (xy 8.369622 -58.169408) (xy 8.327242 -58.211788) (xy 8.279692 -58.248275)
			(xy 8.227786 -58.278242) (xy 8.172413 -58.301178) (xy 8.11452 -58.316691) (xy 8.055098 -58.324514)
			(xy 7.995162 -58.324514) (xy 7.93574 -58.316691) (xy 7.877847 -58.301178) (xy 7.822474 -58.278242)
			(xy 7.770568 -58.248275) (xy 7.723018 -58.211788) (xy 7.680638 -58.169408) (xy 7.644151 -58.121858)
			(xy 7.614184 -58.069952) (xy 7.591248 -58.014579) (xy 7.575735 -57.956686) (xy 7.567912 -57.897264)
			(xy 6.160965 -57.897264) (xy 6.174028 -57.928801) (xy 6.189541 -57.986694) (xy 6.197364 -58.046116)
			(xy 6.197854 -58.076084) (xy 6.197364 -58.106052) (xy 6.189541 -58.165474) (xy 6.174028 -58.223367)
			(xy 6.151092 -58.27874) (xy 6.121125 -58.330646) (xy 6.084638 -58.378196) (xy 6.042258 -58.420576)
			(xy 5.994708 -58.457063) (xy 5.942802 -58.48703) (xy 5.887429 -58.509966) (xy 5.829536 -58.525479)
			(xy 5.770114 -58.533302) (xy 5.710178 -58.533302) (xy 5.650756 -58.525479) (xy 5.592863 -58.509966)
			(xy 5.53749 -58.48703) (xy 5.485584 -58.457063) (xy 5.438034 -58.420576) (xy 5.395654 -58.378196)
			(xy 5.359167 -58.330646) (xy 5.3292 -58.27874) (xy 5.306264 -58.223367) (xy 5.290751 -58.165474)
			(xy 5.282928 -58.106052) (xy 2.875788 -58.106052) (xy 2.875788 -58.591192) (xy 6.487142 -58.591192)
			(xy 6.487142 -58.531256) (xy 6.494965 -58.471834) (xy 6.510478 -58.413941) (xy 6.533414 -58.358568)
			(xy 6.563381 -58.306662) (xy 6.599868 -58.259112) (xy 6.642248 -58.216732) (xy 6.689798 -58.180245)
			(xy 6.741704 -58.150278) (xy 6.797077 -58.127342) (xy 6.85497 -58.111829) (xy 6.914392 -58.104006)
			(xy 6.974328 -58.104006) (xy 7.03375 -58.111829) (xy 7.091643 -58.127342) (xy 7.147016 -58.150278)
			(xy 7.198922 -58.180245) (xy 7.246472 -58.216732) (xy 7.288852 -58.259112) (xy 7.325339 -58.306662)
			(xy 7.355306 -58.358568) (xy 7.378242 -58.413941) (xy 7.393755 -58.471834) (xy 7.394789 -58.479686)
			(xy 8.733772 -58.479686) (xy 8.733772 -58.41975) (xy 8.741595 -58.360328) (xy 8.757108 -58.302435)
			(xy 8.780044 -58.247062) (xy 8.810011 -58.195156) (xy 8.846498 -58.147606) (xy 8.888878 -58.105226)
			(xy 8.936428 -58.068739) (xy 8.988334 -58.038772) (xy 9.043707 -58.015836) (xy 9.1016 -58.000323)
			(xy 9.161022 -57.9925) (xy 9.220958 -57.9925) (xy 9.28038 -58.000323) (xy 9.338273 -58.015836) (xy 9.393646 -58.038772)
			(xy 9.445552 -58.068739) (xy 9.493102 -58.105226) (xy 9.535482 -58.147606) (xy 9.571969 -58.195156)
			(xy 9.601936 -58.247062) (xy 9.624872 -58.302435) (xy 9.640385 -58.360328) (xy 9.648208 -58.41975)
			(xy 9.648698 -58.449718) (xy 9.648208 -58.479686) (xy 9.640385 -58.539108) (xy 9.624872 -58.597001)
			(xy 9.601936 -58.652374) (xy 9.571969 -58.70428) (xy 9.551156 -58.731404) (xy 13.520674 -58.731404)
			(xy 13.521124 -58.704033) (xy 13.528943 -58.649853) (xy 13.544435 -58.597349) (xy 13.567281 -58.547602)
			(xy 13.59701 -58.501636) (xy 13.614654 -58.480706) (xy 13.614908 -58.480452) (xy 13.62048 -58.473355)
			(xy 13.626735 -58.456446) (xy 13.6271 -58.447432) (xy 13.6271 -58.380376) (xy 13.626754 -58.371358)
			(xy 13.620499 -58.354441) (xy 13.614908 -58.347356) (xy 13.614654 -58.347356) (xy 13.614654 -58.347102)
			(xy 13.597016 -58.326167) (xy 13.567289 -58.2802) (xy 13.544442 -58.230454) (xy 13.528944 -58.177952)
			(xy 13.521115 -58.123774) (xy 13.521114 -58.069032) (xy 13.528943 -58.014853) (xy 13.54444 -57.962351)
			(xy 13.567286 -57.912605) (xy 13.597012 -57.866638) (xy 13.614654 -57.845706) (xy 13.614908 -57.845452)
			(xy 13.62048 -57.838355) (xy 13.626735 -57.821446) (xy 13.6271 -57.812432) (xy 13.6271 -57.745376)
			(xy 13.626754 -57.736358) (xy 13.620499 -57.719441) (xy 13.614908 -57.712356) (xy 13.614654 -57.712356)
			(xy 13.614654 -57.712102) (xy 13.597016 -57.691167) (xy 13.567289 -57.6452) (xy 13.544442 -57.595454)
			(xy 13.528944 -57.542952) (xy 13.521115 -57.488774) (xy 13.521114 -57.434032) (xy 13.528943 -57.379853)
			(xy 13.54444 -57.327351) (xy 13.567286 -57.277605) (xy 13.597012 -57.231638) (xy 13.614654 -57.210706)
			(xy 13.614908 -57.210452) (xy 13.62048 -57.203355) (xy 13.626735 -57.186446) (xy 13.6271 -57.177432)
			(xy 13.6271 -57.110376) (xy 13.626754 -57.101358) (xy 13.620499 -57.084441) (xy 13.614908 -57.077356)
			(xy 13.614654 -57.077356) (xy 13.614654 -57.077102) (xy 13.597011 -57.056173) (xy 13.567298 -57.0102)
			(xy 13.544462 -56.960452) (xy 13.528972 -56.90795) (xy 13.521146 -56.853774) (xy 13.520674 -56.826404)
			(xy 13.52116 -56.799153) (xy 13.528916 -56.745205) (xy 13.544271 -56.69291) (xy 13.566913 -56.643333)
			(xy 13.596379 -56.597483) (xy 13.63207 -56.556292) (xy 13.673261 -56.520601) (xy 13.719111 -56.491135)
			(xy 13.768688 -56.468493) (xy 13.820983 -56.453138) (xy 13.874931 -56.445382) (xy 13.929433 -56.445382)
			(xy 13.983381 -56.453138) (xy 14.035676 -56.468493) (xy 14.085253 -56.491135) (xy 14.131103 -56.520601)
			(xy 14.172294 -56.556292) (xy 14.207985 -56.597483) (xy 14.237451 -56.643333) (xy 14.260093 -56.69291)
			(xy 14.275448 -56.745205) (xy 14.283204 -56.799153) (xy 14.2834 -56.810148) (xy 16.100298 -56.810148)
			(xy 16.100298 -56.809894) (xy 16.100788 -56.779926) (xy 16.108611 -56.720504) (xy 16.124124 -56.662611)
			(xy 16.14706 -56.607238) (xy 16.177027 -56.555332) (xy 16.213514 -56.507782) (xy 16.255894 -56.465402)
			(xy 16.303444 -56.428915) (xy 16.35535 -56.398948) (xy 16.410723 -56.376012) (xy 16.468616 -56.360499)
			(xy 16.528038 -56.352676) (xy 16.587974 -56.352676) (xy 16.647396 -56.360499) (xy 16.705289 -56.376012)
			(xy 16.760662 -56.398948) (xy 16.812568 -56.428915) (xy 16.860118 -56.465402) (xy 16.902498 -56.507782)
			(xy 16.938985 -56.555332) (xy 16.968952 -56.607238) (xy 16.991888 -56.662611) (xy 17.007401 -56.720504)
			(xy 17.015224 -56.779926) (xy 17.015714 -56.809894) (xy 17.015714 -56.810148) (xy 17.015136 -56.841671)
			(xy 17.006468 -56.904119) (xy 16.989315 -56.964787) (xy 16.964003 -57.022529) (xy 16.93101 -57.076253)
			(xy 16.890959 -57.124943) (xy 16.86814 -57.146698) (xy 16.861028 -57.153302) (xy 16.852646 -57.17032)
			(xy 16.846296 -57.248806) (xy 16.84593 -57.258371) (xy 16.851547 -57.276654) (xy 16.857218 -57.284366)
			(xy 16.872754 -57.30465) (xy 16.898813 -57.3486) (xy 16.918777 -57.395633) (xy 16.932288 -57.444909)
			(xy 16.935269 -57.467049) (xy 17.118592 -57.467049) (xy 17.118592 -57.412551) (xy 17.126348 -57.358606)
			(xy 17.141702 -57.306315) (xy 17.164341 -57.25674) (xy 17.193805 -57.210893) (xy 17.229493 -57.169704)
			(xy 17.27068 -57.134014) (xy 17.316526 -57.104549) (xy 17.3661 -57.081907) (xy 17.418391 -57.066551)
			(xy 17.472335 -57.058793) (xy 17.499584 -57.058306) (xy 17.525132 -57.058709) (xy 17.575772 -57.065517)
			(xy 17.625049 -57.079027) (xy 17.672081 -57.098998) (xy 17.716024 -57.12507) (xy 17.736312 -57.140602)
			(xy 17.744034 -57.146244) (xy 17.762312 -57.151842) (xy 17.771872 -57.151524) (xy 17.850358 -57.145174)
			(xy 17.867376 -57.136792) (xy 17.87398 -57.12968) (xy 17.895742 -57.106863) (xy 17.944415 -57.066781)
			(xy 17.998132 -57.033766) (xy 18.055875 -57.008441) (xy 18.116549 -56.991288) (xy 18.179004 -56.982632)
			(xy 18.21053 -56.982106) (xy 18.210784 -56.982106) (xy 18.240753 -56.982576) (xy 18.300179 -56.990398)
			(xy 18.358076 -57.00591) (xy 18.413452 -57.028846) (xy 18.465361 -57.058815) (xy 18.488862 -57.076848)
			(xy 19.138646 -57.076848) (xy 19.139129 -57.049478) (xy 19.146941 -56.995299) (xy 19.162426 -56.942796)
			(xy 19.185264 -56.893049) (xy 19.214986 -56.847082) (xy 19.232626 -56.82615) (xy 19.23288 -56.825896)
			(xy 19.238484 -56.818822) (xy 19.244718 -56.801895) (xy 19.245072 -56.792876) (xy 19.245072 -56.72582)
			(xy 19.244711 -56.716803) (xy 19.238467 -56.699886) (xy 19.23288 -56.6928) (xy 19.232626 -56.6928)
			(xy 19.232626 -56.692546) (xy 19.214999 -56.671604) (xy 19.185284 -56.625634) (xy 19.162446 -56.575889)
			(xy 19.146952 -56.523391) (xy 19.139121 -56.469217) (xy 19.138646 -56.441848) (xy 19.139132 -56.414597)
			(xy 19.146888 -56.360649) (xy 19.162243 -56.308354) (xy 19.184885 -56.258777) (xy 19.214351 -56.212927)
			(xy 19.250042 -56.171736) (xy 19.291233 -56.136045) (xy 19.337083 -56.106579) (xy 19.38666 -56.083937)
			(xy 19.438955 -56.068582) (xy 19.492903 -56.060826) (xy 19.547405 -56.060826) (xy 19.601353 -56.068582)
			(xy 19.653648 -56.083937) (xy 19.703225 -56.106579) (xy 19.749075 -56.136045) (xy 19.790266 -56.171736)
			(xy 19.825957 -56.212927) (xy 19.855423 -56.258777) (xy 19.878065 -56.308354) (xy 19.89342 -56.360649)
			(xy 19.901176 -56.414597) (xy 19.901662 -56.441848) (xy 19.901175 -56.469218) (xy 19.893363 -56.523396)
			(xy 19.87788 -56.575899) (xy 19.855043 -56.625647) (xy 19.825322 -56.671614) (xy 19.807682 -56.692546)
			(xy 19.807428 -56.6928) (xy 19.801827 -56.699876) (xy 19.795591 -56.716801) (xy 19.795236 -56.72582)
			(xy 19.795236 -56.792876) (xy 19.795597 -56.801893) (xy 19.801841 -56.81881) (xy 19.807428 -56.825896)
			(xy 19.807682 -56.825896) (xy 19.807682 -56.82615) (xy 19.825308 -56.847092) (xy 19.855023 -56.893062)
			(xy 19.877861 -56.942807) (xy 19.893355 -56.995305) (xy 19.894458 -57.002934) (xy 21.563584 -57.002934)
			(xy 21.564105 -56.974843) (xy 21.572327 -56.919267) (xy 21.588614 -56.865499) (xy 21.612612 -56.814702)
			(xy 21.643803 -56.767974) (xy 21.681511 -56.726329) (xy 21.724921 -56.690665) (xy 21.74875 -56.675782)
			(xy 21.75764 -56.670448) (xy 21.769832 -56.65343) (xy 21.790152 -56.560212) (xy 21.785834 -56.539638)
			(xy 21.779992 -56.531002) (xy 21.76399 -56.50694) (xy 21.738648 -56.455008) (xy 21.721423 -56.399849)
			(xy 21.712708 -56.342725) (xy 21.712174 -56.313832) (xy 21.712685 -56.286581) (xy 21.720437 -56.232632)
			(xy 21.735788 -56.180337) (xy 21.758426 -56.130758) (xy 21.787889 -56.084905) (xy 21.823577 -56.043713)
			(xy 21.864765 -56.008019) (xy 21.910614 -55.97855) (xy 21.96019 -55.955906) (xy 22.012484 -55.940548)
			(xy 22.066431 -55.932789) (xy 22.093682 -55.932324) (xy 22.121052 -55.932795) (xy 22.175231 -55.940611)
			(xy 22.227735 -55.956098) (xy 22.277481 -55.978939) (xy 22.323448 -56.008663) (xy 22.34438 -56.026304)
			(xy 22.344634 -56.026558) (xy 22.35173 -56.03213) (xy 22.36864 -56.038384) (xy 22.377654 -56.03875)
			(xy 22.44471 -56.03875) (xy 22.453729 -56.038408) (xy 22.470646 -56.032151) (xy 22.47773 -56.026558)
			(xy 22.47773 -56.026304) (xy 22.477984 -56.026304) (xy 22.498917 -56.008663) (xy 22.544885 -55.978939)
			(xy 22.594631 -55.956093) (xy 22.647133 -55.940597) (xy 22.701311 -55.932768) (xy 22.756053 -55.932768)
			(xy 22.810231 -55.940597) (xy 22.862733 -55.956093) (xy 22.912479 -55.978939) (xy 22.958447 -56.008663)
			(xy 22.97938 -56.026304) (xy 22.979634 -56.026558) (xy 22.98673 -56.03213) (xy 23.00364 -56.038384)
			(xy 23.012654 -56.03875) (xy 23.07971 -56.03875) (xy 23.088729 -56.038408) (xy 23.105646 -56.032151)
			(xy 23.11273 -56.026558) (xy 23.11273 -56.026304) (xy 23.112984 -56.026304) (xy 23.133912 -56.00866)
			(xy 23.179886 -55.978948) (xy 23.229634 -55.956113) (xy 23.282136 -55.940624) (xy 23.336313 -55.932797)
			(xy 23.363682 -55.932324) (xy 23.390938 -55.932722) (xy 23.444895 -55.940477) (xy 23.4972 -55.955833)
			(xy 23.546787 -55.978476) (xy 23.592646 -56.007946) (xy 23.633844 -56.043643) (xy 23.669543 -56.08484)
			(xy 23.699015 -56.130698) (xy 23.721661 -56.180283) (xy 23.737019 -56.232587) (xy 23.744777 -56.286544)
			(xy 23.744777 -56.297068) (xy 24.086564 -56.297068) (xy 24.090635 -56.241446) (xy 24.102761 -56.187009)
			(xy 24.122684 -56.134918) (xy 24.14998 -56.086283) (xy 24.184066 -56.04214) (xy 24.224215 -56.003431)
			(xy 24.269573 -55.97098) (xy 24.319173 -55.945479) (xy 24.371957 -55.927472) (xy 24.4268 -55.917342)
			(xy 24.482534 -55.915305) (xy 24.537971 -55.921405) (xy 24.591928 -55.935511) (xy 24.643257 -55.957323)
			(xy 24.690863 -55.986377) (xy 24.733731 -56.022052) (xy 24.770948 -56.063589) (xy 24.801721 -56.110102)
			(xy 24.825393 -56.160599) (xy 24.841461 -56.214006) (xy 24.849581 -56.269182) (xy 24.85009 -56.297068)
			(xy 24.849581 -56.324954) (xy 24.845386 -56.353456) (xy 26.94127 -56.353456) (xy 26.945341 -56.297834)
			(xy 26.957467 -56.243397) (xy 26.97739 -56.191306) (xy 27.004686 -56.142671) (xy 27.038772 -56.098528)
			(xy 27.078921 -56.059819) (xy 27.124279 -56.027368) (xy 27.173879 -56.001867) (xy 27.226663 -55.98386)
			(xy 27.281506 -55.97373) (xy 27.33724 -55.971693) (xy 27.392677 -55.977793) (xy 27.446634 -55.991899)
			(xy 27.497963 -56.013711) (xy 27.545569 -56.042765) (xy 27.588437 -56.07844) (xy 27.625654 -56.119977)
			(xy 27.656427 -56.16649) (xy 27.680099 -56.216987) (xy 27.696167 -56.270394) (xy 27.704287 -56.32557)
			(xy 27.704796 -56.353456) (xy 27.704287 -56.381342) (xy 27.696167 -56.436518) (xy 27.680099 -56.489925)
			(xy 27.656427 -56.540422) (xy 27.625654 -56.586935) (xy 27.588437 -56.628472) (xy 27.545569 -56.664147)
			(xy 27.497963 -56.693201) (xy 27.446634 -56.715013) (xy 27.392677 -56.729119) (xy 27.33724 -56.735219)
			(xy 27.281506 -56.733182) (xy 27.226663 -56.723052) (xy 27.173879 -56.705045) (xy 27.124279 -56.679544)
			(xy 27.078921 -56.647093) (xy 27.038772 -56.608384) (xy 27.004686 -56.564241) (xy 26.97739 -56.515606)
			(xy 26.957467 -56.463515) (xy 26.945341 -56.409078) (xy 26.94127 -56.353456) (xy 24.845386 -56.353456)
			(xy 24.841461 -56.38013) (xy 24.825393 -56.433537) (xy 24.801721 -56.484034) (xy 24.770948 -56.530547)
			(xy 24.733731 -56.572084) (xy 24.690863 -56.607759) (xy 24.643257 -56.636813) (xy 24.591928 -56.658625)
			(xy 24.537971 -56.672731) (xy 24.482534 -56.678831) (xy 24.4268 -56.676794) (xy 24.371957 -56.666664)
			(xy 24.319173 -56.648657) (xy 24.269573 -56.623156) (xy 24.224215 -56.590705) (xy 24.184066 -56.551996)
			(xy 24.14998 -56.507853) (xy 24.122684 -56.459218) (xy 24.102761 -56.407127) (xy 24.090635 -56.35269)
			(xy 24.086564 -56.297068) (xy 23.744777 -56.297068) (xy 23.744777 -56.341056) (xy 23.737019 -56.395013)
			(xy 23.721661 -56.447317) (xy 23.699015 -56.496902) (xy 23.669543 -56.54276) (xy 23.633844 -56.583957)
			(xy 23.592646 -56.619654) (xy 23.546787 -56.649124) (xy 23.4972 -56.671767) (xy 23.444895 -56.687123)
			(xy 23.390938 -56.694878) (xy 23.363682 -56.69534) (xy 23.336311 -56.694899) (xy 23.28213 -56.687077)
			(xy 23.229626 -56.671583) (xy 23.179879 -56.648736) (xy 23.133914 -56.619005) (xy 23.112984 -56.60136)
			(xy 23.11273 -56.601106) (xy 23.105639 -56.595527) (xy 23.088726 -56.589275) (xy 23.07971 -56.588914)
			(xy 23.012654 -56.588914) (xy 23.003639 -56.589294) (xy 22.986722 -56.595525) (xy 22.979634 -56.601106)
			(xy 22.979634 -56.60136) (xy 22.97938 -56.60136) (xy 22.958447 -56.619001) (xy 22.912479 -56.648725)
			(xy 22.862733 -56.671571) (xy 22.810231 -56.687067) (xy 22.756053 -56.694896) (xy 22.701311 -56.694896)
			(xy 22.647133 -56.687067) (xy 22.594631 -56.671571) (xy 22.544885 -56.648725) (xy 22.498917 -56.619001)
			(xy 22.477984 -56.60136) (xy 22.47773 -56.601106) (xy 22.470639 -56.595527) (xy 22.453726 -56.589275)
			(xy 22.44471 -56.588914) (xy 22.377654 -56.588914) (xy 22.368639 -56.589294) (xy 22.351722 -56.595525)
			(xy 22.344634 -56.601106) (xy 22.344126 -56.60136) (xy 22.331394 -56.612307) (xy 22.304301 -56.632146)
			(xy 22.290024 -56.640984) (xy 22.281134 -56.646318) (xy 22.268942 -56.663336) (xy 22.248622 -56.756554)
			(xy 22.25294 -56.777128) (xy 22.258782 -56.785764) (xy 22.274767 -56.809837) (xy 22.300113 -56.861765)
			(xy 22.317343 -56.91692) (xy 22.326063 -56.974042) (xy 22.3266 -57.002934) (xy 22.326114 -57.030185)
			(xy 22.318358 -57.084133) (xy 22.303003 -57.136428) (xy 22.280361 -57.186005) (xy 22.250895 -57.231855)
			(xy 22.215204 -57.273046) (xy 22.174013 -57.308737) (xy 22.128163 -57.338203) (xy 22.078586 -57.360845)
			(xy 22.026291 -57.3762) (xy 21.972343 -57.383956) (xy 21.917841 -57.383956) (xy 21.863893 -57.3762)
			(xy 21.811598 -57.360845) (xy 21.762021 -57.338203) (xy 21.716171 -57.308737) (xy 21.67498 -57.273046)
			(xy 21.639289 -57.231855) (xy 21.609823 -57.186005) (xy 21.587181 -57.136428) (xy 21.571826 -57.084133)
			(xy 21.56407 -57.030185) (xy 21.563584 -57.002934) (xy 19.894458 -57.002934) (xy 19.901187 -57.049479)
			(xy 19.901662 -57.076848) (xy 19.901176 -57.104099) (xy 19.89342 -57.158047) (xy 19.878065 -57.210342)
			(xy 19.855423 -57.259919) (xy 19.825957 -57.305769) (xy 19.790266 -57.34696) (xy 19.749075 -57.382651)
			(xy 19.703225 -57.412117) (xy 19.653648 -57.434759) (xy 19.601353 -57.450114) (xy 19.547405 -57.45787)
			(xy 19.492903 -57.45787) (xy 19.438955 -57.450114) (xy 19.38666 -57.434759) (xy 19.337083 -57.412117)
			(xy 19.291233 -57.382651) (xy 19.250042 -57.34696) (xy 19.214351 -57.305769) (xy 19.184885 -57.259919)
			(xy 19.162243 -57.210342) (xy 19.146888 -57.158047) (xy 19.139132 -57.104099) (xy 19.138646 -57.076848)
			(xy 18.488862 -57.076848) (xy 18.512913 -57.095303) (xy 18.555296 -57.137685) (xy 18.591784 -57.185238)
			(xy 18.621753 -57.237146) (xy 18.64469 -57.292522) (xy 18.660202 -57.350419) (xy 18.668024 -57.409845)
			(xy 18.668492 -57.439814) (xy 18.668048 -57.468047) (xy 18.665914 -57.48528) (xy 30.605982 -57.48528)
			(xy 30.610053 -57.429658) (xy 30.622179 -57.375221) (xy 30.642102 -57.32313) (xy 30.669398 -57.274495)
			(xy 30.703484 -57.230352) (xy 30.743633 -57.191643) (xy 30.788991 -57.159192) (xy 30.838591 -57.133691)
			(xy 30.891375 -57.115684) (xy 30.946218 -57.105554) (xy 31.001952 -57.103517) (xy 31.057389 -57.109617)
			(xy 31.111346 -57.123723) (xy 31.162675 -57.145535) (xy 31.210281 -57.174589) (xy 31.253149 -57.210264)
			(xy 31.290366 -57.251801) (xy 31.321139 -57.298314) (xy 31.344811 -57.348811) (xy 31.360879 -57.402218)
			(xy 31.368999 -57.457394) (xy 31.369508 -57.48528) (xy 31.368999 -57.513166) (xy 31.360879 -57.568342)
			(xy 31.344811 -57.621749) (xy 31.321139 -57.672246) (xy 31.290366 -57.718759) (xy 31.253149 -57.760296)
			(xy 31.210281 -57.795971) (xy 31.162675 -57.825025) (xy 31.111346 -57.846837) (xy 31.057389 -57.860943)
			(xy 31.001952 -57.867043) (xy 30.946218 -57.865006) (xy 30.891375 -57.854876) (xy 30.838591 -57.836869)
			(xy 30.788991 -57.811368) (xy 30.743633 -57.778917) (xy 30.703484 -57.740208) (xy 30.669398 -57.696065)
			(xy 30.642102 -57.64743) (xy 30.622179 -57.595339) (xy 30.610053 -57.540902) (xy 30.605982 -57.48528)
			(xy 18.665914 -57.48528) (xy 18.661108 -57.524083) (xy 18.647322 -57.57884) (xy 18.626901 -57.631482)
			(xy 18.600154 -57.681211) (xy 18.584164 -57.704482) (xy 18.576798 -57.71515) (xy 18.57375 -57.740804)
			(xy 18.616168 -57.844436) (xy 18.636234 -57.860692) (xy 18.649188 -57.862978) (xy 18.675305 -57.868083)
			(xy 18.725875 -57.884648) (xy 18.773655 -57.908077) (xy 18.817718 -57.937916) (xy 18.857209 -57.973585)
			(xy 18.891364 -58.014393) (xy 18.919519 -58.059549) (xy 18.941129 -58.108179) (xy 18.955776 -58.159338)
			(xy 18.963175 -58.212037) (xy 18.96364 -58.238644) (xy 18.963156 -58.266014) (xy 18.955345 -58.320193)
			(xy 18.939861 -58.372696) (xy 18.917022 -58.422443) (xy 18.8873 -58.46841) (xy 18.86966 -58.489342)
			(xy 18.869406 -58.489596) (xy 18.863816 -58.49668) (xy 18.857571 -58.513599) (xy 18.857214 -58.522616)
			(xy 18.857214 -58.589672) (xy 18.857582 -58.598688) (xy 18.863822 -58.615605) (xy 18.869406 -58.622692)
			(xy 18.86966 -58.622692) (xy 18.86966 -58.622946) (xy 18.887281 -58.643893) (xy 18.910192 -58.679334)
			(xy 21.919184 -58.679334) (xy 21.919184 -58.67908) (xy 21.919715 -58.647555) (xy 21.928393 -58.585106)
			(xy 21.945554 -58.524437) (xy 21.970875 -58.466695) (xy 22.003877 -58.412972) (xy 22.043935 -58.364284)
			(xy 22.066758 -58.34253) (xy 22.07387 -58.335926) (xy 22.082252 -58.318908) (xy 22.088602 -58.240422)
			(xy 22.088954 -58.230857) (xy 22.083347 -58.212575) (xy 22.07768 -58.204862) (xy 22.062157 -58.184568)
			(xy 22.036095 -58.140621) (xy 22.016129 -58.093591) (xy 22.002615 -58.044317) (xy 21.995795 -57.993681)
			(xy 21.995384 -57.968134) (xy 21.99587 -57.940883) (xy 22.003626 -57.886935) (xy 22.018981 -57.83464)
			(xy 22.041623 -57.785063) (xy 22.071089 -57.739213) (xy 22.10678 -57.698022) (xy 22.147971 -57.662331)
			(xy 22.193821 -57.632865) (xy 22.243398 -57.610223) (xy 22.295693 -57.594868) (xy 22.349641 -57.587112)
			(xy 22.404143 -57.587112) (xy 22.458091 -57.594868) (xy 22.510386 -57.610223) (xy 22.559963 -57.632865)
			(xy 22.605813 -57.662331) (xy 22.647004 -57.698022) (xy 22.682695 -57.739213) (xy 22.712161 -57.785063)
			(xy 22.734803 -57.83464) (xy 22.750158 -57.886935) (xy 22.757914 -57.940883) (xy 22.7584 -57.968134)
			(xy 22.758024 -57.993683) (xy 22.751209 -58.044324) (xy 22.737692 -58.093601) (xy 22.734022 -58.102242)
			(xy 25.918396 -58.102242) (xy 25.918396 -58.042306) (xy 25.926219 -57.982884) (xy 25.941732 -57.924991)
			(xy 25.964668 -57.869618) (xy 25.994635 -57.817712) (xy 26.031122 -57.770162) (xy 26.073502 -57.727782)
			(xy 26.121052 -57.691295) (xy 26.172958 -57.661328) (xy 26.228331 -57.638392) (xy 26.286224 -57.622879)
			(xy 26.345646 -57.615056) (xy 26.405582 -57.615056) (xy 26.465004 -57.622879) (xy 26.522897 -57.638392)
			(xy 26.57827 -57.661328) (xy 26.630176 -57.691295) (xy 26.677726 -57.727782) (xy 26.720106 -57.770162)
			(xy 26.756593 -57.817712) (xy 26.78656 -57.869618) (xy 26.809496 -57.924991) (xy 26.825009 -57.982884)
			(xy 26.832832 -58.042306) (xy 26.833322 -58.072274) (xy 26.83326 -58.076084) (xy 31.358076 -58.076084)
			(xy 31.362147 -58.020462) (xy 31.374273 -57.966025) (xy 31.394196 -57.913934) (xy 31.421492 -57.865299)
			(xy 31.455578 -57.821156) (xy 31.495727 -57.782447) (xy 31.541085 -57.749996) (xy 31.590685 -57.724495)
			(xy 31.643469 -57.706488) (xy 31.698312 -57.696358) (xy 31.754046 -57.694321) (xy 31.809483 -57.700421)
			(xy 31.86344 -57.714527) (xy 31.914769 -57.736339) (xy 31.962375 -57.765393) (xy 32.005243 -57.801068)
			(xy 32.04246 -57.842605) (xy 32.073233 -57.889118) (xy 32.077052 -57.897264) (xy 33.56786 -57.897264)
			(xy 33.56786 -57.837328) (xy 33.575683 -57.777906) (xy 33.591196 -57.720013) (xy 33.614132 -57.66464)
			(xy 33.644099 -57.612734) (xy 33.680586 -57.565184) (xy 33.722966 -57.522804) (xy 33.770516 -57.486317)
			(xy 33.822422 -57.45635) (xy 33.877795 -57.433414) (xy 33.935688 -57.417901) (xy 33.99511 -57.410078)
			(xy 34.055046 -57.410078) (xy 34.114468 -57.417901) (xy 34.172361 -57.433414) (xy 34.227734 -57.45635)
			(xy 34.27964 -57.486317) (xy 34.32719 -57.522804) (xy 34.36957 -57.565184) (xy 34.406057 -57.612734)
			(xy 34.436024 -57.66464) (xy 34.45896 -57.720013) (xy 34.474473 -57.777906) (xy 34.482296 -57.837328)
			(xy 34.482786 -57.867296) (xy 34.482296 -57.897264) (xy 34.474473 -57.956686) (xy 34.45896 -58.014579)
			(xy 34.436024 -58.069952) (xy 34.406057 -58.121858) (xy 34.36957 -58.169408) (xy 34.32719 -58.211788)
			(xy 34.27964 -58.248275) (xy 34.227734 -58.278242) (xy 34.172361 -58.301178) (xy 34.114468 -58.316691)
			(xy 34.055046 -58.324514) (xy 33.99511 -58.324514) (xy 33.935688 -58.316691) (xy 33.877795 -58.301178)
			(xy 33.822422 -58.278242) (xy 33.770516 -58.248275) (xy 33.722966 -58.211788) (xy 33.680586 -58.169408)
			(xy 33.644099 -58.121858) (xy 33.614132 -58.069952) (xy 33.591196 -58.014579) (xy 33.575683 -57.956686)
			(xy 33.56786 -57.897264) (xy 32.077052 -57.897264) (xy 32.096905 -57.939615) (xy 32.112973 -57.993022)
			(xy 32.121093 -58.048198) (xy 32.121602 -58.076084) (xy 32.121093 -58.10397) (xy 32.112973 -58.159146)
			(xy 32.096905 -58.212553) (xy 32.073233 -58.26305) (xy 32.04246 -58.309563) (xy 32.005243 -58.3511)
			(xy 31.962375 -58.386775) (xy 31.914769 -58.415829) (xy 31.86344 -58.437641) (xy 31.809483 -58.451747)
			(xy 31.754046 -58.457847) (xy 31.698312 -58.45581) (xy 31.643469 -58.44568) (xy 31.590685 -58.427673)
			(xy 31.541085 -58.402172) (xy 31.495727 -58.369721) (xy 31.455578 -58.331012) (xy 31.421492 -58.286869)
			(xy 31.394196 -58.238234) (xy 31.374273 -58.186143) (xy 31.362147 -58.131706) (xy 31.358076 -58.076084)
			(xy 26.83326 -58.076084) (xy 26.832832 -58.102242) (xy 26.825009 -58.161664) (xy 26.809496 -58.219557)
			(xy 26.78656 -58.27493) (xy 26.756593 -58.326836) (xy 26.720106 -58.374386) (xy 26.677726 -58.416766)
			(xy 26.630176 -58.453253) (xy 26.57827 -58.48322) (xy 26.522897 -58.506156) (xy 26.465004 -58.521669)
			(xy 26.405582 -58.529492) (xy 26.345646 -58.529492) (xy 26.286224 -58.521669) (xy 26.228331 -58.506156)
			(xy 26.172958 -58.48322) (xy 26.121052 -58.453253) (xy 26.073502 -58.416766) (xy 26.031122 -58.374386)
			(xy 25.994635 -58.326836) (xy 25.964668 -58.27493) (xy 25.941732 -58.219557) (xy 25.926219 -58.161664)
			(xy 25.918396 -58.102242) (xy 22.734022 -58.102242) (xy 22.717716 -58.140632) (xy 22.691638 -58.184574)
			(xy 22.676104 -58.204862) (xy 22.670485 -58.212599) (xy 22.664873 -58.230865) (xy 22.665182 -58.240422)
			(xy 22.671532 -58.318908) (xy 22.679914 -58.335926) (xy 22.687026 -58.34253) (xy 22.709869 -58.364266)
			(xy 22.749947 -58.412945) (xy 22.78296 -58.466667) (xy 22.80828 -58.524415) (xy 22.825427 -58.585094)
			(xy 22.826272 -58.591192) (xy 32.48709 -58.591192) (xy 32.48709 -58.531256) (xy 32.494913 -58.471834)
			(xy 32.510426 -58.413941) (xy 32.533362 -58.358568) (xy 32.563329 -58.306662) (xy 32.599816 -58.259112)
			(xy 32.642196 -58.216732) (xy 32.689746 -58.180245) (xy 32.741652 -58.150278) (xy 32.797025 -58.127342)
			(xy 32.854918 -58.111829) (xy 32.91434 -58.104006) (xy 32.974276 -58.104006) (xy 33.033698 -58.111829)
			(xy 33.091591 -58.127342) (xy 33.146964 -58.150278) (xy 33.19887 -58.180245) (xy 33.24642 -58.216732)
			(xy 33.2888 -58.259112) (xy 33.325287 -58.306662) (xy 33.355254 -58.358568) (xy 33.37819 -58.413941)
			(xy 33.393703 -58.471834) (xy 33.394737 -58.479686) (xy 34.73372 -58.479686) (xy 34.73372 -58.41975)
			(xy 34.741543 -58.360328) (xy 34.757056 -58.302435) (xy 34.779992 -58.247062) (xy 34.809959 -58.195156)
			(xy 34.846446 -58.147606) (xy 34.888826 -58.105226) (xy 34.936376 -58.068739) (xy 34.988282 -58.038772)
			(xy 35.043655 -58.015836) (xy 35.101548 -58.000323) (xy 35.16097 -57.9925) (xy 35.220906 -57.9925)
			(xy 35.280328 -58.000323) (xy 35.338221 -58.015836) (xy 35.393594 -58.038772) (xy 35.4455 -58.068739)
			(xy 35.49305 -58.105226) (xy 35.53543 -58.147606) (xy 35.571917 -58.195156) (xy 35.601884 -58.247062)
			(xy 35.62482 -58.302435) (xy 35.640333 -58.360328) (xy 35.648156 -58.41975) (xy 35.648646 -58.449718)
			(xy 35.648156 -58.479686) (xy 35.640333 -58.539108) (xy 35.62482 -58.597001) (xy 35.601884 -58.652374)
			(xy 35.571917 -58.70428) (xy 35.551104 -58.731404) (xy 39.520622 -58.731404) (xy 39.521085 -58.704034)
			(xy 39.528903 -58.649854) (xy 39.544392 -58.597351) (xy 39.567235 -58.547604) (xy 39.59696 -58.501637)
			(xy 39.614602 -58.480706) (xy 39.614856 -58.480452) (xy 39.620434 -58.47336) (xy 39.626684 -58.456447)
			(xy 39.627048 -58.447432) (xy 39.627048 -58.380376) (xy 39.626714 -58.371357) (xy 39.620452 -58.354439)
			(xy 39.614856 -58.347356) (xy 39.614602 -58.347356) (xy 39.614602 -58.347102) (xy 39.596966 -58.326166)
			(xy 39.567243 -58.280198) (xy 39.544399 -58.230452) (xy 39.528904 -58.177951) (xy 39.521075 -58.123773)
			(xy 39.521075 -58.069033) (xy 39.528902 -58.014855) (xy 39.544397 -57.962354) (xy 39.56724 -57.912607)
			(xy 39.596963 -57.866639) (xy 39.614602 -57.845706) (xy 39.614856 -57.845452) (xy 39.620434 -57.83836)
			(xy 39.626684 -57.821447) (xy 39.627048 -57.812432) (xy 39.627048 -57.745376) (xy 39.626714 -57.736357)
			(xy 39.620452 -57.719439) (xy 39.614856 -57.712356) (xy 39.614602 -57.712356) (xy 39.614602 -57.712102)
			(xy 39.596966 -57.691166) (xy 39.567243 -57.645198) (xy 39.544399 -57.595452) (xy 39.528904 -57.542951)
			(xy 39.521075 -57.488773) (xy 39.521075 -57.434033) (xy 39.528902 -57.379855) (xy 39.544397 -57.327354)
			(xy 39.56724 -57.277607) (xy 39.596963 -57.231639) (xy 39.614602 -57.210706) (xy 39.614856 -57.210452)
			(xy 39.620434 -57.20336) (xy 39.626684 -57.186447) (xy 39.627048 -57.177432) (xy 39.627048 -57.110376)
			(xy 39.626714 -57.101357) (xy 39.620452 -57.084439) (xy 39.614856 -57.077356) (xy 39.614602 -57.077356)
			(xy 39.614602 -57.077102) (xy 39.596951 -57.05618) (xy 39.567241 -57.010204) (xy 39.544407 -56.960454)
			(xy 39.528919 -56.907951) (xy 39.521094 -56.853774) (xy 39.520622 -56.826404) (xy 39.521108 -56.799153)
			(xy 39.528864 -56.745205) (xy 39.544219 -56.69291) (xy 39.566861 -56.643333) (xy 39.596327 -56.597483)
			(xy 39.632018 -56.556292) (xy 39.673209 -56.520601) (xy 39.719059 -56.491135) (xy 39.768636 -56.468493)
			(xy 39.820931 -56.453138) (xy 39.874879 -56.445382) (xy 39.929381 -56.445382) (xy 39.983329 -56.453138)
			(xy 40.035624 -56.468493) (xy 40.085201 -56.491135) (xy 40.131051 -56.520601) (xy 40.172242 -56.556292)
			(xy 40.207933 -56.597483) (xy 40.237399 -56.643333) (xy 40.260041 -56.69291) (xy 40.275396 -56.745205)
			(xy 40.283152 -56.799153) (xy 40.283348 -56.810148) (xy 42.100246 -56.810148) (xy 42.100246 -56.809894)
			(xy 42.100736 -56.779926) (xy 42.108559 -56.720504) (xy 42.124072 -56.662611) (xy 42.147008 -56.607238)
			(xy 42.176975 -56.555332) (xy 42.213462 -56.507782) (xy 42.255842 -56.465402) (xy 42.303392 -56.428915)
			(xy 42.355298 -56.398948) (xy 42.410671 -56.376012) (xy 42.468564 -56.360499) (xy 42.527986 -56.352676)
			(xy 42.587922 -56.352676) (xy 42.647344 -56.360499) (xy 42.705237 -56.376012) (xy 42.76061 -56.398948)
			(xy 42.812516 -56.428915) (xy 42.860066 -56.465402) (xy 42.902446 -56.507782) (xy 42.938933 -56.555332)
			(xy 42.9689 -56.607238) (xy 42.991836 -56.662611) (xy 43.007349 -56.720504) (xy 43.015172 -56.779926)
			(xy 43.015662 -56.809894) (xy 43.015662 -56.810148) (xy 43.015101 -56.841672) (xy 43.006431 -56.904121)
			(xy 42.989277 -56.96479) (xy 42.963962 -57.022532) (xy 42.930965 -57.076256) (xy 42.890909 -57.124944)
			(xy 42.868088 -57.146698) (xy 42.860976 -57.153302) (xy 42.852594 -57.17032) (xy 42.846244 -57.248806)
			(xy 42.845868 -57.258372) (xy 42.851491 -57.276656) (xy 42.857166 -57.284366) (xy 42.872709 -57.304645)
			(xy 42.898765 -57.348597) (xy 42.918727 -57.395631) (xy 42.932237 -57.444908) (xy 42.935218 -57.467053)
			(xy 43.118469 -57.467053) (xy 43.118469 -57.412547) (xy 43.126227 -57.358595) (xy 43.141584 -57.306296)
			(xy 43.164228 -57.256716) (xy 43.193698 -57.210863) (xy 43.229394 -57.169671) (xy 43.270589 -57.133979)
			(xy 43.316444 -57.104513) (xy 43.366026 -57.081873) (xy 43.418326 -57.06652) (xy 43.472279 -57.058767)
			(xy 43.499532 -57.058306) (xy 43.525081 -57.058682) (xy 43.575722 -57.065497) (xy 43.624999 -57.079013)
			(xy 43.67203 -57.09899) (xy 43.715972 -57.125067) (xy 43.73626 -57.140602) (xy 43.743997 -57.146221)
			(xy 43.762263 -57.151832) (xy 43.77182 -57.151524) (xy 43.850306 -57.145174) (xy 43.867324 -57.136792)
			(xy 43.873928 -57.12968) (xy 43.895666 -57.106839) (xy 43.944344 -57.06676) (xy 43.998066 -57.033748)
			(xy 44.055814 -57.008427) (xy 44.116492 -56.991279) (xy 44.178951 -56.982629) (xy 44.210478 -56.982106)
			(xy 44.210732 -56.982106) (xy 44.240701 -56.982552) (xy 44.300126 -56.99038) (xy 44.35802 -57.005896)
			(xy 44.413394 -57.028837) (xy 44.465301 -57.058809) (xy 44.488808 -57.076848) (xy 45.138594 -57.076848)
			(xy 45.13909 -57.049479) (xy 45.146901 -56.995301) (xy 45.162383 -56.942798) (xy 45.185218 -56.893051)
			(xy 45.214936 -56.847083) (xy 45.232574 -56.82615) (xy 45.232828 -56.825896) (xy 45.238425 -56.818817)
			(xy 45.244665 -56.801894) (xy 45.24502 -56.792876) (xy 45.24502 -56.72582) (xy 45.244649 -56.716805)
			(xy 45.238411 -56.699888) (xy 45.232828 -56.6928) (xy 45.232574 -56.6928) (xy 45.232574 -56.692546)
			(xy 45.214939 -56.671611) (xy 45.185227 -56.625638) (xy 45.162391 -56.575892) (xy 45.146899 -56.523392)
			(xy 45.139069 -56.469217) (xy 45.138594 -56.441848) (xy 45.13908 -56.414597) (xy 45.146836 -56.360649)
			(xy 45.162191 -56.308354) (xy 45.184833 -56.258777) (xy 45.214299 -56.212927) (xy 45.24999 -56.171736)
			(xy 45.291181 -56.136045) (xy 45.337031 -56.106579) (xy 45.386608 -56.083937) (xy 45.438903 -56.068582)
			(xy 45.492851 -56.060826) (xy 45.547353 -56.060826) (xy 45.601301 -56.068582) (xy 45.653596 -56.083937)
			(xy 45.703173 -56.106579) (xy 45.749023 -56.136045) (xy 45.790214 -56.171736) (xy 45.825905 -56.212927)
			(xy 45.855371 -56.258777) (xy 45.878013 -56.308354) (xy 45.893368 -56.360649) (xy 45.901124 -56.414597)
			(xy 45.90161 -56.441848) (xy 45.901111 -56.469217) (xy 45.893301 -56.523395) (xy 45.877819 -56.575897)
			(xy 45.854985 -56.625645) (xy 45.825268 -56.671613) (xy 45.80763 -56.692546) (xy 45.807376 -56.6928)
			(xy 45.801781 -56.69988) (xy 45.79554 -56.716802) (xy 45.795184 -56.72582) (xy 45.795184 -56.792876)
			(xy 45.795556 -56.801891) (xy 45.801794 -56.818808) (xy 45.807376 -56.825896) (xy 45.80763 -56.825896)
			(xy 45.80763 -56.82615) (xy 45.825264 -56.847086) (xy 45.854975 -56.893058) (xy 45.877812 -56.942805)
			(xy 45.893304 -56.995304) (xy 45.894407 -57.002934) (xy 47.563532 -57.002934) (xy 47.56403 -56.974842)
			(xy 47.572253 -56.919264) (xy 47.588542 -56.865494) (xy 47.612544 -56.814696) (xy 47.643739 -56.767969)
			(xy 47.681452 -56.726324) (xy 47.724867 -56.690663) (xy 47.748698 -56.675782) (xy 47.757588 -56.670448)
			(xy 47.76978 -56.65343) (xy 47.7901 -56.560212) (xy 47.785782 -56.539638) (xy 47.77994 -56.531002)
			(xy 47.763931 -56.506944) (xy 47.738592 -56.45501) (xy 47.721369 -56.39985) (xy 47.712656 -56.342725)
			(xy 47.712122 -56.313832) (xy 47.712585 -56.286579) (xy 47.720339 -56.232626) (xy 47.735692 -56.180326)
			(xy 47.758333 -56.130744) (xy 47.7878 -56.08489) (xy 47.823494 -56.043696) (xy 47.864688 -56.008002)
			(xy 47.910543 -55.978534) (xy 47.960125 -55.955893) (xy 48.012424 -55.940539) (xy 48.066377 -55.932785)
			(xy 48.09363 -55.932324) (xy 48.121001 -55.932767) (xy 48.175181 -55.940589) (xy 48.227685 -55.956083)
			(xy 48.277432 -55.978931) (xy 48.323397 -56.00866) (xy 48.344328 -56.026304) (xy 48.344582 -56.026558)
			(xy 48.351665 -56.03215) (xy 48.368585 -56.038392) (xy 48.377602 -56.03875) (xy 48.444658 -56.03875)
			(xy 48.453674 -56.038384) (xy 48.470592 -56.032144) (xy 48.477678 -56.026558) (xy 48.477678 -56.026304)
			(xy 48.477932 -56.026304) (xy 48.498865 -56.008663) (xy 48.544833 -55.978939) (xy 48.594579 -55.956093)
			(xy 48.647081 -55.940597) (xy 48.701259 -55.932768) (xy 48.756001 -55.932768) (xy 48.810179 -55.940597)
			(xy 48.862681 -55.956093) (xy 48.912427 -55.978939) (xy 48.958395 -56.008663) (xy 48.979328 -56.026304)
			(xy 48.979582 -56.026558) (xy 48.986665 -56.03215) (xy 49.003585 -56.038392) (xy 49.012602 -56.03875)
			(xy 49.079658 -56.03875) (xy 49.088674 -56.038384) (xy 49.105592 -56.032144) (xy 49.112678 -56.026558)
			(xy 49.112678 -56.026304) (xy 49.112932 -56.026304) (xy 49.133879 -56.008684) (xy 49.179848 -55.978969)
			(xy 49.229592 -55.956129) (xy 49.282089 -55.940634) (xy 49.336262 -55.932801) (xy 49.36363 -55.932324)
			(xy 49.390882 -55.932748) (xy 49.444831 -55.940509) (xy 49.497127 -55.955868) (xy 49.546704 -55.978512)
			(xy 49.592555 -56.007982) (xy 49.633745 -56.043676) (xy 49.669436 -56.084869) (xy 49.698902 -56.130722)
			(xy 49.721543 -56.180301) (xy 49.736898 -56.232598) (xy 49.744654 -56.286548) (xy 49.744654 -56.297068)
			(xy 50.086512 -56.297068) (xy 50.090583 -56.241446) (xy 50.102709 -56.187009) (xy 50.122632 -56.134918)
			(xy 50.149928 -56.086283) (xy 50.184014 -56.04214) (xy 50.224163 -56.003431) (xy 50.269521 -55.97098)
			(xy 50.319121 -55.945479) (xy 50.371905 -55.927472) (xy 50.426748 -55.917342) (xy 50.482482 -55.915305)
			(xy 50.537919 -55.921405) (xy 50.591876 -55.935511) (xy 50.643205 -55.957323) (xy 50.690811 -55.986377)
			(xy 50.733679 -56.022052) (xy 50.770896 -56.063589) (xy 50.801669 -56.110102) (xy 50.825341 -56.160599)
			(xy 50.841409 -56.214006) (xy 50.849529 -56.269182) (xy 50.850038 -56.297068) (xy 50.849529 -56.324954)
			(xy 50.845334 -56.353456) (xy 52.941218 -56.353456) (xy 52.945289 -56.297834) (xy 52.957415 -56.243397)
			(xy 52.977338 -56.191306) (xy 53.004634 -56.142671) (xy 53.03872 -56.098528) (xy 53.078869 -56.059819)
			(xy 53.124227 -56.027368) (xy 53.173827 -56.001867) (xy 53.226611 -55.98386) (xy 53.281454 -55.97373)
			(xy 53.337188 -55.971693) (xy 53.392625 -55.977793) (xy 53.446582 -55.991899) (xy 53.497911 -56.013711)
			(xy 53.545517 -56.042765) (xy 53.588385 -56.07844) (xy 53.625602 -56.119977) (xy 53.656375 -56.16649)
			(xy 53.680047 -56.216987) (xy 53.696115 -56.270394) (xy 53.704235 -56.32557) (xy 53.704744 -56.353456)
			(xy 53.704235 -56.381342) (xy 53.696115 -56.436518) (xy 53.680047 -56.489925) (xy 53.656375 -56.540422)
			(xy 53.625602 -56.586935) (xy 53.588385 -56.628472) (xy 53.545517 -56.664147) (xy 53.497911 -56.693201)
			(xy 53.446582 -56.715013) (xy 53.392625 -56.729119) (xy 53.337188 -56.735219) (xy 53.281454 -56.733182)
			(xy 53.226611 -56.723052) (xy 53.173827 -56.705045) (xy 53.124227 -56.679544) (xy 53.078869 -56.647093)
			(xy 53.03872 -56.608384) (xy 53.004634 -56.564241) (xy 52.977338 -56.515606) (xy 52.957415 -56.463515)
			(xy 52.945289 -56.409078) (xy 52.941218 -56.353456) (xy 50.845334 -56.353456) (xy 50.841409 -56.38013)
			(xy 50.825341 -56.433537) (xy 50.801669 -56.484034) (xy 50.770896 -56.530547) (xy 50.733679 -56.572084)
			(xy 50.690811 -56.607759) (xy 50.643205 -56.636813) (xy 50.591876 -56.658625) (xy 50.537919 -56.672731)
			(xy 50.482482 -56.678831) (xy 50.426748 -56.676794) (xy 50.371905 -56.666664) (xy 50.319121 -56.648657)
			(xy 50.269521 -56.623156) (xy 50.224163 -56.590705) (xy 50.184014 -56.551996) (xy 50.149928 -56.507853)
			(xy 50.122632 -56.459218) (xy 50.102709 -56.407127) (xy 50.090583 -56.35269) (xy 50.086512 -56.297068)
			(xy 49.744654 -56.297068) (xy 49.744654 -56.341052) (xy 49.736898 -56.395002) (xy 49.721543 -56.447299)
			(xy 49.698902 -56.496878) (xy 49.669436 -56.542731) (xy 49.633745 -56.583924) (xy 49.592555 -56.619618)
			(xy 49.546704 -56.649088) (xy 49.497127 -56.671732) (xy 49.444831 -56.687091) (xy 49.390882 -56.694852)
			(xy 49.36363 -56.69534) (xy 49.33626 -56.694871) (xy 49.28208 -56.687056) (xy 49.229577 -56.671569)
			(xy 49.17983 -56.648727) (xy 49.133863 -56.619002) (xy 49.112932 -56.60136) (xy 49.112678 -56.601106)
			(xy 49.105601 -56.595505) (xy 49.088677 -56.589267) (xy 49.079658 -56.588914) (xy 49.012602 -56.588914)
			(xy 49.003585 -56.589269) (xy 48.986668 -56.595518) (xy 48.979582 -56.601106) (xy 48.979582 -56.60136)
			(xy 48.979328 -56.60136) (xy 48.958395 -56.619001) (xy 48.912427 -56.648725) (xy 48.862681 -56.671571)
			(xy 48.810179 -56.687067) (xy 48.756001 -56.694896) (xy 48.701259 -56.694896) (xy 48.647081 -56.687067)
			(xy 48.594579 -56.671571) (xy 48.544833 -56.648725) (xy 48.498865 -56.619001) (xy 48.477932 -56.60136)
			(xy 48.477678 -56.601106) (xy 48.470601 -56.595505) (xy 48.453677 -56.589267) (xy 48.444658 -56.588914)
			(xy 48.377602 -56.588914) (xy 48.368585 -56.589269) (xy 48.351668 -56.595518) (xy 48.344582 -56.601106)
			(xy 48.344074 -56.60136) (xy 48.331339 -56.612303) (xy 48.304248 -56.632145) (xy 48.289972 -56.640984)
			(xy 48.281082 -56.646318) (xy 48.26889 -56.663336) (xy 48.24857 -56.756554) (xy 48.252888 -56.777128)
			(xy 48.25873 -56.785764) (xy 48.27472 -56.809834) (xy 48.300064 -56.861763) (xy 48.317293 -56.91692)
			(xy 48.326011 -56.974042) (xy 48.326548 -57.002934) (xy 48.326062 -57.030185) (xy 48.318306 -57.084133)
			(xy 48.302951 -57.136428) (xy 48.280309 -57.186005) (xy 48.250843 -57.231855) (xy 48.215152 -57.273046)
			(xy 48.173961 -57.308737) (xy 48.128111 -57.338203) (xy 48.078534 -57.360845) (xy 48.026239 -57.3762)
			(xy 47.972291 -57.383956) (xy 47.917789 -57.383956) (xy 47.863841 -57.3762) (xy 47.811546 -57.360845)
			(xy 47.761969 -57.338203) (xy 47.716119 -57.308737) (xy 47.674928 -57.273046) (xy 47.639237 -57.231855)
			(xy 47.609771 -57.186005) (xy 47.587129 -57.136428) (xy 47.571774 -57.084133) (xy 47.564018 -57.030185)
			(xy 47.563532 -57.002934) (xy 45.894407 -57.002934) (xy 45.901135 -57.049479) (xy 45.90161 -57.076848)
			(xy 45.901124 -57.104099) (xy 45.893368 -57.158047) (xy 45.878013 -57.210342) (xy 45.855371 -57.259919)
			(xy 45.825905 -57.305769) (xy 45.790214 -57.34696) (xy 45.749023 -57.382651) (xy 45.703173 -57.412117)
			(xy 45.653596 -57.434759) (xy 45.601301 -57.450114) (xy 45.547353 -57.45787) (xy 45.492851 -57.45787)
			(xy 45.438903 -57.450114) (xy 45.386608 -57.434759) (xy 45.337031 -57.412117) (xy 45.291181 -57.382651)
			(xy 45.24999 -57.34696) (xy 45.214299 -57.305769) (xy 45.184833 -57.259919) (xy 45.162191 -57.210342)
			(xy 45.146836 -57.158047) (xy 45.13908 -57.104099) (xy 45.138594 -57.076848) (xy 44.488808 -57.076848)
			(xy 44.512851 -57.095299) (xy 44.555231 -57.137684) (xy 44.591717 -57.185238) (xy 44.621683 -57.237147)
			(xy 44.644618 -57.292523) (xy 44.660129 -57.35042) (xy 44.667951 -57.409845) (xy 44.66844 -57.439814)
			(xy 44.668006 -57.468047) (xy 44.665871 -57.48528) (xy 56.60593 -57.48528) (xy 56.610001 -57.429658)
			(xy 56.622127 -57.375221) (xy 56.64205 -57.32313) (xy 56.669346 -57.274495) (xy 56.703432 -57.230352)
			(xy 56.743581 -57.191643) (xy 56.788939 -57.159192) (xy 56.838539 -57.133691) (xy 56.891323 -57.115684)
			(xy 56.946166 -57.105554) (xy 57.0019 -57.103517) (xy 57.057337 -57.109617) (xy 57.111294 -57.123723)
			(xy 57.162623 -57.145535) (xy 57.210229 -57.174589) (xy 57.253097 -57.210264) (xy 57.290314 -57.251801)
			(xy 57.321087 -57.298314) (xy 57.344759 -57.348811) (xy 57.360827 -57.402218) (xy 57.368947 -57.457394)
			(xy 57.369456 -57.48528) (xy 57.368947 -57.513166) (xy 57.360827 -57.568342) (xy 57.344759 -57.621749)
			(xy 57.321087 -57.672246) (xy 57.290314 -57.718759) (xy 57.253097 -57.760296) (xy 57.210229 -57.795971)
			(xy 57.162623 -57.825025) (xy 57.111294 -57.846837) (xy 57.057337 -57.860943) (xy 57.0019 -57.867043)
			(xy 56.946166 -57.865006) (xy 56.891323 -57.854876) (xy 56.838539 -57.836869) (xy 56.788939 -57.811368)
			(xy 56.743581 -57.778917) (xy 56.703432 -57.740208) (xy 56.669346 -57.696065) (xy 56.64205 -57.64743)
			(xy 56.622127 -57.595339) (xy 56.610001 -57.540902) (xy 56.60593 -57.48528) (xy 44.665871 -57.48528)
			(xy 44.661065 -57.524084) (xy 44.647277 -57.578841) (xy 44.626853 -57.631484) (xy 44.600104 -57.681211)
			(xy 44.584112 -57.704482) (xy 44.576746 -57.71515) (xy 44.573698 -57.740804) (xy 44.616116 -57.844436)
			(xy 44.636182 -57.860692) (xy 44.649136 -57.862978) (xy 44.675245 -57.868121) (xy 44.725816 -57.88468)
			(xy 44.773596 -57.908103) (xy 44.81766 -57.937936) (xy 44.857152 -57.9736) (xy 44.891308 -58.014405)
			(xy 44.919465 -58.059558) (xy 44.941076 -58.108185) (xy 44.955723 -58.159342) (xy 44.963123 -58.212038)
			(xy 44.963588 -58.238644) (xy 44.963092 -58.266013) (xy 44.955282 -58.320191) (xy 44.9398 -58.372694)
			(xy 44.916965 -58.422441) (xy 44.887246 -58.468409) (xy 44.869608 -58.489342) (xy 44.869354 -58.489596)
			(xy 44.863757 -58.496676) (xy 44.857518 -58.513598) (xy 44.857162 -58.522616) (xy 44.857162 -58.589672)
			(xy 44.857541 -58.598686) (xy 44.863774 -58.615603) (xy 44.869354 -58.622692) (xy 44.869608 -58.622692)
			(xy 44.869608 -58.622946) (xy 44.887236 -58.643887) (xy 44.910148 -58.679334) (xy 47.995332 -58.679334)
			(xy 47.995745 -58.653018) (xy 48.00299 -58.600887) (xy 48.017319 -58.550243) (xy 48.038461 -58.502044)
			(xy 48.066017 -58.457202) (xy 48.099466 -58.416565) (xy 48.118522 -58.39841) (xy 48.125925 -58.39089)
			(xy 48.134448 -58.371608) (xy 48.135032 -58.361072) (xy 48.135032 -58.286396) (xy 48.134509 -58.275846)
			(xy 48.125968 -58.256551) (xy 48.118522 -58.249058) (xy 48.099457 -58.230912) (xy 48.066 -58.19028)
			(xy 48.038442 -58.145438) (xy 48.017305 -58.097236) (xy 48.00299 -58.046586) (xy 47.995768 -57.994451)
			(xy 47.995332 -57.968134) (xy 47.995818 -57.940883) (xy 48.003574 -57.886935) (xy 48.018929 -57.83464)
			(xy 48.041571 -57.785063) (xy 48.071037 -57.739213) (xy 48.106728 -57.698022) (xy 48.147919 -57.662331)
			(xy 48.193769 -57.632865) (xy 48.243346 -57.610223) (xy 48.295641 -57.594868) (xy 48.349589 -57.587112)
			(xy 48.404091 -57.587112) (xy 48.458039 -57.594868) (xy 48.510334 -57.610223) (xy 48.559911 -57.632865)
			(xy 48.605761 -57.662331) (xy 48.646952 -57.698022) (xy 48.682643 -57.739213) (xy 48.712109 -57.785063)
			(xy 48.734751 -57.83464) (xy 48.750106 -57.886935) (xy 48.757862 -57.940883) (xy 48.758348 -57.968134)
			(xy 48.75792 -57.994449) (xy 48.750679 -58.04658) (xy 48.736354 -58.097225) (xy 48.734154 -58.102242)
			(xy 51.918344 -58.102242) (xy 51.918344 -58.042306) (xy 51.926167 -57.982884) (xy 51.94168 -57.924991)
			(xy 51.964616 -57.869618) (xy 51.994583 -57.817712) (xy 52.03107 -57.770162) (xy 52.07345 -57.727782)
			(xy 52.121 -57.691295) (xy 52.172906 -57.661328) (xy 52.228279 -57.638392) (xy 52.286172 -57.622879)
			(xy 52.345594 -57.615056) (xy 52.40553 -57.615056) (xy 52.464952 -57.622879) (xy 52.522845 -57.638392)
			(xy 52.578218 -57.661328) (xy 52.630124 -57.691295) (xy 52.677674 -57.727782) (xy 52.720054 -57.770162)
			(xy 52.756541 -57.817712) (xy 52.786508 -57.869618) (xy 52.809444 -57.924991) (xy 52.824957 -57.982884)
			(xy 52.83278 -58.042306) (xy 52.83327 -58.072274) (xy 52.83278 -58.102242) (xy 52.832278 -58.106052)
			(xy 57.282824 -58.106052) (xy 57.282824 -58.046116) (xy 57.290647 -57.986694) (xy 57.30616 -57.928801)
			(xy 57.329096 -57.873428) (xy 57.359063 -57.821522) (xy 57.39555 -57.773972) (xy 57.43793 -57.731592)
			(xy 57.48548 -57.695105) (xy 57.537386 -57.665138) (xy 57.592759 -57.642202) (xy 57.650652 -57.626689)
			(xy 57.710074 -57.618866) (xy 57.77001 -57.618866) (xy 57.829432 -57.626689) (xy 57.887325 -57.642202)
			(xy 57.942698 -57.665138) (xy 57.994604 -57.695105) (xy 58.042154 -57.731592) (xy 58.084534 -57.773972)
			(xy 58.121021 -57.821522) (xy 58.150988 -57.873428) (xy 58.160861 -57.897264) (xy 59.567808 -57.897264)
			(xy 59.567808 -57.837328) (xy 59.575631 -57.777906) (xy 59.591144 -57.720013) (xy 59.61408 -57.66464)
			(xy 59.644047 -57.612734) (xy 59.680534 -57.565184) (xy 59.722914 -57.522804) (xy 59.770464 -57.486317)
			(xy 59.82237 -57.45635) (xy 59.877743 -57.433414) (xy 59.935636 -57.417901) (xy 59.995058 -57.410078)
			(xy 60.054994 -57.410078) (xy 60.114416 -57.417901) (xy 60.172309 -57.433414) (xy 60.227682 -57.45635)
			(xy 60.279588 -57.486317) (xy 60.327138 -57.522804) (xy 60.369518 -57.565184) (xy 60.406005 -57.612734)
			(xy 60.435972 -57.66464) (xy 60.458908 -57.720013) (xy 60.474421 -57.777906) (xy 60.482244 -57.837328)
			(xy 60.482734 -57.867296) (xy 60.482244 -57.897264) (xy 60.474421 -57.956686) (xy 60.458908 -58.014579)
			(xy 60.435972 -58.069952) (xy 60.406005 -58.121858) (xy 60.369518 -58.169408) (xy 60.327138 -58.211788)
			(xy 60.279588 -58.248275) (xy 60.227682 -58.278242) (xy 60.172309 -58.301178) (xy 60.114416 -58.316691)
			(xy 60.054994 -58.324514) (xy 59.995058 -58.324514) (xy 59.935636 -58.316691) (xy 59.877743 -58.301178)
			(xy 59.82237 -58.278242) (xy 59.770464 -58.248275) (xy 59.722914 -58.211788) (xy 59.680534 -58.169408)
			(xy 59.644047 -58.121858) (xy 59.61408 -58.069952) (xy 59.591144 -58.014579) (xy 59.575631 -57.956686)
			(xy 59.567808 -57.897264) (xy 58.160861 -57.897264) (xy 58.173924 -57.928801) (xy 58.189437 -57.986694)
			(xy 58.19726 -58.046116) (xy 58.19775 -58.076084) (xy 58.19726 -58.106052) (xy 58.189437 -58.165474)
			(xy 58.173924 -58.223367) (xy 58.150988 -58.27874) (xy 58.121021 -58.330646) (xy 58.084534 -58.378196)
			(xy 58.042154 -58.420576) (xy 57.994604 -58.457063) (xy 57.942698 -58.48703) (xy 57.887325 -58.509966)
			(xy 57.829432 -58.525479) (xy 57.77001 -58.533302) (xy 57.710074 -58.533302) (xy 57.650652 -58.525479)
			(xy 57.592759 -58.509966) (xy 57.537386 -58.48703) (xy 57.48548 -58.457063) (xy 57.43793 -58.420576)
			(xy 57.39555 -58.378196) (xy 57.359063 -58.330646) (xy 57.329096 -58.27874) (xy 57.30616 -58.223367)
			(xy 57.290647 -58.165474) (xy 57.282824 -58.106052) (xy 52.832278 -58.106052) (xy 52.824957 -58.161664)
			(xy 52.809444 -58.219557) (xy 52.786508 -58.27493) (xy 52.756541 -58.326836) (xy 52.720054 -58.374386)
			(xy 52.677674 -58.416766) (xy 52.630124 -58.453253) (xy 52.578218 -58.48322) (xy 52.522845 -58.506156)
			(xy 52.464952 -58.521669) (xy 52.40553 -58.529492) (xy 52.345594 -58.529492) (xy 52.286172 -58.521669)
			(xy 52.228279 -58.506156) (xy 52.172906 -58.48322) (xy 52.121 -58.453253) (xy 52.07345 -58.416766)
			(xy 52.03107 -58.374386) (xy 51.994583 -58.326836) (xy 51.964616 -58.27493) (xy 51.94168 -58.219557)
			(xy 51.926167 -58.161664) (xy 51.918344 -58.102242) (xy 48.734154 -58.102242) (xy 48.715214 -58.145424)
			(xy 48.68766 -58.190266) (xy 48.654213 -58.230903) (xy 48.635158 -58.249058) (xy 48.627781 -58.256601)
			(xy 48.619241 -58.275864) (xy 48.618648 -58.286396) (xy 48.618648 -58.361072) (xy 48.619165 -58.371623)
			(xy 48.627707 -58.39092) (xy 48.635158 -58.39841) (xy 48.654222 -58.416556) (xy 48.687677 -58.457189)
			(xy 48.715233 -58.502032) (xy 48.736369 -58.550234) (xy 48.747946 -58.591192) (xy 58.487038 -58.591192)
			(xy 58.487038 -58.531256) (xy 58.494861 -58.471834) (xy 58.510374 -58.413941) (xy 58.53331 -58.358568)
			(xy 58.563277 -58.306662) (xy 58.599764 -58.259112) (xy 58.642144 -58.216732) (xy 58.689694 -58.180245)
			(xy 58.7416 -58.150278) (xy 58.796973 -58.127342) (xy 58.854866 -58.111829) (xy 58.914288 -58.104006)
			(xy 58.974224 -58.104006) (xy 59.033646 -58.111829) (xy 59.091539 -58.127342) (xy 59.146912 -58.150278)
			(xy 59.198818 -58.180245) (xy 59.246368 -58.216732) (xy 59.288748 -58.259112) (xy 59.325235 -58.306662)
			(xy 59.355202 -58.358568) (xy 59.378138 -58.413941) (xy 59.393651 -58.471834) (xy 59.394685 -58.479686)
			(xy 60.733668 -58.479686) (xy 60.733668 -58.41975) (xy 60.741491 -58.360328) (xy 60.757004 -58.302435)
			(xy 60.77994 -58.247062) (xy 60.809907 -58.195156) (xy 60.846394 -58.147606) (xy 60.888774 -58.105226)
			(xy 60.936324 -58.068739) (xy 60.98823 -58.038772) (xy 61.043603 -58.015836) (xy 61.101496 -58.000323)
			(xy 61.160918 -57.9925) (xy 61.220854 -57.9925) (xy 61.280276 -58.000323) (xy 61.338169 -58.015836)
			(xy 61.393542 -58.038772) (xy 61.445448 -58.068739) (xy 61.492998 -58.105226) (xy 61.535378 -58.147606)
			(xy 61.571865 -58.195156) (xy 61.601832 -58.247062) (xy 61.624768 -58.302435) (xy 61.640281 -58.360328)
			(xy 61.648104 -58.41975) (xy 61.648594 -58.449718) (xy 61.648104 -58.479686) (xy 61.640281 -58.539108)
			(xy 61.624768 -58.597001) (xy 61.601832 -58.652374) (xy 61.571865 -58.70428) (xy 61.551052 -58.731404)
			(xy 65.52057 -58.731404) (xy 65.521021 -58.704033) (xy 65.52884 -58.649853) (xy 65.544332 -58.597349)
			(xy 65.567177 -58.547602) (xy 65.596906 -58.501636) (xy 65.61455 -58.480706) (xy 65.614804 -58.480452)
			(xy 65.620375 -58.473355) (xy 65.626631 -58.456446) (xy 65.626996 -58.447432) (xy 65.626996 -58.380376)
			(xy 65.626651 -58.371358) (xy 65.620395 -58.354441) (xy 65.614804 -58.347356) (xy 65.61455 -58.347356)
			(xy 65.61455 -58.347102) (xy 65.596912 -58.326167) (xy 65.567186 -58.2802) (xy 65.544339 -58.230454)
			(xy 65.528841 -58.177952) (xy 65.521012 -58.123774) (xy 65.521011 -58.069032) (xy 65.52884 -58.014854)
			(xy 65.544336 -57.962352) (xy 65.567183 -57.912605) (xy 65.596909 -57.866638) (xy 65.61455 -57.845706)
			(xy 65.614804 -57.845452) (xy 65.620375 -57.838355) (xy 65.626631 -57.821446) (xy 65.626996 -57.812432)
			(xy 65.626996 -57.745376) (xy 65.626651 -57.736358) (xy 65.620395 -57.719441) (xy 65.614804 -57.712356)
			(xy 65.61455 -57.712356) (xy 65.61455 -57.712102) (xy 65.596912 -57.691167) (xy 65.567186 -57.6452)
			(xy 65.544339 -57.595454) (xy 65.528841 -57.542952) (xy 65.521012 -57.488774) (xy 65.521011 -57.434032)
			(xy 65.52884 -57.379854) (xy 65.544336 -57.327352) (xy 65.567183 -57.277605) (xy 65.596909 -57.231638)
			(xy 65.61455 -57.210706) (xy 65.614804 -57.210452) (xy 65.620375 -57.203355) (xy 65.626631 -57.186446)
			(xy 65.626996 -57.177432) (xy 65.626996 -57.110376) (xy 65.626651 -57.101358) (xy 65.620395 -57.084441)
			(xy 65.614804 -57.077356) (xy 65.61455 -57.077356) (xy 65.61455 -57.077102) (xy 65.596906 -57.056174)
			(xy 65.567193 -57.010201) (xy 65.544357 -56.960452) (xy 65.528868 -56.90795) (xy 65.521042 -56.853774)
			(xy 65.52057 -56.826404) (xy 65.521056 -56.799153) (xy 65.528812 -56.745205) (xy 65.544167 -56.69291)
			(xy 65.566809 -56.643333) (xy 65.596275 -56.597483) (xy 65.631966 -56.556292) (xy 65.673157 -56.520601)
			(xy 65.719007 -56.491135) (xy 65.768584 -56.468493) (xy 65.820879 -56.453138) (xy 65.874827 -56.445382)
			(xy 65.929329 -56.445382) (xy 65.983277 -56.453138) (xy 66.035572 -56.468493) (xy 66.085149 -56.491135)
			(xy 66.130999 -56.520601) (xy 66.17219 -56.556292) (xy 66.207881 -56.597483) (xy 66.237347 -56.643333)
			(xy 66.259989 -56.69291) (xy 66.275344 -56.745205) (xy 66.2831 -56.799153) (xy 66.283296 -56.810148)
			(xy 68.100194 -56.810148) (xy 68.100194 -56.809894) (xy 68.100684 -56.779926) (xy 68.108507 -56.720504)
			(xy 68.12402 -56.662611) (xy 68.146956 -56.607238) (xy 68.176923 -56.555332) (xy 68.21341 -56.507782)
			(xy 68.25579 -56.465402) (xy 68.30334 -56.428915) (xy 68.355246 -56.398948) (xy 68.410619 -56.376012)
			(xy 68.468512 -56.360499) (xy 68.527934 -56.352676) (xy 68.58787 -56.352676) (xy 68.647292 -56.360499)
			(xy 68.705185 -56.376012) (xy 68.760558 -56.398948) (xy 68.812464 -56.428915) (xy 68.860014 -56.465402)
			(xy 68.902394 -56.507782) (xy 68.938881 -56.555332) (xy 68.968848 -56.607238) (xy 68.991784 -56.662611)
			(xy 69.007297 -56.720504) (xy 69.01512 -56.779926) (xy 69.01561 -56.809894) (xy 69.01561 -56.810148)
			(xy 69.015033 -56.841671) (xy 69.006365 -56.904119) (xy 68.989213 -56.964787) (xy 68.9639 -57.022529)
			(xy 68.930907 -57.076253) (xy 68.890855 -57.124943) (xy 68.868036 -57.146698) (xy 68.860924 -57.153302)
			(xy 68.852542 -57.17032) (xy 68.846192 -57.248806) (xy 68.845827 -57.258371) (xy 68.851444 -57.276654)
			(xy 68.857114 -57.284366) (xy 68.872649 -57.304651) (xy 68.898709 -57.3486) (xy 68.918673 -57.395633)
			(xy 68.932184 -57.444909) (xy 68.935165 -57.467049) (xy 69.118492 -57.467049) (xy 69.118492 -57.412551)
			(xy 69.126248 -57.358607) (xy 69.141601 -57.306316) (xy 69.16424 -57.256742) (xy 69.193704 -57.210894)
			(xy 69.229392 -57.169706) (xy 69.270578 -57.134016) (xy 69.316424 -57.10455) (xy 69.365997 -57.081908)
			(xy 69.418287 -57.066552) (xy 69.472231 -57.058794) (xy 69.49948 -57.058306) (xy 69.525028 -57.058711)
			(xy 69.575668 -57.065519) (xy 69.624945 -57.079029) (xy 69.671976 -57.098998) (xy 69.71592 -57.12507)
			(xy 69.736208 -57.140602) (xy 69.743932 -57.146243) (xy 69.762208 -57.151841) (xy 69.771768 -57.151524)
			(xy 69.850254 -57.145174) (xy 69.867272 -57.136792) (xy 69.873876 -57.12968) (xy 69.89564 -57.106865)
			(xy 69.944312 -57.066783) (xy 69.998029 -57.033767) (xy 70.055772 -57.008443) (xy 70.116445 -56.991289)
			(xy 70.1789 -56.982632) (xy 70.210426 -56.982106) (xy 70.21068 -56.982106) (xy 70.240649 -56.98258)
			(xy 70.300075 -56.990401) (xy 70.357971 -57.005912) (xy 70.413348 -57.028848) (xy 70.465256 -57.058817)
			(xy 70.488756 -57.076848) (xy 71.138542 -57.076848) (xy 71.139026 -57.049478) (xy 71.146838 -56.9953)
			(xy 71.162322 -56.942796) (xy 71.18516 -56.893049) (xy 71.214882 -56.847082) (xy 71.232522 -56.82615)
			(xy 71.232776 -56.825896) (xy 71.238379 -56.818821) (xy 71.244614 -56.801895) (xy 71.244968 -56.792876)
			(xy 71.244968 -56.72582) (xy 71.244608 -56.716803) (xy 71.238363 -56.699886) (xy 71.232776 -56.6928)
			(xy 71.232522 -56.6928) (xy 71.232522 -56.692546) (xy 71.214894 -56.671605) (xy 71.18518 -56.625635)
			(xy 71.162342 -56.57589) (xy 71.146848 -56.523391) (xy 71.139017 -56.469217) (xy 71.138542 -56.441848)
			(xy 71.139028 -56.414597) (xy 71.146784 -56.360649) (xy 71.162139 -56.308354) (xy 71.184781 -56.258777)
			(xy 71.214247 -56.212927) (xy 71.249938 -56.171736) (xy 71.291129 -56.136045) (xy 71.336979 -56.106579)
			(xy 71.386556 -56.083937) (xy 71.438851 -56.068582) (xy 71.492799 -56.060826) (xy 71.547301 -56.060826)
			(xy 71.601249 -56.068582) (xy 71.653544 -56.083937) (xy 71.703121 -56.106579) (xy 71.748971 -56.136045)
			(xy 71.790162 -56.171736) (xy 71.825853 -56.212927) (xy 71.855319 -56.258777) (xy 71.877961 -56.308354)
			(xy 71.893316 -56.360649) (xy 71.901072 -56.414597) (xy 71.901558 -56.441848) (xy 71.901072 -56.469218)
			(xy 71.89326 -56.523396) (xy 71.877777 -56.5759) (xy 71.854939 -56.625647) (xy 71.825218 -56.671614)
			(xy 71.807578 -56.692546) (xy 71.807324 -56.6928) (xy 71.801722 -56.699876) (xy 71.795487 -56.716801)
			(xy 71.795132 -56.72582) (xy 71.795132 -56.792876) (xy 71.795494 -56.801893) (xy 71.801737 -56.81881)
			(xy 71.807324 -56.825896) (xy 71.807578 -56.825896) (xy 71.807578 -56.82615) (xy 71.825204 -56.847093)
			(xy 71.854918 -56.893062) (xy 71.877757 -56.942807) (xy 71.893251 -56.995306) (xy 71.894354 -57.002934)
			(xy 73.56348 -57.002934) (xy 73.564003 -56.974843) (xy 73.572225 -56.919268) (xy 73.588511 -56.865499)
			(xy 73.612509 -56.814702) (xy 73.6437 -56.767975) (xy 73.681408 -56.726329) (xy 73.724817 -56.690665)
			(xy 73.748646 -56.675782) (xy 73.757536 -56.670448) (xy 73.769728 -56.65343) (xy 73.790048 -56.560212)
			(xy 73.78573 -56.539638) (xy 73.779888 -56.531002) (xy 73.763885 -56.50694) (xy 73.738544 -56.455008)
			(xy 73.721319 -56.399849) (xy 73.712604 -56.342725) (xy 73.71207 -56.313832) (xy 73.712585 -56.286581)
			(xy 73.720337 -56.232633) (xy 73.735688 -56.180337) (xy 73.758325 -56.130759) (xy 73.787788 -56.084907)
			(xy 73.823476 -56.043714) (xy 73.864663 -56.00802) (xy 73.910511 -55.978551) (xy 73.960087 -55.955907)
			(xy 74.01238 -55.940549) (xy 74.066327 -55.932789) (xy 74.093578 -55.932324) (xy 74.120948 -55.932797)
			(xy 74.175127 -55.940612) (xy 74.22763 -55.956099) (xy 74.277377 -55.97894) (xy 74.323344 -56.008663)
			(xy 74.344276 -56.026304) (xy 74.34453 -56.026558) (xy 74.351627 -56.032128) (xy 74.368536 -56.038383)
			(xy 74.37755 -56.03875) (xy 74.444606 -56.03875) (xy 74.453624 -56.038406) (xy 74.470542 -56.032151)
			(xy 74.477626 -56.026558) (xy 74.477626 -56.026304) (xy 74.47788 -56.026304) (xy 74.498813 -56.008663)
			(xy 74.544781 -55.978939) (xy 74.594527 -55.956093) (xy 74.647029 -55.940597) (xy 74.701207 -55.932768)
			(xy 74.755949 -55.932768) (xy 74.810127 -55.940597) (xy 74.862629 -55.956093) (xy 74.912375 -55.978939)
			(xy 74.958343 -56.008663) (xy 74.979276 -56.026304) (xy 74.97953 -56.026558) (xy 74.986627 -56.032128)
			(xy 75.003536 -56.038383) (xy 75.01255 -56.03875) (xy 75.079606 -56.03875) (xy 75.088624 -56.038406)
			(xy 75.105542 -56.032151) (xy 75.112626 -56.026558) (xy 75.112626 -56.026304) (xy 75.11288 -56.026304)
			(xy 75.133809 -56.008661) (xy 75.179783 -55.97895) (xy 75.229531 -55.956115) (xy 75.282032 -55.940624)
			(xy 75.336209 -55.932797) (xy 75.363578 -55.932324) (xy 75.390834 -55.932721) (xy 75.444792 -55.940477)
			(xy 75.497097 -55.955832) (xy 75.546684 -55.978475) (xy 75.592544 -56.007945) (xy 75.633743 -56.043642)
			(xy 75.669442 -56.084838) (xy 75.698914 -56.130697) (xy 75.72156 -56.180282) (xy 75.736919 -56.232586)
			(xy 75.744677 -56.286544) (xy 75.744677 -56.297068) (xy 76.08646 -56.297068) (xy 76.090531 -56.241446)
			(xy 76.102657 -56.187009) (xy 76.12258 -56.134918) (xy 76.149876 -56.086283) (xy 76.183962 -56.04214)
			(xy 76.224111 -56.003431) (xy 76.269469 -55.97098) (xy 76.319069 -55.945479) (xy 76.371853 -55.927472)
			(xy 76.426696 -55.917342) (xy 76.48243 -55.915305) (xy 76.537867 -55.921405) (xy 76.591824 -55.935511)
			(xy 76.643153 -55.957323) (xy 76.690759 -55.986377) (xy 76.733627 -56.022052) (xy 76.770844 -56.063589)
			(xy 76.801617 -56.110102) (xy 76.825289 -56.160599) (xy 76.841357 -56.214006) (xy 76.849477 -56.269182)
			(xy 76.849986 -56.297068) (xy 76.849477 -56.324954) (xy 76.845282 -56.353456) (xy 78.941166 -56.353456)
			(xy 78.945237 -56.297834) (xy 78.957363 -56.243397) (xy 78.977286 -56.191306) (xy 79.004582 -56.142671)
			(xy 79.038668 -56.098528) (xy 79.078817 -56.059819) (xy 79.124175 -56.027368) (xy 79.173775 -56.001867)
			(xy 79.226559 -55.98386) (xy 79.281402 -55.97373) (xy 79.337136 -55.971693) (xy 79.392573 -55.977793)
			(xy 79.44653 -55.991899) (xy 79.497859 -56.013711) (xy 79.545465 -56.042765) (xy 79.588333 -56.07844)
			(xy 79.62555 -56.119977) (xy 79.656323 -56.16649) (xy 79.679995 -56.216987) (xy 79.696063 -56.270394)
			(xy 79.704183 -56.32557) (xy 79.704692 -56.353456) (xy 79.704183 -56.381342) (xy 79.696063 -56.436518)
			(xy 79.679995 -56.489925) (xy 79.656323 -56.540422) (xy 79.62555 -56.586935) (xy 79.588333 -56.628472)
			(xy 79.545465 -56.664147) (xy 79.497859 -56.693201) (xy 79.44653 -56.715013) (xy 79.392573 -56.729119)
			(xy 79.337136 -56.735219) (xy 79.281402 -56.733182) (xy 79.226559 -56.723052) (xy 79.173775 -56.705045)
			(xy 79.124175 -56.679544) (xy 79.078817 -56.647093) (xy 79.038668 -56.608384) (xy 79.004582 -56.564241)
			(xy 78.977286 -56.515606) (xy 78.957363 -56.463515) (xy 78.945237 -56.409078) (xy 78.941166 -56.353456)
			(xy 76.845282 -56.353456) (xy 76.841357 -56.38013) (xy 76.825289 -56.433537) (xy 76.801617 -56.484034)
			(xy 76.770844 -56.530547) (xy 76.733627 -56.572084) (xy 76.690759 -56.607759) (xy 76.643153 -56.636813)
			(xy 76.591824 -56.658625) (xy 76.537867 -56.672731) (xy 76.48243 -56.678831) (xy 76.426696 -56.676794)
			(xy 76.371853 -56.666664) (xy 76.319069 -56.648657) (xy 76.269469 -56.623156) (xy 76.224111 -56.590705)
			(xy 76.183962 -56.551996) (xy 76.149876 -56.507853) (xy 76.12258 -56.459218) (xy 76.102657 -56.407127)
			(xy 76.090531 -56.35269) (xy 76.08646 -56.297068) (xy 75.744677 -56.297068) (xy 75.744677 -56.341056)
			(xy 75.736919 -56.395014) (xy 75.72156 -56.447318) (xy 75.698914 -56.496903) (xy 75.669442 -56.542762)
			(xy 75.633743 -56.583958) (xy 75.592544 -56.619655) (xy 75.546684 -56.649125) (xy 75.497097 -56.671768)
			(xy 75.444792 -56.687123) (xy 75.390834 -56.694879) (xy 75.363578 -56.69534) (xy 75.336207 -56.694901)
			(xy 75.282026 -56.687079) (xy 75.229522 -56.671585) (xy 75.179775 -56.648736) (xy 75.13381 -56.619005)
			(xy 75.11288 -56.60136) (xy 75.112626 -56.601106) (xy 75.105536 -56.595525) (xy 75.088622 -56.589275)
			(xy 75.079606 -56.588914) (xy 75.01255 -56.588914) (xy 75.003535 -56.589292) (xy 74.986618 -56.595525)
			(xy 74.97953 -56.601106) (xy 74.97953 -56.60136) (xy 74.979276 -56.60136) (xy 74.958343 -56.619001)
			(xy 74.912375 -56.648725) (xy 74.862629 -56.671571) (xy 74.810127 -56.687067) (xy 74.755949 -56.694896)
			(xy 74.701207 -56.694896) (xy 74.647029 -56.687067) (xy 74.594527 -56.671571) (xy 74.544781 -56.648725)
			(xy 74.498813 -56.619001) (xy 74.47788 -56.60136) (xy 74.477626 -56.601106) (xy 74.470536 -56.595525)
			(xy 74.453622 -56.589275) (xy 74.444606 -56.588914) (xy 74.37755 -56.588914) (xy 74.368535 -56.589292)
			(xy 74.351618 -56.595525) (xy 74.34453 -56.601106) (xy 74.344022 -56.60136) (xy 74.33129 -56.612307)
			(xy 74.304197 -56.632146) (xy 74.28992 -56.640984) (xy 74.28103 -56.646318) (xy 74.268838 -56.663336)
			(xy 74.248518 -56.756554) (xy 74.252836 -56.777128) (xy 74.258678 -56.785764) (xy 74.274662 -56.809838)
			(xy 74.300009 -56.861765) (xy 74.317239 -56.91692) (xy 74.325959 -56.974042) (xy 74.326496 -57.002934)
			(xy 74.32601 -57.030185) (xy 74.318254 -57.084133) (xy 74.302899 -57.136428) (xy 74.280257 -57.186005)
			(xy 74.250791 -57.231855) (xy 74.2151 -57.273046) (xy 74.173909 -57.308737) (xy 74.128059 -57.338203)
			(xy 74.078482 -57.360845) (xy 74.026187 -57.3762) (xy 73.972239 -57.383956) (xy 73.917737 -57.383956)
			(xy 73.863789 -57.3762) (xy 73.811494 -57.360845) (xy 73.761917 -57.338203) (xy 73.716067 -57.308737)
			(xy 73.674876 -57.273046) (xy 73.639185 -57.231855) (xy 73.609719 -57.186005) (xy 73.587077 -57.136428)
			(xy 73.571722 -57.084133) (xy 73.563966 -57.030185) (xy 73.56348 -57.002934) (xy 71.894354 -57.002934)
			(xy 71.901083 -57.04948) (xy 71.901558 -57.076848) (xy 71.901072 -57.104099) (xy 71.893316 -57.158047)
			(xy 71.877961 -57.210342) (xy 71.855319 -57.259919) (xy 71.825853 -57.305769) (xy 71.790162 -57.34696)
			(xy 71.748971 -57.382651) (xy 71.703121 -57.412117) (xy 71.653544 -57.434759) (xy 71.601249 -57.450114)
			(xy 71.547301 -57.45787) (xy 71.492799 -57.45787) (xy 71.438851 -57.450114) (xy 71.386556 -57.434759)
			(xy 71.336979 -57.412117) (xy 71.291129 -57.382651) (xy 71.249938 -57.34696) (xy 71.214247 -57.305769)
			(xy 71.184781 -57.259919) (xy 71.162139 -57.210342) (xy 71.146784 -57.158047) (xy 71.139028 -57.104099)
			(xy 71.138542 -57.076848) (xy 70.488756 -57.076848) (xy 70.512809 -57.095304) (xy 70.555192 -57.137687)
			(xy 70.59168 -57.185239) (xy 70.621649 -57.237147) (xy 70.644586 -57.292523) (xy 70.660098 -57.350419)
			(xy 70.66792 -57.409845) (xy 70.668388 -57.439814) (xy 70.667945 -57.468047) (xy 70.665811 -57.48528)
			(xy 82.605878 -57.48528) (xy 82.609949 -57.429658) (xy 82.622075 -57.375221) (xy 82.641998 -57.32313)
			(xy 82.669294 -57.274495) (xy 82.70338 -57.230352) (xy 82.743529 -57.191643) (xy 82.788887 -57.159192)
			(xy 82.838487 -57.133691) (xy 82.891271 -57.115684) (xy 82.946114 -57.105554) (xy 83.001848 -57.103517)
			(xy 83.057285 -57.109617) (xy 83.111242 -57.123723) (xy 83.162571 -57.145535) (xy 83.210177 -57.174589)
			(xy 83.253045 -57.210264) (xy 83.290262 -57.251801) (xy 83.321035 -57.298314) (xy 83.344707 -57.348811)
			(xy 83.360775 -57.402218) (xy 83.368895 -57.457394) (xy 83.369404 -57.48528) (xy 83.368895 -57.513166)
			(xy 83.360775 -57.568342) (xy 83.344707 -57.621749) (xy 83.321035 -57.672246) (xy 83.290262 -57.718759)
			(xy 83.253045 -57.760296) (xy 83.210177 -57.795971) (xy 83.162571 -57.825025) (xy 83.111242 -57.846837)
			(xy 83.057285 -57.860943) (xy 83.001848 -57.867043) (xy 82.946114 -57.865006) (xy 82.891271 -57.854876)
			(xy 82.838487 -57.836869) (xy 82.788887 -57.811368) (xy 82.743529 -57.778917) (xy 82.70338 -57.740208)
			(xy 82.669294 -57.696065) (xy 82.641998 -57.64743) (xy 82.622075 -57.595339) (xy 82.609949 -57.540902)
			(xy 82.605878 -57.48528) (xy 70.665811 -57.48528) (xy 70.661005 -57.524083) (xy 70.647219 -57.57884)
			(xy 70.626797 -57.631482) (xy 70.60005 -57.681211) (xy 70.58406 -57.704482) (xy 70.576694 -57.71515)
			(xy 70.573646 -57.740804) (xy 70.616064 -57.844436) (xy 70.63613 -57.860692) (xy 70.649084 -57.862978)
			(xy 70.6752 -57.868086) (xy 70.725771 -57.884651) (xy 70.773551 -57.908079) (xy 70.817614 -57.937917)
			(xy 70.857105 -57.973586) (xy 70.891259 -58.014394) (xy 70.919415 -58.05955) (xy 70.941025 -58.108179)
			(xy 70.955672 -58.159339) (xy 70.963071 -58.212037) (xy 70.963536 -58.238644) (xy 70.963053 -58.266014)
			(xy 70.955241 -58.320193) (xy 70.939757 -58.372696) (xy 70.916919 -58.422444) (xy 70.887197 -58.46841)
			(xy 70.869556 -58.489342) (xy 70.869302 -58.489596) (xy 70.863711 -58.49668) (xy 70.857467 -58.513599)
			(xy 70.85711 -58.522616) (xy 70.85711 -58.589672) (xy 70.857478 -58.598688) (xy 70.863718 -58.615605)
			(xy 70.869302 -58.622692) (xy 70.869556 -58.622692) (xy 70.869556 -58.622946) (xy 70.887176 -58.643893)
			(xy 70.910088 -58.679334) (xy 73.99528 -58.679334) (xy 73.99571 -58.653019) (xy 74.002953 -58.600889)
			(xy 74.01728 -58.550246) (xy 74.03842 -58.502047) (xy 74.065972 -58.457204) (xy 74.099416 -58.416566)
			(xy 74.11847 -58.39841) (xy 74.125865 -58.390883) (xy 74.134394 -58.371607) (xy 74.13498 -58.361072)
			(xy 74.13498 -58.286396) (xy 74.134472 -58.275844) (xy 74.125923 -58.256548) (xy 74.11847 -58.249058)
			(xy 74.099395 -58.230922) (xy 74.065941 -58.190287) (xy 74.038385 -58.145443) (xy 74.01725 -58.097238)
			(xy 74.002937 -58.046588) (xy 73.995716 -57.994451) (xy 73.99528 -57.968134) (xy 73.995766 -57.940883)
			(xy 74.003522 -57.886935) (xy 74.018877 -57.83464) (xy 74.041519 -57.785063) (xy 74.070985 -57.739213)
			(xy 74.106676 -57.698022) (xy 74.147867 -57.662331) (xy 74.193717 -57.632865) (xy 74.243294 -57.610223)
			(xy 74.295589 -57.594868) (xy 74.349537 -57.587112) (xy 74.404039 -57.587112) (xy 74.457987 -57.594868)
			(xy 74.510282 -57.610223) (xy 74.559859 -57.632865) (xy 74.605709 -57.662331) (xy 74.6469 -57.698022)
			(xy 74.682591 -57.739213) (xy 74.712057 -57.785063) (xy 74.734699 -57.83464) (xy 74.750054 -57.886935)
			(xy 74.75781 -57.940883) (xy 74.758296 -57.968134) (xy 74.757853 -57.994449) (xy 74.750613 -58.046578)
			(xy 74.736289 -58.097222) (xy 74.734088 -58.102242) (xy 77.918292 -58.102242) (xy 77.918292 -58.042306)
			(xy 77.926115 -57.982884) (xy 77.941628 -57.924991) (xy 77.964564 -57.869618) (xy 77.994531 -57.817712)
			(xy 78.031018 -57.770162) (xy 78.073398 -57.727782) (xy 78.120948 -57.691295) (xy 78.172854 -57.661328)
			(xy 78.228227 -57.638392) (xy 78.28612 -57.622879) (xy 78.345542 -57.615056) (xy 78.405478 -57.615056)
			(xy 78.4649 -57.622879) (xy 78.522793 -57.638392) (xy 78.578166 -57.661328) (xy 78.630072 -57.691295)
			(xy 78.677622 -57.727782) (xy 78.720002 -57.770162) (xy 78.756489 -57.817712) (xy 78.786456 -57.869618)
			(xy 78.809392 -57.924991) (xy 78.824905 -57.982884) (xy 78.832728 -58.042306) (xy 78.833218 -58.072274)
			(xy 78.832728 -58.102242) (xy 78.832226 -58.106052) (xy 83.282772 -58.106052) (xy 83.282772 -58.046116)
			(xy 83.290595 -57.986694) (xy 83.306108 -57.928801) (xy 83.329044 -57.873428) (xy 83.359011 -57.821522)
			(xy 83.395498 -57.773972) (xy 83.437878 -57.731592) (xy 83.485428 -57.695105) (xy 83.537334 -57.665138)
			(xy 83.592707 -57.642202) (xy 83.6506 -57.626689) (xy 83.710022 -57.618866) (xy 83.769958 -57.618866)
			(xy 83.82938 -57.626689) (xy 83.887273 -57.642202) (xy 83.942646 -57.665138) (xy 83.994552 -57.695105)
			(xy 84.042102 -57.731592) (xy 84.084482 -57.773972) (xy 84.120969 -57.821522) (xy 84.150936 -57.873428)
			(xy 84.160809 -57.897264) (xy 85.567756 -57.897264) (xy 85.567756 -57.837328) (xy 85.575579 -57.777906)
			(xy 85.591092 -57.720013) (xy 85.614028 -57.66464) (xy 85.643995 -57.612734) (xy 85.680482 -57.565184)
			(xy 85.722862 -57.522804) (xy 85.770412 -57.486317) (xy 85.822318 -57.45635) (xy 85.877691 -57.433414)
			(xy 85.935584 -57.417901) (xy 85.995006 -57.410078) (xy 86.054942 -57.410078) (xy 86.114364 -57.417901)
			(xy 86.172257 -57.433414) (xy 86.22763 -57.45635) (xy 86.279536 -57.486317) (xy 86.327086 -57.522804)
			(xy 86.369466 -57.565184) (xy 86.405953 -57.612734) (xy 86.43592 -57.66464) (xy 86.458856 -57.720013)
			(xy 86.474369 -57.777906) (xy 86.482192 -57.837328) (xy 86.482682 -57.867296) (xy 86.482192 -57.897264)
			(xy 86.474369 -57.956686) (xy 86.458856 -58.014579) (xy 86.43592 -58.069952) (xy 86.405953 -58.121858)
			(xy 86.369466 -58.169408) (xy 86.327086 -58.211788) (xy 86.279536 -58.248275) (xy 86.22763 -58.278242)
			(xy 86.172257 -58.301178) (xy 86.114364 -58.316691) (xy 86.054942 -58.324514) (xy 85.995006 -58.324514)
			(xy 85.935584 -58.316691) (xy 85.877691 -58.301178) (xy 85.822318 -58.278242) (xy 85.770412 -58.248275)
			(xy 85.722862 -58.211788) (xy 85.680482 -58.169408) (xy 85.643995 -58.121858) (xy 85.614028 -58.069952)
			(xy 85.591092 -58.014579) (xy 85.575579 -57.956686) (xy 85.567756 -57.897264) (xy 84.160809 -57.897264)
			(xy 84.173872 -57.928801) (xy 84.189385 -57.986694) (xy 84.197208 -58.046116) (xy 84.197698 -58.076084)
			(xy 84.197208 -58.106052) (xy 84.189385 -58.165474) (xy 84.173872 -58.223367) (xy 84.150936 -58.27874)
			(xy 84.120969 -58.330646) (xy 84.084482 -58.378196) (xy 84.042102 -58.420576) (xy 83.994552 -58.457063)
			(xy 83.942646 -58.48703) (xy 83.887273 -58.509966) (xy 83.82938 -58.525479) (xy 83.769958 -58.533302)
			(xy 83.710022 -58.533302) (xy 83.6506 -58.525479) (xy 83.592707 -58.509966) (xy 83.537334 -58.48703)
			(xy 83.485428 -58.457063) (xy 83.437878 -58.420576) (xy 83.395498 -58.378196) (xy 83.359011 -58.330646)
			(xy 83.329044 -58.27874) (xy 83.306108 -58.223367) (xy 83.290595 -58.165474) (xy 83.282772 -58.106052)
			(xy 78.832226 -58.106052) (xy 78.824905 -58.161664) (xy 78.809392 -58.219557) (xy 78.786456 -58.27493)
			(xy 78.756489 -58.326836) (xy 78.720002 -58.374386) (xy 78.677622 -58.416766) (xy 78.630072 -58.453253)
			(xy 78.578166 -58.48322) (xy 78.522793 -58.506156) (xy 78.4649 -58.521669) (xy 78.405478 -58.529492)
			(xy 78.345542 -58.529492) (xy 78.28612 -58.521669) (xy 78.228227 -58.506156) (xy 78.172854 -58.48322)
			(xy 78.120948 -58.453253) (xy 78.073398 -58.416766) (xy 78.031018 -58.374386) (xy 77.994531 -58.326836)
			(xy 77.964564 -58.27493) (xy 77.941628 -58.219557) (xy 77.926115 -58.161664) (xy 77.918292 -58.102242)
			(xy 74.734088 -58.102242) (xy 74.715152 -58.145421) (xy 74.687602 -58.190263) (xy 74.654159 -58.230902)
			(xy 74.635106 -58.249058) (xy 74.627722 -58.256594) (xy 74.619187 -58.275863) (xy 74.618596 -58.286396)
			(xy 74.618596 -58.361072) (xy 74.619128 -58.371621) (xy 74.627661 -58.390917) (xy 74.635106 -58.39841)
			(xy 74.654161 -58.416567) (xy 74.687618 -58.457196) (xy 74.715177 -58.502036) (xy 74.736315 -58.550237)
			(xy 74.747893 -58.591192) (xy 84.486986 -58.591192) (xy 84.486986 -58.531256) (xy 84.494809 -58.471834)
			(xy 84.510322 -58.413941) (xy 84.533258 -58.358568) (xy 84.563225 -58.306662) (xy 84.599712 -58.259112)
			(xy 84.642092 -58.216732) (xy 84.689642 -58.180245) (xy 84.741548 -58.150278) (xy 84.796921 -58.127342)
			(xy 84.854814 -58.111829) (xy 84.914236 -58.104006) (xy 84.974172 -58.104006) (xy 85.033594 -58.111829)
			(xy 85.091487 -58.127342) (xy 85.14686 -58.150278) (xy 85.198766 -58.180245) (xy 85.246316 -58.216732)
			(xy 85.288696 -58.259112) (xy 85.325183 -58.306662) (xy 85.35515 -58.358568) (xy 85.378086 -58.413941)
			(xy 85.393599 -58.471834) (xy 85.394633 -58.479686) (xy 86.733616 -58.479686) (xy 86.733616 -58.41975)
			(xy 86.741439 -58.360328) (xy 86.756952 -58.302435) (xy 86.779888 -58.247062) (xy 86.809855 -58.195156)
			(xy 86.846342 -58.147606) (xy 86.888722 -58.105226) (xy 86.936272 -58.068739) (xy 86.988178 -58.038772)
			(xy 87.043551 -58.015836) (xy 87.101444 -58.000323) (xy 87.160866 -57.9925) (xy 87.220802 -57.9925)
			(xy 87.280224 -58.000323) (xy 87.338117 -58.015836) (xy 87.39349 -58.038772) (xy 87.445396 -58.068739)
			(xy 87.492946 -58.105226) (xy 87.535326 -58.147606) (xy 87.571813 -58.195156) (xy 87.60178 -58.247062)
			(xy 87.624716 -58.302435) (xy 87.640229 -58.360328) (xy 87.648052 -58.41975) (xy 87.648542 -58.449718)
			(xy 87.648052 -58.479686) (xy 87.640229 -58.539108) (xy 87.624716 -58.597001) (xy 87.60178 -58.652374)
			(xy 87.571813 -58.70428) (xy 87.551 -58.731404) (xy 91.520518 -58.731404) (xy 91.520982 -58.704034)
			(xy 91.5288 -58.649854) (xy 91.544289 -58.597351) (xy 91.567131 -58.547604) (xy 91.596856 -58.501638)
			(xy 91.614498 -58.480706) (xy 91.614752 -58.480452) (xy 91.620329 -58.473359) (xy 91.62658 -58.456447)
			(xy 91.626944 -58.447432) (xy 91.626944 -58.380376) (xy 91.626611 -58.371356) (xy 91.620348 -58.354439)
			(xy 91.614752 -58.347356) (xy 91.614498 -58.347356) (xy 91.614498 -58.347102) (xy 91.596862 -58.326166)
			(xy 91.56714 -58.280198) (xy 91.544296 -58.230452) (xy 91.528801 -58.177951) (xy 91.520972 -58.123773)
			(xy 91.520972 -58.069033) (xy 91.528799 -58.014855) (xy 91.544294 -57.962354) (xy 91.567137 -57.912608)
			(xy 91.596859 -57.866639) (xy 91.614498 -57.845706) (xy 91.614752 -57.845452) (xy 91.620329 -57.838359)
			(xy 91.62658 -57.821447) (xy 91.626944 -57.812432) (xy 91.626944 -57.745376) (xy 91.626611 -57.736356)
			(xy 91.620348 -57.719439) (xy 91.614752 -57.712356) (xy 91.614498 -57.712356) (xy 91.614498 -57.712102)
			(xy 91.596862 -57.691166) (xy 91.56714 -57.645198) (xy 91.544296 -57.595452) (xy 91.528801 -57.542951)
			(xy 91.520972 -57.488773) (xy 91.520972 -57.434033) (xy 91.528799 -57.379855) (xy 91.544294 -57.327354)
			(xy 91.567137 -57.277608) (xy 91.596859 -57.231639) (xy 91.614498 -57.210706) (xy 91.614752 -57.210452)
			(xy 91.620329 -57.203359) (xy 91.62658 -57.186447) (xy 91.626944 -57.177432) (xy 91.626944 -57.110376)
			(xy 91.626611 -57.101356) (xy 91.620348 -57.084439) (xy 91.614752 -57.077356) (xy 91.614498 -57.077356)
			(xy 91.614498 -57.077102) (xy 91.596846 -57.05618) (xy 91.567136 -57.010205) (xy 91.544303 -56.960454)
			(xy 91.528815 -56.907951) (xy 91.52099 -56.853774) (xy 91.520518 -56.826404) (xy 91.521004 -56.799153)
			(xy 91.52876 -56.745205) (xy 91.544115 -56.69291) (xy 91.566757 -56.643333) (xy 91.596223 -56.597483)
			(xy 91.631914 -56.556292) (xy 91.673105 -56.520601) (xy 91.718955 -56.491135) (xy 91.768532 -56.468493)
			(xy 91.820827 -56.453138) (xy 91.874775 -56.445382) (xy 91.929277 -56.445382) (xy 91.983225 -56.453138)
			(xy 92.03552 -56.468493) (xy 92.085097 -56.491135) (xy 92.130947 -56.520601) (xy 92.172138 -56.556292)
			(xy 92.207829 -56.597483) (xy 92.237295 -56.643333) (xy 92.259937 -56.69291) (xy 92.275292 -56.745205)
			(xy 92.283048 -56.799153) (xy 92.283244 -56.810148) (xy 94.100142 -56.810148) (xy 94.100142 -56.809894)
			(xy 94.100632 -56.779926) (xy 94.108455 -56.720504) (xy 94.123968 -56.662611) (xy 94.146904 -56.607238)
			(xy 94.176871 -56.555332) (xy 94.213358 -56.507782) (xy 94.255738 -56.465402) (xy 94.303288 -56.428915)
			(xy 94.355194 -56.398948) (xy 94.410567 -56.376012) (xy 94.46846 -56.360499) (xy 94.527882 -56.352676)
			(xy 94.587818 -56.352676) (xy 94.64724 -56.360499) (xy 94.705133 -56.376012) (xy 94.760506 -56.398948)
			(xy 94.812412 -56.428915) (xy 94.859962 -56.465402) (xy 94.902342 -56.507782) (xy 94.938829 -56.555332)
			(xy 94.968796 -56.607238) (xy 94.991732 -56.662611) (xy 95.007245 -56.720504) (xy 95.015068 -56.779926)
			(xy 95.015558 -56.809894) (xy 95.015558 -56.810148) (xy 95.014998 -56.841672) (xy 95.006329 -56.904121)
			(xy 94.989174 -56.96479) (xy 94.963859 -57.022532) (xy 94.930861 -57.076256) (xy 94.890806 -57.124945)
			(xy 94.867984 -57.146698) (xy 94.860872 -57.153302) (xy 94.85249 -57.17032) (xy 94.84614 -57.248806)
			(xy 94.845765 -57.258372) (xy 94.851387 -57.276656) (xy 94.857062 -57.284366) (xy 94.872604 -57.304646)
			(xy 94.898661 -57.348597) (xy 94.918623 -57.395632) (xy 94.932133 -57.444908) (xy 94.935114 -57.467053)
			(xy 95.118369 -57.467053) (xy 95.118369 -57.412547) (xy 95.126127 -57.358595) (xy 95.141484 -57.306297)
			(xy 95.164127 -57.256717) (xy 95.193597 -57.210864) (xy 95.229292 -57.169672) (xy 95.270487 -57.13398)
			(xy 95.316342 -57.104514) (xy 95.365924 -57.081874) (xy 95.418223 -57.066521) (xy 95.472175 -57.058767)
			(xy 95.499428 -57.058306) (xy 95.524977 -57.058684) (xy 95.575618 -57.065499) (xy 95.624895 -57.079015)
			(xy 95.671926 -57.09899) (xy 95.715868 -57.125068) (xy 95.736156 -57.140602) (xy 95.743894 -57.146219)
			(xy 95.762159 -57.151832) (xy 95.771716 -57.151524) (xy 95.850202 -57.145174) (xy 95.86722 -57.136792)
			(xy 95.873824 -57.12968) (xy 95.895564 -57.106841) (xy 95.944242 -57.066762) (xy 95.997964 -57.033749)
			(xy 96.055711 -57.008429) (xy 96.116388 -56.99128) (xy 96.178847 -56.982629) (xy 96.210374 -56.982106)
			(xy 96.210628 -56.982106) (xy 96.240597 -56.982556) (xy 96.300021 -56.990383) (xy 96.357916 -57.005899)
			(xy 96.41329 -57.028839) (xy 96.465196 -57.058811) (xy 96.4887 -57.076848) (xy 97.13849 -57.076848)
			(xy 97.138987 -57.049479) (xy 97.146797 -56.995301) (xy 97.16228 -56.942799) (xy 97.185114 -56.893051)
			(xy 97.214832 -56.847083) (xy 97.23247 -56.82615) (xy 97.232724 -56.825896) (xy 97.238321 -56.818817)
			(xy 97.244561 -56.801894) (xy 97.244916 -56.792876) (xy 97.244916 -56.72582) (xy 97.244546 -56.716805)
			(xy 97.238307 -56.699888) (xy 97.232724 -56.6928) (xy 97.23247 -56.6928) (xy 97.23247 -56.692546)
			(xy 97.214834 -56.671611) (xy 97.185123 -56.625639) (xy 97.162287 -56.575892) (xy 97.146795 -56.523392)
			(xy 97.138965 -56.469217) (xy 97.13849 -56.441848) (xy 97.138976 -56.414597) (xy 97.146732 -56.360649)
			(xy 97.162087 -56.308354) (xy 97.184729 -56.258777) (xy 97.214195 -56.212927) (xy 97.249886 -56.171736)
			(xy 97.291077 -56.136045) (xy 97.336927 -56.106579) (xy 97.386504 -56.083937) (xy 97.438799 -56.068582)
			(xy 97.492747 -56.060826) (xy 97.547249 -56.060826) (xy 97.601197 -56.068582) (xy 97.653492 -56.083937)
			(xy 97.703069 -56.106579) (xy 97.748919 -56.136045) (xy 97.79011 -56.171736) (xy 97.825801 -56.212927)
			(xy 97.855267 -56.258777) (xy 97.877909 -56.308354) (xy 97.893264 -56.360649) (xy 97.90102 -56.414597)
			(xy 97.901506 -56.441848) (xy 97.901008 -56.469217) (xy 97.893198 -56.523395) (xy 97.877716 -56.575897)
			(xy 97.854881 -56.625645) (xy 97.825164 -56.671613) (xy 97.807526 -56.692546) (xy 97.807272 -56.6928)
			(xy 97.801676 -56.69988) (xy 97.795436 -56.716802) (xy 97.79508 -56.72582) (xy 97.79508 -56.792876)
			(xy 97.795453 -56.801891) (xy 97.80169 -56.818808) (xy 97.807272 -56.825896) (xy 97.807526 -56.825896)
			(xy 97.807526 -56.82615) (xy 97.825159 -56.847087) (xy 97.854871 -56.893059) (xy 97.877708 -56.942805)
			(xy 97.8932 -56.995305) (xy 97.894303 -57.002934) (xy 99.563428 -57.002934) (xy 99.563927 -56.974842)
			(xy 99.572151 -56.919264) (xy 99.58844 -56.865494) (xy 99.612441 -56.814696) (xy 99.643636 -56.767969)
			(xy 99.681348 -56.726324) (xy 99.724763 -56.690664) (xy 99.748594 -56.675782) (xy 99.757484 -56.670448)
			(xy 99.769676 -56.65343) (xy 99.789996 -56.560212) (xy 99.785678 -56.539638) (xy 99.779836 -56.531002)
			(xy 99.763839 -56.506936) (xy 99.738494 -56.455006) (xy 99.721268 -56.399848) (xy 99.712552 -56.342724)
			(xy 99.712018 -56.313832) (xy 99.712485 -56.286579) (xy 99.720238 -56.232627) (xy 99.735592 -56.180327)
			(xy 99.758232 -56.130746) (xy 99.787699 -56.084891) (xy 99.823393 -56.043697) (xy 99.864586 -56.008003)
			(xy 99.91044 -55.978535) (xy 99.960022 -55.955894) (xy 100.012321 -55.94054) (xy 100.066273 -55.932786)
			(xy 100.093526 -55.932324) (xy 100.120897 -55.932769) (xy 100.175077 -55.940591) (xy 100.227581 -55.956085)
			(xy 100.277327 -55.978931) (xy 100.323293 -56.00866) (xy 100.344224 -56.026304) (xy 100.344478 -56.026558)
			(xy 100.351562 -56.032148) (xy 100.368481 -56.038391) (xy 100.377498 -56.03875) (xy 100.444554 -56.03875)
			(xy 100.45357 -56.038382) (xy 100.470488 -56.032143) (xy 100.477574 -56.026558) (xy 100.477574 -56.026304)
			(xy 100.477828 -56.026304) (xy 100.498761 -56.008663) (xy 100.544729 -55.978939) (xy 100.594475 -55.956093)
			(xy 100.646977 -55.940597) (xy 100.701155 -55.932768) (xy 100.755897 -55.932768) (xy 100.810075 -55.940597)
			(xy 100.862577 -55.956093) (xy 100.912323 -55.978939) (xy 100.958291 -56.008663) (xy 100.979224 -56.026304)
			(xy 100.979478 -56.026558) (xy 100.986562 -56.032148) (xy 101.003481 -56.038391) (xy 101.012498 -56.03875)
			(xy 101.079554 -56.03875) (xy 101.08857 -56.038382) (xy 101.105488 -56.032143) (xy 101.112574 -56.026558)
			(xy 101.112574 -56.026304) (xy 101.112828 -56.026304) (xy 101.133777 -56.008686) (xy 101.179745 -55.978971)
			(xy 101.229488 -55.956131) (xy 101.281985 -55.940635) (xy 101.336158 -55.932801) (xy 101.363526 -55.932324)
			(xy 101.390778 -55.932748) (xy 101.444728 -55.940508) (xy 101.497024 -55.955866) (xy 101.546602 -55.978511)
			(xy 101.592453 -56.00798) (xy 101.633643 -56.043675) (xy 101.669335 -56.084868) (xy 101.698801 -56.130721)
			(xy 101.721443 -56.180301) (xy 101.736798 -56.232598) (xy 101.744554 -56.286548) (xy 101.744554 -56.297068)
			(xy 102.086408 -56.297068) (xy 102.090479 -56.241446) (xy 102.102605 -56.187009) (xy 102.122528 -56.134918)
			(xy 102.149824 -56.086283) (xy 102.18391 -56.04214) (xy 102.224059 -56.003431) (xy 102.269417 -55.97098)
			(xy 102.319017 -55.945479) (xy 102.371801 -55.927472) (xy 102.426644 -55.917342) (xy 102.482378 -55.915305)
			(xy 102.537815 -55.921405) (xy 102.591772 -55.935511) (xy 102.643101 -55.957323) (xy 102.690707 -55.986377)
			(xy 102.733575 -56.022052) (xy 102.770792 -56.063589) (xy 102.801565 -56.110102) (xy 102.825237 -56.160599)
			(xy 102.841305 -56.214006) (xy 102.849425 -56.269182) (xy 102.849934 -56.297068) (xy 102.849425 -56.324954)
			(xy 102.84523 -56.353456) (xy 104.941114 -56.353456) (xy 104.945185 -56.297834) (xy 104.957311 -56.243397)
			(xy 104.977234 -56.191306) (xy 105.00453 -56.142671) (xy 105.038616 -56.098528) (xy 105.078765 -56.059819)
			(xy 105.124123 -56.027368) (xy 105.173723 -56.001867) (xy 105.226507 -55.98386) (xy 105.28135 -55.97373)
			(xy 105.337084 -55.971693) (xy 105.392521 -55.977793) (xy 105.446478 -55.991899) (xy 105.497807 -56.013711)
			(xy 105.545413 -56.042765) (xy 105.588281 -56.07844) (xy 105.625498 -56.119977) (xy 105.656271 -56.16649)
			(xy 105.679943 -56.216987) (xy 105.696011 -56.270394) (xy 105.704131 -56.32557) (xy 105.70464 -56.353456)
			(xy 105.704131 -56.381342) (xy 105.696011 -56.436518) (xy 105.679943 -56.489925) (xy 105.656271 -56.540422)
			(xy 105.625498 -56.586935) (xy 105.588281 -56.628472) (xy 105.545413 -56.664147) (xy 105.497807 -56.693201)
			(xy 105.446478 -56.715013) (xy 105.392521 -56.729119) (xy 105.337084 -56.735219) (xy 105.28135 -56.733182)
			(xy 105.226507 -56.723052) (xy 105.173723 -56.705045) (xy 105.124123 -56.679544) (xy 105.078765 -56.647093)
			(xy 105.038616 -56.608384) (xy 105.00453 -56.564241) (xy 104.977234 -56.515606) (xy 104.957311 -56.463515)
			(xy 104.945185 -56.409078) (xy 104.941114 -56.353456) (xy 102.84523 -56.353456) (xy 102.841305 -56.38013)
			(xy 102.825237 -56.433537) (xy 102.801565 -56.484034) (xy 102.770792 -56.530547) (xy 102.733575 -56.572084)
			(xy 102.690707 -56.607759) (xy 102.643101 -56.636813) (xy 102.591772 -56.658625) (xy 102.537815 -56.672731)
			(xy 102.482378 -56.678831) (xy 102.426644 -56.676794) (xy 102.371801 -56.666664) (xy 102.319017 -56.648657)
			(xy 102.269417 -56.623156) (xy 102.224059 -56.590705) (xy 102.18391 -56.551996) (xy 102.149824 -56.507853)
			(xy 102.122528 -56.459218) (xy 102.102605 -56.407127) (xy 102.090479 -56.35269) (xy 102.086408 -56.297068)
			(xy 101.744554 -56.297068) (xy 101.744554 -56.341052) (xy 101.736798 -56.395002) (xy 101.721443 -56.447299)
			(xy 101.698801 -56.496879) (xy 101.669335 -56.542732) (xy 101.633643 -56.583925) (xy 101.592453 -56.61962)
			(xy 101.546602 -56.649089) (xy 101.497024 -56.671734) (xy 101.444728 -56.687092) (xy 101.390778 -56.694852)
			(xy 101.363526 -56.69534) (xy 101.336156 -56.694873) (xy 101.281976 -56.687058) (xy 101.229472 -56.67157)
			(xy 101.179725 -56.648728) (xy 101.133759 -56.619002) (xy 101.112828 -56.60136) (xy 101.112574 -56.601106)
			(xy 101.10547 -56.595545) (xy 101.088567 -56.589283) (xy 101.079554 -56.588914) (xy 101.012498 -56.588914)
			(xy 101.003481 -56.589267) (xy 100.986564 -56.595517) (xy 100.979478 -56.601106) (xy 100.979478 -56.60136)
			(xy 100.979224 -56.60136) (xy 100.958291 -56.619001) (xy 100.912323 -56.648725) (xy 100.862577 -56.671571)
			(xy 100.810075 -56.687067) (xy 100.755897 -56.694896) (xy 100.701155 -56.694896) (xy 100.646977 -56.687067)
			(xy 100.594475 -56.671571) (xy 100.544729 -56.648725) (xy 100.498761 -56.619001) (xy 100.477828 -56.60136)
			(xy 100.477574 -56.601106) (xy 100.47047 -56.595545) (xy 100.453567 -56.589283) (xy 100.444554 -56.588914)
			(xy 100.377498 -56.588914) (xy 100.368481 -56.589267) (xy 100.351564 -56.595517) (xy 100.344478 -56.601106)
			(xy 100.34397 -56.60136) (xy 100.331235 -56.612303) (xy 100.304144 -56.632145) (xy 100.289868 -56.640984)
			(xy 100.280978 -56.646318) (xy 100.268786 -56.663336) (xy 100.248466 -56.756554) (xy 100.252784 -56.777128)
			(xy 100.258626 -56.785764) (xy 100.274616 -56.809834) (xy 100.29996 -56.861764) (xy 100.317188 -56.91692)
			(xy 100.325907 -56.974042) (xy 100.326444 -57.002934) (xy 100.325958 -57.030185) (xy 100.318202 -57.084133)
			(xy 100.302847 -57.136428) (xy 100.280205 -57.186005) (xy 100.250739 -57.231855) (xy 100.215048 -57.273046)
			(xy 100.173857 -57.308737) (xy 100.128007 -57.338203) (xy 100.07843 -57.360845) (xy 100.026135 -57.3762)
			(xy 99.972187 -57.383956) (xy 99.917685 -57.383956) (xy 99.863737 -57.3762) (xy 99.811442 -57.360845)
			(xy 99.761865 -57.338203) (xy 99.716015 -57.308737) (xy 99.674824 -57.273046) (xy 99.639133 -57.231855)
			(xy 99.609667 -57.186005) (xy 99.587025 -57.136428) (xy 99.57167 -57.084133) (xy 99.563914 -57.030185)
			(xy 99.563428 -57.002934) (xy 97.894303 -57.002934) (xy 97.901031 -57.049479) (xy 97.901506 -57.076848)
			(xy 97.90102 -57.104099) (xy 97.893264 -57.158047) (xy 97.877909 -57.210342) (xy 97.855267 -57.259919)
			(xy 97.825801 -57.305769) (xy 97.79011 -57.34696) (xy 97.748919 -57.382651) (xy 97.703069 -57.412117)
			(xy 97.653492 -57.434759) (xy 97.601197 -57.450114) (xy 97.547249 -57.45787) (xy 97.492747 -57.45787)
			(xy 97.438799 -57.450114) (xy 97.386504 -57.434759) (xy 97.336927 -57.412117) (xy 97.291077 -57.382651)
			(xy 97.249886 -57.34696) (xy 97.214195 -57.305769) (xy 97.184729 -57.259919) (xy 97.162087 -57.210342)
			(xy 97.146732 -57.158047) (xy 97.138976 -57.104099) (xy 97.13849 -57.076848) (xy 96.4887 -57.076848)
			(xy 96.512746 -57.095301) (xy 96.555127 -57.137685) (xy 96.591613 -57.185239) (xy 96.621579 -57.237148)
			(xy 96.644514 -57.292524) (xy 96.660025 -57.35042) (xy 96.667847 -57.409845) (xy 96.668336 -57.439814)
			(xy 96.667903 -57.468047) (xy 96.665768 -57.48528) (xy 120.706132 -57.48528) (xy 120.710203 -57.429658)
			(xy 120.722329 -57.375221) (xy 120.742252 -57.32313) (xy 120.769548 -57.274495) (xy 120.803634 -57.230352)
			(xy 120.843783 -57.191643) (xy 120.889141 -57.159192) (xy 120.938741 -57.133691) (xy 120.991525 -57.115684)
			(xy 121.046368 -57.105554) (xy 121.102102 -57.103517) (xy 121.157539 -57.109617) (xy 121.211496 -57.123723)
			(xy 121.262825 -57.145535) (xy 121.310431 -57.174589) (xy 121.353299 -57.210264) (xy 121.390516 -57.251801)
			(xy 121.421289 -57.298314) (xy 121.444961 -57.348811) (xy 121.461029 -57.402218) (xy 121.469149 -57.457394)
			(xy 121.469658 -57.48528) (xy 121.469149 -57.513166) (xy 121.461029 -57.568342) (xy 121.444961 -57.621749)
			(xy 121.421289 -57.672246) (xy 121.390516 -57.718759) (xy 121.353299 -57.760296) (xy 121.310431 -57.795971)
			(xy 121.262825 -57.825025) (xy 121.211496 -57.846837) (xy 121.157539 -57.860943) (xy 121.102102 -57.867043)
			(xy 121.046368 -57.865006) (xy 120.991525 -57.854876) (xy 120.938741 -57.836869) (xy 120.889141 -57.811368)
			(xy 120.843783 -57.778917) (xy 120.803634 -57.740208) (xy 120.769548 -57.696065) (xy 120.742252 -57.64743)
			(xy 120.722329 -57.595339) (xy 120.710203 -57.540902) (xy 120.706132 -57.48528) (xy 96.665768 -57.48528)
			(xy 96.660961 -57.524084) (xy 96.647174 -57.578841) (xy 96.62675 -57.631484) (xy 96.6 -57.681211)
			(xy 96.584008 -57.704482) (xy 96.576642 -57.71515) (xy 96.573594 -57.740804) (xy 96.616012 -57.844436)
			(xy 96.636078 -57.860692) (xy 96.649032 -57.862978) (xy 96.67514 -57.868124) (xy 96.725711 -57.884683)
			(xy 96.773491 -57.908105) (xy 96.817555 -57.937937) (xy 96.857048 -57.973601) (xy 96.891204 -58.014406)
			(xy 96.91936 -58.059559) (xy 96.940972 -58.108185) (xy 96.955619 -58.159342) (xy 96.963019 -58.212038)
			(xy 96.963484 -58.238644) (xy 96.962989 -58.266013) (xy 96.955179 -58.320191) (xy 96.939697 -58.372694)
			(xy 96.916861 -58.422442) (xy 96.887143 -58.46841) (xy 96.869504 -58.489342) (xy 96.86925 -58.489596)
			(xy 96.863653 -58.496675) (xy 96.857414 -58.513598) (xy 96.857058 -58.522616) (xy 96.857058 -58.589672)
			(xy 96.857416 -58.598689) (xy 96.863661 -58.615607) (xy 96.86925 -58.622692) (xy 96.869504 -58.622692)
			(xy 96.869504 -58.622946) (xy 96.887132 -58.643887) (xy 96.910043 -58.679334) (xy 99.995228 -58.679334)
			(xy 99.995642 -58.653018) (xy 100.002887 -58.600887) (xy 100.017216 -58.550243) (xy 100.038358 -58.502044)
			(xy 100.065914 -58.457202) (xy 100.099362 -58.416565) (xy 100.118418 -58.39841) (xy 100.12582 -58.390889)
			(xy 100.134344 -58.371608) (xy 100.134928 -58.361072) (xy 100.134928 -58.286396) (xy 100.134406 -58.275846)
			(xy 100.125865 -58.256551) (xy 100.118418 -58.249058) (xy 100.099353 -58.230912) (xy 100.065896 -58.190281)
			(xy 100.038337 -58.145439) (xy 100.017201 -58.097236) (xy 100.002886 -58.046586) (xy 99.995664 -57.994451)
			(xy 99.995228 -57.968134) (xy 99.995714 -57.940883) (xy 100.00347 -57.886935) (xy 100.018825 -57.83464)
			(xy 100.041467 -57.785063) (xy 100.070933 -57.739213) (xy 100.106624 -57.698022) (xy 100.147815 -57.662331)
			(xy 100.193665 -57.632865) (xy 100.243242 -57.610223) (xy 100.295537 -57.594868) (xy 100.349485 -57.587112)
			(xy 100.403987 -57.587112) (xy 100.457935 -57.594868) (xy 100.51023 -57.610223) (xy 100.559807 -57.632865)
			(xy 100.605657 -57.662331) (xy 100.646848 -57.698022) (xy 100.682539 -57.739213) (xy 100.712005 -57.785063)
			(xy 100.734647 -57.83464) (xy 100.750002 -57.886935) (xy 100.757758 -57.940883) (xy 100.758244 -57.968134)
			(xy 100.757817 -57.99445) (xy 100.750577 -58.046581) (xy 100.736251 -58.097225) (xy 100.734051 -58.102242)
			(xy 103.91824 -58.102242) (xy 103.91824 -58.042306) (xy 103.926063 -57.982884) (xy 103.941576 -57.924991)
			(xy 103.964512 -57.869618) (xy 103.994479 -57.817712) (xy 104.030966 -57.770162) (xy 104.073346 -57.727782)
			(xy 104.120896 -57.691295) (xy 104.172802 -57.661328) (xy 104.228175 -57.638392) (xy 104.286068 -57.622879)
			(xy 104.34549 -57.615056) (xy 104.405426 -57.615056) (xy 104.464848 -57.622879) (xy 104.522741 -57.638392)
			(xy 104.578114 -57.661328) (xy 104.63002 -57.691295) (xy 104.67757 -57.727782) (xy 104.71995 -57.770162)
			(xy 104.756437 -57.817712) (xy 104.786404 -57.869618) (xy 104.80934 -57.924991) (xy 104.824853 -57.982884)
			(xy 104.832676 -58.042306) (xy 104.833166 -58.072274) (xy 104.832676 -58.102242) (xy 104.832174 -58.106052)
			(xy 121.383026 -58.106052) (xy 121.383026 -58.046116) (xy 121.390849 -57.986694) (xy 121.406362 -57.928801)
			(xy 121.429298 -57.873428) (xy 121.459265 -57.821522) (xy 121.495752 -57.773972) (xy 121.538132 -57.731592)
			(xy 121.585682 -57.695105) (xy 121.637588 -57.665138) (xy 121.692961 -57.642202) (xy 121.750854 -57.626689)
			(xy 121.810276 -57.618866) (xy 121.870212 -57.618866) (xy 121.929634 -57.626689) (xy 121.987527 -57.642202)
			(xy 122.0429 -57.665138) (xy 122.094806 -57.695105) (xy 122.142356 -57.731592) (xy 122.184736 -57.773972)
			(xy 122.221223 -57.821522) (xy 122.25119 -57.873428) (xy 122.261063 -57.897264) (xy 123.66801 -57.897264)
			(xy 123.66801 -57.837328) (xy 123.675833 -57.777906) (xy 123.691346 -57.720013) (xy 123.714282 -57.66464)
			(xy 123.744249 -57.612734) (xy 123.780736 -57.565184) (xy 123.823116 -57.522804) (xy 123.870666 -57.486317)
			(xy 123.922572 -57.45635) (xy 123.977945 -57.433414) (xy 124.035838 -57.417901) (xy 124.09526 -57.410078)
			(xy 124.155196 -57.410078) (xy 124.214618 -57.417901) (xy 124.272511 -57.433414) (xy 124.327884 -57.45635)
			(xy 124.37979 -57.486317) (xy 124.42734 -57.522804) (xy 124.46972 -57.565184) (xy 124.506207 -57.612734)
			(xy 124.536174 -57.66464) (xy 124.55911 -57.720013) (xy 124.574623 -57.777906) (xy 124.582446 -57.837328)
			(xy 124.582936 -57.867296) (xy 124.582446 -57.897264) (xy 124.574623 -57.956686) (xy 124.55911 -58.014579)
			(xy 124.536174 -58.069952) (xy 124.506207 -58.121858) (xy 124.46972 -58.169408) (xy 124.42734 -58.211788)
			(xy 124.37979 -58.248275) (xy 124.327884 -58.278242) (xy 124.272511 -58.301178) (xy 124.214618 -58.316691)
			(xy 124.155196 -58.324514) (xy 124.09526 -58.324514) (xy 124.035838 -58.316691) (xy 123.977945 -58.301178)
			(xy 123.922572 -58.278242) (xy 123.870666 -58.248275) (xy 123.823116 -58.211788) (xy 123.780736 -58.169408)
			(xy 123.744249 -58.121858) (xy 123.714282 -58.069952) (xy 123.691346 -58.014579) (xy 123.675833 -57.956686)
			(xy 123.66801 -57.897264) (xy 122.261063 -57.897264) (xy 122.274126 -57.928801) (xy 122.289639 -57.986694)
			(xy 122.297462 -58.046116) (xy 122.297952 -58.076084) (xy 122.297462 -58.106052) (xy 122.289639 -58.165474)
			(xy 122.274126 -58.223367) (xy 122.25119 -58.27874) (xy 122.221223 -58.330646) (xy 122.184736 -58.378196)
			(xy 122.142356 -58.420576) (xy 122.094806 -58.457063) (xy 122.0429 -58.48703) (xy 121.987527 -58.509966)
			(xy 121.929634 -58.525479) (xy 121.870212 -58.533302) (xy 121.810276 -58.533302) (xy 121.750854 -58.525479)
			(xy 121.692961 -58.509966) (xy 121.637588 -58.48703) (xy 121.585682 -58.457063) (xy 121.538132 -58.420576)
			(xy 121.495752 -58.378196) (xy 121.459265 -58.330646) (xy 121.429298 -58.27874) (xy 121.406362 -58.223367)
			(xy 121.390849 -58.165474) (xy 121.383026 -58.106052) (xy 104.832174 -58.106052) (xy 104.824853 -58.161664)
			(xy 104.80934 -58.219557) (xy 104.786404 -58.27493) (xy 104.756437 -58.326836) (xy 104.71995 -58.374386)
			(xy 104.67757 -58.416766) (xy 104.63002 -58.453253) (xy 104.578114 -58.48322) (xy 104.522741 -58.506156)
			(xy 104.464848 -58.521669) (xy 104.405426 -58.529492) (xy 104.34549 -58.529492) (xy 104.286068 -58.521669)
			(xy 104.228175 -58.506156) (xy 104.172802 -58.48322) (xy 104.120896 -58.453253) (xy 104.073346 -58.416766)
			(xy 104.030966 -58.374386) (xy 103.994479 -58.326836) (xy 103.964512 -58.27493) (xy 103.941576 -58.219557)
			(xy 103.926063 -58.161664) (xy 103.91824 -58.102242) (xy 100.734051 -58.102242) (xy 100.715111 -58.145424)
			(xy 100.687557 -58.190266) (xy 100.65411 -58.230903) (xy 100.635054 -58.249058) (xy 100.627677 -58.256601)
			(xy 100.619137 -58.275864) (xy 100.618544 -58.286396) (xy 100.618544 -58.361072) (xy 100.619062 -58.371623)
			(xy 100.627604 -58.390919) (xy 100.635054 -58.39841) (xy 100.654118 -58.416557) (xy 100.687572 -58.45719)
			(xy 100.715129 -58.502032) (xy 100.736265 -58.550234) (xy 100.747842 -58.591192) (xy 122.58724 -58.591192)
			(xy 122.58724 -58.531256) (xy 122.595063 -58.471834) (xy 122.610576 -58.413941) (xy 122.633512 -58.358568)
			(xy 122.663479 -58.306662) (xy 122.699966 -58.259112) (xy 122.742346 -58.216732) (xy 122.789896 -58.180245)
			(xy 122.841802 -58.150278) (xy 122.897175 -58.127342) (xy 122.955068 -58.111829) (xy 123.01449 -58.104006)
			(xy 123.074426 -58.104006) (xy 123.133848 -58.111829) (xy 123.191741 -58.127342) (xy 123.247114 -58.150278)
			(xy 123.29902 -58.180245) (xy 123.34657 -58.216732) (xy 123.38895 -58.259112) (xy 123.425437 -58.306662)
			(xy 123.455404 -58.358568) (xy 123.47834 -58.413941) (xy 123.493853 -58.471834) (xy 123.494887 -58.479686)
			(xy 124.83387 -58.479686) (xy 124.83387 -58.41975) (xy 124.841693 -58.360328) (xy 124.857206 -58.302435)
			(xy 124.880142 -58.247062) (xy 124.910109 -58.195156) (xy 124.946596 -58.147606) (xy 124.988976 -58.105226)
			(xy 125.036526 -58.068739) (xy 125.088432 -58.038772) (xy 125.143805 -58.015836) (xy 125.201698 -58.000323)
			(xy 125.26112 -57.9925) (xy 125.321056 -57.9925) (xy 125.380478 -58.000323) (xy 125.438371 -58.015836)
			(xy 125.493744 -58.038772) (xy 125.54565 -58.068739) (xy 125.5932 -58.105226) (xy 125.63558 -58.147606)
			(xy 125.672067 -58.195156) (xy 125.702034 -58.247062) (xy 125.72497 -58.302435) (xy 125.740483 -58.360328)
			(xy 125.748306 -58.41975) (xy 125.748796 -58.449718) (xy 125.748306 -58.479686) (xy 125.740483 -58.539108)
			(xy 125.72497 -58.597001) (xy 125.702034 -58.652374) (xy 125.672067 -58.70428) (xy 125.651254 -58.731404)
			(xy 129.620772 -58.731404) (xy 129.621223 -58.704033) (xy 129.629042 -58.649853) (xy 129.644533 -58.597349)
			(xy 129.667379 -58.547602) (xy 129.697108 -58.501636) (xy 129.714752 -58.480706) (xy 129.715006 -58.480452)
			(xy 129.720578 -58.473355) (xy 129.726833 -58.456446) (xy 129.727198 -58.447432) (xy 129.727198 -58.380376)
			(xy 129.726853 -58.371358) (xy 129.720597 -58.354441) (xy 129.715006 -58.347356) (xy 129.714752 -58.347356)
			(xy 129.714752 -58.347102) (xy 129.697114 -58.326167) (xy 129.667387 -58.2802) (xy 129.64454 -58.230454)
			(xy 129.629043 -58.177952) (xy 129.621213 -58.123774) (xy 129.621213 -58.069032) (xy 129.629041 -58.014854)
			(xy 129.644538 -57.962351) (xy 129.667384 -57.912605) (xy 129.697111 -57.866638) (xy 129.714752 -57.845706)
			(xy 129.715006 -57.845452) (xy 129.720578 -57.838355) (xy 129.726833 -57.821446) (xy 129.727198 -57.812432)
			(xy 129.727198 -57.745376) (xy 129.726853 -57.736358) (xy 129.720597 -57.719441) (xy 129.715006 -57.712356)
			(xy 129.714752 -57.712356) (xy 129.714752 -57.712102) (xy 129.697114 -57.691167) (xy 129.667387 -57.6452)
			(xy 129.64454 -57.595454) (xy 129.629043 -57.542952) (xy 129.621213 -57.488774) (xy 129.621213 -57.434032)
			(xy 129.629041 -57.379854) (xy 129.644538 -57.327351) (xy 129.667384 -57.277605) (xy 129.697111 -57.231638)
			(xy 129.714752 -57.210706) (xy 129.715006 -57.210452) (xy 129.720578 -57.203355) (xy 129.726833 -57.186446)
			(xy 129.727198 -57.177432) (xy 129.727198 -57.110376) (xy 129.726853 -57.101358) (xy 129.720597 -57.084441)
			(xy 129.715006 -57.077356) (xy 129.714752 -57.077356) (xy 129.714752 -57.077102) (xy 129.697108 -57.056173)
			(xy 129.667396 -57.0102) (xy 129.64456 -56.960452) (xy 129.62907 -56.90795) (xy 129.621244 -56.853774)
			(xy 129.620772 -56.826404) (xy 129.621258 -56.799153) (xy 129.629014 -56.745205) (xy 129.644369 -56.69291)
			(xy 129.667011 -56.643333) (xy 129.696477 -56.597483) (xy 129.732168 -56.556292) (xy 129.773359 -56.520601)
			(xy 129.819209 -56.491135) (xy 129.868786 -56.468493) (xy 129.921081 -56.453138) (xy 129.975029 -56.445382)
			(xy 130.029531 -56.445382) (xy 130.083479 -56.453138) (xy 130.135774 -56.468493) (xy 130.185351 -56.491135)
			(xy 130.231201 -56.520601) (xy 130.272392 -56.556292) (xy 130.308083 -56.597483) (xy 130.337549 -56.643333)
			(xy 130.360191 -56.69291) (xy 130.375546 -56.745205) (xy 130.383302 -56.799153) (xy 130.383498 -56.810148)
			(xy 132.200396 -56.810148) (xy 132.200396 -56.809894) (xy 132.200886 -56.779926) (xy 132.208709 -56.720504)
			(xy 132.224222 -56.662611) (xy 132.247158 -56.607238) (xy 132.277125 -56.555332) (xy 132.313612 -56.507782)
			(xy 132.355992 -56.465402) (xy 132.403542 -56.428915) (xy 132.455448 -56.398948) (xy 132.510821 -56.376012)
			(xy 132.568714 -56.360499) (xy 132.628136 -56.352676) (xy 132.688072 -56.352676) (xy 132.747494 -56.360499)
			(xy 132.805387 -56.376012) (xy 132.86076 -56.398948) (xy 132.912666 -56.428915) (xy 132.960216 -56.465402)
			(xy 133.002596 -56.507782) (xy 133.039083 -56.555332) (xy 133.06905 -56.607238) (xy 133.091986 -56.662611)
			(xy 133.107499 -56.720504) (xy 133.115322 -56.779926) (xy 133.115812 -56.809894) (xy 133.115812 -56.810148)
			(xy 133.115235 -56.841671) (xy 133.106566 -56.904119) (xy 133.089414 -56.964787) (xy 133.064102 -57.022529)
			(xy 133.031108 -57.076253) (xy 132.991057 -57.124943) (xy 132.968238 -57.146698) (xy 132.961126 -57.153302)
			(xy 132.952744 -57.17032) (xy 132.946394 -57.248806) (xy 132.946028 -57.258371) (xy 132.951645 -57.276654)
			(xy 132.957316 -57.284366) (xy 132.972851 -57.304651) (xy 132.998911 -57.3486) (xy 133.018875 -57.395633)
			(xy 133.032386 -57.444909) (xy 133.035367 -57.467049) (xy 133.218692 -57.467049) (xy 133.218692 -57.412551)
			(xy 133.226448 -57.358607) (xy 133.241802 -57.306315) (xy 133.264441 -57.256741) (xy 133.293904 -57.210893)
			(xy 133.329592 -57.169705) (xy 133.370779 -57.134015) (xy 133.416625 -57.104549) (xy 133.466198 -57.081908)
			(xy 133.518489 -57.066552) (xy 133.572433 -57.058793) (xy 133.599682 -57.058306) (xy 133.62523 -57.05871)
			(xy 133.67587 -57.065518) (xy 133.725147 -57.079028) (xy 133.772178 -57.098998) (xy 133.816122 -57.12507)
			(xy 133.83641 -57.140602) (xy 133.844133 -57.146244) (xy 133.86241 -57.151841) (xy 133.87197 -57.151524)
			(xy 133.950456 -57.145174) (xy 133.967474 -57.136792) (xy 133.974078 -57.12968) (xy 133.995841 -57.106864)
			(xy 134.044513 -57.066782) (xy 134.09823 -57.033767) (xy 134.155973 -57.008442) (xy 134.216647 -56.991289)
			(xy 134.279102 -56.982632) (xy 134.310628 -56.982106) (xy 134.310882 -56.982106) (xy 134.340851 -56.982578)
			(xy 134.400277 -56.990399) (xy 134.458173 -57.005911) (xy 134.51355 -57.028847) (xy 134.565458 -57.058816)
			(xy 134.588959 -57.076848) (xy 135.238744 -57.076848) (xy 135.239227 -57.049478) (xy 135.247039 -56.9953)
			(xy 135.262524 -56.942796) (xy 135.285362 -56.893049) (xy 135.315084 -56.847082) (xy 135.332724 -56.82615)
			(xy 135.332978 -56.825896) (xy 135.338581 -56.818821) (xy 135.344816 -56.801895) (xy 135.34517 -56.792876)
			(xy 135.34517 -56.72582) (xy 135.34481 -56.716803) (xy 135.338565 -56.699886) (xy 135.332978 -56.6928)
			(xy 135.332724 -56.6928) (xy 135.332724 -56.692546) (xy 135.315097 -56.671604) (xy 135.285382 -56.625635)
			(xy 135.262544 -56.57589) (xy 135.24705 -56.523391) (xy 135.239219 -56.469217) (xy 135.238744 -56.441848)
			(xy 135.23923 -56.414597) (xy 135.246986 -56.360649) (xy 135.262341 -56.308354) (xy 135.284983 -56.258777)
			(xy 135.314449 -56.212927) (xy 135.35014 -56.171736) (xy 135.391331 -56.136045) (xy 135.437181 -56.106579)
			(xy 135.486758 -56.083937) (xy 135.539053 -56.068582) (xy 135.593001 -56.060826) (xy 135.647503 -56.060826)
			(xy 135.701451 -56.068582) (xy 135.753746 -56.083937) (xy 135.803323 -56.106579) (xy 135.849173 -56.136045)
			(xy 135.890364 -56.171736) (xy 135.926055 -56.212927) (xy 135.955521 -56.258777) (xy 135.978163 -56.308354)
			(xy 135.993518 -56.360649) (xy 136.001274 -56.414597) (xy 136.00176 -56.441848) (xy 136.001273 -56.469218)
			(xy 135.993462 -56.523396) (xy 135.977978 -56.575899) (xy 135.955141 -56.625647) (xy 135.92542 -56.671614)
			(xy 135.90778 -56.692546) (xy 135.907526 -56.6928) (xy 135.901925 -56.699876) (xy 135.895689 -56.716801)
			(xy 135.895334 -56.72582) (xy 135.895334 -56.792876) (xy 135.895695 -56.801893) (xy 135.901939 -56.81881)
			(xy 135.907526 -56.825896) (xy 135.90778 -56.825896) (xy 135.90778 -56.82615) (xy 135.925406 -56.847093)
			(xy 135.95512 -56.893062) (xy 135.977959 -56.942807) (xy 135.993453 -56.995305) (xy 135.994556 -57.002934)
			(xy 137.663682 -57.002934) (xy 137.664204 -56.974843) (xy 137.672426 -56.919268) (xy 137.688712 -56.865499)
			(xy 137.712711 -56.814702) (xy 137.743901 -56.767975) (xy 137.78161 -56.726329) (xy 137.825019 -56.690665)
			(xy 137.848848 -56.675782) (xy 137.857738 -56.670448) (xy 137.86993 -56.65343) (xy 137.89025 -56.560212)
			(xy 137.885932 -56.539638) (xy 137.88009 -56.531002) (xy 137.864087 -56.50694) (xy 137.838746 -56.455008)
			(xy 137.821521 -56.399849) (xy 137.812806 -56.342725) (xy 137.812272 -56.313832) (xy 137.812785 -56.286581)
			(xy 137.820537 -56.232633) (xy 137.835888 -56.180337) (xy 137.858525 -56.130758) (xy 137.887988 -56.084906)
			(xy 137.923677 -56.043714) (xy 137.964864 -56.008019) (xy 138.010713 -55.97855) (xy 138.060288 -55.955906)
			(xy 138.112582 -55.940548) (xy 138.166529 -55.932789) (xy 138.19378 -55.932324) (xy 138.22115 -55.932796)
			(xy 138.275329 -55.940611) (xy 138.327832 -55.956099) (xy 138.377579 -55.978939) (xy 138.423546 -56.008663)
			(xy 138.444478 -56.026304) (xy 138.444732 -56.026558) (xy 138.451829 -56.032129) (xy 138.468738 -56.038384)
			(xy 138.477752 -56.03875) (xy 138.544808 -56.03875) (xy 138.553827 -56.038407) (xy 138.570744 -56.032151)
			(xy 138.577828 -56.026558) (xy 138.577828 -56.026304) (xy 138.578082 -56.026304) (xy 138.599015 -56.008663)
			(xy 138.644983 -55.978939) (xy 138.694729 -55.956093) (xy 138.747231 -55.940597) (xy 138.801409 -55.932768)
			(xy 138.856151 -55.932768) (xy 138.910329 -55.940597) (xy 138.962831 -55.956093) (xy 139.012577 -55.978939)
			(xy 139.058545 -56.008663) (xy 139.079478 -56.026304) (xy 139.079732 -56.026558) (xy 139.086829 -56.032129)
			(xy 139.103738 -56.038384) (xy 139.112752 -56.03875) (xy 139.179808 -56.03875) (xy 139.188827 -56.038407)
			(xy 139.205744 -56.032151) (xy 139.212828 -56.026558) (xy 139.212828 -56.026304) (xy 139.213082 -56.026304)
			(xy 139.234011 -56.008661) (xy 139.279984 -55.978949) (xy 139.329733 -55.956114) (xy 139.382234 -55.940624)
			(xy 139.436411 -55.932797) (xy 139.46378 -55.932324) (xy 139.491036 -55.932722) (xy 139.544994 -55.940477)
			(xy 139.597298 -55.955832) (xy 139.646885 -55.978476) (xy 139.692745 -56.007946) (xy 139.733943 -56.043642)
			(xy 139.769642 -56.084839) (xy 139.799115 -56.130697) (xy 139.821761 -56.180283) (xy 139.837119 -56.232587)
			(xy 139.844877 -56.286544) (xy 139.844877 -56.297068) (xy 140.186662 -56.297068) (xy 140.190733 -56.241446)
			(xy 140.202859 -56.187009) (xy 140.222782 -56.134918) (xy 140.250078 -56.086283) (xy 140.284164 -56.04214)
			(xy 140.324313 -56.003431) (xy 140.369671 -55.97098) (xy 140.419271 -55.945479) (xy 140.472055 -55.927472)
			(xy 140.526898 -55.917342) (xy 140.582632 -55.915305) (xy 140.638069 -55.921405) (xy 140.692026 -55.935511)
			(xy 140.743355 -55.957323) (xy 140.790961 -55.986377) (xy 140.833829 -56.022052) (xy 140.871046 -56.063589)
			(xy 140.901819 -56.110102) (xy 140.925491 -56.160599) (xy 140.941559 -56.214006) (xy 140.949679 -56.269182)
			(xy 140.950188 -56.297068) (xy 140.949679 -56.324954) (xy 140.945484 -56.353456) (xy 143.041368 -56.353456)
			(xy 143.045439 -56.297834) (xy 143.057565 -56.243397) (xy 143.077488 -56.191306) (xy 143.104784 -56.142671)
			(xy 143.13887 -56.098528) (xy 143.179019 -56.059819) (xy 143.224377 -56.027368) (xy 143.273977 -56.001867)
			(xy 143.326761 -55.98386) (xy 143.381604 -55.97373) (xy 143.437338 -55.971693) (xy 143.492775 -55.977793)
			(xy 143.546732 -55.991899) (xy 143.598061 -56.013711) (xy 143.645667 -56.042765) (xy 143.688535 -56.07844)
			(xy 143.725752 -56.119977) (xy 143.756525 -56.16649) (xy 143.780197 -56.216987) (xy 143.796265 -56.270394)
			(xy 143.804385 -56.32557) (xy 143.804894 -56.353456) (xy 143.804385 -56.381342) (xy 143.796265 -56.436518)
			(xy 143.780197 -56.489925) (xy 143.756525 -56.540422) (xy 143.725752 -56.586935) (xy 143.688535 -56.628472)
			(xy 143.645667 -56.664147) (xy 143.598061 -56.693201) (xy 143.546732 -56.715013) (xy 143.492775 -56.729119)
			(xy 143.437338 -56.735219) (xy 143.381604 -56.733182) (xy 143.326761 -56.723052) (xy 143.273977 -56.705045)
			(xy 143.224377 -56.679544) (xy 143.179019 -56.647093) (xy 143.13887 -56.608384) (xy 143.104784 -56.564241)
			(xy 143.077488 -56.515606) (xy 143.057565 -56.463515) (xy 143.045439 -56.409078) (xy 143.041368 -56.353456)
			(xy 140.945484 -56.353456) (xy 140.941559 -56.38013) (xy 140.925491 -56.433537) (xy 140.901819 -56.484034)
			(xy 140.871046 -56.530547) (xy 140.833829 -56.572084) (xy 140.790961 -56.607759) (xy 140.743355 -56.636813)
			(xy 140.692026 -56.658625) (xy 140.638069 -56.672731) (xy 140.582632 -56.678831) (xy 140.526898 -56.676794)
			(xy 140.472055 -56.666664) (xy 140.419271 -56.648657) (xy 140.369671 -56.623156) (xy 140.324313 -56.590705)
			(xy 140.284164 -56.551996) (xy 140.250078 -56.507853) (xy 140.222782 -56.459218) (xy 140.202859 -56.407127)
			(xy 140.190733 -56.35269) (xy 140.186662 -56.297068) (xy 139.844877 -56.297068) (xy 139.844877 -56.341056)
			(xy 139.837119 -56.395013) (xy 139.821761 -56.447317) (xy 139.799115 -56.496903) (xy 139.769642 -56.542761)
			(xy 139.733943 -56.583958) (xy 139.692745 -56.619654) (xy 139.646885 -56.649124) (xy 139.597298 -56.671768)
			(xy 139.544994 -56.687123) (xy 139.491036 -56.694878) (xy 139.46378 -56.69534) (xy 139.436409 -56.6949)
			(xy 139.382228 -56.687078) (xy 139.329724 -56.671584) (xy 139.279977 -56.648736) (xy 139.234012 -56.619005)
			(xy 139.213082 -56.60136) (xy 139.212828 -56.601106) (xy 139.205737 -56.595526) (xy 139.188824 -56.589275)
			(xy 139.179808 -56.588914) (xy 139.112752 -56.588914) (xy 139.103737 -56.589293) (xy 139.08682 -56.595525)
			(xy 139.079732 -56.601106) (xy 139.079732 -56.60136) (xy 139.079478 -56.60136) (xy 139.058545 -56.619001)
			(xy 139.012577 -56.648725) (xy 138.962831 -56.671571) (xy 138.910329 -56.687067) (xy 138.856151 -56.694896)
			(xy 138.801409 -56.694896) (xy 138.747231 -56.687067) (xy 138.694729 -56.671571) (xy 138.644983 -56.648725)
			(xy 138.599015 -56.619001) (xy 138.578082 -56.60136) (xy 138.577828 -56.601106) (xy 138.570737 -56.595526)
			(xy 138.553824 -56.589275) (xy 138.544808 -56.588914) (xy 138.477752 -56.588914) (xy 138.468737 -56.589293)
			(xy 138.45182 -56.595525) (xy 138.444732 -56.601106) (xy 138.444224 -56.60136) (xy 138.431492 -56.612307)
			(xy 138.404399 -56.632146) (xy 138.390122 -56.640984) (xy 138.381232 -56.646318) (xy 138.36904 -56.663336)
			(xy 138.34872 -56.756554) (xy 138.353038 -56.777128) (xy 138.35888 -56.785764) (xy 138.374865 -56.809838)
			(xy 138.400211 -56.861765) (xy 138.417441 -56.91692) (xy 138.426161 -56.974042) (xy 138.426698 -57.002934)
			(xy 138.426212 -57.030185) (xy 138.418456 -57.084133) (xy 138.403101 -57.136428) (xy 138.380459 -57.186005)
			(xy 138.350993 -57.231855) (xy 138.315302 -57.273046) (xy 138.274111 -57.308737) (xy 138.228261 -57.338203)
			(xy 138.178684 -57.360845) (xy 138.126389 -57.3762) (xy 138.072441 -57.383956) (xy 138.017939 -57.383956)
			(xy 137.963991 -57.3762) (xy 137.911696 -57.360845) (xy 137.862119 -57.338203) (xy 137.816269 -57.308737)
			(xy 137.775078 -57.273046) (xy 137.739387 -57.231855) (xy 137.709921 -57.186005) (xy 137.687279 -57.136428)
			(xy 137.671924 -57.084133) (xy 137.664168 -57.030185) (xy 137.663682 -57.002934) (xy 135.994556 -57.002934)
			(xy 136.001285 -57.04948) (xy 136.00176 -57.076848) (xy 136.001274 -57.104099) (xy 135.993518 -57.158047)
			(xy 135.978163 -57.210342) (xy 135.955521 -57.259919) (xy 135.926055 -57.305769) (xy 135.890364 -57.34696)
			(xy 135.849173 -57.382651) (xy 135.803323 -57.412117) (xy 135.753746 -57.434759) (xy 135.701451 -57.450114)
			(xy 135.647503 -57.45787) (xy 135.593001 -57.45787) (xy 135.539053 -57.450114) (xy 135.486758 -57.434759)
			(xy 135.437181 -57.412117) (xy 135.391331 -57.382651) (xy 135.35014 -57.34696) (xy 135.314449 -57.305769)
			(xy 135.284983 -57.259919) (xy 135.262341 -57.210342) (xy 135.246986 -57.158047) (xy 135.23923 -57.104099)
			(xy 135.238744 -57.076848) (xy 134.588959 -57.076848) (xy 134.613011 -57.095303) (xy 134.655394 -57.137686)
			(xy 134.691882 -57.185238) (xy 134.721851 -57.237147) (xy 134.744788 -57.292523) (xy 134.7603 -57.350419)
			(xy 134.768122 -57.409845) (xy 134.76859 -57.439814) (xy 134.768147 -57.468047) (xy 134.766012 -57.48528)
			(xy 146.70608 -57.48528) (xy 146.710151 -57.429658) (xy 146.722277 -57.375221) (xy 146.7422 -57.32313)
			(xy 146.769496 -57.274495) (xy 146.803582 -57.230352) (xy 146.843731 -57.191643) (xy 146.889089 -57.159192)
			(xy 146.938689 -57.133691) (xy 146.991473 -57.115684) (xy 147.046316 -57.105554) (xy 147.10205 -57.103517)
			(xy 147.157487 -57.109617) (xy 147.211444 -57.123723) (xy 147.262773 -57.145535) (xy 147.310379 -57.174589)
			(xy 147.353247 -57.210264) (xy 147.390464 -57.251801) (xy 147.421237 -57.298314) (xy 147.444909 -57.348811)
			(xy 147.460977 -57.402218) (xy 147.469097 -57.457394) (xy 147.469606 -57.48528) (xy 147.469097 -57.513166)
			(xy 147.460977 -57.568342) (xy 147.444909 -57.621749) (xy 147.421237 -57.672246) (xy 147.390464 -57.718759)
			(xy 147.353247 -57.760296) (xy 147.310379 -57.795971) (xy 147.262773 -57.825025) (xy 147.211444 -57.846837)
			(xy 147.157487 -57.860943) (xy 147.10205 -57.867043) (xy 147.046316 -57.865006) (xy 146.991473 -57.854876)
			(xy 146.938689 -57.836869) (xy 146.889089 -57.811368) (xy 146.843731 -57.778917) (xy 146.803582 -57.740208)
			(xy 146.769496 -57.696065) (xy 146.7422 -57.64743) (xy 146.722277 -57.595339) (xy 146.710151 -57.540902)
			(xy 146.70608 -57.48528) (xy 134.766012 -57.48528) (xy 134.761206 -57.524083) (xy 134.747421 -57.57884)
			(xy 134.726999 -57.631482) (xy 134.700252 -57.681211) (xy 134.684262 -57.704482) (xy 134.676896 -57.71515)
			(xy 134.673848 -57.740804) (xy 134.716266 -57.844436) (xy 134.736332 -57.860692) (xy 134.749286 -57.862978)
			(xy 134.775402 -57.868084) (xy 134.825973 -57.88465) (xy 134.873753 -57.908078) (xy 134.917816 -57.937916)
			(xy 134.957307 -57.973585) (xy 134.991461 -58.014393) (xy 135.019617 -58.05955) (xy 135.041227 -58.108179)
			(xy 135.055874 -58.159339) (xy 135.063273 -58.212037) (xy 135.063738 -58.238644) (xy 135.063254 -58.266014)
			(xy 135.055443 -58.320193) (xy 135.039959 -58.372696) (xy 135.017121 -58.422443) (xy 134.987398 -58.46841)
			(xy 134.969758 -58.489342) (xy 134.969504 -58.489596) (xy 134.963913 -58.49668) (xy 134.957669 -58.513599)
			(xy 134.957312 -58.522616) (xy 134.957312 -58.589672) (xy 134.95768 -58.598688) (xy 134.963919 -58.615605)
			(xy 134.969504 -58.622692) (xy 134.969758 -58.622692) (xy 134.969758 -58.622946) (xy 134.987379 -58.643893)
			(xy 135.01029 -58.679334) (xy 138.095482 -58.679334) (xy 138.095911 -58.653019) (xy 138.103155 -58.600889)
			(xy 138.117482 -58.550246) (xy 138.138621 -58.502047) (xy 138.166174 -58.457204) (xy 138.199618 -58.416566)
			(xy 138.218672 -58.39841) (xy 138.226067 -58.390883) (xy 138.234596 -58.371607) (xy 138.235182 -58.361072)
			(xy 138.235182 -58.286396) (xy 138.234674 -58.275844) (xy 138.226124 -58.256548) (xy 138.218672 -58.249058)
			(xy 138.199598 -58.230921) (xy 138.166143 -58.190287) (xy 138.138588 -58.145443) (xy 138.117453 -58.097238)
			(xy 138.103139 -58.046588) (xy 138.095918 -57.994451) (xy 138.095482 -57.968134) (xy 138.095968 -57.940883)
			(xy 138.103724 -57.886935) (xy 138.119079 -57.83464) (xy 138.141721 -57.785063) (xy 138.171187 -57.739213)
			(xy 138.206878 -57.698022) (xy 138.248069 -57.662331) (xy 138.293919 -57.632865) (xy 138.343496 -57.610223)
			(xy 138.395791 -57.594868) (xy 138.449739 -57.587112) (xy 138.504241 -57.587112) (xy 138.558189 -57.594868)
			(xy 138.610484 -57.610223) (xy 138.660061 -57.632865) (xy 138.705911 -57.662331) (xy 138.747102 -57.698022)
			(xy 138.782793 -57.739213) (xy 138.812259 -57.785063) (xy 138.834901 -57.83464) (xy 138.850256 -57.886935)
			(xy 138.858012 -57.940883) (xy 138.858498 -57.968134) (xy 138.858054 -57.994449) (xy 138.850814 -58.046578)
			(xy 138.836491 -58.097221) (xy 138.834289 -58.102242) (xy 142.018494 -58.102242) (xy 142.018494 -58.042306)
			(xy 142.026317 -57.982884) (xy 142.04183 -57.924991) (xy 142.064766 -57.869618) (xy 142.094733 -57.817712)
			(xy 142.13122 -57.770162) (xy 142.1736 -57.727782) (xy 142.22115 -57.691295) (xy 142.273056 -57.661328)
			(xy 142.328429 -57.638392) (xy 142.386322 -57.622879) (xy 142.445744 -57.615056) (xy 142.50568 -57.615056)
			(xy 142.565102 -57.622879) (xy 142.622995 -57.638392) (xy 142.678368 -57.661328) (xy 142.730274 -57.691295)
			(xy 142.777824 -57.727782) (xy 142.820204 -57.770162) (xy 142.856691 -57.817712) (xy 142.886658 -57.869618)
			(xy 142.909594 -57.924991) (xy 142.925107 -57.982884) (xy 142.93293 -58.042306) (xy 142.93342 -58.072274)
			(xy 142.93293 -58.102242) (xy 142.932428 -58.106052) (xy 147.382974 -58.106052) (xy 147.382974 -58.046116)
			(xy 147.390797 -57.986694) (xy 147.40631 -57.928801) (xy 147.429246 -57.873428) (xy 147.459213 -57.821522)
			(xy 147.4957 -57.773972) (xy 147.53808 -57.731592) (xy 147.58563 -57.695105) (xy 147.637536 -57.665138)
			(xy 147.692909 -57.642202) (xy 147.750802 -57.626689) (xy 147.810224 -57.618866) (xy 147.87016 -57.618866)
			(xy 147.929582 -57.626689) (xy 147.987475 -57.642202) (xy 148.042848 -57.665138) (xy 148.094754 -57.695105)
			(xy 148.142304 -57.731592) (xy 148.184684 -57.773972) (xy 148.221171 -57.821522) (xy 148.251138 -57.873428)
			(xy 148.261011 -57.897264) (xy 149.667958 -57.897264) (xy 149.667958 -57.837328) (xy 149.675781 -57.777906)
			(xy 149.691294 -57.720013) (xy 149.71423 -57.66464) (xy 149.744197 -57.612734) (xy 149.780684 -57.565184)
			(xy 149.823064 -57.522804) (xy 149.870614 -57.486317) (xy 149.92252 -57.45635) (xy 149.977893 -57.433414)
			(xy 150.035786 -57.417901) (xy 150.095208 -57.410078) (xy 150.155144 -57.410078) (xy 150.214566 -57.417901)
			(xy 150.272459 -57.433414) (xy 150.327832 -57.45635) (xy 150.379738 -57.486317) (xy 150.427288 -57.522804)
			(xy 150.469668 -57.565184) (xy 150.506155 -57.612734) (xy 150.536122 -57.66464) (xy 150.559058 -57.720013)
			(xy 150.574571 -57.777906) (xy 150.582394 -57.837328) (xy 150.582884 -57.867296) (xy 150.582394 -57.897264)
			(xy 150.574571 -57.956686) (xy 150.559058 -58.014579) (xy 150.536122 -58.069952) (xy 150.506155 -58.121858)
			(xy 150.469668 -58.169408) (xy 150.427288 -58.211788) (xy 150.379738 -58.248275) (xy 150.327832 -58.278242)
			(xy 150.272459 -58.301178) (xy 150.214566 -58.316691) (xy 150.155144 -58.324514) (xy 150.095208 -58.324514)
			(xy 150.035786 -58.316691) (xy 149.977893 -58.301178) (xy 149.92252 -58.278242) (xy 149.870614 -58.248275)
			(xy 149.823064 -58.211788) (xy 149.780684 -58.169408) (xy 149.744197 -58.121858) (xy 149.71423 -58.069952)
			(xy 149.691294 -58.014579) (xy 149.675781 -57.956686) (xy 149.667958 -57.897264) (xy 148.261011 -57.897264)
			(xy 148.274074 -57.928801) (xy 148.289587 -57.986694) (xy 148.29741 -58.046116) (xy 148.2979 -58.076084)
			(xy 148.29741 -58.106052) (xy 148.289587 -58.165474) (xy 148.274074 -58.223367) (xy 148.251138 -58.27874)
			(xy 148.221171 -58.330646) (xy 148.184684 -58.378196) (xy 148.142304 -58.420576) (xy 148.094754 -58.457063)
			(xy 148.042848 -58.48703) (xy 147.987475 -58.509966) (xy 147.929582 -58.525479) (xy 147.87016 -58.533302)
			(xy 147.810224 -58.533302) (xy 147.750802 -58.525479) (xy 147.692909 -58.509966) (xy 147.637536 -58.48703)
			(xy 147.58563 -58.457063) (xy 147.53808 -58.420576) (xy 147.4957 -58.378196) (xy 147.459213 -58.330646)
			(xy 147.429246 -58.27874) (xy 147.40631 -58.223367) (xy 147.390797 -58.165474) (xy 147.382974 -58.106052)
			(xy 142.932428 -58.106052) (xy 142.925107 -58.161664) (xy 142.909594 -58.219557) (xy 142.886658 -58.27493)
			(xy 142.856691 -58.326836) (xy 142.820204 -58.374386) (xy 142.777824 -58.416766) (xy 142.730274 -58.453253)
			(xy 142.678368 -58.48322) (xy 142.622995 -58.506156) (xy 142.565102 -58.521669) (xy 142.50568 -58.529492)
			(xy 142.445744 -58.529492) (xy 142.386322 -58.521669) (xy 142.328429 -58.506156) (xy 142.273056 -58.48322)
			(xy 142.22115 -58.453253) (xy 142.1736 -58.416766) (xy 142.13122 -58.374386) (xy 142.094733 -58.326836)
			(xy 142.064766 -58.27493) (xy 142.04183 -58.219557) (xy 142.026317 -58.161664) (xy 142.018494 -58.102242)
			(xy 138.834289 -58.102242) (xy 138.815354 -58.14542) (xy 138.787804 -58.190263) (xy 138.754361 -58.230902)
			(xy 138.735308 -58.249058) (xy 138.727924 -58.256594) (xy 138.719389 -58.275863) (xy 138.718798 -58.286396)
			(xy 138.718798 -58.361072) (xy 138.719329 -58.371621) (xy 138.727863 -58.390917) (xy 138.735308 -58.39841)
			(xy 138.754363 -58.416566) (xy 138.78782 -58.457196) (xy 138.815379 -58.502036) (xy 138.836517 -58.550237)
			(xy 138.848095 -58.591192) (xy 148.587188 -58.591192) (xy 148.587188 -58.531256) (xy 148.595011 -58.471834)
			(xy 148.610524 -58.413941) (xy 148.63346 -58.358568) (xy 148.663427 -58.306662) (xy 148.699914 -58.259112)
			(xy 148.742294 -58.216732) (xy 148.789844 -58.180245) (xy 148.84175 -58.150278) (xy 148.897123 -58.127342)
			(xy 148.955016 -58.111829) (xy 149.014438 -58.104006) (xy 149.074374 -58.104006) (xy 149.133796 -58.111829)
			(xy 149.191689 -58.127342) (xy 149.247062 -58.150278) (xy 149.298968 -58.180245) (xy 149.346518 -58.216732)
			(xy 149.388898 -58.259112) (xy 149.425385 -58.306662) (xy 149.455352 -58.358568) (xy 149.478288 -58.413941)
			(xy 149.493801 -58.471834) (xy 149.494835 -58.479686) (xy 150.833818 -58.479686) (xy 150.833818 -58.41975)
			(xy 150.841641 -58.360328) (xy 150.857154 -58.302435) (xy 150.88009 -58.247062) (xy 150.910057 -58.195156)
			(xy 150.946544 -58.147606) (xy 150.988924 -58.105226) (xy 151.036474 -58.068739) (xy 151.08838 -58.038772)
			(xy 151.143753 -58.015836) (xy 151.201646 -58.000323) (xy 151.261068 -57.9925) (xy 151.321004 -57.9925)
			(xy 151.380426 -58.000323) (xy 151.438319 -58.015836) (xy 151.493692 -58.038772) (xy 151.545598 -58.068739)
			(xy 151.593148 -58.105226) (xy 151.635528 -58.147606) (xy 151.672015 -58.195156) (xy 151.701982 -58.247062)
			(xy 151.724918 -58.302435) (xy 151.740431 -58.360328) (xy 151.748254 -58.41975) (xy 151.748744 -58.449718)
			(xy 151.748254 -58.479686) (xy 151.740431 -58.539108) (xy 151.724918 -58.597001) (xy 151.701982 -58.652374)
			(xy 151.672015 -58.70428) (xy 151.651202 -58.731404) (xy 155.62072 -58.731404) (xy 155.621184 -58.704034)
			(xy 155.629001 -58.649854) (xy 155.644491 -58.597351) (xy 155.667333 -58.547604) (xy 155.697058 -58.501637)
			(xy 155.7147 -58.480706) (xy 155.714954 -58.480452) (xy 155.720531 -58.473359) (xy 155.726782 -58.456447)
			(xy 155.727146 -58.447432) (xy 155.727146 -58.380376) (xy 155.726812 -58.371356) (xy 155.72055 -58.354439)
			(xy 155.714954 -58.347356) (xy 155.7147 -58.347356) (xy 155.7147 -58.347102) (xy 155.697064 -58.326166)
			(xy 155.667341 -58.280198) (xy 155.644498 -58.230452) (xy 155.629002 -58.177951) (xy 155.621174 -58.123773)
			(xy 155.621173 -58.069033) (xy 155.629001 -58.014855) (xy 155.644495 -57.962354) (xy 155.667339 -57.912608)
			(xy 155.697061 -57.866639) (xy 155.7147 -57.845706) (xy 155.714954 -57.845452) (xy 155.720531 -57.838359)
			(xy 155.726782 -57.821447) (xy 155.727146 -57.812432) (xy 155.727146 -57.745376) (xy 155.726812 -57.736356)
			(xy 155.72055 -57.719439) (xy 155.714954 -57.712356) (xy 155.7147 -57.712356) (xy 155.7147 -57.712102)
			(xy 155.697064 -57.691166) (xy 155.667341 -57.645198) (xy 155.644498 -57.595452) (xy 155.629002 -57.542951)
			(xy 155.621174 -57.488773) (xy 155.621173 -57.434033) (xy 155.629001 -57.379855) (xy 155.644495 -57.327354)
			(xy 155.667339 -57.277608) (xy 155.697061 -57.231639) (xy 155.7147 -57.210706) (xy 155.714954 -57.210452)
			(xy 155.720531 -57.203359) (xy 155.726782 -57.186447) (xy 155.727146 -57.177432) (xy 155.727146 -57.110376)
			(xy 155.726812 -57.101356) (xy 155.72055 -57.084439) (xy 155.714954 -57.077356) (xy 155.7147 -57.077356)
			(xy 155.7147 -57.077102) (xy 155.697048 -57.05618) (xy 155.667338 -57.010204) (xy 155.644505 -56.960454)
			(xy 155.629017 -56.907951) (xy 155.621192 -56.853774) (xy 155.62072 -56.826404) (xy 155.621206 -56.799153)
			(xy 155.628962 -56.745205) (xy 155.644317 -56.69291) (xy 155.666959 -56.643333) (xy 155.696425 -56.597483)
			(xy 155.732116 -56.556292) (xy 155.773307 -56.520601) (xy 155.819157 -56.491135) (xy 155.868734 -56.468493)
			(xy 155.921029 -56.453138) (xy 155.974977 -56.445382) (xy 156.029479 -56.445382) (xy 156.083427 -56.453138)
			(xy 156.135722 -56.468493) (xy 156.185299 -56.491135) (xy 156.231149 -56.520601) (xy 156.27234 -56.556292)
			(xy 156.308031 -56.597483) (xy 156.337497 -56.643333) (xy 156.360139 -56.69291) (xy 156.375494 -56.745205)
			(xy 156.38325 -56.799153) (xy 156.383446 -56.810148) (xy 158.200344 -56.810148) (xy 158.200344 -56.809894)
			(xy 158.200834 -56.779926) (xy 158.208657 -56.720504) (xy 158.22417 -56.662611) (xy 158.247106 -56.607238)
			(xy 158.277073 -56.555332) (xy 158.31356 -56.507782) (xy 158.35594 -56.465402) (xy 158.40349 -56.428915)
			(xy 158.455396 -56.398948) (xy 158.510769 -56.376012) (xy 158.568662 -56.360499) (xy 158.628084 -56.352676)
			(xy 158.68802 -56.352676) (xy 158.747442 -56.360499) (xy 158.805335 -56.376012) (xy 158.860708 -56.398948)
			(xy 158.912614 -56.428915) (xy 158.960164 -56.465402) (xy 159.002544 -56.507782) (xy 159.039031 -56.555332)
			(xy 159.068998 -56.607238) (xy 159.091934 -56.662611) (xy 159.107447 -56.720504) (xy 159.11527 -56.779926)
			(xy 159.11576 -56.809894) (xy 159.11576 -56.810148) (xy 159.115199 -56.841672) (xy 159.10653 -56.904121)
			(xy 159.089375 -56.96479) (xy 159.06406 -57.022532) (xy 159.031063 -57.076256) (xy 158.991008 -57.124945)
			(xy 158.968186 -57.146698) (xy 158.961074 -57.153302) (xy 158.952692 -57.17032) (xy 158.946342 -57.248806)
			(xy 158.945967 -57.258372) (xy 158.951589 -57.276656) (xy 158.957264 -57.284366) (xy 158.972806 -57.304646)
			(xy 158.998863 -57.348597) (xy 159.018825 -57.395631) (xy 159.032335 -57.444908) (xy 159.035316 -57.467053)
			(xy 159.218569 -57.467053) (xy 159.218569 -57.412547) (xy 159.226327 -57.358595) (xy 159.241684 -57.306297)
			(xy 159.264328 -57.256717) (xy 159.293797 -57.210864) (xy 159.329493 -57.169672) (xy 159.370688 -57.133979)
			(xy 159.416543 -57.104513) (xy 159.466125 -57.081873) (xy 159.518425 -57.06652) (xy 159.572377 -57.058767)
			(xy 159.59963 -57.058306) (xy 159.625179 -57.058683) (xy 159.67582 -57.065498) (xy 159.725097 -57.079014)
			(xy 159.772128 -57.09899) (xy 159.81607 -57.125068) (xy 159.836358 -57.140602) (xy 159.844096 -57.14622)
			(xy 159.862361 -57.151832) (xy 159.871918 -57.151524) (xy 159.950404 -57.145174) (xy 159.967422 -57.136792)
			(xy 159.974026 -57.12968) (xy 159.995765 -57.10684) (xy 160.044443 -57.066761) (xy 160.098165 -57.033748)
			(xy 160.155912 -57.008428) (xy 160.21659 -56.99128) (xy 160.279049 -56.982629) (xy 160.310576 -56.982106)
			(xy 160.31083 -56.982106) (xy 160.340799 -56.982554) (xy 160.400224 -56.990381) (xy 160.458118 -57.005898)
			(xy 160.513492 -57.028838) (xy 160.565398 -57.05881) (xy 160.588903 -57.076848) (xy 161.238692 -57.076848)
			(xy 161.239188 -57.049479) (xy 161.246999 -56.995301) (xy 161.262481 -56.942798) (xy 161.285316 -56.893051)
			(xy 161.315034 -56.847083) (xy 161.332672 -56.82615) (xy 161.332926 -56.825896) (xy 161.338523 -56.818817)
			(xy 161.344763 -56.801894) (xy 161.345118 -56.792876) (xy 161.345118 -56.72582) (xy 161.344748 -56.716805)
			(xy 161.338509 -56.699888) (xy 161.332926 -56.6928) (xy 161.332672 -56.6928) (xy 161.332672 -56.692546)
			(xy 161.315037 -56.671611) (xy 161.285325 -56.625639) (xy 161.262489 -56.575892) (xy 161.246997 -56.523392)
			(xy 161.239167 -56.469217) (xy 161.238692 -56.441848) (xy 161.239178 -56.414597) (xy 161.246934 -56.360649)
			(xy 161.262289 -56.308354) (xy 161.284931 -56.258777) (xy 161.314397 -56.212927) (xy 161.350088 -56.171736)
			(xy 161.391279 -56.136045) (xy 161.437129 -56.106579) (xy 161.486706 -56.083937) (xy 161.539001 -56.068582)
			(xy 161.592949 -56.060826) (xy 161.647451 -56.060826) (xy 161.701399 -56.068582) (xy 161.753694 -56.083937)
			(xy 161.803271 -56.106579) (xy 161.849121 -56.136045) (xy 161.890312 -56.171736) (xy 161.926003 -56.212927)
			(xy 161.955469 -56.258777) (xy 161.978111 -56.308354) (xy 161.993466 -56.360649) (xy 162.001222 -56.414597)
			(xy 162.001708 -56.441848) (xy 162.001209 -56.469217) (xy 161.993399 -56.523395) (xy 161.977918 -56.575897)
			(xy 161.955083 -56.625645) (xy 161.925366 -56.671613) (xy 161.907728 -56.692546) (xy 161.907474 -56.6928)
			(xy 161.901878 -56.69988) (xy 161.895638 -56.716802) (xy 161.895282 -56.72582) (xy 161.895282 -56.792876)
			(xy 161.895654 -56.801891) (xy 161.901892 -56.818808) (xy 161.907474 -56.825896) (xy 161.907728 -56.825896)
			(xy 161.907728 -56.82615) (xy 161.925361 -56.847087) (xy 161.955073 -56.893059) (xy 161.97791 -56.942805)
			(xy 161.993402 -56.995304) (xy 161.994505 -57.002934) (xy 163.66363 -57.002934) (xy 163.664128 -56.974842)
			(xy 163.672352 -56.919264) (xy 163.688641 -56.865494) (xy 163.712642 -56.814696) (xy 163.743837 -56.767969)
			(xy 163.78155 -56.726324) (xy 163.824965 -56.690663) (xy 163.848796 -56.675782) (xy 163.857686 -56.670448)
			(xy 163.869878 -56.65343) (xy 163.890198 -56.560212) (xy 163.88588 -56.539638) (xy 163.880038 -56.531002)
			(xy 163.864041 -56.506936) (xy 163.838697 -56.455006) (xy 163.82147 -56.399848) (xy 163.812754 -56.342724)
			(xy 163.81222 -56.313832) (xy 163.812685 -56.286579) (xy 163.820439 -56.232626) (xy 163.835792 -56.180327)
			(xy 163.858433 -56.130745) (xy 163.8879 -56.08489) (xy 163.923594 -56.043697) (xy 163.964787 -56.008002)
			(xy 164.010641 -55.978535) (xy 164.060223 -55.955893) (xy 164.112522 -55.940539) (xy 164.166475 -55.932785)
			(xy 164.193728 -55.932324) (xy 164.221099 -55.932768) (xy 164.275279 -55.94059) (xy 164.327783 -55.956084)
			(xy 164.377529 -55.978931) (xy 164.423495 -56.00866) (xy 164.444426 -56.026304) (xy 164.44468 -56.026558)
			(xy 164.451763 -56.032149) (xy 164.468683 -56.038392) (xy 164.4777 -56.03875) (xy 164.544756 -56.03875)
			(xy 164.553772 -56.038383) (xy 164.57069 -56.032144) (xy 164.577776 -56.026558) (xy 164.577776 -56.026304)
			(xy 164.57803 -56.026304) (xy 164.598963 -56.008663) (xy 164.644931 -55.978939) (xy 164.694677 -55.956093)
			(xy 164.747179 -55.940597) (xy 164.801357 -55.932768) (xy 164.856099 -55.932768) (xy 164.910277 -55.940597)
			(xy 164.962779 -55.956093) (xy 165.012525 -55.978939) (xy 165.058493 -56.008663) (xy 165.079426 -56.026304)
			(xy 165.07968 -56.026558) (xy 165.086763 -56.032149) (xy 165.103683 -56.038392) (xy 165.1127 -56.03875)
			(xy 165.179756 -56.03875) (xy 165.188772 -56.038383) (xy 165.20569 -56.032144) (xy 165.212776 -56.026558)
			(xy 165.212776 -56.026304) (xy 165.21303 -56.026304) (xy 165.233978 -56.008685) (xy 165.279946 -55.97897)
			(xy 165.32969 -55.95613) (xy 165.382187 -55.940634) (xy 165.43636 -55.932801) (xy 165.463728 -55.932324)
			(xy 165.49098 -55.932748) (xy 165.544929 -55.940508) (xy 165.597225 -55.955867) (xy 165.646803 -55.978512)
			(xy 165.692654 -56.007981) (xy 165.733844 -56.043676) (xy 165.769536 -56.084869) (xy 165.799002 -56.130722)
			(xy 165.821643 -56.180301) (xy 165.836998 -56.232598) (xy 165.844754 -56.286548) (xy 165.844754 -56.297068)
			(xy 166.18661 -56.297068) (xy 166.190681 -56.241446) (xy 166.202807 -56.187009) (xy 166.22273 -56.134918)
			(xy 166.250026 -56.086283) (xy 166.284112 -56.04214) (xy 166.324261 -56.003431) (xy 166.369619 -55.97098)
			(xy 166.419219 -55.945479) (xy 166.472003 -55.927472) (xy 166.526846 -55.917342) (xy 166.58258 -55.915305)
			(xy 166.638017 -55.921405) (xy 166.691974 -55.935511) (xy 166.743303 -55.957323) (xy 166.790909 -55.986377)
			(xy 166.833777 -56.022052) (xy 166.870994 -56.063589) (xy 166.901767 -56.110102) (xy 166.925439 -56.160599)
			(xy 166.941507 -56.214006) (xy 166.949627 -56.269182) (xy 166.950136 -56.297068) (xy 166.949627 -56.324954)
			(xy 166.945432 -56.353456) (xy 169.041316 -56.353456) (xy 169.045387 -56.297834) (xy 169.057513 -56.243397)
			(xy 169.077436 -56.191306) (xy 169.104732 -56.142671) (xy 169.138818 -56.098528) (xy 169.178967 -56.059819)
			(xy 169.224325 -56.027368) (xy 169.273925 -56.001867) (xy 169.326709 -55.98386) (xy 169.381552 -55.97373)
			(xy 169.437286 -55.971693) (xy 169.492723 -55.977793) (xy 169.54668 -55.991899) (xy 169.598009 -56.013711)
			(xy 169.645615 -56.042765) (xy 169.688483 -56.07844) (xy 169.7257 -56.119977) (xy 169.756473 -56.16649)
			(xy 169.780145 -56.216987) (xy 169.796213 -56.270394) (xy 169.804333 -56.32557) (xy 169.804842 -56.353456)
			(xy 169.804333 -56.381342) (xy 169.796213 -56.436518) (xy 169.780145 -56.489925) (xy 169.756473 -56.540422)
			(xy 169.7257 -56.586935) (xy 169.688483 -56.628472) (xy 169.645615 -56.664147) (xy 169.598009 -56.693201)
			(xy 169.54668 -56.715013) (xy 169.492723 -56.729119) (xy 169.437286 -56.735219) (xy 169.381552 -56.733182)
			(xy 169.326709 -56.723052) (xy 169.273925 -56.705045) (xy 169.224325 -56.679544) (xy 169.178967 -56.647093)
			(xy 169.138818 -56.608384) (xy 169.104732 -56.564241) (xy 169.077436 -56.515606) (xy 169.057513 -56.463515)
			(xy 169.045387 -56.409078) (xy 169.041316 -56.353456) (xy 166.945432 -56.353456) (xy 166.941507 -56.38013)
			(xy 166.925439 -56.433537) (xy 166.901767 -56.484034) (xy 166.870994 -56.530547) (xy 166.833777 -56.572084)
			(xy 166.790909 -56.607759) (xy 166.743303 -56.636813) (xy 166.691974 -56.658625) (xy 166.638017 -56.672731)
			(xy 166.58258 -56.678831) (xy 166.526846 -56.676794) (xy 166.472003 -56.666664) (xy 166.419219 -56.648657)
			(xy 166.369619 -56.623156) (xy 166.324261 -56.590705) (xy 166.284112 -56.551996) (xy 166.250026 -56.507853)
			(xy 166.22273 -56.459218) (xy 166.202807 -56.407127) (xy 166.190681 -56.35269) (xy 166.18661 -56.297068)
			(xy 165.844754 -56.297068) (xy 165.844754 -56.341052) (xy 165.836998 -56.395002) (xy 165.821643 -56.447299)
			(xy 165.799002 -56.496878) (xy 165.769536 -56.542731) (xy 165.733844 -56.583924) (xy 165.692654 -56.619619)
			(xy 165.646803 -56.649088) (xy 165.597225 -56.671733) (xy 165.544929 -56.687092) (xy 165.49098 -56.694852)
			(xy 165.463728 -56.69534) (xy 165.436358 -56.694872) (xy 165.382178 -56.687057) (xy 165.329674 -56.671569)
			(xy 165.279927 -56.648727) (xy 165.233961 -56.619002) (xy 165.21303 -56.60136) (xy 165.212776 -56.601106)
			(xy 165.2057 -56.595504) (xy 165.188775 -56.589266) (xy 165.179756 -56.588914) (xy 165.1127 -56.588914)
			(xy 165.103683 -56.589268) (xy 165.086766 -56.595517) (xy 165.07968 -56.601106) (xy 165.07968 -56.60136)
			(xy 165.079426 -56.60136) (xy 165.058493 -56.619001) (xy 165.012525 -56.648725) (xy 164.962779 -56.671571)
			(xy 164.910277 -56.687067) (xy 164.856099 -56.694896) (xy 164.801357 -56.694896) (xy 164.747179 -56.687067)
			(xy 164.694677 -56.671571) (xy 164.644931 -56.648725) (xy 164.598963 -56.619001) (xy 164.57803 -56.60136)
			(xy 164.577776 -56.601106) (xy 164.5707 -56.595504) (xy 164.553775 -56.589266) (xy 164.544756 -56.588914)
			(xy 164.4777 -56.588914) (xy 164.468683 -56.589268) (xy 164.451766 -56.595517) (xy 164.44468 -56.601106)
			(xy 164.444172 -56.60136) (xy 164.431437 -56.612303) (xy 164.404346 -56.632145) (xy 164.39007 -56.640984)
			(xy 164.38118 -56.646318) (xy 164.368988 -56.663336) (xy 164.348668 -56.756554) (xy 164.352986 -56.777128)
			(xy 164.358828 -56.785764) (xy 164.374818 -56.809834) (xy 164.400162 -56.861764) (xy 164.417391 -56.91692)
			(xy 164.426109 -56.974042) (xy 164.426646 -57.002934) (xy 164.42616 -57.030185) (xy 164.418404 -57.084133)
			(xy 164.403049 -57.136428) (xy 164.380407 -57.186005) (xy 164.350941 -57.231855) (xy 164.31525 -57.273046)
			(xy 164.274059 -57.308737) (xy 164.228209 -57.338203) (xy 164.178632 -57.360845) (xy 164.126337 -57.3762)
			(xy 164.072389 -57.383956) (xy 164.017887 -57.383956) (xy 163.963939 -57.3762) (xy 163.911644 -57.360845)
			(xy 163.862067 -57.338203) (xy 163.816217 -57.308737) (xy 163.775026 -57.273046) (xy 163.739335 -57.231855)
			(xy 163.709869 -57.186005) (xy 163.687227 -57.136428) (xy 163.671872 -57.084133) (xy 163.664116 -57.030185)
			(xy 163.66363 -57.002934) (xy 161.994505 -57.002934) (xy 162.001233 -57.049479) (xy 162.001708 -57.076848)
			(xy 162.001222 -57.104099) (xy 161.993466 -57.158047) (xy 161.978111 -57.210342) (xy 161.955469 -57.259919)
			(xy 161.926003 -57.305769) (xy 161.890312 -57.34696) (xy 161.849121 -57.382651) (xy 161.803271 -57.412117)
			(xy 161.753694 -57.434759) (xy 161.701399 -57.450114) (xy 161.647451 -57.45787) (xy 161.592949 -57.45787)
			(xy 161.539001 -57.450114) (xy 161.486706 -57.434759) (xy 161.437129 -57.412117) (xy 161.391279 -57.382651)
			(xy 161.350088 -57.34696) (xy 161.314397 -57.305769) (xy 161.284931 -57.259919) (xy 161.262289 -57.210342)
			(xy 161.246934 -57.158047) (xy 161.239178 -57.104099) (xy 161.238692 -57.076848) (xy 160.588903 -57.076848)
			(xy 160.612948 -57.0953) (xy 160.655329 -57.137685) (xy 160.691815 -57.185238) (xy 160.721781 -57.237147)
			(xy 160.744716 -57.292524) (xy 160.760227 -57.35042) (xy 160.768049 -57.409845) (xy 160.768538 -57.439814)
			(xy 160.768104 -57.468047) (xy 160.765969 -57.48528) (xy 172.706028 -57.48528) (xy 172.710099 -57.429658)
			(xy 172.722225 -57.375221) (xy 172.742148 -57.32313) (xy 172.769444 -57.274495) (xy 172.80353 -57.230352)
			(xy 172.843679 -57.191643) (xy 172.889037 -57.159192) (xy 172.938637 -57.133691) (xy 172.991421 -57.115684)
			(xy 173.046264 -57.105554) (xy 173.101998 -57.103517) (xy 173.157435 -57.109617) (xy 173.211392 -57.123723)
			(xy 173.262721 -57.145535) (xy 173.310327 -57.174589) (xy 173.353195 -57.210264) (xy 173.390412 -57.251801)
			(xy 173.421185 -57.298314) (xy 173.444857 -57.348811) (xy 173.460925 -57.402218) (xy 173.469045 -57.457394)
			(xy 173.469554 -57.48528) (xy 173.469045 -57.513166) (xy 173.460925 -57.568342) (xy 173.444857 -57.621749)
			(xy 173.421185 -57.672246) (xy 173.390412 -57.718759) (xy 173.353195 -57.760296) (xy 173.310327 -57.795971)
			(xy 173.262721 -57.825025) (xy 173.211392 -57.846837) (xy 173.157435 -57.860943) (xy 173.101998 -57.867043)
			(xy 173.046264 -57.865006) (xy 172.991421 -57.854876) (xy 172.938637 -57.836869) (xy 172.889037 -57.811368)
			(xy 172.843679 -57.778917) (xy 172.80353 -57.740208) (xy 172.769444 -57.696065) (xy 172.742148 -57.64743)
			(xy 172.722225 -57.595339) (xy 172.710099 -57.540902) (xy 172.706028 -57.48528) (xy 160.765969 -57.48528)
			(xy 160.761163 -57.524084) (xy 160.747376 -57.578841) (xy 160.726952 -57.631484) (xy 160.700202 -57.681211)
			(xy 160.68421 -57.704482) (xy 160.676844 -57.71515) (xy 160.673796 -57.740804) (xy 160.716214 -57.844436)
			(xy 160.73628 -57.860692) (xy 160.749234 -57.862978) (xy 160.775342 -57.868123) (xy 160.825913 -57.884681)
			(xy 160.873694 -57.908104) (xy 160.917757 -57.937937) (xy 160.95725 -57.973601) (xy 160.991406 -58.014405)
			(xy 161.019562 -58.059558) (xy 161.041174 -58.108185) (xy 161.055821 -58.159342) (xy 161.063221 -58.212038)
			(xy 161.063686 -58.238644) (xy 161.063191 -58.266013) (xy 161.05538 -58.320191) (xy 161.039898 -58.372694)
			(xy 161.017063 -58.422441) (xy 160.987344 -58.468409) (xy 160.969706 -58.489342) (xy 160.969452 -58.489596)
			(xy 160.963855 -58.496675) (xy 160.957616 -58.513598) (xy 160.95726 -58.522616) (xy 160.95726 -58.589672)
			(xy 160.957617 -58.598689) (xy 160.963863 -58.615607) (xy 160.969452 -58.622692) (xy 160.969706 -58.622692)
			(xy 160.969706 -58.622946) (xy 160.987334 -58.643887) (xy 161.010245 -58.679334) (xy 164.01923 -58.679334)
			(xy 164.01923 -58.67908) (xy 164.019746 -58.647555) (xy 164.028425 -58.585104) (xy 164.045588 -58.524434)
			(xy 164.070912 -58.466692) (xy 164.103917 -58.41297) (xy 164.143979 -58.364282) (xy 164.166804 -58.34253)
			(xy 164.173916 -58.335926) (xy 164.182298 -58.318908) (xy 164.188648 -58.240422) (xy 164.18899 -58.230858)
			(xy 164.183388 -58.212576) (xy 164.177726 -58.204862) (xy 164.162195 -58.184574) (xy 164.136137 -58.140625)
			(xy 164.116173 -58.093593) (xy 164.10266 -58.044318) (xy 164.095841 -57.993681) (xy 164.09543 -57.968134)
			(xy 164.095916 -57.940883) (xy 164.103672 -57.886935) (xy 164.119027 -57.83464) (xy 164.141669 -57.785063)
			(xy 164.171135 -57.739213) (xy 164.206826 -57.698022) (xy 164.248017 -57.662331) (xy 164.293867 -57.632865)
			(xy 164.343444 -57.610223) (xy 164.395739 -57.594868) (xy 164.449687 -57.587112) (xy 164.504189 -57.587112)
			(xy 164.558137 -57.594868) (xy 164.610432 -57.610223) (xy 164.660009 -57.632865) (xy 164.705859 -57.662331)
			(xy 164.74705 -57.698022) (xy 164.782741 -57.739213) (xy 164.812207 -57.785063) (xy 164.834849 -57.83464)
			(xy 164.850204 -57.886935) (xy 164.85796 -57.940883) (xy 164.858446 -57.968134) (xy 164.85806 -57.993682)
			(xy 164.851246 -58.044323) (xy 164.837731 -58.0936) (xy 164.834061 -58.102242) (xy 168.018442 -58.102242)
			(xy 168.018442 -58.042306) (xy 168.026265 -57.982884) (xy 168.041778 -57.924991) (xy 168.064714 -57.869618)
			(xy 168.094681 -57.817712) (xy 168.131168 -57.770162) (xy 168.173548 -57.727782) (xy 168.221098 -57.691295)
			(xy 168.273004 -57.661328) (xy 168.328377 -57.638392) (xy 168.38627 -57.622879) (xy 168.445692 -57.615056)
			(xy 168.505628 -57.615056) (xy 168.56505 -57.622879) (xy 168.622943 -57.638392) (xy 168.678316 -57.661328)
			(xy 168.730222 -57.691295) (xy 168.777772 -57.727782) (xy 168.820152 -57.770162) (xy 168.856639 -57.817712)
			(xy 168.886606 -57.869618) (xy 168.909542 -57.924991) (xy 168.925055 -57.982884) (xy 168.932878 -58.042306)
			(xy 168.933368 -58.072274) (xy 168.932878 -58.102242) (xy 168.932376 -58.106052) (xy 173.382922 -58.106052)
			(xy 173.382922 -58.046116) (xy 173.390745 -57.986694) (xy 173.406258 -57.928801) (xy 173.429194 -57.873428)
			(xy 173.459161 -57.821522) (xy 173.495648 -57.773972) (xy 173.538028 -57.731592) (xy 173.585578 -57.695105)
			(xy 173.637484 -57.665138) (xy 173.692857 -57.642202) (xy 173.75075 -57.626689) (xy 173.810172 -57.618866)
			(xy 173.870108 -57.618866) (xy 173.92953 -57.626689) (xy 173.987423 -57.642202) (xy 174.042796 -57.665138)
			(xy 174.094702 -57.695105) (xy 174.142252 -57.731592) (xy 174.184632 -57.773972) (xy 174.221119 -57.821522)
			(xy 174.251086 -57.873428) (xy 174.260959 -57.897264) (xy 175.667906 -57.897264) (xy 175.667906 -57.837328)
			(xy 175.675729 -57.777906) (xy 175.691242 -57.720013) (xy 175.714178 -57.66464) (xy 175.744145 -57.612734)
			(xy 175.780632 -57.565184) (xy 175.823012 -57.522804) (xy 175.870562 -57.486317) (xy 175.922468 -57.45635)
			(xy 175.977841 -57.433414) (xy 176.035734 -57.417901) (xy 176.095156 -57.410078) (xy 176.155092 -57.410078)
			(xy 176.214514 -57.417901) (xy 176.272407 -57.433414) (xy 176.32778 -57.45635) (xy 176.379686 -57.486317)
			(xy 176.427236 -57.522804) (xy 176.469616 -57.565184) (xy 176.506103 -57.612734) (xy 176.53607 -57.66464)
			(xy 176.559006 -57.720013) (xy 176.574519 -57.777906) (xy 176.582342 -57.837328) (xy 176.582832 -57.867296)
			(xy 176.582342 -57.897264) (xy 176.574519 -57.956686) (xy 176.559006 -58.014579) (xy 176.53607 -58.069952)
			(xy 176.506103 -58.121858) (xy 176.469616 -58.169408) (xy 176.427236 -58.211788) (xy 176.379686 -58.248275)
			(xy 176.32778 -58.278242) (xy 176.272407 -58.301178) (xy 176.214514 -58.316691) (xy 176.155092 -58.324514)
			(xy 176.095156 -58.324514) (xy 176.035734 -58.316691) (xy 175.977841 -58.301178) (xy 175.922468 -58.278242)
			(xy 175.870562 -58.248275) (xy 175.823012 -58.211788) (xy 175.780632 -58.169408) (xy 175.744145 -58.121858)
			(xy 175.714178 -58.069952) (xy 175.691242 -58.014579) (xy 175.675729 -57.956686) (xy 175.667906 -57.897264)
			(xy 174.260959 -57.897264) (xy 174.274022 -57.928801) (xy 174.289535 -57.986694) (xy 174.297358 -58.046116)
			(xy 174.297848 -58.076084) (xy 174.297358 -58.106052) (xy 174.289535 -58.165474) (xy 174.274022 -58.223367)
			(xy 174.251086 -58.27874) (xy 174.221119 -58.330646) (xy 174.184632 -58.378196) (xy 174.142252 -58.420576)
			(xy 174.094702 -58.457063) (xy 174.042796 -58.48703) (xy 173.987423 -58.509966) (xy 173.92953 -58.525479)
			(xy 173.870108 -58.533302) (xy 173.810172 -58.533302) (xy 173.75075 -58.525479) (xy 173.692857 -58.509966)
			(xy 173.637484 -58.48703) (xy 173.585578 -58.457063) (xy 173.538028 -58.420576) (xy 173.495648 -58.378196)
			(xy 173.459161 -58.330646) (xy 173.429194 -58.27874) (xy 173.406258 -58.223367) (xy 173.390745 -58.165474)
			(xy 173.382922 -58.106052) (xy 168.932376 -58.106052) (xy 168.925055 -58.161664) (xy 168.909542 -58.219557)
			(xy 168.886606 -58.27493) (xy 168.856639 -58.326836) (xy 168.820152 -58.374386) (xy 168.777772 -58.416766)
			(xy 168.730222 -58.453253) (xy 168.678316 -58.48322) (xy 168.622943 -58.506156) (xy 168.56505 -58.521669)
			(xy 168.505628 -58.529492) (xy 168.445692 -58.529492) (xy 168.38627 -58.521669) (xy 168.328377 -58.506156)
			(xy 168.273004 -58.48322) (xy 168.221098 -58.453253) (xy 168.173548 -58.416766) (xy 168.131168 -58.374386)
			(xy 168.094681 -58.326836) (xy 168.064714 -58.27493) (xy 168.041778 -58.219557) (xy 168.026265 -58.161664)
			(xy 168.018442 -58.102242) (xy 164.834061 -58.102242) (xy 164.817757 -58.140631) (xy 164.791683 -58.184574)
			(xy 164.77615 -58.204862) (xy 164.770536 -58.212602) (xy 164.76492 -58.230866) (xy 164.765228 -58.240422)
			(xy 164.771578 -58.318908) (xy 164.77996 -58.335926) (xy 164.787072 -58.34253) (xy 164.809924 -58.364257)
			(xy 164.85 -58.412939) (xy 164.88301 -58.466664) (xy 164.908328 -58.524413) (xy 164.925474 -58.585093)
			(xy 164.926319 -58.591192) (xy 174.587136 -58.591192) (xy 174.587136 -58.531256) (xy 174.594959 -58.471834)
			(xy 174.610472 -58.413941) (xy 174.633408 -58.358568) (xy 174.663375 -58.306662) (xy 174.699862 -58.259112)
			(xy 174.742242 -58.216732) (xy 174.789792 -58.180245) (xy 174.841698 -58.150278) (xy 174.897071 -58.127342)
			(xy 174.954964 -58.111829) (xy 175.014386 -58.104006) (xy 175.074322 -58.104006) (xy 175.133744 -58.111829)
			(xy 175.191637 -58.127342) (xy 175.24701 -58.150278) (xy 175.298916 -58.180245) (xy 175.346466 -58.216732)
			(xy 175.388846 -58.259112) (xy 175.425333 -58.306662) (xy 175.4553 -58.358568) (xy 175.478236 -58.413941)
			(xy 175.493749 -58.471834) (xy 175.494783 -58.479686) (xy 176.833766 -58.479686) (xy 176.833766 -58.41975)
			(xy 176.841589 -58.360328) (xy 176.857102 -58.302435) (xy 176.880038 -58.247062) (xy 176.910005 -58.195156)
			(xy 176.946492 -58.147606) (xy 176.988872 -58.105226) (xy 177.036422 -58.068739) (xy 177.088328 -58.038772)
			(xy 177.143701 -58.015836) (xy 177.201594 -58.000323) (xy 177.261016 -57.9925) (xy 177.320952 -57.9925)
			(xy 177.380374 -58.000323) (xy 177.438267 -58.015836) (xy 177.49364 -58.038772) (xy 177.545546 -58.068739)
			(xy 177.593096 -58.105226) (xy 177.635476 -58.147606) (xy 177.671963 -58.195156) (xy 177.70193 -58.247062)
			(xy 177.724866 -58.302435) (xy 177.740379 -58.360328) (xy 177.748202 -58.41975) (xy 177.748692 -58.449718)
			(xy 177.748202 -58.479686) (xy 177.740379 -58.539108) (xy 177.724866 -58.597001) (xy 177.70193 -58.652374)
			(xy 177.671963 -58.70428) (xy 177.65115 -58.731404) (xy 181.620668 -58.731404) (xy 181.62112 -58.704033)
			(xy 181.628939 -58.649853) (xy 181.64443 -58.597349) (xy 181.667275 -58.547602) (xy 181.697004 -58.501637)
			(xy 181.714648 -58.480706) (xy 181.714902 -58.480452) (xy 181.720473 -58.473355) (xy 181.726729 -58.456446)
			(xy 181.727094 -58.447432) (xy 181.727094 -58.380376) (xy 181.72675 -58.371358) (xy 181.720493 -58.354441)
			(xy 181.714902 -58.347356) (xy 181.714648 -58.347356) (xy 181.714648 -58.347102) (xy 181.69701 -58.326167)
			(xy 181.667284 -58.2802) (xy 181.644437 -58.230454) (xy 181.628939 -58.177952) (xy 181.62111 -58.123774)
			(xy 181.62111 -58.069032) (xy 181.628938 -58.014854) (xy 181.644435 -57.962352) (xy 181.667281 -57.912606)
			(xy 181.697007 -57.866638) (xy 181.714648 -57.845706) (xy 181.714902 -57.845452) (xy 181.720473 -57.838355)
			(xy 181.726729 -57.821446) (xy 181.727094 -57.812432) (xy 181.727094 -57.745376) (xy 181.72675 -57.736358)
			(xy 181.720493 -57.719441) (xy 181.714902 -57.712356) (xy 181.714648 -57.712356) (xy 181.714648 -57.712102)
			(xy 181.69701 -57.691167) (xy 181.667284 -57.6452) (xy 181.644437 -57.595454) (xy 181.628939 -57.542952)
			(xy 181.62111 -57.488774) (xy 181.62111 -57.434032) (xy 181.628938 -57.379854) (xy 181.644435 -57.327352)
			(xy 181.667281 -57.277606) (xy 181.697007 -57.231638) (xy 181.714648 -57.210706) (xy 181.714902 -57.210452)
			(xy 181.720473 -57.203355) (xy 181.726729 -57.186446) (xy 181.727094 -57.177432) (xy 181.727094 -57.110376)
			(xy 181.72675 -57.101358) (xy 181.720493 -57.084441) (xy 181.714902 -57.077356) (xy 181.714648 -57.077356)
			(xy 181.714648 -57.077102) (xy 181.697004 -57.056174) (xy 181.667291 -57.010201) (xy 181.644455 -56.960452)
			(xy 181.628966 -56.90795) (xy 181.62114 -56.853774) (xy 181.620668 -56.826404) (xy 181.621154 -56.799153)
			(xy 181.62891 -56.745205) (xy 181.644265 -56.69291) (xy 181.666907 -56.643333) (xy 181.696373 -56.597483)
			(xy 181.732064 -56.556292) (xy 181.773255 -56.520601) (xy 181.819105 -56.491135) (xy 181.868682 -56.468493)
			(xy 181.920977 -56.453138) (xy 181.974925 -56.445382) (xy 182.029427 -56.445382) (xy 182.083375 -56.453138)
			(xy 182.13567 -56.468493) (xy 182.185247 -56.491135) (xy 182.231097 -56.520601) (xy 182.272288 -56.556292)
			(xy 182.307979 -56.597483) (xy 182.337445 -56.643333) (xy 182.360087 -56.69291) (xy 182.375442 -56.745205)
			(xy 182.383198 -56.799153) (xy 182.383394 -56.810148) (xy 184.200292 -56.810148) (xy 184.200292 -56.809894)
			(xy 184.200782 -56.779926) (xy 184.208605 -56.720504) (xy 184.224118 -56.662611) (xy 184.247054 -56.607238)
			(xy 184.277021 -56.555332) (xy 184.313508 -56.507782) (xy 184.355888 -56.465402) (xy 184.403438 -56.428915)
			(xy 184.455344 -56.398948) (xy 184.510717 -56.376012) (xy 184.56861 -56.360499) (xy 184.628032 -56.352676)
			(xy 184.687968 -56.352676) (xy 184.74739 -56.360499) (xy 184.805283 -56.376012) (xy 184.860656 -56.398948)
			(xy 184.912562 -56.428915) (xy 184.960112 -56.465402) (xy 185.002492 -56.507782) (xy 185.038979 -56.555332)
			(xy 185.068946 -56.607238) (xy 185.091882 -56.662611) (xy 185.107395 -56.720504) (xy 185.115218 -56.779926)
			(xy 185.115708 -56.809894) (xy 185.115708 -56.810148) (xy 185.115132 -56.841671) (xy 185.106464 -56.904119)
			(xy 185.089311 -56.964787) (xy 185.063999 -57.022529) (xy 185.031005 -57.076253) (xy 184.990953 -57.124943)
			(xy 184.968134 -57.146698) (xy 184.961022 -57.153302) (xy 184.95264 -57.17032) (xy 184.94629 -57.248806)
			(xy 184.945925 -57.258371) (xy 184.951542 -57.276654) (xy 184.957212 -57.284366) (xy 184.972747 -57.304651)
			(xy 184.998807 -57.3486) (xy 185.018771 -57.395633) (xy 185.032282 -57.444909) (xy 185.035263 -57.467049)
			(xy 185.218592 -57.467049) (xy 185.218592 -57.412551) (xy 185.226348 -57.358607) (xy 185.241701 -57.306316)
			(xy 185.26434 -57.256742) (xy 185.293803 -57.210895) (xy 185.329491 -57.169706) (xy 185.370677 -57.134016)
			(xy 185.416523 -57.10455) (xy 185.466095 -57.081909) (xy 185.518386 -57.066553) (xy 185.572329 -57.058794)
			(xy 185.599578 -57.058306) (xy 185.625126 -57.058712) (xy 185.675766 -57.06552) (xy 185.725043 -57.079029)
			(xy 185.772074 -57.098999) (xy 185.816018 -57.12507) (xy 185.836306 -57.140602) (xy 185.84403 -57.146242)
			(xy 185.862306 -57.151841) (xy 185.871866 -57.151524) (xy 185.950352 -57.145174) (xy 185.96737 -57.136792)
			(xy 185.973974 -57.12968) (xy 185.995739 -57.106866) (xy 186.044411 -57.066784) (xy 186.098128 -57.033768)
			(xy 186.15587 -57.008443) (xy 186.216543 -56.991289) (xy 186.278998 -56.982632) (xy 186.310524 -56.982106)
			(xy 186.310778 -56.982106) (xy 186.340747 -56.982582) (xy 186.400173 -56.990403) (xy 186.458069 -57.005914)
			(xy 186.513445 -57.02885) (xy 186.565354 -57.058818) (xy 186.588852 -57.076848) (xy 187.23864 -57.076848)
			(xy 187.239124 -57.049478) (xy 187.246936 -56.9953) (xy 187.262421 -56.942796) (xy 187.285258 -56.893049)
			(xy 187.31498 -56.847082) (xy 187.33262 -56.82615) (xy 187.332874 -56.825896) (xy 187.338477 -56.818821)
			(xy 187.344712 -56.801895) (xy 187.345066 -56.792876) (xy 187.345066 -56.72582) (xy 187.344707 -56.716803)
			(xy 187.338461 -56.699886) (xy 187.332874 -56.6928) (xy 187.33262 -56.6928) (xy 187.33262 -56.692546)
			(xy 187.314992 -56.671605) (xy 187.285278 -56.625635) (xy 187.262439 -56.57589) (xy 187.246946 -56.523391)
			(xy 187.239115 -56.469217) (xy 187.23864 -56.441848) (xy 187.239126 -56.414597) (xy 187.246882 -56.360649)
			(xy 187.262237 -56.308354) (xy 187.284879 -56.258777) (xy 187.314345 -56.212927) (xy 187.350036 -56.171736)
			(xy 187.391227 -56.136045) (xy 187.437077 -56.106579) (xy 187.486654 -56.083937) (xy 187.538949 -56.068582)
			(xy 187.592897 -56.060826) (xy 187.647399 -56.060826) (xy 187.701347 -56.068582) (xy 187.753642 -56.083937)
			(xy 187.803219 -56.106579) (xy 187.849069 -56.136045) (xy 187.89026 -56.171736) (xy 187.925951 -56.212927)
			(xy 187.955417 -56.258777) (xy 187.978059 -56.308354) (xy 187.993414 -56.360649) (xy 188.00117 -56.414597)
			(xy 188.001656 -56.441848) (xy 188.00117 -56.469218) (xy 187.993359 -56.523396) (xy 187.977875 -56.5759)
			(xy 187.955037 -56.625647) (xy 187.925316 -56.671614) (xy 187.907676 -56.692546) (xy 187.907422 -56.6928)
			(xy 187.90182 -56.699876) (xy 187.895585 -56.716801) (xy 187.89523 -56.72582) (xy 187.89523 -56.792876)
			(xy 187.895592 -56.801892) (xy 187.901836 -56.81881) (xy 187.907422 -56.825896) (xy 187.907676 -56.825896)
			(xy 187.907676 -56.82615) (xy 187.925301 -56.847093) (xy 187.955016 -56.893063) (xy 187.977855 -56.942807)
			(xy 187.993349 -56.995306) (xy 187.994452 -57.002934) (xy 189.663578 -57.002934) (xy 189.664102 -56.974843)
			(xy 189.672324 -56.919268) (xy 189.68861 -56.8655) (xy 189.712608 -56.814702) (xy 189.743798 -56.767975)
			(xy 189.781506 -56.726329) (xy 189.824915 -56.690665) (xy 189.848744 -56.675782) (xy 189.857634 -56.670448)
			(xy 189.869826 -56.65343) (xy 189.890146 -56.560212) (xy 189.885828 -56.539638) (xy 189.879986 -56.531002)
			(xy 189.863983 -56.50694) (xy 189.838641 -56.455008) (xy 189.821417 -56.399849) (xy 189.812702 -56.342725)
			(xy 189.812168 -56.313832) (xy 189.812685 -56.286581) (xy 189.820437 -56.232633) (xy 189.835788 -56.180338)
			(xy 189.858425 -56.130759) (xy 189.887887 -56.084907) (xy 189.923575 -56.043715) (xy 189.964762 -56.008021)
			(xy 190.01061 -55.978552) (xy 190.060185 -55.955907) (xy 190.112478 -55.940549) (xy 190.166425 -55.932789)
			(xy 190.193676 -55.932324) (xy 190.221046 -55.932798) (xy 190.275225 -55.940613) (xy 190.327728 -55.9561)
			(xy 190.377475 -55.97894) (xy 190.423442 -56.008663) (xy 190.444374 -56.026304) (xy 190.444628 -56.026558)
			(xy 190.451726 -56.032127) (xy 190.468634 -56.038383) (xy 190.477648 -56.03875) (xy 190.544704 -56.03875)
			(xy 190.553722 -56.038406) (xy 190.57064 -56.03215) (xy 190.577724 -56.026558) (xy 190.577724 -56.026304)
			(xy 190.577978 -56.026304) (xy 190.598911 -56.008663) (xy 190.644879 -55.978939) (xy 190.694625 -55.956093)
			(xy 190.747127 -55.940597) (xy 190.801305 -55.932768) (xy 190.856047 -55.932768) (xy 190.910225 -55.940597)
			(xy 190.962727 -55.956093) (xy 191.012473 -55.978939) (xy 191.058441 -56.008663) (xy 191.079374 -56.026304)
			(xy 191.079628 -56.026558) (xy 191.086726 -56.032127) (xy 191.103634 -56.038383) (xy 191.112648 -56.03875)
			(xy 191.179704 -56.03875) (xy 191.188722 -56.038406) (xy 191.20564 -56.03215) (xy 191.212724 -56.026558)
			(xy 191.212724 -56.026304) (xy 191.212978 -56.026304) (xy 191.233908 -56.008662) (xy 191.279881 -55.978951)
			(xy 191.329629 -55.956115) (xy 191.382131 -55.940625) (xy 191.436307 -55.932797) (xy 191.463676 -55.932324)
			(xy 191.490932 -55.932721) (xy 191.54489 -55.940476) (xy 191.597196 -55.955831) (xy 191.646783 -55.978474)
			(xy 191.692643 -56.007944) (xy 191.733842 -56.043641) (xy 191.769541 -56.084838) (xy 191.799014 -56.130696)
			(xy 191.82166 -56.180282) (xy 191.837019 -56.232586) (xy 191.844777 -56.286544) (xy 191.844777 -56.297068)
			(xy 192.186558 -56.297068) (xy 192.190629 -56.241446) (xy 192.202755 -56.187009) (xy 192.222678 -56.134918)
			(xy 192.249974 -56.086283) (xy 192.28406 -56.04214) (xy 192.324209 -56.003431) (xy 192.369567 -55.97098)
			(xy 192.419167 -55.945479) (xy 192.471951 -55.927472) (xy 192.526794 -55.917342) (xy 192.582528 -55.915305)
			(xy 192.637965 -55.921405) (xy 192.691922 -55.935511) (xy 192.743251 -55.957323) (xy 192.790857 -55.986377)
			(xy 192.833725 -56.022052) (xy 192.870942 -56.063589) (xy 192.901715 -56.110102) (xy 192.925387 -56.160599)
			(xy 192.941455 -56.214006) (xy 192.949575 -56.269182) (xy 192.950084 -56.297068) (xy 192.949575 -56.324954)
			(xy 192.94538 -56.353456) (xy 195.041264 -56.353456) (xy 195.045335 -56.297834) (xy 195.057461 -56.243397)
			(xy 195.077384 -56.191306) (xy 195.10468 -56.142671) (xy 195.138766 -56.098528) (xy 195.178915 -56.059819)
			(xy 195.224273 -56.027368) (xy 195.273873 -56.001867) (xy 195.326657 -55.98386) (xy 195.3815 -55.97373)
			(xy 195.437234 -55.971693) (xy 195.492671 -55.977793) (xy 195.546628 -55.991899) (xy 195.597957 -56.013711)
			(xy 195.645563 -56.042765) (xy 195.688431 -56.07844) (xy 195.725648 -56.119977) (xy 195.756421 -56.16649)
			(xy 195.780093 -56.216987) (xy 195.796161 -56.270394) (xy 195.804281 -56.32557) (xy 195.80479 -56.353456)
			(xy 195.804281 -56.381342) (xy 195.796161 -56.436518) (xy 195.780093 -56.489925) (xy 195.756421 -56.540422)
			(xy 195.725648 -56.586935) (xy 195.688431 -56.628472) (xy 195.645563 -56.664147) (xy 195.597957 -56.693201)
			(xy 195.546628 -56.715013) (xy 195.492671 -56.729119) (xy 195.437234 -56.735219) (xy 195.3815 -56.733182)
			(xy 195.326657 -56.723052) (xy 195.273873 -56.705045) (xy 195.224273 -56.679544) (xy 195.178915 -56.647093)
			(xy 195.138766 -56.608384) (xy 195.10468 -56.564241) (xy 195.077384 -56.515606) (xy 195.057461 -56.463515)
			(xy 195.045335 -56.409078) (xy 195.041264 -56.353456) (xy 192.94538 -56.353456) (xy 192.941455 -56.38013)
			(xy 192.925387 -56.433537) (xy 192.901715 -56.484034) (xy 192.870942 -56.530547) (xy 192.833725 -56.572084)
			(xy 192.790857 -56.607759) (xy 192.743251 -56.636813) (xy 192.691922 -56.658625) (xy 192.637965 -56.672731)
			(xy 192.582528 -56.678831) (xy 192.526794 -56.676794) (xy 192.471951 -56.666664) (xy 192.419167 -56.648657)
			(xy 192.369567 -56.623156) (xy 192.324209 -56.590705) (xy 192.28406 -56.551996) (xy 192.249974 -56.507853)
			(xy 192.222678 -56.459218) (xy 192.202755 -56.407127) (xy 192.190629 -56.35269) (xy 192.186558 -56.297068)
			(xy 191.844777 -56.297068) (xy 191.844777 -56.341056) (xy 191.837019 -56.395014) (xy 191.82166 -56.447318)
			(xy 191.799014 -56.496904) (xy 191.769541 -56.542762) (xy 191.733842 -56.583959) (xy 191.692643 -56.619656)
			(xy 191.646783 -56.649126) (xy 191.597196 -56.671769) (xy 191.54489 -56.687124) (xy 191.490932 -56.694879)
			(xy 191.463676 -56.69534) (xy 191.436305 -56.694903) (xy 191.382124 -56.68708) (xy 191.32962 -56.671585)
			(xy 191.279873 -56.648737) (xy 191.233908 -56.619005) (xy 191.212978 -56.60136) (xy 191.212724 -56.601106)
			(xy 191.205634 -56.595524) (xy 191.18872 -56.589274) (xy 191.179704 -56.588914) (xy 191.112648 -56.588914)
			(xy 191.103633 -56.589291) (xy 191.086716 -56.595524) (xy 191.079628 -56.601106) (xy 191.079628 -56.60136)
			(xy 191.079374 -56.60136) (xy 191.058441 -56.619001) (xy 191.012473 -56.648725) (xy 190.962727 -56.671571)
			(xy 190.910225 -56.687067) (xy 190.856047 -56.694896) (xy 190.801305 -56.694896) (xy 190.747127 -56.687067)
			(xy 190.694625 -56.671571) (xy 190.644879 -56.648725) (xy 190.598911 -56.619001) (xy 190.577978 -56.60136)
			(xy 190.577724 -56.601106) (xy 190.570634 -56.595524) (xy 190.55372 -56.589274) (xy 190.544704 -56.588914)
			(xy 190.477648 -56.588914) (xy 190.468633 -56.589291) (xy 190.451716 -56.595524) (xy 190.444628 -56.601106)
			(xy 190.44412 -56.60136) (xy 190.431388 -56.612307) (xy 190.404295 -56.632146) (xy 190.390018 -56.640984)
			(xy 190.381128 -56.646318) (xy 190.368936 -56.663336) (xy 190.348616 -56.756554) (xy 190.352934 -56.777128)
			(xy 190.358776 -56.785764) (xy 190.37476 -56.809838) (xy 190.400107 -56.861766) (xy 190.417337 -56.91692)
			(xy 190.426057 -56.974042) (xy 190.426594 -57.002934) (xy 190.426108 -57.030185) (xy 190.425826 -57.032144)
			(xy 193.585844 -57.032144) (xy 193.589915 -56.976522) (xy 193.602041 -56.922085) (xy 193.621964 -56.869994)
			(xy 193.64926 -56.821359) (xy 193.683346 -56.777216) (xy 193.723495 -56.738507) (xy 193.768853 -56.706056)
			(xy 193.818453 -56.680555) (xy 193.871237 -56.662548) (xy 193.92608 -56.652418) (xy 193.981814 -56.650381)
			(xy 194.037251 -56.656481) (xy 194.091208 -56.670587) (xy 194.142537 -56.692399) (xy 194.190143 -56.721453)
			(xy 194.233011 -56.757128) (xy 194.270228 -56.798665) (xy 194.301001 -56.845178) (xy 194.324673 -56.895675)
			(xy 194.340741 -56.949082) (xy 194.348861 -57.004258) (xy 194.34937 -57.032144) (xy 194.348861 -57.06003)
			(xy 194.340741 -57.115206) (xy 194.324673 -57.168613) (xy 194.301001 -57.21911) (xy 194.270228 -57.265623)
			(xy 194.233011 -57.30716) (xy 194.190143 -57.342835) (xy 194.142537 -57.371889) (xy 194.091208 -57.393701)
			(xy 194.037251 -57.407807) (xy 193.981814 -57.413907) (xy 193.92608 -57.41187) (xy 193.871237 -57.40174)
			(xy 193.818453 -57.383733) (xy 193.768853 -57.358232) (xy 193.723495 -57.325781) (xy 193.683346 -57.287072)
			(xy 193.64926 -57.242929) (xy 193.621964 -57.194294) (xy 193.602041 -57.142203) (xy 193.589915 -57.087766)
			(xy 193.585844 -57.032144) (xy 190.425826 -57.032144) (xy 190.418352 -57.084133) (xy 190.402997 -57.136428)
			(xy 190.380355 -57.186005) (xy 190.350889 -57.231855) (xy 190.315198 -57.273046) (xy 190.274007 -57.308737)
			(xy 190.228157 -57.338203) (xy 190.17858 -57.360845) (xy 190.126285 -57.3762) (xy 190.072337 -57.383956)
			(xy 190.017835 -57.383956) (xy 189.963887 -57.3762) (xy 189.911592 -57.360845) (xy 189.862015 -57.338203)
			(xy 189.816165 -57.308737) (xy 189.774974 -57.273046) (xy 189.739283 -57.231855) (xy 189.709817 -57.186005)
			(xy 189.687175 -57.136428) (xy 189.67182 -57.084133) (xy 189.664064 -57.030185) (xy 189.663578 -57.002934)
			(xy 187.994452 -57.002934) (xy 188.001181 -57.04948) (xy 188.001656 -57.076848) (xy 188.00117 -57.104099)
			(xy 187.993414 -57.158047) (xy 187.978059 -57.210342) (xy 187.955417 -57.259919) (xy 187.925951 -57.305769)
			(xy 187.89026 -57.34696) (xy 187.849069 -57.382651) (xy 187.803219 -57.412117) (xy 187.753642 -57.434759)
			(xy 187.701347 -57.450114) (xy 187.647399 -57.45787) (xy 187.592897 -57.45787) (xy 187.538949 -57.450114)
			(xy 187.486654 -57.434759) (xy 187.437077 -57.412117) (xy 187.391227 -57.382651) (xy 187.350036 -57.34696)
			(xy 187.314345 -57.305769) (xy 187.284879 -57.259919) (xy 187.262237 -57.210342) (xy 187.246882 -57.158047)
			(xy 187.239126 -57.104099) (xy 187.23864 -57.076848) (xy 186.588852 -57.076848) (xy 186.612907 -57.095305)
			(xy 186.65529 -57.137687) (xy 186.691778 -57.185239) (xy 186.721747 -57.237147) (xy 186.744684 -57.292523)
			(xy 186.760196 -57.350419) (xy 186.768018 -57.409845) (xy 186.768486 -57.439814) (xy 186.768043 -57.468047)
			(xy 186.765909 -57.48528) (xy 198.705976 -57.48528) (xy 198.710047 -57.429658) (xy 198.722173 -57.375221)
			(xy 198.742096 -57.32313) (xy 198.769392 -57.274495) (xy 198.803478 -57.230352) (xy 198.843627 -57.191643)
			(xy 198.888985 -57.159192) (xy 198.938585 -57.133691) (xy 198.991369 -57.115684) (xy 199.046212 -57.105554)
			(xy 199.101946 -57.103517) (xy 199.157383 -57.109617) (xy 199.21134 -57.123723) (xy 199.262669 -57.145535)
			(xy 199.310275 -57.174589) (xy 199.353143 -57.210264) (xy 199.39036 -57.251801) (xy 199.421133 -57.298314)
			(xy 199.444805 -57.348811) (xy 199.460873 -57.402218) (xy 199.468993 -57.457394) (xy 199.469502 -57.48528)
			(xy 199.468993 -57.513166) (xy 199.460873 -57.568342) (xy 199.444805 -57.621749) (xy 199.421133 -57.672246)
			(xy 199.39036 -57.718759) (xy 199.353143 -57.760296) (xy 199.310275 -57.795971) (xy 199.262669 -57.825025)
			(xy 199.21134 -57.846837) (xy 199.157383 -57.860943) (xy 199.101946 -57.867043) (xy 199.046212 -57.865006)
			(xy 198.991369 -57.854876) (xy 198.938585 -57.836869) (xy 198.888985 -57.811368) (xy 198.843627 -57.778917)
			(xy 198.803478 -57.740208) (xy 198.769392 -57.696065) (xy 198.742096 -57.64743) (xy 198.722173 -57.595339)
			(xy 198.710047 -57.540902) (xy 198.705976 -57.48528) (xy 186.765909 -57.48528) (xy 186.761103 -57.524083)
			(xy 186.747317 -57.57884) (xy 186.726895 -57.631482) (xy 186.700148 -57.681211) (xy 186.684158 -57.704482)
			(xy 186.676792 -57.71515) (xy 186.673744 -57.740804) (xy 186.716162 -57.844436) (xy 186.736228 -57.860692)
			(xy 186.749182 -57.862978) (xy 186.775298 -57.868087) (xy 186.825869 -57.884652) (xy 186.873649 -57.90808)
			(xy 186.917711 -57.937918) (xy 186.957203 -57.973586) (xy 186.991357 -58.014394) (xy 187.019513 -58.05955)
			(xy 187.041123 -58.108179) (xy 187.05577 -58.159339) (xy 187.063169 -58.212037) (xy 187.063634 -58.238644)
			(xy 187.063151 -58.266014) (xy 187.05534 -58.320193) (xy 187.039856 -58.372696) (xy 187.017017 -58.422444)
			(xy 186.987295 -58.46841) (xy 186.969654 -58.489342) (xy 186.9694 -58.489596) (xy 186.963809 -58.49668)
			(xy 186.957565 -58.513599) (xy 186.957208 -58.522616) (xy 186.957208 -58.589672) (xy 186.957576 -58.598688)
			(xy 186.963816 -58.615605) (xy 186.9694 -58.622692) (xy 186.969654 -58.622692) (xy 186.969654 -58.622946)
			(xy 186.987274 -58.643894) (xy 187.010185 -58.679334) (xy 190.095378 -58.679334) (xy 190.095808 -58.653019)
			(xy 190.103052 -58.600889) (xy 190.117379 -58.550246) (xy 190.138518 -58.502047) (xy 190.16607 -58.457205)
			(xy 190.199514 -58.416566) (xy 190.218568 -58.39841) (xy 190.225963 -58.390882) (xy 190.234492 -58.371607)
			(xy 190.235078 -58.361072) (xy 190.235078 -58.286396) (xy 190.234571 -58.275844) (xy 190.226021 -58.256548)
			(xy 190.218568 -58.249058) (xy 190.199493 -58.230922) (xy 190.166039 -58.190287) (xy 190.138483 -58.145443)
			(xy 190.117348 -58.097238) (xy 190.103035 -58.046588) (xy 190.095814 -57.994451) (xy 190.095378 -57.968134)
			(xy 190.095864 -57.940883) (xy 190.10362 -57.886935) (xy 190.118975 -57.83464) (xy 190.141617 -57.785063)
			(xy 190.171083 -57.739213) (xy 190.206774 -57.698022) (xy 190.247965 -57.662331) (xy 190.293815 -57.632865)
			(xy 190.343392 -57.610223) (xy 190.395687 -57.594868) (xy 190.449635 -57.587112) (xy 190.504137 -57.587112)
			(xy 190.558085 -57.594868) (xy 190.61038 -57.610223) (xy 190.659957 -57.632865) (xy 190.705807 -57.662331)
			(xy 190.746998 -57.698022) (xy 190.782689 -57.739213) (xy 190.812155 -57.785063) (xy 190.834797 -57.83464)
			(xy 190.850152 -57.886935) (xy 190.857908 -57.940883) (xy 190.858394 -57.968134) (xy 190.857951 -57.994449)
			(xy 190.850712 -58.046578) (xy 190.836388 -58.097222) (xy 190.832516 -58.106052) (xy 199.38287 -58.106052)
			(xy 199.38287 -58.046116) (xy 199.390693 -57.986694) (xy 199.406206 -57.928801) (xy 199.429142 -57.873428)
			(xy 199.459109 -57.821522) (xy 199.495596 -57.773972) (xy 199.537976 -57.731592) (xy 199.585526 -57.695105)
			(xy 199.637432 -57.665138) (xy 199.692805 -57.642202) (xy 199.750698 -57.626689) (xy 199.81012 -57.618866)
			(xy 199.870056 -57.618866) (xy 199.929478 -57.626689) (xy 199.987371 -57.642202) (xy 200.042744 -57.665138)
			(xy 200.09465 -57.695105) (xy 200.1422 -57.731592) (xy 200.18458 -57.773972) (xy 200.221067 -57.821522)
			(xy 200.251034 -57.873428) (xy 200.260907 -57.897264) (xy 201.667854 -57.897264) (xy 201.667854 -57.837328)
			(xy 201.675677 -57.777906) (xy 201.69119 -57.720013) (xy 201.714126 -57.66464) (xy 201.744093 -57.612734)
			(xy 201.78058 -57.565184) (xy 201.82296 -57.522804) (xy 201.87051 -57.486317) (xy 201.922416 -57.45635)
			(xy 201.977789 -57.433414) (xy 202.035682 -57.417901) (xy 202.095104 -57.410078) (xy 202.15504 -57.410078)
			(xy 202.214462 -57.417901) (xy 202.272355 -57.433414) (xy 202.327728 -57.45635) (xy 202.379634 -57.486317)
			(xy 202.427184 -57.522804) (xy 202.469564 -57.565184) (xy 202.506051 -57.612734) (xy 202.536018 -57.66464)
			(xy 202.558954 -57.720013) (xy 202.574467 -57.777906) (xy 202.58229 -57.837328) (xy 202.58278 -57.867296)
			(xy 202.58229 -57.897264) (xy 202.574467 -57.956686) (xy 202.558954 -58.014579) (xy 202.536018 -58.069952)
			(xy 202.506051 -58.121858) (xy 202.469564 -58.169408) (xy 202.427184 -58.211788) (xy 202.379634 -58.248275)
			(xy 202.327728 -58.278242) (xy 202.272355 -58.301178) (xy 202.214462 -58.316691) (xy 202.15504 -58.324514)
			(xy 202.095104 -58.324514) (xy 202.035682 -58.316691) (xy 201.977789 -58.301178) (xy 201.922416 -58.278242)
			(xy 201.87051 -58.248275) (xy 201.82296 -58.211788) (xy 201.78058 -58.169408) (xy 201.744093 -58.121858)
			(xy 201.714126 -58.069952) (xy 201.69119 -58.014579) (xy 201.675677 -57.956686) (xy 201.667854 -57.897264)
			(xy 200.260907 -57.897264) (xy 200.27397 -57.928801) (xy 200.289483 -57.986694) (xy 200.297306 -58.046116)
			(xy 200.297796 -58.076084) (xy 200.297306 -58.106052) (xy 200.289483 -58.165474) (xy 200.27397 -58.223367)
			(xy 200.251034 -58.27874) (xy 200.221067 -58.330646) (xy 200.18458 -58.378196) (xy 200.1422 -58.420576)
			(xy 200.09465 -58.457063) (xy 200.042744 -58.48703) (xy 199.987371 -58.509966) (xy 199.929478 -58.525479)
			(xy 199.870056 -58.533302) (xy 199.81012 -58.533302) (xy 199.750698 -58.525479) (xy 199.692805 -58.509966)
			(xy 199.637432 -58.48703) (xy 199.585526 -58.457063) (xy 199.537976 -58.420576) (xy 199.495596 -58.378196)
			(xy 199.459109 -58.330646) (xy 199.429142 -58.27874) (xy 199.406206 -58.223367) (xy 199.390693 -58.165474)
			(xy 199.38287 -58.106052) (xy 190.832516 -58.106052) (xy 190.815251 -58.145421) (xy 190.7877 -58.190264)
			(xy 190.754257 -58.230902) (xy 190.735204 -58.249058) (xy 190.72782 -58.256594) (xy 190.719285 -58.275863)
			(xy 190.718694 -58.286396) (xy 190.718694 -58.361072) (xy 190.719227 -58.371621) (xy 190.72776 -58.390916)
			(xy 190.735204 -58.39841) (xy 190.754258 -58.416567) (xy 190.787715 -58.457196) (xy 190.815274 -58.502036)
			(xy 190.836413 -58.550237) (xy 190.847991 -58.591192) (xy 200.587084 -58.591192) (xy 200.587084 -58.531256)
			(xy 200.594907 -58.471834) (xy 200.61042 -58.413941) (xy 200.633356 -58.358568) (xy 200.663323 -58.306662)
			(xy 200.69981 -58.259112) (xy 200.74219 -58.216732) (xy 200.78974 -58.180245) (xy 200.841646 -58.150278)
			(xy 200.897019 -58.127342) (xy 200.954912 -58.111829) (xy 201.014334 -58.104006) (xy 201.07427 -58.104006)
			(xy 201.133692 -58.111829) (xy 201.191585 -58.127342) (xy 201.246958 -58.150278) (xy 201.298864 -58.180245)
			(xy 201.346414 -58.216732) (xy 201.388794 -58.259112) (xy 201.425281 -58.306662) (xy 201.455248 -58.358568)
			(xy 201.478184 -58.413941) (xy 201.493697 -58.471834) (xy 201.494731 -58.479686) (xy 202.833714 -58.479686)
			(xy 202.833714 -58.41975) (xy 202.841537 -58.360328) (xy 202.85705 -58.302435) (xy 202.879986 -58.247062)
			(xy 202.909953 -58.195156) (xy 202.94644 -58.147606) (xy 202.98882 -58.105226) (xy 203.03637 -58.068739)
			(xy 203.088276 -58.038772) (xy 203.143649 -58.015836) (xy 203.201542 -58.000323) (xy 203.260964 -57.9925)
			(xy 203.3209 -57.9925) (xy 203.380322 -58.000323) (xy 203.438215 -58.015836) (xy 203.493588 -58.038772)
			(xy 203.545494 -58.068739) (xy 203.593044 -58.105226) (xy 203.635424 -58.147606) (xy 203.671911 -58.195156)
			(xy 203.701878 -58.247062) (xy 203.724814 -58.302435) (xy 203.740327 -58.360328) (xy 203.74815 -58.41975)
			(xy 203.74864 -58.449718) (xy 203.74815 -58.479686) (xy 203.740327 -58.539108) (xy 203.724814 -58.597001)
			(xy 203.701878 -58.652374) (xy 203.671911 -58.70428) (xy 203.651098 -58.731404) (xy 207.620616 -58.731404)
			(xy 207.621081 -58.704034) (xy 207.628898 -58.649854) (xy 207.644387 -58.597351) (xy 207.66723 -58.547604)
			(xy 207.696955 -58.501638) (xy 207.714596 -58.480706) (xy 207.71485 -58.480452) (xy 207.720427 -58.473359)
			(xy 207.726678 -58.456447) (xy 207.727042 -58.447432) (xy 207.727042 -58.380376) (xy 207.726709 -58.371356)
			(xy 207.720446 -58.354439) (xy 207.71485 -58.347356) (xy 207.714596 -58.347356) (xy 207.714596 -58.347102)
			(xy 207.696961 -58.326165) (xy 207.667238 -58.280198) (xy 207.644394 -58.230452) (xy 207.628899 -58.177951)
			(xy 207.621071 -58.123773) (xy 207.62107 -58.069033) (xy 207.628898 -58.014855) (xy 207.644392 -57.962354)
			(xy 207.667235 -57.912608) (xy 207.696957 -57.866639) (xy 207.714596 -57.845706) (xy 207.71485 -57.845452)
			(xy 207.720427 -57.838359) (xy 207.726678 -57.821447) (xy 207.727042 -57.812432) (xy 207.727042 -57.745376)
			(xy 207.726709 -57.736356) (xy 207.720446 -57.719439) (xy 207.71485 -57.712356) (xy 207.714596 -57.712356)
			(xy 207.714596 -57.712102) (xy 207.696961 -57.691165) (xy 207.667238 -57.645198) (xy 207.644394 -57.595452)
			(xy 207.628899 -57.542951) (xy 207.621071 -57.488773) (xy 207.62107 -57.434033) (xy 207.628898 -57.379855)
			(xy 207.644392 -57.327354) (xy 207.667235 -57.277608) (xy 207.696957 -57.231639) (xy 207.714596 -57.210706)
			(xy 207.71485 -57.210452) (xy 207.720427 -57.203359) (xy 207.726678 -57.186447) (xy 207.727042 -57.177432)
			(xy 207.727042 -57.110376) (xy 207.726709 -57.101356) (xy 207.720446 -57.084439) (xy 207.71485 -57.077356)
			(xy 207.714596 -57.077356) (xy 207.714596 -57.077102) (xy 207.696944 -57.056181) (xy 207.667234 -57.010205)
			(xy 207.644401 -56.960455) (xy 207.628913 -56.907952) (xy 207.621088 -56.853774) (xy 207.620616 -56.826404)
			(xy 207.621102 -56.799153) (xy 207.628858 -56.745205) (xy 207.644213 -56.69291) (xy 207.666855 -56.643333)
			(xy 207.696321 -56.597483) (xy 207.732012 -56.556292) (xy 207.773203 -56.520601) (xy 207.819053 -56.491135)
			(xy 207.86863 -56.468493) (xy 207.920925 -56.453138) (xy 207.974873 -56.445382) (xy 208.029375 -56.445382)
			(xy 208.083323 -56.453138) (xy 208.135618 -56.468493) (xy 208.185195 -56.491135) (xy 208.231045 -56.520601)
			(xy 208.272236 -56.556292) (xy 208.307927 -56.597483) (xy 208.337393 -56.643333) (xy 208.360035 -56.69291)
			(xy 208.37539 -56.745205) (xy 208.383146 -56.799153) (xy 208.383342 -56.810148) (xy 210.20024 -56.810148)
			(xy 210.20024 -56.809894) (xy 210.20073 -56.779926) (xy 210.208553 -56.720504) (xy 210.224066 -56.662611)
			(xy 210.247002 -56.607238) (xy 210.276969 -56.555332) (xy 210.313456 -56.507782) (xy 210.355836 -56.465402)
			(xy 210.403386 -56.428915) (xy 210.455292 -56.398948) (xy 210.510665 -56.376012) (xy 210.568558 -56.360499)
			(xy 210.62798 -56.352676) (xy 210.687916 -56.352676) (xy 210.747338 -56.360499) (xy 210.805231 -56.376012)
			(xy 210.860604 -56.398948) (xy 210.91251 -56.428915) (xy 210.96006 -56.465402) (xy 211.00244 -56.507782)
			(xy 211.038927 -56.555332) (xy 211.068894 -56.607238) (xy 211.09183 -56.662611) (xy 211.107343 -56.720504)
			(xy 211.115166 -56.779926) (xy 211.115656 -56.809894) (xy 211.115656 -56.810148) (xy 211.115097 -56.841672)
			(xy 211.106427 -56.904121) (xy 211.089272 -56.96479) (xy 211.063957 -57.022533) (xy 211.030959 -57.076256)
			(xy 210.990904 -57.124945) (xy 210.968082 -57.146698) (xy 210.96097 -57.153302) (xy 210.952588 -57.17032)
			(xy 210.946238 -57.248806) (xy 210.945863 -57.258372) (xy 210.951485 -57.276655) (xy 210.95716 -57.284366)
			(xy 210.972702 -57.304646) (xy 210.998759 -57.348597) (xy 211.018721 -57.395632) (xy 211.032231 -57.444908)
			(xy 211.035212 -57.467053) (xy 211.218469 -57.467053) (xy 211.218469 -57.412547) (xy 211.226227 -57.358596)
			(xy 211.241584 -57.306298) (xy 211.264227 -57.256718) (xy 211.293696 -57.210865) (xy 211.329392 -57.169673)
			(xy 211.370586 -57.133981) (xy 211.416441 -57.104515) (xy 211.466022 -57.081874) (xy 211.518321 -57.066521)
			(xy 211.572273 -57.058768) (xy 211.599526 -57.058306) (xy 211.625075 -57.058685) (xy 211.675716 -57.065499)
			(xy 211.724993 -57.079015) (xy 211.772024 -57.098991) (xy 211.815966 -57.125068) (xy 211.836254 -57.140602)
			(xy 211.843993 -57.146218) (xy 211.862257 -57.151831) (xy 211.871814 -57.151524) (xy 211.9503 -57.145174)
			(xy 211.967318 -57.136792) (xy 211.973922 -57.12968) (xy 211.995663 -57.106842) (xy 212.044341 -57.066763)
			(xy 212.098062 -57.03375) (xy 212.155809 -57.008429) (xy 212.216487 -56.99128) (xy 212.278945 -56.982629)
			(xy 212.310472 -56.982106) (xy 212.310726 -56.982106) (xy 212.340695 -56.982558) (xy 212.400119 -56.990384)
			(xy 212.458014 -57.005901) (xy 212.513388 -57.02884) (xy 212.565294 -57.058812) (xy 212.588797 -57.076848)
			(xy 213.238588 -57.076848) (xy 213.239085 -57.049479) (xy 213.246896 -56.995301) (xy 213.262378 -56.942799)
			(xy 213.285213 -56.893051) (xy 213.31493 -56.847083) (xy 213.332568 -56.82615) (xy 213.332822 -56.825896)
			(xy 213.338419 -56.818817) (xy 213.344659 -56.801894) (xy 213.345014 -56.792876) (xy 213.345014 -56.72582)
			(xy 213.344644 -56.716804) (xy 213.338405 -56.699888) (xy 213.332822 -56.6928) (xy 213.332568 -56.6928)
			(xy 213.332568 -56.692546) (xy 213.314932 -56.671612) (xy 213.285221 -56.625639) (xy 213.262385 -56.575892)
			(xy 213.246893 -56.523392) (xy 213.239063 -56.469217) (xy 213.238588 -56.441848) (xy 213.239074 -56.414597)
			(xy 213.24683 -56.360649) (xy 213.262185 -56.308354) (xy 213.284827 -56.258777) (xy 213.314293 -56.212927)
			(xy 213.349984 -56.171736) (xy 213.391175 -56.136045) (xy 213.437025 -56.106579) (xy 213.486602 -56.083937)
			(xy 213.538897 -56.068582) (xy 213.592845 -56.060826) (xy 213.647347 -56.060826) (xy 213.701295 -56.068582)
			(xy 213.75359 -56.083937) (xy 213.803167 -56.106579) (xy 213.849017 -56.136045) (xy 213.890208 -56.171736)
			(xy 213.925899 -56.212927) (xy 213.955365 -56.258777) (xy 213.978007 -56.308354) (xy 213.993362 -56.360649)
			(xy 214.001118 -56.414597) (xy 214.001604 -56.441848) (xy 214.001106 -56.469217) (xy 213.993296 -56.523395)
			(xy 213.977814 -56.575898) (xy 213.95498 -56.625645) (xy 213.925262 -56.671613) (xy 213.907624 -56.692546)
			(xy 213.90737 -56.6928) (xy 213.901774 -56.69988) (xy 213.895534 -56.716802) (xy 213.895178 -56.72582)
			(xy 213.895178 -56.792876) (xy 213.895551 -56.801891) (xy 213.901788 -56.818808) (xy 213.90737 -56.825896)
			(xy 213.907624 -56.825896) (xy 213.907624 -56.82615) (xy 213.925257 -56.847087) (xy 213.954969 -56.893059)
			(xy 213.977806 -56.942805) (xy 213.993298 -56.995305) (xy 213.994401 -57.002934) (xy 215.663526 -57.002934)
			(xy 215.664026 -56.974842) (xy 215.67225 -56.919265) (xy 215.688538 -56.865495) (xy 215.71254 -56.814696)
			(xy 215.743734 -56.767969) (xy 215.781447 -56.726325) (xy 215.824861 -56.690664) (xy 215.848692 -56.675782)
			(xy 215.857582 -56.670448) (xy 215.869774 -56.65343) (xy 215.890094 -56.560212) (xy 215.885776 -56.539638)
			(xy 215.879934 -56.531002) (xy 215.863937 -56.506936) (xy 215.838592 -56.455006) (xy 215.821366 -56.399848)
			(xy 215.81265 -56.342724) (xy 215.812116 -56.313832) (xy 215.812585 -56.286579) (xy 215.820338 -56.232627)
			(xy 215.835692 -56.180328) (xy 215.858332 -56.130746) (xy 215.887799 -56.084892) (xy 215.923492 -56.043698)
			(xy 215.964685 -56.008004) (xy 216.010539 -55.978536) (xy 216.06012 -55.955894) (xy 216.112419 -55.94054)
			(xy 216.166371 -55.932786) (xy 216.193624 -55.932324) (xy 216.220995 -55.93277) (xy 216.275175 -55.940592)
			(xy 216.327679 -55.956085) (xy 216.377425 -55.978932) (xy 216.423391 -56.008661) (xy 216.444322 -56.026304)
			(xy 216.444576 -56.026558) (xy 216.45166 -56.032148) (xy 216.468579 -56.038391) (xy 216.477596 -56.03875)
			(xy 216.544652 -56.03875) (xy 216.553668 -56.038381) (xy 216.570586 -56.032143) (xy 216.577672 -56.026558)
			(xy 216.577672 -56.026304) (xy 216.577926 -56.026304) (xy 216.598859 -56.008663) (xy 216.644827 -55.978939)
			(xy 216.694573 -55.956093) (xy 216.747075 -55.940597) (xy 216.801253 -55.932768) (xy 216.855995 -55.932768)
			(xy 216.910173 -55.940597) (xy 216.962675 -55.956093) (xy 217.012421 -55.978939) (xy 217.058389 -56.008663)
			(xy 217.079322 -56.026304) (xy 217.079576 -56.026558) (xy 217.08666 -56.032148) (xy 217.103579 -56.038391)
			(xy 217.112596 -56.03875) (xy 217.179652 -56.03875) (xy 217.188668 -56.038381) (xy 217.205586 -56.032143)
			(xy 217.212672 -56.026558) (xy 217.212672 -56.026304) (xy 217.212926 -56.026304) (xy 217.233876 -56.008687)
			(xy 217.279844 -55.978971) (xy 217.329587 -55.956131) (xy 217.382083 -55.940635) (xy 217.436256 -55.932801)
			(xy 217.463624 -55.932324) (xy 217.490876 -55.932747) (xy 217.544826 -55.940507) (xy 217.597122 -55.955866)
			(xy 217.646701 -55.97851) (xy 217.692552 -56.00798) (xy 217.733743 -56.043674) (xy 217.769435 -56.084867)
			(xy 217.798901 -56.13072) (xy 217.821542 -56.1803) (xy 217.836898 -56.232597) (xy 217.844654 -56.286548)
			(xy 217.844654 -56.297068) (xy 218.186506 -56.297068) (xy 218.190577 -56.241446) (xy 218.202703 -56.187009)
			(xy 218.222626 -56.134918) (xy 218.249922 -56.086283) (xy 218.284008 -56.04214) (xy 218.324157 -56.003431)
			(xy 218.369515 -55.97098) (xy 218.419115 -55.945479) (xy 218.471899 -55.927472) (xy 218.526742 -55.917342)
			(xy 218.582476 -55.915305) (xy 218.637913 -55.921405) (xy 218.69187 -55.935511) (xy 218.743199 -55.957323)
			(xy 218.790805 -55.986377) (xy 218.833673 -56.022052) (xy 218.87089 -56.063589) (xy 218.901663 -56.110102)
			(xy 218.925335 -56.160599) (xy 218.941403 -56.214006) (xy 218.949523 -56.269182) (xy 218.950032 -56.297068)
			(xy 218.949523 -56.324954) (xy 218.945328 -56.353456) (xy 221.041212 -56.353456) (xy 221.045283 -56.297834)
			(xy 221.057409 -56.243397) (xy 221.077332 -56.191306) (xy 221.104628 -56.142671) (xy 221.138714 -56.098528)
			(xy 221.178863 -56.059819) (xy 221.224221 -56.027368) (xy 221.273821 -56.001867) (xy 221.326605 -55.98386)
			(xy 221.381448 -55.97373) (xy 221.437182 -55.971693) (xy 221.492619 -55.977793) (xy 221.546576 -55.991899)
			(xy 221.597905 -56.013711) (xy 221.645511 -56.042765) (xy 221.688379 -56.07844) (xy 221.725596 -56.119977)
			(xy 221.756369 -56.16649) (xy 221.775907 -56.208168) (xy 237.455708 -56.208168) (xy 237.459779 -56.152546)
			(xy 237.471905 -56.098109) (xy 237.491828 -56.046018) (xy 237.519124 -55.997383) (xy 237.55321 -55.95324)
			(xy 237.593359 -55.914531) (xy 237.638717 -55.88208) (xy 237.688317 -55.856579) (xy 237.741101 -55.838572)
			(xy 237.795944 -55.828442) (xy 237.851678 -55.826405) (xy 237.907115 -55.832505) (xy 237.961072 -55.846611)
			(xy 238.012401 -55.868423) (xy 238.060007 -55.897477) (xy 238.102875 -55.933152) (xy 238.140092 -55.974689)
			(xy 238.170865 -56.021202) (xy 238.194537 -56.071699) (xy 238.210605 -56.125106) (xy 238.218725 -56.180282)
			(xy 238.219234 -56.208168) (xy 238.218725 -56.236054) (xy 238.210605 -56.29123) (xy 238.194537 -56.344637)
			(xy 238.170865 -56.395134) (xy 238.140092 -56.441647) (xy 238.102875 -56.483184) (xy 238.060007 -56.518859)
			(xy 238.012401 -56.547913) (xy 237.961072 -56.569725) (xy 237.907115 -56.583831) (xy 237.851678 -56.589931)
			(xy 237.795944 -56.587894) (xy 237.741101 -56.577764) (xy 237.688317 -56.559757) (xy 237.638717 -56.534256)
			(xy 237.593359 -56.501805) (xy 237.55321 -56.463096) (xy 237.519124 -56.418953) (xy 237.491828 -56.370318)
			(xy 237.471905 -56.318227) (xy 237.459779 -56.26379) (xy 237.455708 -56.208168) (xy 221.775907 -56.208168)
			(xy 221.780041 -56.216987) (xy 221.796109 -56.270394) (xy 221.804229 -56.32557) (xy 221.804738 -56.353456)
			(xy 221.804229 -56.381342) (xy 221.796109 -56.436518) (xy 221.780041 -56.489925) (xy 221.756369 -56.540422)
			(xy 221.725596 -56.586935) (xy 221.688379 -56.628472) (xy 221.645511 -56.664147) (xy 221.597905 -56.693201)
			(xy 221.546576 -56.715013) (xy 221.492619 -56.729119) (xy 221.437182 -56.735219) (xy 221.381448 -56.733182)
			(xy 221.326605 -56.723052) (xy 221.273821 -56.705045) (xy 221.224221 -56.679544) (xy 221.178863 -56.647093)
			(xy 221.138714 -56.608384) (xy 221.104628 -56.564241) (xy 221.077332 -56.515606) (xy 221.057409 -56.463515)
			(xy 221.045283 -56.409078) (xy 221.041212 -56.353456) (xy 218.945328 -56.353456) (xy 218.941403 -56.38013)
			(xy 218.925335 -56.433537) (xy 218.901663 -56.484034) (xy 218.87089 -56.530547) (xy 218.833673 -56.572084)
			(xy 218.790805 -56.607759) (xy 218.743199 -56.636813) (xy 218.69187 -56.658625) (xy 218.637913 -56.672731)
			(xy 218.582476 -56.678831) (xy 218.526742 -56.676794) (xy 218.471899 -56.666664) (xy 218.419115 -56.648657)
			(xy 218.369515 -56.623156) (xy 218.324157 -56.590705) (xy 218.284008 -56.551996) (xy 218.249922 -56.507853)
			(xy 218.222626 -56.459218) (xy 218.202703 -56.407127) (xy 218.190577 -56.35269) (xy 218.186506 -56.297068)
			(xy 217.844654 -56.297068) (xy 217.844654 -56.341052) (xy 217.836898 -56.395003) (xy 217.821542 -56.4473)
			(xy 217.798901 -56.49688) (xy 217.769435 -56.542733) (xy 217.733743 -56.583926) (xy 217.692552 -56.61962)
			(xy 217.646701 -56.64909) (xy 217.597122 -56.671734) (xy 217.544826 -56.687093) (xy 217.490876 -56.694853)
			(xy 217.463624 -56.69534) (xy 217.436254 -56.694874) (xy 217.382074 -56.687059) (xy 217.32957 -56.67157)
			(xy 217.279823 -56.648728) (xy 217.233857 -56.619002) (xy 217.212926 -56.60136) (xy 217.212672 -56.601106)
			(xy 217.205568 -56.595544) (xy 217.188665 -56.589282) (xy 217.179652 -56.588914) (xy 217.112596 -56.588914)
			(xy 217.103579 -56.589266) (xy 217.086661 -56.595517) (xy 217.079576 -56.601106) (xy 217.079576 -56.60136)
			(xy 217.079322 -56.60136) (xy 217.058389 -56.619001) (xy 217.012421 -56.648725) (xy 216.962675 -56.671571)
			(xy 216.910173 -56.687067) (xy 216.855995 -56.694896) (xy 216.801253 -56.694896) (xy 216.747075 -56.687067)
			(xy 216.694573 -56.671571) (xy 216.644827 -56.648725) (xy 216.598859 -56.619001) (xy 216.577926 -56.60136)
			(xy 216.577672 -56.601106) (xy 216.570568 -56.595544) (xy 216.553665 -56.589282) (xy 216.544652 -56.588914)
			(xy 216.477596 -56.588914) (xy 216.468579 -56.589266) (xy 216.451661 -56.595517) (xy 216.444576 -56.601106)
			(xy 216.444068 -56.60136) (xy 216.431333 -56.612303) (xy 216.404242 -56.632145) (xy 216.389966 -56.640984)
			(xy 216.381076 -56.646318) (xy 216.368884 -56.663336) (xy 216.348564 -56.756554) (xy 216.352882 -56.777128)
			(xy 216.358724 -56.785764) (xy 216.374714 -56.809834) (xy 216.400058 -56.861764) (xy 216.417286 -56.91692)
			(xy 216.426005 -56.974042) (xy 216.426542 -57.002934) (xy 216.426056 -57.030185) (xy 216.421466 -57.062112)
			(xy 219.510592 -57.062112) (xy 219.510592 -57.002176) (xy 219.518415 -56.942754) (xy 219.533928 -56.884861)
			(xy 219.556864 -56.829488) (xy 219.586831 -56.777582) (xy 219.623318 -56.730032) (xy 219.665698 -56.687652)
			(xy 219.713248 -56.651165) (xy 219.765154 -56.621198) (xy 219.820527 -56.598262) (xy 219.87842 -56.582749)
			(xy 219.937842 -56.574926) (xy 219.997778 -56.574926) (xy 220.0572 -56.582749) (xy 220.115093 -56.598262)
			(xy 220.170466 -56.621198) (xy 220.222372 -56.651165) (xy 220.269922 -56.687652) (xy 220.312302 -56.730032)
			(xy 220.348789 -56.777582) (xy 220.378756 -56.829488) (xy 220.391577 -56.86044) (xy 239.090452 -56.86044)
			(xy 239.094523 -56.804818) (xy 239.106649 -56.750381) (xy 239.126572 -56.69829) (xy 239.153868 -56.649655)
			(xy 239.187954 -56.605512) (xy 239.228103 -56.566803) (xy 239.273461 -56.534352) (xy 239.323061 -56.508851)
			(xy 239.375845 -56.490844) (xy 239.430688 -56.480714) (xy 239.486422 -56.478677) (xy 239.541859 -56.484777)
			(xy 239.595816 -56.498883) (xy 239.647145 -56.520695) (xy 239.694751 -56.549749) (xy 239.737619 -56.585424)
			(xy 239.774836 -56.626961) (xy 239.805609 -56.673474) (xy 239.829281 -56.723971) (xy 239.845349 -56.777378)
			(xy 239.853469 -56.832554) (xy 239.853978 -56.86044) (xy 239.853862 -56.86679) (xy 240.166142 -56.86679)
			(xy 240.170213 -56.811168) (xy 240.182339 -56.756731) (xy 240.202262 -56.70464) (xy 240.229558 -56.656005)
			(xy 240.263644 -56.611862) (xy 240.303793 -56.573153) (xy 240.349151 -56.540702) (xy 240.398751 -56.515201)
			(xy 240.451535 -56.497194) (xy 240.506378 -56.487064) (xy 240.562112 -56.485027) (xy 240.617549 -56.491127)
			(xy 240.671506 -56.505233) (xy 240.722835 -56.527045) (xy 240.770441 -56.556099) (xy 240.813309 -56.591774)
			(xy 240.850526 -56.633311) (xy 240.881299 -56.679824) (xy 240.904971 -56.730321) (xy 240.921039 -56.783728)
			(xy 240.929159 -56.838904) (xy 240.929668 -56.86679) (xy 241.182142 -56.86679) (xy 241.186213 -56.811168)
			(xy 241.198339 -56.756731) (xy 241.218262 -56.70464) (xy 241.245558 -56.656005) (xy 241.279644 -56.611862)
			(xy 241.319793 -56.573153) (xy 241.365151 -56.540702) (xy 241.414751 -56.515201) (xy 241.467535 -56.497194)
			(xy 241.522378 -56.487064) (xy 241.578112 -56.485027) (xy 241.633549 -56.491127) (xy 241.687506 -56.505233)
			(xy 241.738835 -56.527045) (xy 241.786441 -56.556099) (xy 241.829309 -56.591774) (xy 241.866526 -56.633311)
			(xy 241.897299 -56.679824) (xy 241.920971 -56.730321) (xy 241.937039 -56.783728) (xy 241.945159 -56.838904)
			(xy 241.945668 -56.86679) (xy 241.945159 -56.894676) (xy 241.937039 -56.949852) (xy 241.920971 -57.003259)
			(xy 241.897299 -57.053756) (xy 241.866526 -57.100269) (xy 241.829309 -57.141806) (xy 241.786441 -57.177481)
			(xy 241.738835 -57.206535) (xy 241.687506 -57.228347) (xy 241.633549 -57.242453) (xy 241.578112 -57.248553)
			(xy 241.522378 -57.246516) (xy 241.467535 -57.236386) (xy 241.414751 -57.218379) (xy 241.365151 -57.192878)
			(xy 241.319793 -57.160427) (xy 241.279644 -57.121718) (xy 241.245558 -57.077575) (xy 241.218262 -57.02894)
			(xy 241.198339 -56.976849) (xy 241.186213 -56.922412) (xy 241.182142 -56.86679) (xy 240.929668 -56.86679)
			(xy 240.929159 -56.894676) (xy 240.921039 -56.949852) (xy 240.904971 -57.003259) (xy 240.881299 -57.053756)
			(xy 240.850526 -57.100269) (xy 240.813309 -57.141806) (xy 240.770441 -57.177481) (xy 240.722835 -57.206535)
			(xy 240.671506 -57.228347) (xy 240.617549 -57.242453) (xy 240.562112 -57.248553) (xy 240.506378 -57.246516)
			(xy 240.451535 -57.236386) (xy 240.398751 -57.218379) (xy 240.349151 -57.192878) (xy 240.303793 -57.160427)
			(xy 240.263644 -57.121718) (xy 240.229558 -57.077575) (xy 240.202262 -57.02894) (xy 240.182339 -56.976849)
			(xy 240.170213 -56.922412) (xy 240.166142 -56.86679) (xy 239.853862 -56.86679) (xy 239.853469 -56.888326)
			(xy 239.845349 -56.943502) (xy 239.829281 -56.996909) (xy 239.805609 -57.047406) (xy 239.774836 -57.093919)
			(xy 239.737619 -57.135456) (xy 239.694751 -57.171131) (xy 239.647145 -57.200185) (xy 239.595816 -57.221997)
			(xy 239.541859 -57.236103) (xy 239.486422 -57.242203) (xy 239.430688 -57.240166) (xy 239.375845 -57.230036)
			(xy 239.323061 -57.212029) (xy 239.273461 -57.186528) (xy 239.228103 -57.154077) (xy 239.187954 -57.115368)
			(xy 239.153868 -57.071225) (xy 239.126572 -57.02259) (xy 239.106649 -56.970499) (xy 239.094523 -56.916062)
			(xy 239.090452 -56.86044) (xy 220.391577 -56.86044) (xy 220.401692 -56.884861) (xy 220.417205 -56.942754)
			(xy 220.425028 -57.002176) (xy 220.425518 -57.032144) (xy 220.425028 -57.062112) (xy 220.417205 -57.121534)
			(xy 220.401692 -57.179427) (xy 220.378756 -57.2348) (xy 220.348789 -57.286706) (xy 220.312302 -57.334256)
			(xy 220.269922 -57.376636) (xy 220.222372 -57.413123) (xy 220.170466 -57.44309) (xy 220.115093 -57.466026)
			(xy 220.0572 -57.481539) (xy 219.997778 -57.489362) (xy 219.937842 -57.489362) (xy 219.87842 -57.481539)
			(xy 219.820527 -57.466026) (xy 219.765154 -57.44309) (xy 219.713248 -57.413123) (xy 219.665698 -57.376636)
			(xy 219.623318 -57.334256) (xy 219.586831 -57.286706) (xy 219.556864 -57.2348) (xy 219.533928 -57.179427)
			(xy 219.518415 -57.121534) (xy 219.510592 -57.062112) (xy 216.421466 -57.062112) (xy 216.4183 -57.084133)
			(xy 216.402945 -57.136428) (xy 216.380303 -57.186005) (xy 216.350837 -57.231855) (xy 216.315146 -57.273046)
			(xy 216.273955 -57.308737) (xy 216.228105 -57.338203) (xy 216.178528 -57.360845) (xy 216.126233 -57.3762)
			(xy 216.072285 -57.383956) (xy 216.017783 -57.383956) (xy 215.963835 -57.3762) (xy 215.91154 -57.360845)
			(xy 215.861963 -57.338203) (xy 215.816113 -57.308737) (xy 215.774922 -57.273046) (xy 215.739231 -57.231855)
			(xy 215.709765 -57.186005) (xy 215.687123 -57.136428) (xy 215.671768 -57.084133) (xy 215.664012 -57.030185)
			(xy 215.663526 -57.002934) (xy 213.994401 -57.002934) (xy 214.001129 -57.049479) (xy 214.001604 -57.076848)
			(xy 214.001118 -57.104099) (xy 213.993362 -57.158047) (xy 213.978007 -57.210342) (xy 213.955365 -57.259919)
			(xy 213.925899 -57.305769) (xy 213.890208 -57.34696) (xy 213.849017 -57.382651) (xy 213.803167 -57.412117)
			(xy 213.75359 -57.434759) (xy 213.701295 -57.450114) (xy 213.647347 -57.45787) (xy 213.592845 -57.45787)
			(xy 213.538897 -57.450114) (xy 213.486602 -57.434759) (xy 213.437025 -57.412117) (xy 213.391175 -57.382651)
			(xy 213.349984 -57.34696) (xy 213.314293 -57.305769) (xy 213.284827 -57.259919) (xy 213.262185 -57.210342)
			(xy 213.24683 -57.158047) (xy 213.239074 -57.104099) (xy 213.238588 -57.076848) (xy 212.588797 -57.076848)
			(xy 212.612844 -57.095302) (xy 212.655225 -57.137686) (xy 212.69171 -57.185239) (xy 212.721677 -57.237148)
			(xy 212.744612 -57.292524) (xy 212.760123 -57.35042) (xy 212.767945 -57.409845) (xy 212.768434 -57.439814)
			(xy 212.768001 -57.468047) (xy 212.76106 -57.524085) (xy 212.747272 -57.578841) (xy 212.726848 -57.631484)
			(xy 212.700098 -57.681211) (xy 212.684106 -57.704482) (xy 212.67674 -57.71515) (xy 212.673692 -57.740804)
			(xy 212.71611 -57.844436) (xy 212.736176 -57.860692) (xy 212.74913 -57.862978) (xy 212.775238 -57.868126)
			(xy 212.825809 -57.884684) (xy 212.873589 -57.908106) (xy 212.917653 -57.937938) (xy 212.957146 -57.973602)
			(xy 212.991302 -58.014406) (xy 213.019458 -58.059559) (xy 213.04107 -58.108185) (xy 213.055717 -58.159342)
			(xy 213.063117 -58.212038) (xy 213.063582 -58.238644) (xy 213.063087 -58.266013) (xy 213.055277 -58.320191)
			(xy 213.039795 -58.372694) (xy 213.016959 -58.422442) (xy 212.987241 -58.46841) (xy 212.969602 -58.489342)
			(xy 212.969348 -58.489596) (xy 212.963751 -58.496675) (xy 212.957512 -58.513598) (xy 212.957156 -58.522616)
			(xy 212.957156 -58.589672) (xy 212.957514 -58.598689) (xy 212.96376 -58.615607) (xy 212.969348 -58.622692)
			(xy 212.969602 -58.622692) (xy 212.969602 -58.622946) (xy 212.98723 -58.643887) (xy 213.010141 -58.679334)
			(xy 216.019126 -58.679334) (xy 216.019126 -58.67908) (xy 216.019643 -58.647555) (xy 216.028322 -58.585104)
			(xy 216.045485 -58.524434) (xy 216.070809 -58.466692) (xy 216.103814 -58.41297) (xy 216.143876 -58.364283)
			(xy 216.1667 -58.34253) (xy 216.173812 -58.335926) (xy 216.182194 -58.318908) (xy 216.188544 -58.240422)
			(xy 216.188887 -58.230858) (xy 216.183284 -58.212576) (xy 216.177622 -58.204862) (xy 216.162091 -58.184575)
			(xy 216.136032 -58.140625) (xy 216.116069 -58.093593) (xy 216.102556 -58.044318) (xy 216.095737 -57.993681)
			(xy 216.095326 -57.968134) (xy 216.095812 -57.940883) (xy 216.103568 -57.886935) (xy 216.118923 -57.83464)
			(xy 216.141565 -57.785063) (xy 216.171031 -57.739213) (xy 216.206722 -57.698022) (xy 216.247913 -57.662331)
			(xy 216.293763 -57.632865) (xy 216.34334 -57.610223) (xy 216.395635 -57.594868) (xy 216.449583 -57.587112)
			(xy 216.504085 -57.587112) (xy 216.558033 -57.594868) (xy 216.610328 -57.610223) (xy 216.659905 -57.632865)
			(xy 216.705755 -57.662331) (xy 216.746946 -57.698022) (xy 216.782637 -57.739213) (xy 216.812103 -57.785063)
			(xy 216.834745 -57.83464) (xy 216.8501 -57.886935) (xy 216.857856 -57.940883) (xy 216.858342 -57.968134)
			(xy 216.857957 -57.993682) (xy 216.851143 -58.044323) (xy 216.837628 -58.0936) (xy 216.817654 -58.140631)
			(xy 216.791579 -58.184574) (xy 216.776046 -58.204862) (xy 216.770431 -58.212602) (xy 216.764816 -58.230865)
			(xy 216.765124 -58.240422) (xy 216.771474 -58.318908) (xy 216.779856 -58.335926) (xy 216.786968 -58.34253)
			(xy 216.809819 -58.364258) (xy 216.849895 -58.412939) (xy 216.882905 -58.466664) (xy 216.908223 -58.524413)
			(xy 216.92537 -58.585093) (xy 216.93402 -58.647552) (xy 216.934542 -58.67908) (xy 216.934542 -58.679334)
			(xy 216.934052 -58.709302) (xy 216.926229 -58.768724) (xy 216.910716 -58.826617) (xy 216.88778 -58.88199)
			(xy 216.857813 -58.933896) (xy 216.821326 -58.981446) (xy 216.778946 -59.023826) (xy 216.731396 -59.060313)
			(xy 216.67949 -59.09028) (xy 216.624117 -59.113216) (xy 216.566224 -59.128729) (xy 216.506802 -59.136552)
			(xy 216.446866 -59.136552) (xy 216.387444 -59.128729) (xy 216.329551 -59.113216) (xy 216.274178 -59.09028)
			(xy 216.222272 -59.060313) (xy 216.174722 -59.023826) (xy 216.132342 -58.981446) (xy 216.095855 -58.933896)
			(xy 216.065888 -58.88199) (xy 216.042952 -58.826617) (xy 216.027439 -58.768724) (xy 216.019616 -58.709302)
			(xy 216.019126 -58.679334) (xy 213.010141 -58.679334) (xy 213.016943 -58.689858) (xy 213.039781 -58.739603)
			(xy 213.055275 -58.792101) (xy 213.063106 -58.846275) (xy 213.063582 -58.873644) (xy 213.063096 -58.900895)
			(xy 213.05534 -58.954843) (xy 213.039985 -59.007138) (xy 213.017343 -59.056715) (xy 212.987877 -59.102565)
			(xy 212.952186 -59.143756) (xy 212.910995 -59.179447) (xy 212.865145 -59.208913) (xy 212.815568 -59.231555)
			(xy 212.763273 -59.24691) (xy 212.709325 -59.254666) (xy 212.654823 -59.254666) (xy 212.600875 -59.24691)
			(xy 212.54858 -59.231555) (xy 212.499003 -59.208913) (xy 212.453153 -59.179447) (xy 212.411962 -59.143756)
			(xy 212.376271 -59.102565) (xy 212.346805 -59.056715) (xy 212.324163 -59.007138) (xy 212.308808 -58.954843)
			(xy 212.301052 -58.900895) (xy 212.300566 -58.873644) (xy 212.301042 -58.846274) (xy 212.308855 -58.792095)
			(xy 212.324341 -58.739591) (xy 212.347181 -58.689844) (xy 212.376905 -58.643877) (xy 212.394546 -58.622946)
			(xy 212.3948 -58.622692) (xy 212.400396 -58.615612) (xy 212.406637 -58.59869) (xy 212.406992 -58.589672)
			(xy 212.406992 -58.522616) (xy 212.406629 -58.5136) (xy 212.400386 -58.496683) (xy 212.3948 -58.489596)
			(xy 212.394546 -58.489596) (xy 212.394546 -58.489342) (xy 212.37692 -58.468399) (xy 212.347205 -58.42243)
			(xy 212.324366 -58.372685) (xy 212.308872 -58.320187) (xy 212.301041 -58.266013) (xy 212.300566 -58.238644)
			(xy 212.300566 -58.23839) (xy 212.300939 -58.213442) (xy 212.307456 -58.163975) (xy 212.320376 -58.115781)
			(xy 212.339479 -58.069688) (xy 212.35162 -58.04789) (xy 212.358224 -58.03646) (xy 212.358732 -58.010806)
			(xy 212.313012 -57.923176) (xy 212.308778 -57.915718) (xy 212.296302 -57.903965) (xy 212.280634 -57.897014)
			(xy 212.272118 -57.895998) (xy 212.243927 -57.893199) (xy 212.188495 -57.881503) (xy 212.134931 -57.863054)
			(xy 212.084054 -57.838134) (xy 212.036641 -57.807125) (xy 211.993419 -57.770501) (xy 211.973922 -57.749948)
			(xy 211.967318 -57.742836) (xy 211.9503 -57.734454) (xy 211.871814 -57.728104) (xy 211.862249 -57.727747)
			(xy 211.843966 -57.733358) (xy 211.836254 -57.739026) (xy 211.815964 -57.754554) (xy 211.772016 -57.780614)
			(xy 211.724984 -57.800579) (xy 211.67571 -57.814092) (xy 211.625073 -57.820911) (xy 211.599526 -57.821322)
			(xy 211.572273 -57.820832) (xy 211.518321 -57.813079) (xy 211.466022 -57.797726) (xy 211.416441 -57.775085)
			(xy 211.370586 -57.745619) (xy 211.329392 -57.709927) (xy 211.293696 -57.668735) (xy 211.264227 -57.622882)
			(xy 211.241584 -57.573302) (xy 211.226227 -57.521004) (xy 211.218469 -57.467053) (xy 211.035212 -57.467053)
			(xy 211.039047 -57.495547) (xy 211.039456 -57.521094) (xy 211.038997 -57.548465) (xy 211.031179 -57.602644)
			(xy 211.015689 -57.655148) (xy 210.992845 -57.704895) (xy 210.963119 -57.750861) (xy 210.945476 -57.771792)
			(xy 210.945222 -57.772046) (xy 210.939643 -57.779137) (xy 210.933394 -57.796051) (xy 210.93303 -57.805066)
			(xy 210.93303 -57.872122) (xy 210.93337 -57.881141) (xy 210.939629 -57.898058) (xy 210.945222 -57.905142)
			(xy 210.945476 -57.905142) (xy 210.945476 -57.905396) (xy 210.963111 -57.926334) (xy 210.992835 -57.972301)
			(xy 211.015681 -58.022046) (xy 211.031178 -58.074547) (xy 211.039007 -58.128725) (xy 211.039007 -58.183466)
			(xy 211.03118 -58.237644) (xy 211.015684 -58.290145) (xy 210.99284 -58.339891) (xy 210.963116 -58.385859)
			(xy 210.945476 -58.406792) (xy 210.945222 -58.407046) (xy 210.939643 -58.414137) (xy 210.933394 -58.431051)
			(xy 210.93303 -58.440066) (xy 210.93303 -58.507122) (xy 210.93337 -58.516141) (xy 210.939629 -58.533058)
			(xy 210.945222 -58.540142) (xy 210.945476 -58.540142) (xy 210.945476 -58.540396) (xy 210.963123 -58.561322)
			(xy 210.992834 -58.607296) (xy 211.015669 -58.657045) (xy 211.031158 -58.709547) (xy 211.038984 -58.763724)
			(xy 211.039456 -58.791094) (xy 211.03897 -58.818345) (xy 211.031214 -58.872293) (xy 211.015859 -58.924588)
			(xy 210.993217 -58.974165) (xy 210.963751 -59.020015) (xy 210.92806 -59.061206) (xy 210.886869 -59.096897)
			(xy 210.841019 -59.126363) (xy 210.791442 -59.149005) (xy 210.739147 -59.16436) (xy 210.685199 -59.172116)
			(xy 210.630697 -59.172116) (xy 210.576749 -59.16436) (xy 210.524454 -59.149005) (xy 210.474877 -59.126363)
			(xy 210.429027 -59.096897) (xy 210.387836 -59.061206) (xy 210.352145 -59.020015) (xy 210.322679 -58.974165)
			(xy 210.300037 -58.924588) (xy 210.284682 -58.872293) (xy 210.276926 -58.818345) (xy 210.27644 -58.791094)
			(xy 210.276893 -58.763723) (xy 210.284712 -58.709543) (xy 210.300204 -58.657039) (xy 210.323049 -58.607293)
			(xy 210.352777 -58.561327) (xy 210.37042 -58.540396) (xy 210.370674 -58.540142) (xy 210.376258 -58.533054)
			(xy 210.382504 -58.516138) (xy 210.382866 -58.507122) (xy 210.382866 -58.440066) (xy 210.382533 -58.431047)
			(xy 210.376269 -58.414129) (xy 210.370674 -58.407046) (xy 210.37042 -58.407046) (xy 210.37042 -58.406792)
			(xy 210.352774 -58.385864) (xy 210.32305 -58.339895) (xy 210.300205 -58.290148) (xy 210.28471 -58.237645)
			(xy 210.276882 -58.183466) (xy 210.276882 -58.128725) (xy 210.284712 -58.074546) (xy 210.300208 -58.022043)
			(xy 210.323054 -57.972297) (xy 210.352779 -57.926329) (xy 210.37042 -57.905396) (xy 210.370674 -57.905142)
			(xy 210.376258 -57.898054) (xy 210.382504 -57.881138) (xy 210.382866 -57.872122) (xy 210.382866 -57.805066)
			(xy 210.382533 -57.796047) (xy 210.376269 -57.779129) (xy 210.370674 -57.772046) (xy 210.37042 -57.772046)
			(xy 210.37042 -57.771792) (xy 210.352767 -57.750871) (xy 210.323056 -57.704896) (xy 210.300223 -57.655145)
			(xy 210.284735 -57.602642) (xy 210.276911 -57.548464) (xy 210.27644 -57.521094) (xy 210.276823 -57.495545)
			(xy 210.283635 -57.444904) (xy 210.29715 -57.395627) (xy 210.317124 -57.348595) (xy 210.343202 -57.304653)
			(xy 210.358736 -57.284366) (xy 210.364336 -57.276617) (xy 210.369961 -57.258361) (xy 210.369658 -57.248806)
			(xy 210.363308 -57.17032) (xy 210.354926 -57.153302) (xy 210.347814 -57.146698) (xy 210.324992 -57.12494)
			(xy 210.28491 -57.076267) (xy 210.251894 -57.022549) (xy 210.22657 -56.964806) (xy 210.209419 -56.90413)
			(xy 210.200764 -56.841674) (xy 210.20024 -56.810148) (xy 208.383342 -56.810148) (xy 208.383632 -56.826404)
			(xy 208.383185 -56.853775) (xy 208.375365 -56.907956) (xy 208.359872 -56.96046) (xy 208.337026 -57.010206)
			(xy 208.307296 -57.056172) (xy 208.289652 -57.077102) (xy 208.289398 -57.077356) (xy 208.283823 -57.084451)
			(xy 208.27757 -57.101361) (xy 208.277206 -57.110376) (xy 208.277206 -57.177432) (xy 208.277547 -57.186451)
			(xy 208.283805 -57.203367) (xy 208.289398 -57.210452) (xy 208.289652 -57.210452) (xy 208.289652 -57.210706)
			(xy 208.307297 -57.231635) (xy 208.337024 -57.277603) (xy 208.35987 -57.32735) (xy 208.375367 -57.379853)
			(xy 208.383196 -57.434032) (xy 208.383195 -57.488774) (xy 208.375366 -57.542953) (xy 208.359868 -57.595456)
			(xy 208.337021 -57.645202) (xy 208.307294 -57.69117) (xy 208.289652 -57.712102) (xy 208.289398 -57.712356)
			(xy 208.283823 -57.719451) (xy 208.27757 -57.736361) (xy 208.277206 -57.745376) (xy 208.277206 -57.812432)
			(xy 208.277547 -57.821451) (xy 208.283805 -57.838367) (xy 208.289398 -57.845452) (xy 208.289652 -57.845452)
			(xy 208.289652 -57.845706) (xy 208.307297 -57.866635) (xy 208.337024 -57.912603) (xy 208.35987 -57.96235)
			(xy 208.375367 -58.014853) (xy 208.383196 -58.069032) (xy 208.383195 -58.123774) (xy 208.375366 -58.177953)
			(xy 208.359868 -58.230456) (xy 208.337021 -58.280202) (xy 208.307294 -58.32617) (xy 208.289652 -58.347102)
			(xy 208.289398 -58.347356) (xy 208.283823 -58.354451) (xy 208.27757 -58.371361) (xy 208.277206 -58.380376)
			(xy 208.277206 -58.447432) (xy 208.277547 -58.456451) (xy 208.283805 -58.473367) (xy 208.289398 -58.480452)
			(xy 208.289652 -58.480452) (xy 208.289652 -58.480706) (xy 208.3073 -58.501631) (xy 208.337012 -58.547605)
			(xy 208.359847 -58.597354) (xy 208.375336 -58.649857) (xy 208.38316 -58.704034) (xy 208.383632 -58.731404)
			(xy 208.383146 -58.758655) (xy 208.37539 -58.812603) (xy 208.360035 -58.864898) (xy 208.337393 -58.914475)
			(xy 208.307927 -58.960325) (xy 208.272236 -59.001516) (xy 208.231045 -59.037207) (xy 208.185195 -59.066673)
			(xy 208.135618 -59.089315) (xy 208.083323 -59.10467) (xy 208.029375 -59.112426) (xy 207.974873 -59.112426)
			(xy 207.920925 -59.10467) (xy 207.86863 -59.089315) (xy 207.819053 -59.066673) (xy 207.773203 -59.037207)
			(xy 207.732012 -59.001516) (xy 207.696321 -58.960325) (xy 207.666855 -58.914475) (xy 207.644213 -58.864898)
			(xy 207.628858 -58.812603) (xy 207.621102 -58.758655) (xy 207.620616 -58.731404) (xy 203.651098 -58.731404)
			(xy 203.635424 -58.75183) (xy 203.593044 -58.79421) (xy 203.545494 -58.830697) (xy 203.493588 -58.860664)
			(xy 203.438215 -58.8836) (xy 203.380322 -58.899113) (xy 203.3209 -58.906936) (xy 203.260964 -58.906936)
			(xy 203.201542 -58.899113) (xy 203.143649 -58.8836) (xy 203.088276 -58.860664) (xy 203.03637 -58.830697)
			(xy 202.98882 -58.79421) (xy 202.94644 -58.75183) (xy 202.909953 -58.70428) (xy 202.879986 -58.652374)
			(xy 202.85705 -58.597001) (xy 202.841537 -58.539108) (xy 202.833714 -58.479686) (xy 201.494731 -58.479686)
			(xy 201.50152 -58.531256) (xy 201.50201 -58.561224) (xy 201.50152 -58.591192) (xy 201.493697 -58.650614)
			(xy 201.478184 -58.708507) (xy 201.455248 -58.76388) (xy 201.425281 -58.815786) (xy 201.388794 -58.863336)
			(xy 201.346414 -58.905716) (xy 201.298864 -58.942203) (xy 201.246958 -58.97217) (xy 201.191585 -58.995106)
			(xy 201.133692 -59.010619) (xy 201.07427 -59.018442) (xy 201.014334 -59.018442) (xy 200.954912 -59.010619)
			(xy 200.897019 -58.995106) (xy 200.841646 -58.97217) (xy 200.78974 -58.942203) (xy 200.74219 -58.905716)
			(xy 200.69981 -58.863336) (xy 200.663323 -58.815786) (xy 200.633356 -58.76388) (xy 200.61042 -58.708507)
			(xy 200.594907 -58.650614) (xy 200.587084 -58.591192) (xy 190.847991 -58.591192) (xy 190.850731 -58.600884)
			(xy 190.857955 -58.653018) (xy 190.858394 -58.679334) (xy 190.857908 -58.706585) (xy 190.850152 -58.760533)
			(xy 190.834797 -58.812828) (xy 190.812155 -58.862405) (xy 190.782689 -58.908255) (xy 190.746998 -58.949446)
			(xy 190.705807 -58.985137) (xy 190.659957 -59.014603) (xy 190.61038 -59.037245) (xy 190.558085 -59.0526)
			(xy 190.504137 -59.060356) (xy 190.449635 -59.060356) (xy 190.395687 -59.0526) (xy 190.343392 -59.037245)
			(xy 190.293815 -59.014603) (xy 190.247965 -58.985137) (xy 190.206774 -58.949446) (xy 190.171083 -58.908255)
			(xy 190.141617 -58.862405) (xy 190.118975 -58.812828) (xy 190.10362 -58.760533) (xy 190.095864 -58.706585)
			(xy 190.095378 -58.679334) (xy 187.010185 -58.679334) (xy 187.01699 -58.689861) (xy 187.039831 -58.739605)
			(xy 187.055326 -58.792102) (xy 187.063158 -58.846276) (xy 187.063634 -58.873644) (xy 187.063148 -58.900895)
			(xy 187.055392 -58.954843) (xy 187.040037 -59.007138) (xy 187.017395 -59.056715) (xy 186.987929 -59.102565)
			(xy 186.952238 -59.143756) (xy 186.911047 -59.179447) (xy 186.865197 -59.208913) (xy 186.81562 -59.231555)
			(xy 186.763325 -59.24691) (xy 186.709377 -59.254666) (xy 186.654875 -59.254666) (xy 186.600927 -59.24691)
			(xy 186.548632 -59.231555) (xy 186.499055 -59.208913) (xy 186.453205 -59.179447) (xy 186.412014 -59.143756)
			(xy 186.376323 -59.102565) (xy 186.346857 -59.056715) (xy 186.324215 -59.007138) (xy 186.30886 -58.954843)
			(xy 186.301104 -58.900895) (xy 186.300618 -58.873644) (xy 186.301105 -58.846274) (xy 186.308917 -58.792096)
			(xy 186.324401 -58.739593) (xy 186.347238 -58.689846) (xy 186.376959 -58.643878) (xy 186.394598 -58.622946)
			(xy 186.394852 -58.622692) (xy 186.400454 -58.615616) (xy 186.40669 -58.598691) (xy 186.407044 -58.589672)
			(xy 186.407044 -58.522616) (xy 186.406691 -58.513598) (xy 186.400442 -58.496681) (xy 186.394852 -58.489596)
			(xy 186.394598 -58.489596) (xy 186.394598 -58.489342) (xy 186.376965 -58.468405) (xy 186.347252 -58.422434)
			(xy 186.324415 -58.372687) (xy 186.308923 -58.320188) (xy 186.301093 -58.266013) (xy 186.300618 -58.238644)
			(xy 186.300618 -58.23839) (xy 186.300984 -58.213442) (xy 186.307502 -58.163974) (xy 186.320424 -58.11578)
			(xy 186.33953 -58.069687) (xy 186.351672 -58.04789) (xy 186.358276 -58.03646) (xy 186.358784 -58.010806)
			(xy 186.313064 -57.923176) (xy 186.308859 -57.915699) (xy 186.29637 -57.903948) (xy 186.280691 -57.897007)
			(xy 186.27217 -57.895998) (xy 186.243983 -57.893168) (xy 186.188552 -57.881479) (xy 186.134987 -57.863036)
			(xy 186.084109 -57.838122) (xy 186.036696 -57.807118) (xy 185.993472 -57.770498) (xy 185.973974 -57.749948)
			(xy 185.96737 -57.742836) (xy 185.950352 -57.734454) (xy 185.871866 -57.728104) (xy 185.8623 -57.727722)
			(xy 185.844016 -57.73335) (xy 185.836306 -57.739026) (xy 185.815998 -57.75453) (xy 185.772055 -57.780594)
			(xy 185.725028 -57.800564) (xy 185.675757 -57.814083) (xy 185.625124 -57.820908) (xy 185.599578 -57.821322)
			(xy 185.572329 -57.820806) (xy 185.518386 -57.813047) (xy 185.466095 -57.797691) (xy 185.416523 -57.77505)
			(xy 185.370677 -57.745584) (xy 185.329491 -57.709894) (xy 185.293803 -57.668705) (xy 185.26434 -57.622858)
			(xy 185.241701 -57.573284) (xy 185.226348 -57.520993) (xy 185.218592 -57.467049) (xy 185.035263 -57.467049)
			(xy 185.039099 -57.495547) (xy 185.039508 -57.521094) (xy 185.039036 -57.548464) (xy 185.03122 -57.602643)
			(xy 185.015732 -57.655146) (xy 184.992891 -57.704893) (xy 184.963168 -57.75086) (xy 184.945528 -57.771792)
			(xy 184.945274 -57.772046) (xy 184.939701 -57.779142) (xy 184.933447 -57.796052) (xy 184.933082 -57.805066)
			(xy 184.933082 -57.872122) (xy 184.933433 -57.881139) (xy 184.939685 -57.898056) (xy 184.945274 -57.905142)
			(xy 184.945528 -57.905142) (xy 184.945528 -57.905396) (xy 184.963165 -57.926333) (xy 184.992893 -57.972299)
			(xy 185.015742 -58.022044) (xy 185.03124 -58.074546) (xy 185.03907 -58.128725) (xy 185.039071 -58.183466)
			(xy 185.031242 -58.237645) (xy 185.015745 -58.290148) (xy 184.992898 -58.339893) (xy 184.96317 -58.38586)
			(xy 184.945528 -58.406792) (xy 184.945274 -58.407046) (xy 184.939701 -58.414142) (xy 184.933447 -58.431052)
			(xy 184.933082 -58.440066) (xy 184.933082 -58.507122) (xy 184.933433 -58.516139) (xy 184.939685 -58.533056)
			(xy 184.945274 -58.540142) (xy 184.945528 -58.540142) (xy 184.945528 -58.540396) (xy 184.963183 -58.561315)
			(xy 184.992892 -58.607292) (xy 185.015724 -58.657043) (xy 185.031211 -58.709546) (xy 185.039036 -58.763724)
			(xy 185.039508 -58.791094) (xy 185.039022 -58.818345) (xy 185.031266 -58.872293) (xy 185.015911 -58.924588)
			(xy 184.993269 -58.974165) (xy 184.963803 -59.020015) (xy 184.928112 -59.061206) (xy 184.886921 -59.096897)
			(xy 184.841071 -59.126363) (xy 184.791494 -59.149005) (xy 184.739199 -59.16436) (xy 184.685251 -59.172116)
			(xy 184.630749 -59.172116) (xy 184.576801 -59.16436) (xy 184.524506 -59.149005) (xy 184.474929 -59.126363)
			(xy 184.429079 -59.096897) (xy 184.387888 -59.061206) (xy 184.352197 -59.020015) (xy 184.322731 -58.974165)
			(xy 184.300089 -58.924588) (xy 184.284734 -58.872293) (xy 184.276978 -58.818345) (xy 184.276492 -58.791094)
			(xy 184.276957 -58.763724) (xy 184.284775 -58.709545) (xy 184.300265 -58.657042) (xy 184.323107 -58.607295)
			(xy 184.352831 -58.561328) (xy 184.370472 -58.540396) (xy 184.370726 -58.540142) (xy 184.376304 -58.53305)
			(xy 184.382555 -58.516137) (xy 184.382918 -58.507122) (xy 184.382918 -58.440066) (xy 184.382574 -58.431048)
			(xy 184.376317 -58.414131) (xy 184.370726 -58.407046) (xy 184.370472 -58.407046) (xy 184.370472 -58.406792)
			(xy 184.352824 -58.385865) (xy 184.323096 -58.339897) (xy 184.300248 -58.29015) (xy 184.28475 -58.237647)
			(xy 184.276921 -58.183467) (xy 184.276922 -58.128724) (xy 184.284752 -58.074544) (xy 184.300251 -58.022041)
			(xy 184.3231 -57.972295) (xy 184.352829 -57.926328) (xy 184.370472 -57.905396) (xy 184.370726 -57.905142)
			(xy 184.376304 -57.89805) (xy 184.382555 -57.881137) (xy 184.382918 -57.872122) (xy 184.382918 -57.805066)
			(xy 184.382574 -57.796048) (xy 184.376317 -57.779131) (xy 184.370726 -57.772046) (xy 184.370472 -57.772046)
			(xy 184.370472 -57.771792) (xy 184.352811 -57.750877) (xy 184.323104 -57.704899) (xy 184.300272 -57.655147)
			(xy 184.284786 -57.602643) (xy 184.276963 -57.548464) (xy 184.276492 -57.521094) (xy 184.276885 -57.495546)
			(xy 184.283697 -57.444905) (xy 184.297209 -57.395628) (xy 184.317181 -57.348597) (xy 184.343255 -57.304654)
			(xy 184.358788 -57.284366) (xy 184.364394 -57.276621) (xy 184.370014 -57.258361) (xy 184.36971 -57.248806)
			(xy 184.36336 -57.17032) (xy 184.354978 -57.153302) (xy 184.347866 -57.146698) (xy 184.325035 -57.12495)
			(xy 184.284956 -57.076274) (xy 184.251942 -57.022553) (xy 184.22662 -56.964808) (xy 184.20947 -56.904132)
			(xy 184.200816 -56.841675) (xy 184.200292 -56.810148) (xy 182.383394 -56.810148) (xy 182.383684 -56.826404)
			(xy 182.383224 -56.853774) (xy 182.375405 -56.907954) (xy 182.359915 -56.960457) (xy 182.337072 -57.010204)
			(xy 182.307346 -57.056171) (xy 182.289704 -57.077102) (xy 182.28945 -57.077356) (xy 182.28387 -57.084447)
			(xy 182.27762 -57.10136) (xy 182.277258 -57.110376) (xy 182.277258 -57.177432) (xy 182.277587 -57.186452)
			(xy 182.283852 -57.203369) (xy 182.28945 -57.210452) (xy 182.289704 -57.210452) (xy 182.289704 -57.210706)
			(xy 182.307347 -57.231636) (xy 182.33707 -57.277605) (xy 182.359913 -57.327352) (xy 182.375407 -57.379854)
			(xy 182.383235 -57.434033) (xy 182.383235 -57.488773) (xy 182.375406 -57.542952) (xy 182.359911 -57.595454)
			(xy 182.337067 -57.6452) (xy 182.307344 -57.691169) (xy 182.289704 -57.712102) (xy 182.28945 -57.712356)
			(xy 182.28387 -57.719447) (xy 182.27762 -57.73636) (xy 182.277258 -57.745376) (xy 182.277258 -57.812432)
			(xy 182.277587 -57.821452) (xy 182.283852 -57.838369) (xy 182.28945 -57.845452) (xy 182.289704 -57.845452)
			(xy 182.289704 -57.845706) (xy 182.307347 -57.866636) (xy 182.33707 -57.912605) (xy 182.359913 -57.962352)
			(xy 182.375407 -58.014854) (xy 182.383235 -58.069033) (xy 182.383235 -58.123773) (xy 182.375406 -58.177952)
			(xy 182.359911 -58.230454) (xy 182.337067 -58.2802) (xy 182.307344 -58.326169) (xy 182.289704 -58.347102)
			(xy 182.28945 -58.347356) (xy 182.28387 -58.354447) (xy 182.27762 -58.37136) (xy 182.277258 -58.380376)
			(xy 182.277258 -58.447432) (xy 182.277587 -58.456452) (xy 182.283852 -58.473369) (xy 182.28945 -58.480452)
			(xy 182.289704 -58.480452) (xy 182.289704 -58.480706) (xy 182.30736 -58.501624) (xy 182.337069 -58.547601)
			(xy 182.359902 -58.597352) (xy 182.375389 -58.649856) (xy 182.383212 -58.704034) (xy 182.383684 -58.731404)
			(xy 182.383198 -58.758655) (xy 182.375442 -58.812603) (xy 182.360087 -58.864898) (xy 182.337445 -58.914475)
			(xy 182.307979 -58.960325) (xy 182.272288 -59.001516) (xy 182.231097 -59.037207) (xy 182.185247 -59.066673)
			(xy 182.13567 -59.089315) (xy 182.083375 -59.10467) (xy 182.029427 -59.112426) (xy 181.974925 -59.112426)
			(xy 181.920977 -59.10467) (xy 181.868682 -59.089315) (xy 181.819105 -59.066673) (xy 181.773255 -59.037207)
			(xy 181.732064 -59.001516) (xy 181.696373 -58.960325) (xy 181.666907 -58.914475) (xy 181.644265 -58.864898)
			(xy 181.62891 -58.812603) (xy 181.621154 -58.758655) (xy 181.620668 -58.731404) (xy 177.65115 -58.731404)
			(xy 177.635476 -58.75183) (xy 177.593096 -58.79421) (xy 177.545546 -58.830697) (xy 177.49364 -58.860664)
			(xy 177.438267 -58.8836) (xy 177.380374 -58.899113) (xy 177.320952 -58.906936) (xy 177.261016 -58.906936)
			(xy 177.201594 -58.899113) (xy 177.143701 -58.8836) (xy 177.088328 -58.860664) (xy 177.036422 -58.830697)
			(xy 176.988872 -58.79421) (xy 176.946492 -58.75183) (xy 176.910005 -58.70428) (xy 176.880038 -58.652374)
			(xy 176.857102 -58.597001) (xy 176.841589 -58.539108) (xy 176.833766 -58.479686) (xy 175.494783 -58.479686)
			(xy 175.501572 -58.531256) (xy 175.502062 -58.561224) (xy 175.501572 -58.591192) (xy 175.493749 -58.650614)
			(xy 175.478236 -58.708507) (xy 175.4553 -58.76388) (xy 175.425333 -58.815786) (xy 175.388846 -58.863336)
			(xy 175.346466 -58.905716) (xy 175.298916 -58.942203) (xy 175.24701 -58.97217) (xy 175.191637 -58.995106)
			(xy 175.133744 -59.010619) (xy 175.074322 -59.018442) (xy 175.014386 -59.018442) (xy 174.954964 -59.010619)
			(xy 174.897071 -58.995106) (xy 174.841698 -58.97217) (xy 174.789792 -58.942203) (xy 174.742242 -58.905716)
			(xy 174.699862 -58.863336) (xy 174.663375 -58.815786) (xy 174.633408 -58.76388) (xy 174.610472 -58.708507)
			(xy 174.594959 -58.650614) (xy 174.587136 -58.591192) (xy 164.926319 -58.591192) (xy 164.934124 -58.647552)
			(xy 164.934646 -58.67908) (xy 164.934646 -58.679334) (xy 164.934156 -58.709302) (xy 164.926333 -58.768724)
			(xy 164.91082 -58.826617) (xy 164.887884 -58.88199) (xy 164.857917 -58.933896) (xy 164.82143 -58.981446)
			(xy 164.77905 -59.023826) (xy 164.7315 -59.060313) (xy 164.679594 -59.09028) (xy 164.624221 -59.113216)
			(xy 164.566328 -59.128729) (xy 164.506906 -59.136552) (xy 164.44697 -59.136552) (xy 164.387548 -59.128729)
			(xy 164.329655 -59.113216) (xy 164.274282 -59.09028) (xy 164.222376 -59.060313) (xy 164.174826 -59.023826)
			(xy 164.132446 -58.981446) (xy 164.095959 -58.933896) (xy 164.065992 -58.88199) (xy 164.043056 -58.826617)
			(xy 164.027543 -58.768724) (xy 164.01972 -58.709302) (xy 164.01923 -58.679334) (xy 161.010245 -58.679334)
			(xy 161.017047 -58.689857) (xy 161.039885 -58.739603) (xy 161.055379 -58.792101) (xy 161.06321 -58.846275)
			(xy 161.063686 -58.873644) (xy 161.0632 -58.900895) (xy 161.055444 -58.954843) (xy 161.040089 -59.007138)
			(xy 161.017447 -59.056715) (xy 160.987981 -59.102565) (xy 160.95229 -59.143756) (xy 160.911099 -59.179447)
			(xy 160.865249 -59.208913) (xy 160.815672 -59.231555) (xy 160.763377 -59.24691) (xy 160.709429 -59.254666)
			(xy 160.654927 -59.254666) (xy 160.600979 -59.24691) (xy 160.548684 -59.231555) (xy 160.499107 -59.208913)
			(xy 160.453257 -59.179447) (xy 160.412066 -59.143756) (xy 160.376375 -59.102565) (xy 160.346909 -59.056715)
			(xy 160.324267 -59.007138) (xy 160.308912 -58.954843) (xy 160.301156 -58.900895) (xy 160.30067 -58.873644)
			(xy 160.301145 -58.846274) (xy 160.308958 -58.792094) (xy 160.324444 -58.739591) (xy 160.347284 -58.689844)
			(xy 160.377009 -58.643877) (xy 160.39465 -58.622946) (xy 160.394904 -58.622692) (xy 160.400501 -58.615612)
			(xy 160.406741 -58.59869) (xy 160.407096 -58.589672) (xy 160.407096 -58.522616) (xy 160.406732 -58.5136)
			(xy 160.40049 -58.496683) (xy 160.394904 -58.489596) (xy 160.39465 -58.489596) (xy 160.39465 -58.489342)
			(xy 160.377025 -58.468398) (xy 160.347309 -58.42243) (xy 160.32447 -58.372685) (xy 160.308976 -58.320187)
			(xy 160.301145 -58.266013) (xy 160.30067 -58.238644) (xy 160.30067 -58.23839) (xy 160.301042 -58.213442)
			(xy 160.307559 -58.163974) (xy 160.32048 -58.115781) (xy 160.339583 -58.069688) (xy 160.351724 -58.04789)
			(xy 160.358328 -58.03646) (xy 160.358836 -58.010806) (xy 160.313116 -57.923176) (xy 160.308879 -57.915719)
			(xy 160.296404 -57.903966) (xy 160.280738 -57.897014) (xy 160.272222 -57.895998) (xy 160.244032 -57.893196)
			(xy 160.1886 -57.881501) (xy 160.135035 -57.863053) (xy 160.084158 -57.838133) (xy 160.036746 -57.807125)
			(xy 159.993523 -57.7705) (xy 159.974026 -57.749948) (xy 159.967422 -57.742836) (xy 159.950404 -57.734454)
			(xy 159.871918 -57.728104) (xy 159.862353 -57.727749) (xy 159.84407 -57.733358) (xy 159.836358 -57.739026)
			(xy 159.816066 -57.754552) (xy 159.772119 -57.780613) (xy 159.725087 -57.800578) (xy 159.675813 -57.814092)
			(xy 159.625177 -57.820911) (xy 159.59963 -57.821322) (xy 159.572377 -57.820833) (xy 159.518425 -57.81308)
			(xy 159.466125 -57.797727) (xy 159.416543 -57.775087) (xy 159.370688 -57.745621) (xy 159.329493 -57.709928)
			(xy 159.293797 -57.668736) (xy 159.264328 -57.622883) (xy 159.241684 -57.573303) (xy 159.226327 -57.521005)
			(xy 159.218569 -57.467053) (xy 159.035316 -57.467053) (xy 159.039151 -57.495546) (xy 159.03956 -57.521094)
			(xy 159.0391 -57.548465) (xy 159.031282 -57.602644) (xy 159.015792 -57.655148) (xy 158.992949 -57.704895)
			(xy 158.963222 -57.750861) (xy 158.94558 -57.771792) (xy 158.945326 -57.772046) (xy 158.939747 -57.779138)
			(xy 158.933498 -57.796051) (xy 158.933134 -57.805066) (xy 158.933134 -57.872122) (xy 158.933473 -57.881141)
			(xy 158.939732 -57.898058) (xy 158.945326 -57.905142) (xy 158.94558 -57.905142) (xy 158.94558 -57.905396)
			(xy 158.963215 -57.926334) (xy 158.992939 -57.972301) (xy 159.015784 -58.022046) (xy 159.031281 -58.074547)
			(xy 159.03911 -58.128725) (xy 159.03911 -58.183466) (xy 159.031283 -58.237644) (xy 159.015787 -58.290145)
			(xy 158.992943 -58.339891) (xy 158.96322 -58.385859) (xy 158.94558 -58.406792) (xy 158.945326 -58.407046)
			(xy 158.939747 -58.414138) (xy 158.933498 -58.431051) (xy 158.933134 -58.440066) (xy 158.933134 -58.507122)
			(xy 158.933473 -58.516141) (xy 158.939732 -58.533058) (xy 158.945326 -58.540142) (xy 158.94558 -58.540142)
			(xy 158.94558 -58.540396) (xy 158.963228 -58.561321) (xy 158.992939 -58.607296) (xy 159.015773 -58.657045)
			(xy 159.031262 -58.709547) (xy 159.039088 -58.763724) (xy 159.03956 -58.791094) (xy 159.039074 -58.818345)
			(xy 159.031318 -58.872293) (xy 159.015963 -58.924588) (xy 158.993321 -58.974165) (xy 158.963855 -59.020015)
			(xy 158.928164 -59.061206) (xy 158.886973 -59.096897) (xy 158.841123 -59.126363) (xy 158.791546 -59.149005)
			(xy 158.739251 -59.16436) (xy 158.685303 -59.172116) (xy 158.630801 -59.172116) (xy 158.576853 -59.16436)
			(xy 158.524558 -59.149005) (xy 158.474981 -59.126363) (xy 158.429131 -59.096897) (xy 158.38794 -59.061206)
			(xy 158.352249 -59.020015) (xy 158.322783 -58.974165) (xy 158.300141 -58.924588) (xy 158.284786 -58.872293)
			(xy 158.27703 -58.818345) (xy 158.276544 -58.791094) (xy 158.276996 -58.763723) (xy 158.284815 -58.709543)
			(xy 158.300307 -58.657039) (xy 158.323152 -58.607293) (xy 158.352881 -58.561327) (xy 158.370524 -58.540396)
			(xy 158.370778 -58.540142) (xy 158.376362 -58.533054) (xy 158.382608 -58.516138) (xy 158.38297 -58.507122)
			(xy 158.38297 -58.440066) (xy 158.382636 -58.431047) (xy 158.376373 -58.41413) (xy 158.370778 -58.407046)
			(xy 158.370524 -58.407046) (xy 158.370524 -58.406792) (xy 158.352878 -58.385864) (xy 158.323153 -58.339895)
			(xy 158.300308 -58.290148) (xy 158.284813 -58.237645) (xy 158.276985 -58.183466) (xy 158.276985 -58.128725)
			(xy 158.284815 -58.074546) (xy 158.300312 -58.022043) (xy 158.323158 -57.972297) (xy 158.352883 -57.926329)
			(xy 158.370524 -57.905396) (xy 158.370778 -57.905142) (xy 158.376362 -57.898054) (xy 158.382608 -57.881138)
			(xy 158.38297 -57.872122) (xy 158.38297 -57.805066) (xy 158.382636 -57.796047) (xy 158.376373 -57.77913)
			(xy 158.370778 -57.772046) (xy 158.370524 -57.772046) (xy 158.370524 -57.771792) (xy 158.352871 -57.750871)
			(xy 158.323161 -57.704895) (xy 158.300327 -57.655145) (xy 158.284839 -57.602642) (xy 158.277015 -57.548464)
			(xy 158.276544 -57.521094) (xy 158.276926 -57.495545) (xy 158.283738 -57.444904) (xy 158.297253 -57.395627)
			(xy 158.317228 -57.348595) (xy 158.343305 -57.304653) (xy 158.35884 -57.284366) (xy 158.364441 -57.276617)
			(xy 158.370065 -57.258361) (xy 158.369762 -57.248806) (xy 158.363412 -57.17032) (xy 158.35503 -57.153302)
			(xy 158.347918 -57.146698) (xy 158.325097 -57.12494) (xy 158.285015 -57.076267) (xy 158.251999 -57.022549)
			(xy 158.226675 -56.964805) (xy 158.209523 -56.90413) (xy 158.200868 -56.841674) (xy 158.200344 -56.810148)
			(xy 156.383446 -56.810148) (xy 156.383736 -56.826404) (xy 156.383288 -56.853775) (xy 156.375468 -56.907956)
			(xy 156.359976 -56.960459) (xy 156.33713 -57.010206) (xy 156.3074 -57.056172) (xy 156.289756 -57.077102)
			(xy 156.289502 -57.077356) (xy 156.283928 -57.084451) (xy 156.277674 -57.101361) (xy 156.27731 -57.110376)
			(xy 156.27731 -57.177432) (xy 156.27765 -57.186451) (xy 156.283909 -57.203368) (xy 156.289502 -57.210452)
			(xy 156.289756 -57.210452) (xy 156.289756 -57.210706) (xy 156.307401 -57.231635) (xy 156.337127 -57.277603)
			(xy 156.359973 -57.32735) (xy 156.37547 -57.379853) (xy 156.383299 -57.434032) (xy 156.383298 -57.488774)
			(xy 156.375469 -57.542953) (xy 156.359971 -57.595456) (xy 156.337124 -57.645202) (xy 156.307398 -57.69117)
			(xy 156.289756 -57.712102) (xy 156.289502 -57.712356) (xy 156.283928 -57.719451) (xy 156.277674 -57.736361)
			(xy 156.27731 -57.745376) (xy 156.27731 -57.812432) (xy 156.27765 -57.821451) (xy 156.283909 -57.838368)
			(xy 156.289502 -57.845452) (xy 156.289756 -57.845452) (xy 156.289756 -57.845706) (xy 156.307401 -57.866635)
			(xy 156.337127 -57.912603) (xy 156.359973 -57.96235) (xy 156.37547 -58.014853) (xy 156.383299 -58.069032)
			(xy 156.383298 -58.123774) (xy 156.375469 -58.177953) (xy 156.359971 -58.230456) (xy 156.337124 -58.280202)
			(xy 156.307398 -58.32617) (xy 156.289756 -58.347102) (xy 156.289502 -58.347356) (xy 156.283928 -58.354451)
			(xy 156.277674 -58.371361) (xy 156.27731 -58.380376) (xy 156.27731 -58.447432) (xy 156.27765 -58.456451)
			(xy 156.283909 -58.473368) (xy 156.289502 -58.480452) (xy 156.289756 -58.480452) (xy 156.289756 -58.480706)
			(xy 156.307405 -58.501631) (xy 156.337116 -58.547605) (xy 156.359951 -58.597354) (xy 156.37544 -58.649857)
			(xy 156.383264 -58.704034) (xy 156.383736 -58.731404) (xy 156.38325 -58.758655) (xy 156.375494 -58.812603)
			(xy 156.360139 -58.864898) (xy 156.337497 -58.914475) (xy 156.308031 -58.960325) (xy 156.27234 -59.001516)
			(xy 156.231149 -59.037207) (xy 156.185299 -59.066673) (xy 156.135722 -59.089315) (xy 156.083427 -59.10467)
			(xy 156.029479 -59.112426) (xy 155.974977 -59.112426) (xy 155.921029 -59.10467) (xy 155.868734 -59.089315)
			(xy 155.819157 -59.066673) (xy 155.773307 -59.037207) (xy 155.732116 -59.001516) (xy 155.696425 -58.960325)
			(xy 155.666959 -58.914475) (xy 155.644317 -58.864898) (xy 155.628962 -58.812603) (xy 155.621206 -58.758655)
			(xy 155.62072 -58.731404) (xy 151.651202 -58.731404) (xy 151.635528 -58.75183) (xy 151.593148 -58.79421)
			(xy 151.545598 -58.830697) (xy 151.493692 -58.860664) (xy 151.438319 -58.8836) (xy 151.380426 -58.899113)
			(xy 151.321004 -58.906936) (xy 151.261068 -58.906936) (xy 151.201646 -58.899113) (xy 151.143753 -58.8836)
			(xy 151.08838 -58.860664) (xy 151.036474 -58.830697) (xy 150.988924 -58.79421) (xy 150.946544 -58.75183)
			(xy 150.910057 -58.70428) (xy 150.88009 -58.652374) (xy 150.857154 -58.597001) (xy 150.841641 -58.539108)
			(xy 150.833818 -58.479686) (xy 149.494835 -58.479686) (xy 149.501624 -58.531256) (xy 149.502114 -58.561224)
			(xy 149.501624 -58.591192) (xy 149.493801 -58.650614) (xy 149.478288 -58.708507) (xy 149.455352 -58.76388)
			(xy 149.425385 -58.815786) (xy 149.388898 -58.863336) (xy 149.346518 -58.905716) (xy 149.298968 -58.942203)
			(xy 149.247062 -58.97217) (xy 149.191689 -58.995106) (xy 149.133796 -59.010619) (xy 149.074374 -59.018442)
			(xy 149.014438 -59.018442) (xy 148.955016 -59.010619) (xy 148.897123 -58.995106) (xy 148.84175 -58.97217)
			(xy 148.789844 -58.942203) (xy 148.742294 -58.905716) (xy 148.699914 -58.863336) (xy 148.663427 -58.815786)
			(xy 148.63346 -58.76388) (xy 148.610524 -58.708507) (xy 148.595011 -58.650614) (xy 148.587188 -58.591192)
			(xy 138.848095 -58.591192) (xy 138.850835 -58.600884) (xy 138.858059 -58.653018) (xy 138.858498 -58.679334)
			(xy 138.858012 -58.706585) (xy 138.850256 -58.760533) (xy 138.834901 -58.812828) (xy 138.812259 -58.862405)
			(xy 138.782793 -58.908255) (xy 138.747102 -58.949446) (xy 138.705911 -58.985137) (xy 138.660061 -59.014603)
			(xy 138.610484 -59.037245) (xy 138.558189 -59.0526) (xy 138.504241 -59.060356) (xy 138.449739 -59.060356)
			(xy 138.395791 -59.0526) (xy 138.343496 -59.037245) (xy 138.293919 -59.014603) (xy 138.248069 -58.985137)
			(xy 138.206878 -58.949446) (xy 138.171187 -58.908255) (xy 138.141721 -58.862405) (xy 138.119079 -58.812828)
			(xy 138.103724 -58.760533) (xy 138.095968 -58.706585) (xy 138.095482 -58.679334) (xy 135.01029 -58.679334)
			(xy 135.017095 -58.689861) (xy 135.039935 -58.739605) (xy 135.05543 -58.792102) (xy 135.063262 -58.846276)
			(xy 135.063738 -58.873644) (xy 135.063252 -58.900895) (xy 135.055496 -58.954843) (xy 135.040141 -59.007138)
			(xy 135.017499 -59.056715) (xy 134.988033 -59.102565) (xy 134.952342 -59.143756) (xy 134.911151 -59.179447)
			(xy 134.865301 -59.208913) (xy 134.815724 -59.231555) (xy 134.763429 -59.24691) (xy 134.709481 -59.254666)
			(xy 134.654979 -59.254666) (xy 134.601031 -59.24691) (xy 134.548736 -59.231555) (xy 134.499159 -59.208913)
			(xy 134.453309 -59.179447) (xy 134.412118 -59.143756) (xy 134.376427 -59.102565) (xy 134.346961 -59.056715)
			(xy 134.324319 -59.007138) (xy 134.308964 -58.954843) (xy 134.301208 -58.900895) (xy 134.300722 -58.873644)
			(xy 134.301208 -58.846274) (xy 134.309021 -58.792096) (xy 134.324505 -58.739593) (xy 134.347342 -58.689846)
			(xy 134.377063 -58.643878) (xy 134.394702 -58.622946) (xy 134.394956 -58.622692) (xy 134.400559 -58.615617)
			(xy 134.406794 -58.598691) (xy 134.407148 -58.589672) (xy 134.407148 -58.522616) (xy 134.406795 -58.513599)
			(xy 134.400546 -58.496681) (xy 134.394956 -58.489596) (xy 134.394702 -58.489596) (xy 134.394702 -58.489342)
			(xy 134.377069 -58.468405) (xy 134.347357 -58.422433) (xy 134.324519 -58.372687) (xy 134.309027 -58.320188)
			(xy 134.301197 -58.266013) (xy 134.300722 -58.238644) (xy 134.300722 -58.23839) (xy 134.301087 -58.213442)
			(xy 134.307605 -58.163974) (xy 134.320528 -58.11578) (xy 134.339634 -58.069687) (xy 134.351776 -58.04789)
			(xy 134.35838 -58.03646) (xy 134.358888 -58.010806) (xy 134.313168 -57.923176) (xy 134.30896 -57.9157)
			(xy 134.296473 -57.90395) (xy 134.280794 -57.897007) (xy 134.272274 -57.895998) (xy 134.24408 -57.893224)
			(xy 134.188648 -57.881523) (xy 134.135083 -57.863069) (xy 134.084207 -57.838145) (xy 134.036795 -57.807131)
			(xy 133.993575 -57.770502) (xy 133.974078 -57.749948) (xy 133.967474 -57.742836) (xy 133.950456 -57.734454)
			(xy 133.87197 -57.728104) (xy 133.862404 -57.727724) (xy 133.844121 -57.733351) (xy 133.83641 -57.739026)
			(xy 133.816101 -57.754528) (xy 133.772158 -57.780593) (xy 133.725131 -57.800563) (xy 133.675861 -57.814082)
			(xy 133.625228 -57.820908) (xy 133.599682 -57.821322) (xy 133.572433 -57.820807) (xy 133.518489 -57.813048)
			(xy 133.466198 -57.797692) (xy 133.416625 -57.775051) (xy 133.370779 -57.745585) (xy 133.329592 -57.709895)
			(xy 133.293904 -57.668707) (xy 133.264441 -57.622859) (xy 133.241802 -57.573285) (xy 133.226448 -57.520994)
			(xy 133.218692 -57.467049) (xy 133.035367 -57.467049) (xy 133.039203 -57.495547) (xy 133.039612 -57.521094)
			(xy 133.039139 -57.548464) (xy 133.031323 -57.602643) (xy 133.015835 -57.655146) (xy 132.992995 -57.704893)
			(xy 132.963272 -57.75086) (xy 132.945632 -57.771792) (xy 132.945378 -57.772046) (xy 132.939805 -57.779142)
			(xy 132.933551 -57.796052) (xy 132.933186 -57.805066) (xy 132.933186 -57.872122) (xy 132.933536 -57.88114)
			(xy 132.939789 -57.898056) (xy 132.945378 -57.905142) (xy 132.945632 -57.905142) (xy 132.945632 -57.905396)
			(xy 132.963269 -57.926333) (xy 132.992997 -57.972299) (xy 133.015845 -58.022044) (xy 133.031343 -58.074546)
			(xy 133.039173 -58.128725) (xy 133.039174 -58.183466) (xy 133.031345 -58.237645) (xy 133.015848 -58.290147)
			(xy 132.993001 -58.339893) (xy 132.963274 -58.38586) (xy 132.945632 -58.406792) (xy 132.945378 -58.407046)
			(xy 132.939805 -58.414142) (xy 132.933551 -58.431052) (xy 132.933186 -58.440066) (xy 132.933186 -58.507122)
			(xy 132.933536 -58.51614) (xy 132.939789 -58.533056) (xy 132.945378 -58.540142) (xy 132.945632 -58.540142)
			(xy 132.945632 -58.540396) (xy 132.963288 -58.561315) (xy 132.992996 -58.607292) (xy 133.015828 -58.657043)
			(xy 133.031315 -58.709546) (xy 133.03914 -58.763724) (xy 133.039612 -58.791094) (xy 133.039126 -58.818345)
			(xy 133.03137 -58.872293) (xy 133.016015 -58.924588) (xy 132.993373 -58.974165) (xy 132.963907 -59.020015)
			(xy 132.928216 -59.061206) (xy 132.887025 -59.096897) (xy 132.841175 -59.126363) (xy 132.791598 -59.149005)
			(xy 132.739303 -59.16436) (xy 132.685355 -59.172116) (xy 132.630853 -59.172116) (xy 132.576905 -59.16436)
			(xy 132.52461 -59.149005) (xy 132.475033 -59.126363) (xy 132.429183 -59.096897) (xy 132.387992 -59.061206)
			(xy 132.352301 -59.020015) (xy 132.322835 -58.974165) (xy 132.300193 -58.924588) (xy 132.284838 -58.872293)
			(xy 132.277082 -58.818345) (xy 132.276596 -58.791094) (xy 132.27706 -58.763724) (xy 132.284878 -58.709545)
			(xy 132.300368 -58.657041) (xy 132.32321 -58.607295) (xy 132.352935 -58.561328) (xy 132.370576 -58.540396)
			(xy 132.37083 -58.540142) (xy 132.376408 -58.53305) (xy 132.382659 -58.516137) (xy 132.383022 -58.507122)
			(xy 132.383022 -58.440066) (xy 132.382677 -58.431048) (xy 132.376421 -58.414131) (xy 132.37083 -58.407046)
			(xy 132.370576 -58.407046) (xy 132.370576 -58.406792) (xy 132.352927 -58.385865) (xy 132.323199 -58.339897)
			(xy 132.300351 -58.290151) (xy 132.284853 -58.237647) (xy 132.277024 -58.183467) (xy 132.277025 -58.128724)
			(xy 132.284855 -58.074544) (xy 132.300354 -58.022041) (xy 132.323203 -57.972295) (xy 132.352933 -57.926328)
			(xy 132.370576 -57.905396) (xy 132.37083 -57.905142) (xy 132.376408 -57.89805) (xy 132.382659 -57.881137)
			(xy 132.383022 -57.872122) (xy 132.383022 -57.805066) (xy 132.382677 -57.796048) (xy 132.376421 -57.779131)
			(xy 132.37083 -57.772046) (xy 132.370576 -57.772046) (xy 132.370576 -57.771792) (xy 132.352916 -57.750877)
			(xy 132.323208 -57.704899) (xy 132.300377 -57.655147) (xy 132.28489 -57.602643) (xy 132.277067 -57.548464)
			(xy 132.276596 -57.521094) (xy 132.276989 -57.495546) (xy 132.2838 -57.444905) (xy 132.297313 -57.395628)
			(xy 132.317285 -57.348597) (xy 132.343359 -57.304654) (xy 132.358892 -57.284366) (xy 132.364498 -57.276621)
			(xy 132.370118 -57.258361) (xy 132.369814 -57.248806) (xy 132.363464 -57.17032) (xy 132.355082 -57.153302)
			(xy 132.34797 -57.146698) (xy 132.32514 -57.124949) (xy 132.28506 -57.076273) (xy 132.252047 -57.022553)
			(xy 132.226724 -56.964808) (xy 132.209574 -56.904132) (xy 132.20092 -56.841675) (xy 132.200396 -56.810148)
			(xy 130.383498 -56.810148) (xy 130.383788 -56.826404) (xy 130.383327 -56.853774) (xy 130.375509 -56.907954)
			(xy 130.360018 -56.960457) (xy 130.337175 -57.010204) (xy 130.30745 -57.056171) (xy 130.289808 -57.077102)
			(xy 130.289554 -57.077356) (xy 130.283974 -57.084447) (xy 130.277725 -57.101361) (xy 130.277362 -57.110376)
			(xy 130.277362 -57.177432) (xy 130.277712 -57.186449) (xy 130.283965 -57.203366) (xy 130.289554 -57.210452)
			(xy 130.289808 -57.210452) (xy 130.289808 -57.210706) (xy 130.307451 -57.231636) (xy 130.337173 -57.277605)
			(xy 130.360016 -57.327352) (xy 130.375511 -57.379854) (xy 130.383338 -57.434033) (xy 130.383338 -57.488773)
			(xy 130.375509 -57.542952) (xy 130.360014 -57.595453) (xy 130.33717 -57.6452) (xy 130.307448 -57.691169)
			(xy 130.289808 -57.712102) (xy 130.289554 -57.712356) (xy 130.283974 -57.719447) (xy 130.277725 -57.736361)
			(xy 130.277362 -57.745376) (xy 130.277362 -57.812432) (xy 130.277712 -57.821449) (xy 130.283965 -57.838366)
			(xy 130.289554 -57.845452) (xy 130.289808 -57.845452) (xy 130.289808 -57.845706) (xy 130.307451 -57.866636)
			(xy 130.337173 -57.912605) (xy 130.360016 -57.962352) (xy 130.375511 -58.014854) (xy 130.383338 -58.069033)
			(xy 130.383338 -58.123773) (xy 130.375509 -58.177952) (xy 130.360014 -58.230453) (xy 130.33717 -58.2802)
			(xy 130.307448 -58.326169) (xy 130.289808 -58.347102) (xy 130.289554 -58.347356) (xy 130.283974 -58.354447)
			(xy 130.277725 -58.371361) (xy 130.277362 -58.380376) (xy 130.277362 -58.447432) (xy 130.277712 -58.456449)
			(xy 130.283965 -58.473366) (xy 130.289554 -58.480452) (xy 130.289808 -58.480452) (xy 130.289808 -58.480706)
			(xy 130.307465 -58.501624) (xy 130.337174 -58.547601) (xy 130.360006 -58.597352) (xy 130.375493 -58.649856)
			(xy 130.383316 -58.704034) (xy 130.383788 -58.731404) (xy 130.383302 -58.758655) (xy 130.375546 -58.812603)
			(xy 130.360191 -58.864898) (xy 130.337549 -58.914475) (xy 130.308083 -58.960325) (xy 130.272392 -59.001516)
			(xy 130.231201 -59.037207) (xy 130.185351 -59.066673) (xy 130.135774 -59.089315) (xy 130.083479 -59.10467)
			(xy 130.029531 -59.112426) (xy 129.975029 -59.112426) (xy 129.921081 -59.10467) (xy 129.868786 -59.089315)
			(xy 129.819209 -59.066673) (xy 129.773359 -59.037207) (xy 129.732168 -59.001516) (xy 129.696477 -58.960325)
			(xy 129.667011 -58.914475) (xy 129.644369 -58.864898) (xy 129.629014 -58.812603) (xy 129.621258 -58.758655)
			(xy 129.620772 -58.731404) (xy 125.651254 -58.731404) (xy 125.63558 -58.75183) (xy 125.5932 -58.79421)
			(xy 125.54565 -58.830697) (xy 125.493744 -58.860664) (xy 125.438371 -58.8836) (xy 125.380478 -58.899113)
			(xy 125.321056 -58.906936) (xy 125.26112 -58.906936) (xy 125.201698 -58.899113) (xy 125.143805 -58.8836)
			(xy 125.088432 -58.860664) (xy 125.036526 -58.830697) (xy 124.988976 -58.79421) (xy 124.946596 -58.75183)
			(xy 124.910109 -58.70428) (xy 124.880142 -58.652374) (xy 124.857206 -58.597001) (xy 124.841693 -58.539108)
			(xy 124.83387 -58.479686) (xy 123.494887 -58.479686) (xy 123.501676 -58.531256) (xy 123.502166 -58.561224)
			(xy 123.501676 -58.591192) (xy 123.493853 -58.650614) (xy 123.47834 -58.708507) (xy 123.455404 -58.76388)
			(xy 123.425437 -58.815786) (xy 123.38895 -58.863336) (xy 123.34657 -58.905716) (xy 123.29902 -58.942203)
			(xy 123.247114 -58.97217) (xy 123.191741 -58.995106) (xy 123.133848 -59.010619) (xy 123.074426 -59.018442)
			(xy 123.01449 -59.018442) (xy 122.955068 -59.010619) (xy 122.897175 -58.995106) (xy 122.841802 -58.97217)
			(xy 122.789896 -58.942203) (xy 122.742346 -58.905716) (xy 122.699966 -58.863336) (xy 122.663479 -58.815786)
			(xy 122.633512 -58.76388) (xy 122.610576 -58.708507) (xy 122.595063 -58.650614) (xy 122.58724 -58.591192)
			(xy 100.747842 -58.591192) (xy 100.750581 -58.600883) (xy 100.757806 -58.653018) (xy 100.758244 -58.679334)
			(xy 100.757758 -58.706585) (xy 100.750002 -58.760533) (xy 100.734647 -58.812828) (xy 100.712005 -58.862405)
			(xy 100.682539 -58.908255) (xy 100.646848 -58.949446) (xy 100.605657 -58.985137) (xy 100.559807 -59.014603)
			(xy 100.51023 -59.037245) (xy 100.457935 -59.0526) (xy 100.403987 -59.060356) (xy 100.349485 -59.060356)
			(xy 100.295537 -59.0526) (xy 100.243242 -59.037245) (xy 100.193665 -59.014603) (xy 100.147815 -58.985137)
			(xy 100.106624 -58.949446) (xy 100.070933 -58.908255) (xy 100.041467 -58.862405) (xy 100.018825 -58.812828)
			(xy 100.00347 -58.760533) (xy 99.995714 -58.706585) (xy 99.995228 -58.679334) (xy 96.910043 -58.679334)
			(xy 96.916845 -58.689857) (xy 96.939683 -58.739603) (xy 96.955177 -58.792101) (xy 96.963008 -58.846275)
			(xy 96.963484 -58.873644) (xy 96.962998 -58.900895) (xy 96.955242 -58.954843) (xy 96.939887 -59.007138)
			(xy 96.917245 -59.056715) (xy 96.887779 -59.102565) (xy 96.852088 -59.143756) (xy 96.810897 -59.179447)
			(xy 96.765047 -59.208913) (xy 96.71547 -59.231555) (xy 96.663175 -59.24691) (xy 96.609227 -59.254666)
			(xy 96.554725 -59.254666) (xy 96.500777 -59.24691) (xy 96.448482 -59.231555) (xy 96.398905 -59.208913)
			(xy 96.353055 -59.179447) (xy 96.311864 -59.143756) (xy 96.276173 -59.102565) (xy 96.246707 -59.056715)
			(xy 96.224065 -59.007138) (xy 96.20871 -58.954843) (xy 96.200954 -58.900895) (xy 96.200468 -58.873644)
			(xy 96.200943 -58.846274) (xy 96.208756 -58.792095) (xy 96.224242 -58.739591) (xy 96.247082 -58.689844)
			(xy 96.276807 -58.643877) (xy 96.294448 -58.622946) (xy 96.294702 -58.622692) (xy 96.300298 -58.615612)
			(xy 96.306539 -58.59869) (xy 96.306894 -58.589672) (xy 96.306894 -58.522616) (xy 96.306531 -58.5136)
			(xy 96.300288 -58.496683) (xy 96.294702 -58.489596) (xy 96.294448 -58.489596) (xy 96.294448 -58.489342)
			(xy 96.276823 -58.468399) (xy 96.247107 -58.42243) (xy 96.224268 -58.372685) (xy 96.208774 -58.320187)
			(xy 96.200943 -58.266013) (xy 96.200468 -58.238644) (xy 96.200468 -58.23839) (xy 96.200841 -58.213442)
			(xy 96.207357 -58.163974) (xy 96.220278 -58.115781) (xy 96.239381 -58.069688) (xy 96.251522 -58.04789)
			(xy 96.258126 -58.03646) (xy 96.258634 -58.010806) (xy 96.212914 -57.923176) (xy 96.208679 -57.915718)
			(xy 96.196203 -57.903965) (xy 96.180536 -57.897014) (xy 96.17202 -57.895998) (xy 96.143829 -57.893197)
			(xy 96.088398 -57.881502) (xy 96.034833 -57.863053) (xy 95.983956 -57.838134) (xy 95.936543 -57.807125)
			(xy 95.893321 -57.7705) (xy 95.873824 -57.749948) (xy 95.86722 -57.742836) (xy 95.850202 -57.734454)
			(xy 95.771716 -57.728104) (xy 95.762151 -57.727748) (xy 95.743868 -57.733358) (xy 95.736156 -57.739026)
			(xy 95.715865 -57.754553) (xy 95.671917 -57.780613) (xy 95.624886 -57.800579) (xy 95.575611 -57.814092)
			(xy 95.524975 -57.820911) (xy 95.499428 -57.821322) (xy 95.472175 -57.820833) (xy 95.418223 -57.813079)
			(xy 95.365924 -57.797726) (xy 95.316342 -57.775086) (xy 95.270487 -57.74562) (xy 95.229292 -57.709928)
			(xy 95.193597 -57.668736) (xy 95.164127 -57.622883) (xy 95.141484 -57.573303) (xy 95.126127 -57.521005)
			(xy 95.118369 -57.467053) (xy 94.935114 -57.467053) (xy 94.938949 -57.495546) (xy 94.939358 -57.521094)
			(xy 94.938899 -57.548465) (xy 94.931081 -57.602644) (xy 94.915591 -57.655148) (xy 94.892747 -57.704895)
			(xy 94.86302 -57.750861) (xy 94.845378 -57.771792) (xy 94.845124 -57.772046) (xy 94.839545 -57.779137)
			(xy 94.833296 -57.796051) (xy 94.832932 -57.805066) (xy 94.832932 -57.872122) (xy 94.833271 -57.881141)
			(xy 94.83953 -57.898058) (xy 94.845124 -57.905142) (xy 94.845378 -57.905142) (xy 94.845378 -57.905396)
			(xy 94.863013 -57.926334) (xy 94.892737 -57.972301) (xy 94.915583 -58.022046) (xy 94.931079 -58.074547)
			(xy 94.938908 -58.128725) (xy 94.938909 -58.183466) (xy 94.931081 -58.237644) (xy 94.915586 -58.290145)
			(xy 94.892742 -58.339891) (xy 94.863018 -58.385859) (xy 94.845378 -58.406792) (xy 94.845124 -58.407046)
			(xy 94.839545 -58.414137) (xy 94.833296 -58.431051) (xy 94.832932 -58.440066) (xy 94.832932 -58.507122)
			(xy 94.833271 -58.516141) (xy 94.83953 -58.533058) (xy 94.845124 -58.540142) (xy 94.845378 -58.540142)
			(xy 94.845378 -58.540396) (xy 94.863025 -58.561322) (xy 94.892737 -58.607296) (xy 94.915571 -58.657045)
			(xy 94.93106 -58.709547) (xy 94.938886 -58.763724) (xy 94.939358 -58.791094) (xy 94.938872 -58.818345)
			(xy 94.931116 -58.872293) (xy 94.915761 -58.924588) (xy 94.893119 -58.974165) (xy 94.863653 -59.020015)
			(xy 94.827962 -59.061206) (xy 94.786771 -59.096897) (xy 94.740921 -59.126363) (xy 94.691344 -59.149005)
			(xy 94.639049 -59.16436) (xy 94.585101 -59.172116) (xy 94.530599 -59.172116) (xy 94.476651 -59.16436)
			(xy 94.424356 -59.149005) (xy 94.374779 -59.126363) (xy 94.328929 -59.096897) (xy 94.287738 -59.061206)
			(xy 94.252047 -59.020015) (xy 94.222581 -58.974165) (xy 94.199939 -58.924588) (xy 94.184584 -58.872293)
			(xy 94.176828 -58.818345) (xy 94.176342 -58.791094) (xy 94.176794 -58.763723) (xy 94.184614 -58.709543)
			(xy 94.200106 -58.657039) (xy 94.222951 -58.607293) (xy 94.252679 -58.561327) (xy 94.270322 -58.540396)
			(xy 94.270576 -58.540142) (xy 94.27616 -58.533054) (xy 94.282406 -58.516138) (xy 94.282768 -58.507122)
			(xy 94.282768 -58.440066) (xy 94.282434 -58.431047) (xy 94.276171 -58.414129) (xy 94.270576 -58.407046)
			(xy 94.270322 -58.407046) (xy 94.270322 -58.406792) (xy 94.252676 -58.385864) (xy 94.222951 -58.339895)
			(xy 94.200107 -58.290148) (xy 94.184611 -58.237645) (xy 94.176783 -58.183466) (xy 94.176784 -58.128725)
			(xy 94.184613 -58.074546) (xy 94.20011 -58.022043) (xy 94.222956 -57.972297) (xy 94.252681 -57.926329)
			(xy 94.270322 -57.905396) (xy 94.270576 -57.905142) (xy 94.27616 -57.898054) (xy 94.282406 -57.881138)
			(xy 94.282768 -57.872122) (xy 94.282768 -57.805066) (xy 94.282434 -57.796047) (xy 94.276171 -57.779129)
			(xy 94.270576 -57.772046) (xy 94.270322 -57.772046) (xy 94.270322 -57.771792) (xy 94.252669 -57.750871)
			(xy 94.222959 -57.704895) (xy 94.200125 -57.655145) (xy 94.184637 -57.602642) (xy 94.176813 -57.548464)
			(xy 94.176342 -57.521094) (xy 94.176725 -57.495545) (xy 94.183537 -57.444904) (xy 94.197051 -57.395627)
			(xy 94.217026 -57.348595) (xy 94.243104 -57.304653) (xy 94.258638 -57.284366) (xy 94.264238 -57.276617)
			(xy 94.269863 -57.258361) (xy 94.26956 -57.248806) (xy 94.26321 -57.17032) (xy 94.254828 -57.153302)
			(xy 94.247716 -57.146698) (xy 94.224895 -57.12494) (xy 94.184813 -57.076267) (xy 94.151797 -57.022549)
			(xy 94.126473 -56.964806) (xy 94.109321 -56.90413) (xy 94.100666 -56.841674) (xy 94.100142 -56.810148)
			(xy 92.283244 -56.810148) (xy 92.283534 -56.826404) (xy 92.283086 -56.853775) (xy 92.275267 -56.907956)
			(xy 92.259774 -56.96046) (xy 92.236928 -57.010206) (xy 92.207198 -57.056172) (xy 92.189554 -57.077102)
			(xy 92.1893 -57.077356) (xy 92.183726 -57.084451) (xy 92.177472 -57.101361) (xy 92.177108 -57.110376)
			(xy 92.177108 -57.177432) (xy 92.177448 -57.186451) (xy 92.183707 -57.203367) (xy 92.1893 -57.210452)
			(xy 92.189554 -57.210452) (xy 92.189554 -57.210706) (xy 92.207199 -57.231635) (xy 92.236925 -57.277603)
			(xy 92.259772 -57.32735) (xy 92.275269 -57.379853) (xy 92.283097 -57.434032) (xy 92.283097 -57.488774)
			(xy 92.275267 -57.542953) (xy 92.25977 -57.595456) (xy 92.236923 -57.645202) (xy 92.207196 -57.69117)
			(xy 92.189554 -57.712102) (xy 92.1893 -57.712356) (xy 92.183726 -57.719451) (xy 92.177472 -57.736361)
			(xy 92.177108 -57.745376) (xy 92.177108 -57.812432) (xy 92.177448 -57.821451) (xy 92.183707 -57.838367)
			(xy 92.1893 -57.845452) (xy 92.189554 -57.845452) (xy 92.189554 -57.845706) (xy 92.207199 -57.866635)
			(xy 92.236925 -57.912603) (xy 92.259772 -57.96235) (xy 92.275269 -58.014853) (xy 92.283097 -58.069032)
			(xy 92.283097 -58.123774) (xy 92.275267 -58.177953) (xy 92.25977 -58.230456) (xy 92.236923 -58.280202)
			(xy 92.207196 -58.32617) (xy 92.189554 -58.347102) (xy 92.1893 -58.347356) (xy 92.183726 -58.354451)
			(xy 92.177472 -58.371361) (xy 92.177108 -58.380376) (xy 92.177108 -58.447432) (xy 92.177448 -58.456451)
			(xy 92.183707 -58.473367) (xy 92.1893 -58.480452) (xy 92.189554 -58.480452) (xy 92.189554 -58.480706)
			(xy 92.207202 -58.501631) (xy 92.236914 -58.547605) (xy 92.259749 -58.597354) (xy 92.275238 -58.649857)
			(xy 92.283062 -58.704034) (xy 92.283534 -58.731404) (xy 92.283048 -58.758655) (xy 92.275292 -58.812603)
			(xy 92.259937 -58.864898) (xy 92.237295 -58.914475) (xy 92.207829 -58.960325) (xy 92.172138 -59.001516)
			(xy 92.130947 -59.037207) (xy 92.085097 -59.066673) (xy 92.03552 -59.089315) (xy 91.983225 -59.10467)
			(xy 91.929277 -59.112426) (xy 91.874775 -59.112426) (xy 91.820827 -59.10467) (xy 91.768532 -59.089315)
			(xy 91.718955 -59.066673) (xy 91.673105 -59.037207) (xy 91.631914 -59.001516) (xy 91.596223 -58.960325)
			(xy 91.566757 -58.914475) (xy 91.544115 -58.864898) (xy 91.52876 -58.812603) (xy 91.521004 -58.758655)
			(xy 91.520518 -58.731404) (xy 87.551 -58.731404) (xy 87.535326 -58.75183) (xy 87.492946 -58.79421)
			(xy 87.445396 -58.830697) (xy 87.39349 -58.860664) (xy 87.338117 -58.8836) (xy 87.280224 -58.899113)
			(xy 87.220802 -58.906936) (xy 87.160866 -58.906936) (xy 87.101444 -58.899113) (xy 87.043551 -58.8836)
			(xy 86.988178 -58.860664) (xy 86.936272 -58.830697) (xy 86.888722 -58.79421) (xy 86.846342 -58.75183)
			(xy 86.809855 -58.70428) (xy 86.779888 -58.652374) (xy 86.756952 -58.597001) (xy 86.741439 -58.539108)
			(xy 86.733616 -58.479686) (xy 85.394633 -58.479686) (xy 85.401422 -58.531256) (xy 85.401912 -58.561224)
			(xy 85.401422 -58.591192) (xy 85.393599 -58.650614) (xy 85.378086 -58.708507) (xy 85.35515 -58.76388)
			(xy 85.325183 -58.815786) (xy 85.288696 -58.863336) (xy 85.246316 -58.905716) (xy 85.198766 -58.942203)
			(xy 85.14686 -58.97217) (xy 85.091487 -58.995106) (xy 85.033594 -59.010619) (xy 84.974172 -59.018442)
			(xy 84.914236 -59.018442) (xy 84.854814 -59.010619) (xy 84.796921 -58.995106) (xy 84.741548 -58.97217)
			(xy 84.689642 -58.942203) (xy 84.642092 -58.905716) (xy 84.599712 -58.863336) (xy 84.563225 -58.815786)
			(xy 84.533258 -58.76388) (xy 84.510322 -58.708507) (xy 84.494809 -58.650614) (xy 84.486986 -58.591192)
			(xy 74.747893 -58.591192) (xy 74.750633 -58.600884) (xy 74.757857 -58.653018) (xy 74.758296 -58.679334)
			(xy 74.75781 -58.706585) (xy 74.750054 -58.760533) (xy 74.734699 -58.812828) (xy 74.712057 -58.862405)
			(xy 74.682591 -58.908255) (xy 74.6469 -58.949446) (xy 74.605709 -58.985137) (xy 74.559859 -59.014603)
			(xy 74.510282 -59.037245) (xy 74.457987 -59.0526) (xy 74.404039 -59.060356) (xy 74.349537 -59.060356)
			(xy 74.295589 -59.0526) (xy 74.243294 -59.037245) (xy 74.193717 -59.014603) (xy 74.147867 -58.985137)
			(xy 74.106676 -58.949446) (xy 74.070985 -58.908255) (xy 74.041519 -58.862405) (xy 74.018877 -58.812828)
			(xy 74.003522 -58.760533) (xy 73.995766 -58.706585) (xy 73.99528 -58.679334) (xy 70.910088 -58.679334)
			(xy 70.916893 -58.689861) (xy 70.939733 -58.739605) (xy 70.955228 -58.792102) (xy 70.96306 -58.846276)
			(xy 70.963536 -58.873644) (xy 70.96305 -58.900895) (xy 70.955294 -58.954843) (xy 70.939939 -59.007138)
			(xy 70.917297 -59.056715) (xy 70.887831 -59.102565) (xy 70.85214 -59.143756) (xy 70.810949 -59.179447)
			(xy 70.765099 -59.208913) (xy 70.715522 -59.231555) (xy 70.663227 -59.24691) (xy 70.609279 -59.254666)
			(xy 70.554777 -59.254666) (xy 70.500829 -59.24691) (xy 70.448534 -59.231555) (xy 70.398957 -59.208913)
			(xy 70.353107 -59.179447) (xy 70.311916 -59.143756) (xy 70.276225 -59.102565) (xy 70.246759 -59.056715)
			(xy 70.224117 -59.007138) (xy 70.208762 -58.954843) (xy 70.201006 -58.900895) (xy 70.20052 -58.873644)
			(xy 70.201007 -58.846274) (xy 70.208819 -58.792096) (xy 70.224303 -58.739593) (xy 70.24714 -58.689846)
			(xy 70.276861 -58.643878) (xy 70.2945 -58.622946) (xy 70.294754 -58.622692) (xy 70.300356 -58.615617)
			(xy 70.306592 -58.598691) (xy 70.306946 -58.589672) (xy 70.306946 -58.522616) (xy 70.306593 -58.513598)
			(xy 70.300344 -58.496681) (xy 70.294754 -58.489596) (xy 70.2945 -58.489596) (xy 70.2945 -58.489342)
			(xy 70.276867 -58.468405) (xy 70.247154 -58.422433) (xy 70.224317 -58.372687) (xy 70.208825 -58.320188)
			(xy 70.200995 -58.266013) (xy 70.20052 -58.238644) (xy 70.20052 -58.23839) (xy 70.200886 -58.213442)
			(xy 70.207403 -58.163974) (xy 70.220326 -58.11578) (xy 70.239432 -58.069687) (xy 70.251574 -58.04789)
			(xy 70.258178 -58.03646) (xy 70.258686 -58.010806) (xy 70.212966 -57.923176) (xy 70.20876 -57.915699)
			(xy 70.196272 -57.903949) (xy 70.180593 -57.897007) (xy 70.172072 -57.895998) (xy 70.143878 -57.893226)
			(xy 70.088446 -57.881524) (xy 70.034881 -57.86307) (xy 69.984004 -57.838145) (xy 69.936593 -57.807131)
			(xy 69.893373 -57.770503) (xy 69.873876 -57.749948) (xy 69.867272 -57.742836) (xy 69.850254 -57.734454)
			(xy 69.771768 -57.728104) (xy 69.762202 -57.727723) (xy 69.743919 -57.73335) (xy 69.736208 -57.739026)
			(xy 69.7159 -57.754529) (xy 69.671957 -57.780594) (xy 69.62493 -57.800564) (xy 69.575659 -57.814082)
			(xy 69.525026 -57.820908) (xy 69.49948 -57.821322) (xy 69.472231 -57.820806) (xy 69.418287 -57.813048)
			(xy 69.365997 -57.797692) (xy 69.316424 -57.77505) (xy 69.270578 -57.745584) (xy 69.229392 -57.709894)
			(xy 69.193704 -57.668706) (xy 69.16424 -57.622858) (xy 69.141601 -57.573284) (xy 69.126248 -57.520993)
			(xy 69.118492 -57.467049) (xy 68.935165 -57.467049) (xy 68.939001 -57.495547) (xy 68.93941 -57.521094)
			(xy 68.938938 -57.548464) (xy 68.931121 -57.602643) (xy 68.915633 -57.655146) (xy 68.892793 -57.704893)
			(xy 68.86307 -57.75086) (xy 68.84543 -57.771792) (xy 68.845176 -57.772046) (xy 68.839603 -57.779142)
			(xy 68.833349 -57.796052) (xy 68.832984 -57.805066) (xy 68.832984 -57.872122) (xy 68.833334 -57.881139)
			(xy 68.839587 -57.898056) (xy 68.845176 -57.905142) (xy 68.84543 -57.905142) (xy 68.84543 -57.905396)
			(xy 68.863067 -57.926333) (xy 68.892795 -57.972299) (xy 68.915643 -58.022044) (xy 68.931142 -58.074546)
			(xy 68.938972 -58.128725) (xy 68.938973 -58.183466) (xy 68.931144 -58.237645) (xy 68.915646 -58.290147)
			(xy 68.892799 -58.339893) (xy 68.863072 -58.38586) (xy 68.84543 -58.406792) (xy 68.845176 -58.407046)
			(xy 68.839603 -58.414142) (xy 68.833349 -58.431052) (xy 68.832984 -58.440066) (xy 68.832984 -58.507122)
			(xy 68.833334 -58.516139) (xy 68.839587 -58.533056) (xy 68.845176 -58.540142) (xy 68.84543 -58.540142)
			(xy 68.84543 -58.540396) (xy 68.863085 -58.561315) (xy 68.892794 -58.607292) (xy 68.915626 -58.657043)
			(xy 68.931113 -58.709546) (xy 68.938938 -58.763724) (xy 68.93941 -58.791094) (xy 68.938924 -58.818345)
			(xy 68.931168 -58.872293) (xy 68.915813 -58.924588) (xy 68.893171 -58.974165) (xy 68.863705 -59.020015)
			(xy 68.828014 -59.061206) (xy 68.786823 -59.096897) (xy 68.740973 -59.126363) (xy 68.691396 -59.149005)
			(xy 68.639101 -59.16436) (xy 68.585153 -59.172116) (xy 68.530651 -59.172116) (xy 68.476703 -59.16436)
			(xy 68.424408 -59.149005) (xy 68.374831 -59.126363) (xy 68.328981 -59.096897) (xy 68.28779 -59.061206)
			(xy 68.252099 -59.020015) (xy 68.222633 -58.974165) (xy 68.199991 -58.924588) (xy 68.184636 -58.872293)
			(xy 68.17688 -58.818345) (xy 68.176394 -58.791094) (xy 68.176858 -58.763724) (xy 68.184677 -58.709545)
			(xy 68.200166 -58.657042) (xy 68.223008 -58.607295) (xy 68.252733 -58.561328) (xy 68.270374 -58.540396)
			(xy 68.270628 -58.540142) (xy 68.276206 -58.53305) (xy 68.282457 -58.516137) (xy 68.28282 -58.507122)
			(xy 68.28282 -58.440066) (xy 68.282475 -58.431048) (xy 68.276219 -58.414131) (xy 68.270628 -58.407046)
			(xy 68.270374 -58.407046) (xy 68.270374 -58.406792) (xy 68.252725 -58.385865) (xy 68.222997 -58.339897)
			(xy 68.200149 -58.29015) (xy 68.184652 -58.237647) (xy 68.176823 -58.183467) (xy 68.176823 -58.128724)
			(xy 68.184654 -58.074544) (xy 68.200153 -58.022041) (xy 68.223002 -57.972295) (xy 68.252731 -57.926328)
			(xy 68.270374 -57.905396) (xy 68.270628 -57.905142) (xy 68.276206 -57.89805) (xy 68.282457 -57.881137)
			(xy 68.28282 -57.872122) (xy 68.28282 -57.805066) (xy 68.282475 -57.796048) (xy 68.276219 -57.779131)
			(xy 68.270628 -57.772046) (xy 68.270374 -57.772046) (xy 68.270374 -57.771792) (xy 68.252714 -57.750877)
			(xy 68.223006 -57.704899) (xy 68.200174 -57.655147) (xy 68.184688 -57.602643) (xy 68.176865 -57.548464)
			(xy 68.176394 -57.521094) (xy 68.176787 -57.495546) (xy 68.183598 -57.444905) (xy 68.197111 -57.395628)
			(xy 68.217083 -57.348597) (xy 68.243157 -57.304654) (xy 68.25869 -57.284366) (xy 68.264296 -57.276621)
			(xy 68.269916 -57.258361) (xy 68.269612 -57.248806) (xy 68.263262 -57.17032) (xy 68.25488 -57.153302)
			(xy 68.247768 -57.146698) (xy 68.224938 -57.12495) (xy 68.184858 -57.076273) (xy 68.151844 -57.022553)
			(xy 68.126522 -56.964808) (xy 68.109372 -56.904132) (xy 68.100718 -56.841675) (xy 68.100194 -56.810148)
			(xy 66.283296 -56.810148) (xy 66.283586 -56.826404) (xy 66.283126 -56.853774) (xy 66.275307 -56.907954)
			(xy 66.259817 -56.960457) (xy 66.236974 -57.010204) (xy 66.207248 -57.056171) (xy 66.189606 -57.077102)
			(xy 66.189352 -57.077356) (xy 66.183772 -57.084447) (xy 66.177523 -57.101361) (xy 66.17716 -57.110376)
			(xy 66.17716 -57.177432) (xy 66.177488 -57.186452) (xy 66.183754 -57.20337) (xy 66.189352 -57.210452)
			(xy 66.189606 -57.210452) (xy 66.189606 -57.210706) (xy 66.207249 -57.231636) (xy 66.236971 -57.277605)
			(xy 66.259814 -57.327352) (xy 66.275309 -57.379854) (xy 66.283137 -57.434033) (xy 66.283136 -57.488773)
			(xy 66.275308 -57.542952) (xy 66.259812 -57.595454) (xy 66.236968 -57.6452) (xy 66.207246 -57.691169)
			(xy 66.189606 -57.712102) (xy 66.189352 -57.712356) (xy 66.183772 -57.719447) (xy 66.177523 -57.736361)
			(xy 66.17716 -57.745376) (xy 66.17716 -57.812432) (xy 66.177488 -57.821452) (xy 66.183754 -57.83837)
			(xy 66.189352 -57.845452) (xy 66.189606 -57.845452) (xy 66.189606 -57.845706) (xy 66.207249 -57.866636)
			(xy 66.236971 -57.912605) (xy 66.259814 -57.962352) (xy 66.275309 -58.014854) (xy 66.283137 -58.069033)
			(xy 66.283136 -58.123773) (xy 66.275308 -58.177952) (xy 66.259812 -58.230454) (xy 66.236968 -58.2802)
			(xy 66.207246 -58.326169) (xy 66.189606 -58.347102) (xy 66.189352 -58.347356) (xy 66.183772 -58.354447)
			(xy 66.177523 -58.371361) (xy 66.17716 -58.380376) (xy 66.17716 -58.447432) (xy 66.177488 -58.456452)
			(xy 66.183754 -58.47337) (xy 66.189352 -58.480452) (xy 66.189606 -58.480452) (xy 66.189606 -58.480706)
			(xy 66.207262 -58.501624) (xy 66.236971 -58.547601) (xy 66.259804 -58.597352) (xy 66.275291 -58.649856)
			(xy 66.283114 -58.704034) (xy 66.283586 -58.731404) (xy 66.2831 -58.758655) (xy 66.275344 -58.812603)
			(xy 66.259989 -58.864898) (xy 66.237347 -58.914475) (xy 66.207881 -58.960325) (xy 66.17219 -59.001516)
			(xy 66.130999 -59.037207) (xy 66.085149 -59.066673) (xy 66.035572 -59.089315) (xy 65.983277 -59.10467)
			(xy 65.929329 -59.112426) (xy 65.874827 -59.112426) (xy 65.820879 -59.10467) (xy 65.768584 -59.089315)
			(xy 65.719007 -59.066673) (xy 65.673157 -59.037207) (xy 65.631966 -59.001516) (xy 65.596275 -58.960325)
			(xy 65.566809 -58.914475) (xy 65.544167 -58.864898) (xy 65.528812 -58.812603) (xy 65.521056 -58.758655)
			(xy 65.52057 -58.731404) (xy 61.551052 -58.731404) (xy 61.535378 -58.75183) (xy 61.492998 -58.79421)
			(xy 61.445448 -58.830697) (xy 61.393542 -58.860664) (xy 61.338169 -58.8836) (xy 61.280276 -58.899113)
			(xy 61.220854 -58.906936) (xy 61.160918 -58.906936) (xy 61.101496 -58.899113) (xy 61.043603 -58.8836)
			(xy 60.98823 -58.860664) (xy 60.936324 -58.830697) (xy 60.888774 -58.79421) (xy 60.846394 -58.75183)
			(xy 60.809907 -58.70428) (xy 60.77994 -58.652374) (xy 60.757004 -58.597001) (xy 60.741491 -58.539108)
			(xy 60.733668 -58.479686) (xy 59.394685 -58.479686) (xy 59.401474 -58.531256) (xy 59.401964 -58.561224)
			(xy 59.401474 -58.591192) (xy 59.393651 -58.650614) (xy 59.378138 -58.708507) (xy 59.355202 -58.76388)
			(xy 59.325235 -58.815786) (xy 59.288748 -58.863336) (xy 59.246368 -58.905716) (xy 59.198818 -58.942203)
			(xy 59.146912 -58.97217) (xy 59.091539 -58.995106) (xy 59.033646 -59.010619) (xy 58.974224 -59.018442)
			(xy 58.914288 -59.018442) (xy 58.854866 -59.010619) (xy 58.796973 -58.995106) (xy 58.7416 -58.97217)
			(xy 58.689694 -58.942203) (xy 58.642144 -58.905716) (xy 58.599764 -58.863336) (xy 58.563277 -58.815786)
			(xy 58.53331 -58.76388) (xy 58.510374 -58.708507) (xy 58.494861 -58.650614) (xy 58.487038 -58.591192)
			(xy 48.747946 -58.591192) (xy 48.750685 -58.600883) (xy 48.75791 -58.653018) (xy 48.758348 -58.679334)
			(xy 48.757862 -58.706585) (xy 48.750106 -58.760533) (xy 48.734751 -58.812828) (xy 48.712109 -58.862405)
			(xy 48.682643 -58.908255) (xy 48.646952 -58.949446) (xy 48.605761 -58.985137) (xy 48.559911 -59.014603)
			(xy 48.510334 -59.037245) (xy 48.458039 -59.0526) (xy 48.404091 -59.060356) (xy 48.349589 -59.060356)
			(xy 48.295641 -59.0526) (xy 48.243346 -59.037245) (xy 48.193769 -59.014603) (xy 48.147919 -58.985137)
			(xy 48.106728 -58.949446) (xy 48.071037 -58.908255) (xy 48.041571 -58.862405) (xy 48.018929 -58.812828)
			(xy 48.003574 -58.760533) (xy 47.995818 -58.706585) (xy 47.995332 -58.679334) (xy 44.910148 -58.679334)
			(xy 44.91695 -58.689857) (xy 44.939787 -58.739603) (xy 44.955281 -58.792101) (xy 44.963112 -58.846275)
			(xy 44.963588 -58.873644) (xy 44.963102 -58.900895) (xy 44.955346 -58.954843) (xy 44.939991 -59.007138)
			(xy 44.917349 -59.056715) (xy 44.887883 -59.102565) (xy 44.852192 -59.143756) (xy 44.811001 -59.179447)
			(xy 44.765151 -59.208913) (xy 44.715574 -59.231555) (xy 44.663279 -59.24691) (xy 44.609331 -59.254666)
			(xy 44.554829 -59.254666) (xy 44.500881 -59.24691) (xy 44.448586 -59.231555) (xy 44.399009 -59.208913)
			(xy 44.353159 -59.179447) (xy 44.311968 -59.143756) (xy 44.276277 -59.102565) (xy 44.246811 -59.056715)
			(xy 44.224169 -59.007138) (xy 44.208814 -58.954843) (xy 44.201058 -58.900895) (xy 44.200572 -58.873644)
			(xy 44.201046 -58.846274) (xy 44.208859 -58.792094) (xy 44.224346 -58.739591) (xy 44.247186 -58.689844)
			(xy 44.27691 -58.643877) (xy 44.294552 -58.622946) (xy 44.294806 -58.622692) (xy 44.300403 -58.615612)
			(xy 44.306643 -58.59869) (xy 44.306998 -58.589672) (xy 44.306998 -58.522616) (xy 44.306634 -58.5136)
			(xy 44.300391 -58.496683) (xy 44.294806 -58.489596) (xy 44.294552 -58.489596) (xy 44.294552 -58.489342)
			(xy 44.276927 -58.468398) (xy 44.247211 -58.422429) (xy 44.224372 -58.372685) (xy 44.208878 -58.320187)
			(xy 44.201047 -58.266013) (xy 44.200572 -58.238644) (xy 44.200572 -58.23839) (xy 44.200944 -58.213442)
			(xy 44.207461 -58.163974) (xy 44.220382 -58.115781) (xy 44.239485 -58.069688) (xy 44.251626 -58.04789)
			(xy 44.25823 -58.03646) (xy 44.258738 -58.010806) (xy 44.213018 -57.923176) (xy 44.20878 -57.91572)
			(xy 44.196306 -57.903967) (xy 44.18064 -57.897015) (xy 44.172124 -57.895998) (xy 44.143934 -57.893195)
			(xy 44.088502 -57.8815) (xy 44.034938 -57.863052) (xy 43.98406 -57.838133) (xy 43.936648 -57.807124)
			(xy 43.893425 -57.7705) (xy 43.873928 -57.749948) (xy 43.867324 -57.742836) (xy 43.850306 -57.734454)
			(xy 43.77182 -57.728104) (xy 43.762255 -57.72775) (xy 43.743973 -57.733359) (xy 43.73626 -57.739026)
			(xy 43.715968 -57.754551) (xy 43.67202 -57.780612) (xy 43.624989 -57.800578) (xy 43.575715 -57.814091)
			(xy 43.525079 -57.820911) (xy 43.499532 -57.821322) (xy 43.472279 -57.820833) (xy 43.418326 -57.81308)
			(xy 43.366026 -57.797727) (xy 43.316444 -57.775087) (xy 43.270589 -57.745621) (xy 43.229394 -57.709929)
			(xy 43.193698 -57.668737) (xy 43.164228 -57.622884) (xy 43.141584 -57.573304) (xy 43.126227 -57.521005)
			(xy 43.118469 -57.467053) (xy 42.935218 -57.467053) (xy 42.939053 -57.495546) (xy 42.939462 -57.521094)
			(xy 42.939002 -57.548465) (xy 42.931184 -57.602644) (xy 42.915694 -57.655148) (xy 42.892851 -57.704895)
			(xy 42.863124 -57.750861) (xy 42.845482 -57.771792) (xy 42.845228 -57.772046) (xy 42.839649 -57.779138)
			(xy 42.8334 -57.796051) (xy 42.833036 -57.805066) (xy 42.833036 -57.872122) (xy 42.833375 -57.881141)
			(xy 42.839634 -57.898058) (xy 42.845228 -57.905142) (xy 42.845482 -57.905142) (xy 42.845482 -57.905396)
			(xy 42.863116 -57.926334) (xy 42.892841 -57.972301) (xy 42.915686 -58.022046) (xy 42.931182 -58.074548)
			(xy 42.939011 -58.128725) (xy 42.939012 -58.183466) (xy 42.931184 -58.237644) (xy 42.915689 -58.290145)
			(xy 42.892845 -58.339891) (xy 42.863122 -58.385859) (xy 42.845482 -58.406792) (xy 42.845228 -58.407046)
			(xy 42.839649 -58.414138) (xy 42.8334 -58.431051) (xy 42.833036 -58.440066) (xy 42.833036 -58.507122)
			(xy 42.833375 -58.516141) (xy 42.839634 -58.533058) (xy 42.845228 -58.540142) (xy 42.845482 -58.540142)
			(xy 42.845482 -58.540396) (xy 42.86313 -58.561321) (xy 42.892841 -58.607296) (xy 42.915676 -58.657045)
			(xy 42.931164 -58.709547) (xy 42.93899 -58.763724) (xy 42.939462 -58.791094) (xy 42.938976 -58.818345)
			(xy 42.93122 -58.872293) (xy 42.915865 -58.924588) (xy 42.893223 -58.974165) (xy 42.863757 -59.020015)
			(xy 42.828066 -59.061206) (xy 42.786875 -59.096897) (xy 42.741025 -59.126363) (xy 42.691448 -59.149005)
			(xy 42.639153 -59.16436) (xy 42.585205 -59.172116) (xy 42.530703 -59.172116) (xy 42.476755 -59.16436)
			(xy 42.42446 -59.149005) (xy 42.374883 -59.126363) (xy 42.329033 -59.096897) (xy 42.287842 -59.061206)
			(xy 42.252151 -59.020015) (xy 42.222685 -58.974165) (xy 42.200043 -58.924588) (xy 42.184688 -58.872293)
			(xy 42.176932 -58.818345) (xy 42.176446 -58.791094) (xy 42.176897 -58.763723) (xy 42.184717 -58.709543)
			(xy 42.200209 -58.657039) (xy 42.223054 -58.607293) (xy 42.252783 -58.561327) (xy 42.270426 -58.540396)
			(xy 42.27068 -58.540142) (xy 42.276264 -58.533054) (xy 42.28251 -58.516138) (xy 42.282872 -58.507122)
			(xy 42.282872 -58.440066) (xy 42.282537 -58.431047) (xy 42.276275 -58.41413) (xy 42.27068 -58.407046)
			(xy 42.270426 -58.407046) (xy 42.270426 -58.406792) (xy 42.252779 -58.385864) (xy 42.223055 -58.339895)
			(xy 42.20021 -58.290148) (xy 42.184714 -58.237646) (xy 42.176886 -58.183466) (xy 42.176887 -58.128725)
			(xy 42.184716 -58.074546) (xy 42.200213 -58.022043) (xy 42.223059 -57.972297) (xy 42.252785 -57.926329)
			(xy 42.270426 -57.905396) (xy 42.27068 -57.905142) (xy 42.276264 -57.898054) (xy 42.28251 -57.881138)
			(xy 42.282872 -57.872122) (xy 42.282872 -57.805066) (xy 42.282537 -57.796047) (xy 42.276275 -57.77913)
			(xy 42.27068 -57.772046) (xy 42.270426 -57.772046) (xy 42.270426 -57.771792) (xy 42.252774 -57.75087)
			(xy 42.223063 -57.704895) (xy 42.200229 -57.655145) (xy 42.184741 -57.602642) (xy 42.176917 -57.548464)
			(xy 42.176446 -57.521094) (xy 42.176828 -57.495545) (xy 42.18364 -57.444904) (xy 42.197155 -57.395626)
			(xy 42.21713 -57.348595) (xy 42.243207 -57.304653) (xy 42.258742 -57.284366) (xy 42.264343 -57.276617)
			(xy 42.269967 -57.258361) (xy 42.269664 -57.248806) (xy 42.263314 -57.17032) (xy 42.254932 -57.153302)
			(xy 42.24782 -57.146698) (xy 42.225 -57.124939) (xy 42.184917 -57.076266) (xy 42.151901 -57.022549)
			(xy 42.126577 -56.964805) (xy 42.109425 -56.90413) (xy 42.10077 -56.841674) (xy 42.100246 -56.810148)
			(xy 40.283348 -56.810148) (xy 40.283638 -56.826404) (xy 40.283189 -56.853775) (xy 40.27537 -56.907955)
			(xy 40.259877 -56.960459) (xy 40.237031 -57.010206) (xy 40.207302 -57.056171) (xy 40.189658 -57.077102)
			(xy 40.189404 -57.077356) (xy 40.18383 -57.084451) (xy 40.177576 -57.101361) (xy 40.177212 -57.110376)
			(xy 40.177212 -57.177432) (xy 40.177551 -57.186451) (xy 40.183811 -57.203368) (xy 40.189404 -57.210452)
			(xy 40.189658 -57.210452) (xy 40.189658 -57.210706) (xy 40.207303 -57.231635) (xy 40.237029 -57.277603)
			(xy 40.259875 -57.32735) (xy 40.275372 -57.379853) (xy 40.2832 -57.434032) (xy 40.2832 -57.488774)
			(xy 40.27537 -57.542953) (xy 40.259873 -57.595456) (xy 40.237026 -57.645202) (xy 40.2073 -57.69117)
			(xy 40.189658 -57.712102) (xy 40.189404 -57.712356) (xy 40.18383 -57.719451) (xy 40.177576 -57.736361)
			(xy 40.177212 -57.745376) (xy 40.177212 -57.812432) (xy 40.177551 -57.821451) (xy 40.183811 -57.838368)
			(xy 40.189404 -57.845452) (xy 40.189658 -57.845452) (xy 40.189658 -57.845706) (xy 40.207303 -57.866635)
			(xy 40.237029 -57.912603) (xy 40.259875 -57.96235) (xy 40.275372 -58.014853) (xy 40.2832 -58.069032)
			(xy 40.2832 -58.123774) (xy 40.27537 -58.177953) (xy 40.259873 -58.230456) (xy 40.237026 -58.280202)
			(xy 40.2073 -58.32617) (xy 40.189658 -58.347102) (xy 40.189404 -58.347356) (xy 40.18383 -58.354451)
			(xy 40.177576 -58.371361) (xy 40.177212 -58.380376) (xy 40.177212 -58.447432) (xy 40.177551 -58.456451)
			(xy 40.183811 -58.473368) (xy 40.189404 -58.480452) (xy 40.189658 -58.480452) (xy 40.189658 -58.480706)
			(xy 40.207307 -58.50163) (xy 40.237019 -58.547605) (xy 40.259853 -58.597354) (xy 40.275342 -58.649857)
			(xy 40.283166 -58.704034) (xy 40.283638 -58.731404) (xy 40.283152 -58.758655) (xy 40.275396 -58.812603)
			(xy 40.260041 -58.864898) (xy 40.237399 -58.914475) (xy 40.207933 -58.960325) (xy 40.172242 -59.001516)
			(xy 40.131051 -59.037207) (xy 40.085201 -59.066673) (xy 40.035624 -59.089315) (xy 39.983329 -59.10467)
			(xy 39.929381 -59.112426) (xy 39.874879 -59.112426) (xy 39.820931 -59.10467) (xy 39.768636 -59.089315)
			(xy 39.719059 -59.066673) (xy 39.673209 -59.037207) (xy 39.632018 -59.001516) (xy 39.596327 -58.960325)
			(xy 39.566861 -58.914475) (xy 39.544219 -58.864898) (xy 39.528864 -58.812603) (xy 39.521108 -58.758655)
			(xy 39.520622 -58.731404) (xy 35.551104 -58.731404) (xy 35.53543 -58.75183) (xy 35.49305 -58.79421)
			(xy 35.4455 -58.830697) (xy 35.393594 -58.860664) (xy 35.338221 -58.8836) (xy 35.280328 -58.899113)
			(xy 35.220906 -58.906936) (xy 35.16097 -58.906936) (xy 35.101548 -58.899113) (xy 35.043655 -58.8836)
			(xy 34.988282 -58.860664) (xy 34.936376 -58.830697) (xy 34.888826 -58.79421) (xy 34.846446 -58.75183)
			(xy 34.809959 -58.70428) (xy 34.779992 -58.652374) (xy 34.757056 -58.597001) (xy 34.741543 -58.539108)
			(xy 34.73372 -58.479686) (xy 33.394737 -58.479686) (xy 33.401526 -58.531256) (xy 33.402016 -58.561224)
			(xy 33.401526 -58.591192) (xy 33.393703 -58.650614) (xy 33.37819 -58.708507) (xy 33.355254 -58.76388)
			(xy 33.325287 -58.815786) (xy 33.2888 -58.863336) (xy 33.24642 -58.905716) (xy 33.19887 -58.942203)
			(xy 33.146964 -58.97217) (xy 33.091591 -58.995106) (xy 33.033698 -59.010619) (xy 32.974276 -59.018442)
			(xy 32.91434 -59.018442) (xy 32.854918 -59.010619) (xy 32.797025 -58.995106) (xy 32.741652 -58.97217)
			(xy 32.689746 -58.942203) (xy 32.642196 -58.905716) (xy 32.599816 -58.863336) (xy 32.563329 -58.815786)
			(xy 32.533362 -58.76388) (xy 32.510426 -58.708507) (xy 32.494913 -58.650614) (xy 32.48709 -58.591192)
			(xy 22.826272 -58.591192) (xy 22.834077 -58.647552) (xy 22.8346 -58.67908) (xy 22.8346 -58.679334)
			(xy 22.83411 -58.709302) (xy 22.826287 -58.768724) (xy 22.810774 -58.826617) (xy 22.787838 -58.88199)
			(xy 22.757871 -58.933896) (xy 22.721384 -58.981446) (xy 22.679004 -59.023826) (xy 22.631454 -59.060313)
			(xy 22.579548 -59.09028) (xy 22.524175 -59.113216) (xy 22.466282 -59.128729) (xy 22.40686 -59.136552)
			(xy 22.346924 -59.136552) (xy 22.287502 -59.128729) (xy 22.229609 -59.113216) (xy 22.174236 -59.09028)
			(xy 22.12233 -59.060313) (xy 22.07478 -59.023826) (xy 22.0324 -58.981446) (xy 21.995913 -58.933896)
			(xy 21.965946 -58.88199) (xy 21.94301 -58.826617) (xy 21.927497 -58.768724) (xy 21.919674 -58.709302)
			(xy 21.919184 -58.679334) (xy 18.910192 -58.679334) (xy 18.916997 -58.689861) (xy 18.939837 -58.739605)
			(xy 18.955332 -58.792102) (xy 18.963164 -58.846276) (xy 18.96364 -58.873644) (xy 18.963154 -58.900895)
			(xy 18.955398 -58.954843) (xy 18.940043 -59.007138) (xy 18.917401 -59.056715) (xy 18.887935 -59.102565)
			(xy 18.852244 -59.143756) (xy 18.811053 -59.179447) (xy 18.765203 -59.208913) (xy 18.715626 -59.231555)
			(xy 18.663331 -59.24691) (xy 18.609383 -59.254666) (xy 18.554881 -59.254666) (xy 18.500933 -59.24691)
			(xy 18.448638 -59.231555) (xy 18.399061 -59.208913) (xy 18.353211 -59.179447) (xy 18.31202 -59.143756)
			(xy 18.276329 -59.102565) (xy 18.246863 -59.056715) (xy 18.224221 -59.007138) (xy 18.208866 -58.954843)
			(xy 18.20111 -58.900895) (xy 18.200624 -58.873644) (xy 18.20111 -58.846274) (xy 18.208922 -58.792096)
			(xy 18.224406 -58.739593) (xy 18.247244 -58.689846) (xy 18.276964 -58.643878) (xy 18.294604 -58.622946)
			(xy 18.294858 -58.622692) (xy 18.300461 -58.615617) (xy 18.306696 -58.598691) (xy 18.30705 -58.589672)
			(xy 18.30705 -58.522616) (xy 18.306696 -58.513599) (xy 18.300448 -58.496681) (xy 18.294858 -58.489596)
			(xy 18.294604 -58.489596) (xy 18.294604 -58.489342) (xy 18.276972 -58.468404) (xy 18.247259 -58.422433)
			(xy 18.224421 -58.372687) (xy 18.208929 -58.320188) (xy 18.201099 -58.266013) (xy 18.200624 -58.238644)
			(xy 18.200624 -58.23839) (xy 18.200989 -58.213442) (xy 18.207507 -58.163974) (xy 18.22043 -58.11578)
			(xy 18.239536 -58.069687) (xy 18.251678 -58.04789) (xy 18.258282 -58.03646) (xy 18.25879 -58.010806)
			(xy 18.21307 -57.923176) (xy 18.208861 -57.915701) (xy 18.196374 -57.90395) (xy 18.180696 -57.897008)
			(xy 18.172176 -57.895998) (xy 18.143983 -57.893223) (xy 18.08855 -57.881522) (xy 18.034986 -57.863069)
			(xy 17.984109 -57.838144) (xy 17.936697 -57.807131) (xy 17.893477 -57.770502) (xy 17.87398 -57.749948)
			(xy 17.867376 -57.742836) (xy 17.850358 -57.734454) (xy 17.771872 -57.728104) (xy 17.762306 -57.727725)
			(xy 17.744023 -57.733351) (xy 17.736312 -57.739026) (xy 17.716002 -57.754527) (xy 17.67206 -57.780592)
			(xy 17.625033 -57.800562) (xy 17.575763 -57.814081) (xy 17.52513 -57.820908) (xy 17.499584 -57.821322)
			(xy 17.472335 -57.820807) (xy 17.418391 -57.813049) (xy 17.3661 -57.797693) (xy 17.316526 -57.775051)
			(xy 17.27068 -57.745586) (xy 17.229493 -57.709896) (xy 17.193805 -57.668707) (xy 17.164341 -57.62286)
			(xy 17.141702 -57.573285) (xy 17.126348 -57.520994) (xy 17.118592 -57.467049) (xy 16.935269 -57.467049)
			(xy 16.939105 -57.495547) (xy 16.939514 -57.521094) (xy 16.939041 -57.548464) (xy 16.931224 -57.602643)
			(xy 16.915737 -57.655146) (xy 16.892897 -57.704892) (xy 16.863174 -57.75086) (xy 16.845534 -57.771792)
			(xy 16.84528 -57.772046) (xy 16.839708 -57.779142) (xy 16.833453 -57.796052) (xy 16.833088 -57.805066)
			(xy 16.833088 -57.872122) (xy 16.833437 -57.88114) (xy 16.839691 -57.898056) (xy 16.84528 -57.905142)
			(xy 16.845534 -57.905142) (xy 16.845534 -57.905396) (xy 16.86317 -57.926333) (xy 16.892898 -57.972299)
			(xy 16.915747 -58.022044) (xy 16.931245 -58.074546) (xy 16.939075 -58.128725) (xy 16.939076 -58.183466)
			(xy 16.931247 -58.237645) (xy 16.91575 -58.290147) (xy 16.892903 -58.339893) (xy 16.863176 -58.38586)
			(xy 16.845534 -58.406792) (xy 16.84528 -58.407046) (xy 16.839708 -58.414142) (xy 16.833453 -58.431052)
			(xy 16.833088 -58.440066) (xy 16.833088 -58.507122) (xy 16.833437 -58.51614) (xy 16.839691 -58.533056)
			(xy 16.84528 -58.540142) (xy 16.845534 -58.540142) (xy 16.845534 -58.540396) (xy 16.86319 -58.561314)
			(xy 16.892898 -58.607291) (xy 16.91573 -58.657043) (xy 16.931217 -58.709546) (xy 16.939042 -58.763724)
			(xy 16.939514 -58.791094) (xy 16.939028 -58.818345) (xy 16.931272 -58.872293) (xy 16.915917 -58.924588)
			(xy 16.893275 -58.974165) (xy 16.863809 -59.020015) (xy 16.828118 -59.061206) (xy 16.786927 -59.096897)
			(xy 16.741077 -59.126363) (xy 16.6915 -59.149005) (xy 16.639205 -59.16436) (xy 16.585257 -59.172116)
			(xy 16.530755 -59.172116) (xy 16.476807 -59.16436) (xy 16.424512 -59.149005) (xy 16.374935 -59.126363)
			(xy 16.329085 -59.096897) (xy 16.287894 -59.061206) (xy 16.252203 -59.020015) (xy 16.222737 -58.974165)
			(xy 16.200095 -58.924588) (xy 16.18474 -58.872293) (xy 16.176984 -58.818345) (xy 16.176498 -58.791094)
			(xy 16.176961 -58.763724) (xy 16.18478 -58.709544) (xy 16.200269 -58.657041) (xy 16.223112 -58.607295)
			(xy 16.252837 -58.561328) (xy 16.270478 -58.540396) (xy 16.270732 -58.540142) (xy 16.276311 -58.53305)
			(xy 16.282561 -58.516137) (xy 16.282924 -58.507122) (xy 16.282924 -58.440066) (xy 16.282578 -58.431048)
			(xy 16.276322 -58.414131) (xy 16.270732 -58.407046) (xy 16.270478 -58.407046) (xy 16.270478 -58.406792)
			(xy 16.252833 -58.385863) (xy 16.223113 -58.339893) (xy 16.200271 -58.290146) (xy 16.184777 -58.237644)
			(xy 16.17695 -58.183466) (xy 16.176951 -58.128725) (xy 16.184779 -58.074547) (xy 16.200274 -58.022045)
			(xy 16.223117 -57.972299) (xy 16.252839 -57.92633) (xy 16.270478 -57.905396) (xy 16.270732 -57.905142)
			(xy 16.276311 -57.89805) (xy 16.282561 -57.881137) (xy 16.282924 -57.872122) (xy 16.282924 -57.805066)
			(xy 16.282578 -57.796048) (xy 16.276322 -57.779131) (xy 16.270732 -57.772046) (xy 16.270478 -57.772046)
			(xy 16.270478 -57.771792) (xy 16.252818 -57.750877) (xy 16.22311 -57.704899) (xy 16.200279 -57.655147)
			(xy 16.184792 -57.602643) (xy 16.176969 -57.548464) (xy 16.176498 -57.521094) (xy 16.17689 -57.495546)
			(xy 16.183701 -57.444905) (xy 16.197214 -57.395628) (xy 16.217187 -57.348597) (xy 16.243261 -57.304654)
			(xy 16.258794 -57.284366) (xy 16.2644 -57.276621) (xy 16.27002 -57.258361) (xy 16.269716 -57.248806)
			(xy 16.263366 -57.17032) (xy 16.254984 -57.153302) (xy 16.247872 -57.146698) (xy 16.225042 -57.124949)
			(xy 16.184963 -57.076273) (xy 16.151949 -57.022553) (xy 16.126627 -56.964808) (xy 16.109476 -56.904132)
			(xy 16.100822 -56.841675) (xy 16.100298 -56.810148) (xy 14.2834 -56.810148) (xy 14.28369 -56.826404)
			(xy 14.283229 -56.853774) (xy 14.27541 -56.907954) (xy 14.25992 -56.960457) (xy 14.237077 -57.010204)
			(xy 14.207352 -57.05617) (xy 14.18971 -57.077102) (xy 14.189456 -57.077356) (xy 14.183876 -57.084447)
			(xy 14.177627 -57.101361) (xy 14.177264 -57.110376) (xy 14.177264 -57.177432) (xy 14.177613 -57.186449)
			(xy 14.183867 -57.203366) (xy 14.189456 -57.210452) (xy 14.18971 -57.210452) (xy 14.18971 -57.210706)
			(xy 14.207353 -57.231636) (xy 14.237075 -57.277605) (xy 14.259918 -57.327352) (xy 14.275412 -57.379854)
			(xy 14.28324 -57.434033) (xy 14.283239 -57.488773) (xy 14.275411 -57.542951) (xy 14.259916 -57.595453)
			(xy 14.237072 -57.6452) (xy 14.207349 -57.691169) (xy 14.18971 -57.712102) (xy 14.189456 -57.712356)
			(xy 14.183876 -57.719447) (xy 14.177627 -57.736361) (xy 14.177264 -57.745376) (xy 14.177264 -57.812432)
			(xy 14.177613 -57.821449) (xy 14.183867 -57.838366) (xy 14.189456 -57.845452) (xy 14.18971 -57.845452)
			(xy 14.18971 -57.845706) (xy 14.207353 -57.866636) (xy 14.237075 -57.912605) (xy 14.259918 -57.962352)
			(xy 14.275412 -58.014854) (xy 14.28324 -58.069033) (xy 14.283239 -58.123773) (xy 14.275411 -58.177951)
			(xy 14.259916 -58.230453) (xy 14.237072 -58.2802) (xy 14.207349 -58.326169) (xy 14.18971 -58.347102)
			(xy 14.189456 -58.347356) (xy 14.183876 -58.354447) (xy 14.177627 -58.371361) (xy 14.177264 -58.380376)
			(xy 14.177264 -58.447432) (xy 14.177613 -58.456449) (xy 14.183867 -58.473366) (xy 14.189456 -58.480452)
			(xy 14.18971 -58.480452) (xy 14.18971 -58.480706) (xy 14.207367 -58.501624) (xy 14.237076 -58.547601)
			(xy 14.259908 -58.597352) (xy 14.275395 -58.649856) (xy 14.283218 -58.704034) (xy 14.28369 -58.731404)
			(xy 14.283204 -58.758655) (xy 14.275448 -58.812603) (xy 14.260093 -58.864898) (xy 14.237451 -58.914475)
			(xy 14.207985 -58.960325) (xy 14.172294 -59.001516) (xy 14.131103 -59.037207) (xy 14.085253 -59.066673)
			(xy 14.035676 -59.089315) (xy 13.983381 -59.10467) (xy 13.929433 -59.112426) (xy 13.874931 -59.112426)
			(xy 13.820983 -59.10467) (xy 13.768688 -59.089315) (xy 13.719111 -59.066673) (xy 13.673261 -59.037207)
			(xy 13.63207 -59.001516) (xy 13.596379 -58.960325) (xy 13.566913 -58.914475) (xy 13.544271 -58.864898)
			(xy 13.528916 -58.812603) (xy 13.52116 -58.758655) (xy 13.520674 -58.731404) (xy 9.551156 -58.731404)
			(xy 9.535482 -58.75183) (xy 9.493102 -58.79421) (xy 9.445552 -58.830697) (xy 9.393646 -58.860664)
			(xy 9.338273 -58.8836) (xy 9.28038 -58.899113) (xy 9.220958 -58.906936) (xy 9.161022 -58.906936)
			(xy 9.1016 -58.899113) (xy 9.043707 -58.8836) (xy 8.988334 -58.860664) (xy 8.936428 -58.830697) (xy 8.888878 -58.79421)
			(xy 8.846498 -58.75183) (xy 8.810011 -58.70428) (xy 8.780044 -58.652374) (xy 8.757108 -58.597001)
			(xy 8.741595 -58.539108) (xy 8.733772 -58.479686) (xy 7.394789 -58.479686) (xy 7.401578 -58.531256)
			(xy 7.402068 -58.561224) (xy 7.401578 -58.591192) (xy 7.393755 -58.650614) (xy 7.378242 -58.708507)
			(xy 7.355306 -58.76388) (xy 7.325339 -58.815786) (xy 7.288852 -58.863336) (xy 7.246472 -58.905716)
			(xy 7.198922 -58.942203) (xy 7.147016 -58.97217) (xy 7.091643 -58.995106) (xy 7.03375 -59.010619)
			(xy 6.974328 -59.018442) (xy 6.914392 -59.018442) (xy 6.85497 -59.010619) (xy 6.797077 -58.995106)
			(xy 6.741704 -58.97217) (xy 6.689798 -58.942203) (xy 6.642248 -58.905716) (xy 6.599868 -58.863336)
			(xy 6.563381 -58.815786) (xy 6.533414 -58.76388) (xy 6.510478 -58.708507) (xy 6.494965 -58.650614)
			(xy 6.487142 -58.591192) (xy 2.875788 -58.591192) (xy 2.875788 -59.974734) (xy 5.086602 -59.974734)
			(xy 5.090673 -59.919112) (xy 5.102799 -59.864675) (xy 5.122722 -59.812584) (xy 5.150018 -59.763949)
			(xy 5.184104 -59.719806) (xy 5.224253 -59.681097) (xy 5.269611 -59.648646) (xy 5.319211 -59.623145)
			(xy 5.371995 -59.605138) (xy 5.426838 -59.595008) (xy 5.482572 -59.592971) (xy 5.538009 -59.599071)
			(xy 5.591966 -59.613177) (xy 5.643295 -59.634989) (xy 5.690901 -59.664043) (xy 5.733769 -59.699718)
			(xy 5.770986 -59.741255) (xy 5.801759 -59.787768) (xy 5.825431 -59.838265) (xy 5.841499 -59.891672)
			(xy 5.849619 -59.946848) (xy 5.850128 -59.974734) (xy 5.849619 -60.00262) (xy 5.841499 -60.057796)
			(xy 5.825431 -60.111203) (xy 5.818282 -60.126454) (xy 17.180249 -60.126454) (xy 17.180249 -60.071946)
			(xy 17.188007 -60.017994) (xy 17.203363 -59.965695) (xy 17.226006 -59.916114) (xy 17.255476 -59.87026)
			(xy 17.29117 -59.829066) (xy 17.332364 -59.793372) (xy 17.378219 -59.763904) (xy 17.427801 -59.741261)
			(xy 17.4801 -59.725905) (xy 17.534052 -59.718149) (xy 17.561306 -59.717686) (xy 17.588676 -59.718152)
			(xy 17.642855 -59.72597) (xy 17.695358 -59.74146) (xy 17.745105 -59.764301) (xy 17.791072 -59.794025)
			(xy 17.812004 -59.811666) (xy 17.812258 -59.81192) (xy 17.819351 -59.817497) (xy 17.836263 -59.823749)
			(xy 17.845278 -59.824112) (xy 17.912334 -59.824112) (xy 17.921352 -59.823769) (xy 17.938269 -59.817512)
			(xy 17.945354 -59.81192) (xy 17.945354 -59.811666) (xy 17.945608 -59.811666) (xy 17.966541 -59.794025)
			(xy 18.012509 -59.764301) (xy 18.062255 -59.741455) (xy 18.114757 -59.725959) (xy 18.168935 -59.71813)
			(xy 18.223677 -59.71813) (xy 18.277855 -59.725959) (xy 18.330357 -59.741455) (xy 18.380103 -59.764301)
			(xy 18.426071 -59.794025) (xy 18.447004 -59.811666) (xy 18.447258 -59.81192) (xy 18.454351 -59.817497)
			(xy 18.471263 -59.823749) (xy 18.480278 -59.824112) (xy 18.547334 -59.824112) (xy 18.556352 -59.823769)
			(xy 18.573269 -59.817512) (xy 18.580354 -59.81192) (xy 18.580354 -59.811666) (xy 18.580608 -59.811666)
			(xy 18.601522 -59.794004) (xy 18.6475 -59.764297) (xy 18.697252 -59.741466) (xy 18.749757 -59.72598)
			(xy 18.803936 -59.718157) (xy 18.831306 -59.717686) (xy 18.858557 -59.718184) (xy 18.912503 -59.725941)
			(xy 18.964796 -59.741297) (xy 19.014372 -59.763938) (xy 19.060221 -59.793404) (xy 19.101409 -59.829095)
			(xy 19.1371 -59.870284) (xy 19.166565 -59.916134) (xy 19.189205 -59.96571) (xy 19.20456 -60.018003)
			(xy 19.204741 -60.019261) (xy 22.135824 -60.019261) (xy 22.135824 -59.964759) (xy 22.14358 -59.910811)
			(xy 22.158935 -59.858516) (xy 22.181576 -59.808938) (xy 22.211043 -59.763088) (xy 22.246734 -59.721897)
			(xy 22.287924 -59.686205) (xy 22.333775 -59.656738) (xy 22.383352 -59.634097) (xy 22.435647 -59.618741)
			(xy 22.489595 -59.610984) (xy 22.516846 -59.610498) (xy 22.544215 -59.610996) (xy 22.598393 -59.618806)
			(xy 22.650895 -59.634288) (xy 22.700643 -59.657123) (xy 22.746611 -59.68684) (xy 22.767544 -59.704478)
			(xy 22.767798 -59.704732) (xy 22.774878 -59.710327) (xy 22.7918 -59.716568) (xy 22.800818 -59.716924)
			(xy 22.867874 -59.716924) (xy 22.876889 -59.716549) (xy 22.893806 -59.710313) (xy 22.900894 -59.704732)
			(xy 22.900894 -59.704478) (xy 22.901148 -59.704478) (xy 22.922081 -59.686837) (xy 22.968049 -59.657113)
			(xy 23.017795 -59.634267) (xy 23.070297 -59.618771) (xy 23.124475 -59.610942) (xy 23.179217 -59.610942)
			(xy 23.233395 -59.618771) (xy 23.285897 -59.634267) (xy 23.335643 -59.657113) (xy 23.381611 -59.686837)
			(xy 23.402544 -59.704478) (xy 23.402798 -59.704732) (xy 23.409878 -59.710327) (xy 23.4268 -59.716568)
			(xy 23.435818 -59.716924) (xy 23.502874 -59.716924) (xy 23.511889 -59.716549) (xy 23.528806 -59.710313)
			(xy 23.535894 -59.704732) (xy 23.535894 -59.704478) (xy 23.536148 -59.704478) (xy 23.557086 -59.686846)
			(xy 23.603058 -59.657134) (xy 23.652804 -59.634297) (xy 23.705303 -59.618804) (xy 23.759477 -59.610974)
			(xy 23.786846 -59.610498) (xy 23.814099 -59.610969) (xy 23.86805 -59.618725) (xy 23.920347 -59.634081)
			(xy 23.969927 -59.656723) (xy 24.015781 -59.686191) (xy 24.056973 -59.721884) (xy 24.092667 -59.763076)
			(xy 24.122135 -59.808929) (xy 24.144778 -59.858509) (xy 24.160134 -59.910807) (xy 24.167891 -59.964757)
			(xy 24.167891 -59.974734) (xy 31.08655 -59.974734) (xy 31.090621 -59.919112) (xy 31.102747 -59.864675)
			(xy 31.12267 -59.812584) (xy 31.149966 -59.763949) (xy 31.184052 -59.719806) (xy 31.224201 -59.681097)
			(xy 31.269559 -59.648646) (xy 31.319159 -59.623145) (xy 31.371943 -59.605138) (xy 31.426786 -59.595008)
			(xy 31.48252 -59.592971) (xy 31.537957 -59.599071) (xy 31.591914 -59.613177) (xy 31.643243 -59.634989)
			(xy 31.690849 -59.664043) (xy 31.733717 -59.699718) (xy 31.770934 -59.741255) (xy 31.801707 -59.787768)
			(xy 31.825379 -59.838265) (xy 31.841447 -59.891672) (xy 31.849567 -59.946848) (xy 31.850076 -59.974734)
			(xy 31.849567 -60.00262) (xy 31.841447 -60.057796) (xy 31.825379 -60.111203) (xy 31.818232 -60.12645)
			(xy 43.180272 -60.12645) (xy 43.180272 -60.07195) (xy 43.188027 -60.018006) (xy 43.20338 -59.965714)
			(xy 43.226018 -59.916139) (xy 43.255481 -59.87029) (xy 43.291168 -59.8291) (xy 43.332353 -59.793408)
			(xy 43.378199 -59.76394) (xy 43.427771 -59.741296) (xy 43.480061 -59.725937) (xy 43.534004 -59.718175)
			(xy 43.561254 -59.717686) (xy 43.588623 -59.718182) (xy 43.642801 -59.725993) (xy 43.695303 -59.741476)
			(xy 43.745051 -59.76431) (xy 43.791019 -59.794028) (xy 43.811952 -59.811666) (xy 43.812206 -59.81192)
			(xy 43.819285 -59.817517) (xy 43.836208 -59.823757) (xy 43.845226 -59.824112) (xy 43.912282 -59.824112)
			(xy 43.921298 -59.823744) (xy 43.938215 -59.817504) (xy 43.945302 -59.81192) (xy 43.945302 -59.811666)
			(xy 43.945556 -59.811666) (xy 43.966489 -59.794025) (xy 44.012457 -59.764301) (xy 44.062203 -59.741455)
			(xy 44.114705 -59.725959) (xy 44.168883 -59.71813) (xy 44.223625 -59.71813) (xy 44.277803 -59.725959)
			(xy 44.330305 -59.741455) (xy 44.380051 -59.764301) (xy 44.426019 -59.794025) (xy 44.446952 -59.811666)
			(xy 44.447206 -59.81192) (xy 44.454285 -59.817517) (xy 44.471208 -59.823757) (xy 44.480226 -59.824112)
			(xy 44.547282 -59.824112) (xy 44.556298 -59.823744) (xy 44.573215 -59.817504) (xy 44.580302 -59.81192)
			(xy 44.580302 -59.811666) (xy 44.580556 -59.811666) (xy 44.601489 -59.794029) (xy 44.647462 -59.764318)
			(xy 44.69721 -59.741482) (xy 44.74971 -59.72599) (xy 44.803885 -59.718161) (xy 44.831254 -59.717686)
			(xy 44.858509 -59.718158) (xy 44.912464 -59.72591) (xy 44.964766 -59.741262) (xy 45.014351 -59.763901)
			(xy 45.060209 -59.793367) (xy 45.101407 -59.82906) (xy 45.137105 -59.870254) (xy 45.166577 -59.916108)
			(xy 45.189222 -59.965691) (xy 45.20458 -60.017991) (xy 45.204761 -60.019251) (xy 48.135784 -60.019251)
			(xy 48.135784 -59.964749) (xy 48.14354 -59.910803) (xy 48.158895 -59.85851) (xy 48.181535 -59.808934)
			(xy 48.211 -59.763084) (xy 48.246691 -59.721895) (xy 48.287879 -59.686204) (xy 48.333728 -59.656738)
			(xy 48.383304 -59.634097) (xy 48.435597 -59.618741) (xy 48.489543 -59.610984) (xy 48.516794 -59.610498)
			(xy 48.544164 -59.610968) (xy 48.598343 -59.618785) (xy 48.650846 -59.634273) (xy 48.700593 -59.657114)
			(xy 48.74656 -59.686837) (xy 48.767492 -59.704478) (xy 48.767746 -59.704732) (xy 48.774841 -59.710306)
			(xy 48.791751 -59.716559) (xy 48.800766 -59.716924) (xy 48.867822 -59.716924) (xy 48.876839 -59.716573)
			(xy 48.893756 -59.710321) (xy 48.900842 -59.704732) (xy 48.900842 -59.704478) (xy 48.901096 -59.704478)
			(xy 48.922029 -59.686837) (xy 48.967997 -59.657113) (xy 49.017743 -59.634267) (xy 49.070245 -59.618771)
			(xy 49.124423 -59.610942) (xy 49.179165 -59.610942) (xy 49.233343 -59.618771) (xy 49.285845 -59.634267)
			(xy 49.335591 -59.657113) (xy 49.381559 -59.686837) (xy 49.402492 -59.704478) (xy 49.402746 -59.704732)
			(xy 49.409841 -59.710306) (xy 49.426751 -59.716559) (xy 49.435766 -59.716924) (xy 49.502822 -59.716924)
			(xy 49.511839 -59.716573) (xy 49.528756 -59.710321) (xy 49.535842 -59.704732) (xy 49.535842 -59.704478)
			(xy 49.536096 -59.704478) (xy 49.557016 -59.686824) (xy 49.602992 -59.657115) (xy 49.652743 -59.634282)
			(xy 49.705246 -59.618795) (xy 49.759424 -59.61097) (xy 49.786794 -59.610498) (xy 49.814048 -59.610949)
			(xy 49.868 -59.618705) (xy 49.920299 -59.634061) (xy 49.969881 -59.656704) (xy 50.015736 -59.686172)
			(xy 50.05693 -59.721866) (xy 50.092624 -59.76306) (xy 50.122094 -59.808914) (xy 50.144737 -59.858495)
			(xy 50.160093 -59.910794) (xy 50.167851 -59.964746) (xy 50.167851 -59.974734) (xy 57.086498 -59.974734)
			(xy 57.090569 -59.919112) (xy 57.102695 -59.864675) (xy 57.122618 -59.812584) (xy 57.149914 -59.763949)
			(xy 57.184 -59.719806) (xy 57.224149 -59.681097) (xy 57.269507 -59.648646) (xy 57.319107 -59.623145)
			(xy 57.371891 -59.605138) (xy 57.426734 -59.595008) (xy 57.482468 -59.592971) (xy 57.537905 -59.599071)
			(xy 57.591862 -59.613177) (xy 57.643191 -59.634989) (xy 57.690797 -59.664043) (xy 57.733665 -59.699718)
			(xy 57.770882 -59.741255) (xy 57.801655 -59.787768) (xy 57.825327 -59.838265) (xy 57.841395 -59.891672)
			(xy 57.849515 -59.946848) (xy 57.850024 -59.974734) (xy 57.849515 -60.00262) (xy 57.841395 -60.057796)
			(xy 57.825327 -60.111203) (xy 57.818178 -60.126453) (xy 69.180149 -60.126453) (xy 69.180149 -60.071947)
			(xy 69.187907 -60.017995) (xy 69.203263 -59.965696) (xy 69.225906 -59.916115) (xy 69.255375 -59.870261)
			(xy 69.291069 -59.829068) (xy 69.332262 -59.793373) (xy 69.378117 -59.763905) (xy 69.427698 -59.741262)
			(xy 69.479997 -59.725906) (xy 69.533949 -59.718149) (xy 69.561202 -59.717686) (xy 69.588572 -59.718154)
			(xy 69.642751 -59.725972) (xy 69.695254 -59.741461) (xy 69.745001 -59.764302) (xy 69.790968 -59.794025)
			(xy 69.8119 -59.811666) (xy 69.812154 -59.81192) (xy 69.819248 -59.817496) (xy 69.836159 -59.823748)
			(xy 69.845174 -59.824112) (xy 69.91223 -59.824112) (xy 69.921248 -59.823766) (xy 69.938165 -59.817511)
			(xy 69.94525 -59.81192) (xy 69.94525 -59.811666) (xy 69.945504 -59.811666) (xy 69.966437 -59.794025)
			(xy 70.012405 -59.764301) (xy 70.062151 -59.741455) (xy 70.114653 -59.725959) (xy 70.168831 -59.71813)
			(xy 70.223573 -59.71813) (xy 70.277751 -59.725959) (xy 70.330253 -59.741455) (xy 70.379999 -59.764301)
			(xy 70.425967 -59.794025) (xy 70.4469 -59.811666) (xy 70.447154 -59.81192) (xy 70.454248 -59.817496)
			(xy 70.471159 -59.823748) (xy 70.480174 -59.824112) (xy 70.54723 -59.824112) (xy 70.556248 -59.823766)
			(xy 70.573165 -59.817511) (xy 70.58025 -59.81192) (xy 70.58025 -59.811666) (xy 70.580504 -59.811666)
			(xy 70.601419 -59.794006) (xy 70.647397 -59.764299) (xy 70.697149 -59.741467) (xy 70.749653 -59.725981)
			(xy 70.803832 -59.718158) (xy 70.831202 -59.717686) (xy 70.858453 -59.718184) (xy 70.912399 -59.725941)
			(xy 70.964693 -59.741296) (xy 71.014269 -59.763936) (xy 71.060119 -59.793402) (xy 71.101308 -59.829093)
			(xy 71.136999 -59.870283) (xy 71.166464 -59.916132) (xy 71.189105 -59.965709) (xy 71.20446 -60.018003)
			(xy 71.20464 -60.019254) (xy 74.135661 -60.019254) (xy 74.135661 -59.964746) (xy 74.143419 -59.910792)
			(xy 74.158777 -59.858492) (xy 74.181423 -59.808909) (xy 74.210894 -59.763055) (xy 74.246592 -59.721862)
			(xy 74.287789 -59.686169) (xy 74.333646 -59.656702) (xy 74.383231 -59.634063) (xy 74.435533 -59.61871)
			(xy 74.489488 -59.610958) (xy 74.516742 -59.610498) (xy 74.544111 -59.610999) (xy 74.598289 -59.618808)
			(xy 74.650791 -59.634289) (xy 74.700539 -59.657123) (xy 74.746507 -59.68684) (xy 74.76744 -59.704478)
			(xy 74.767694 -59.704732) (xy 74.774775 -59.710326) (xy 74.791696 -59.716567) (xy 74.800714 -59.716924)
			(xy 74.86777 -59.716924) (xy 74.876785 -59.716547) (xy 74.893702 -59.710313) (xy 74.90079 -59.704732)
			(xy 74.90079 -59.704478) (xy 74.901044 -59.704478) (xy 74.921977 -59.686837) (xy 74.967945 -59.657113)
			(xy 75.017691 -59.634267) (xy 75.070193 -59.618771) (xy 75.124371 -59.610942) (xy 75.179113 -59.610942)
			(xy 75.233291 -59.618771) (xy 75.285793 -59.634267) (xy 75.335539 -59.657113) (xy 75.381507 -59.686837)
			(xy 75.40244 -59.704478) (xy 75.402694 -59.704732) (xy 75.409775 -59.710326) (xy 75.426696 -59.716567)
			(xy 75.435714 -59.716924) (xy 75.50277 -59.716924) (xy 75.511785 -59.716547) (xy 75.528702 -59.710313)
			(xy 75.53579 -59.704732) (xy 75.53579 -59.704478) (xy 75.536044 -59.704478) (xy 75.556984 -59.686848)
			(xy 75.602955 -59.657136) (xy 75.6527 -59.634298) (xy 75.705199 -59.618805) (xy 75.759373 -59.610974)
			(xy 75.786742 -59.610498) (xy 75.813992 -59.610975) (xy 75.867936 -59.618736) (xy 75.920226 -59.634095)
			(xy 75.969799 -59.656739) (xy 76.015645 -59.686207) (xy 76.056831 -59.721899) (xy 76.092518 -59.763089)
			(xy 76.121981 -59.808938) (xy 76.14462 -59.858513) (xy 76.159973 -59.910805) (xy 76.167728 -59.96475)
			(xy 76.167728 -59.974734) (xy 83.086446 -59.974734) (xy 83.090517 -59.919112) (xy 83.102643 -59.864675)
			(xy 83.122566 -59.812584) (xy 83.149862 -59.763949) (xy 83.183948 -59.719806) (xy 83.224097 -59.681097)
			(xy 83.269455 -59.648646) (xy 83.319055 -59.623145) (xy 83.371839 -59.605138) (xy 83.426682 -59.595008)
			(xy 83.482416 -59.592971) (xy 83.537853 -59.599071) (xy 83.59181 -59.613177) (xy 83.643139 -59.634989)
			(xy 83.690745 -59.664043) (xy 83.733613 -59.699718) (xy 83.77083 -59.741255) (xy 83.801603 -59.787768)
			(xy 83.825275 -59.838265) (xy 83.841343 -59.891672) (xy 83.849463 -59.946848) (xy 83.849972 -59.974734)
			(xy 83.849463 -60.00262) (xy 83.841343 -60.057796) (xy 83.825275 -60.111203) (xy 83.818128 -60.126449)
			(xy 95.180172 -60.126449) (xy 95.180172 -60.071951) (xy 95.187927 -60.018006) (xy 95.20328 -59.965715)
			(xy 95.225918 -59.91614) (xy 95.25538 -59.870291) (xy 95.291066 -59.829102) (xy 95.332251 -59.79341)
			(xy 95.378096 -59.763942) (xy 95.427668 -59.741297) (xy 95.479957 -59.725938) (xy 95.533901 -59.718175)
			(xy 95.56115 -59.717686) (xy 95.588519 -59.718185) (xy 95.642697 -59.725995) (xy 95.695199 -59.741477)
			(xy 95.744947 -59.764311) (xy 95.790915 -59.794028) (xy 95.811848 -59.811666) (xy 95.812102 -59.81192)
			(xy 95.819182 -59.817516) (xy 95.836104 -59.823756) (xy 95.845122 -59.824112) (xy 95.912178 -59.824112)
			(xy 95.921193 -59.823742) (xy 95.93811 -59.817503) (xy 95.945198 -59.81192) (xy 95.945198 -59.811666)
			(xy 95.945452 -59.811666) (xy 95.966385 -59.794025) (xy 96.012353 -59.764301) (xy 96.062099 -59.741455)
			(xy 96.114601 -59.725959) (xy 96.168779 -59.71813) (xy 96.223521 -59.71813) (xy 96.277699 -59.725959)
			(xy 96.330201 -59.741455) (xy 96.379947 -59.764301) (xy 96.425915 -59.794025) (xy 96.446848 -59.811666)
			(xy 96.447102 -59.81192) (xy 96.454182 -59.817516) (xy 96.471104 -59.823756) (xy 96.480122 -59.824112)
			(xy 96.547178 -59.824112) (xy 96.556193 -59.823742) (xy 96.57311 -59.817503) (xy 96.580198 -59.81192)
			(xy 96.580198 -59.811666) (xy 96.580452 -59.811666) (xy 96.601387 -59.794031) (xy 96.64736 -59.764319)
			(xy 96.697106 -59.741483) (xy 96.749606 -59.725991) (xy 96.803781 -59.718161) (xy 96.83115 -59.717686)
			(xy 96.858405 -59.718158) (xy 96.91236 -59.725909) (xy 96.964663 -59.74126) (xy 97.014249 -59.7639)
			(xy 97.060108 -59.793366) (xy 97.101306 -59.829059) (xy 97.137004 -59.870252) (xy 97.166476 -59.916107)
			(xy 97.189122 -59.96569) (xy 97.20448 -60.017991) (xy 97.204661 -60.01925) (xy 100.135684 -60.01925)
			(xy 100.135684 -59.96475) (xy 100.14344 -59.910804) (xy 100.158794 -59.85851) (xy 100.181434 -59.808935)
			(xy 100.210899 -59.763086) (xy 100.246589 -59.721896) (xy 100.287777 -59.686205) (xy 100.333626 -59.656739)
			(xy 100.383201 -59.634098) (xy 100.435494 -59.618742) (xy 100.48944 -59.610984) (xy 100.51669 -59.610498)
			(xy 100.54406 -59.61097) (xy 100.598239 -59.618787) (xy 100.650742 -59.634274) (xy 100.700489 -59.657115)
			(xy 100.746456 -59.686838) (xy 100.767388 -59.704478) (xy 100.767642 -59.704732) (xy 100.774738 -59.710304)
			(xy 100.791648 -59.716558) (xy 100.800662 -59.716924) (xy 100.867718 -59.716924) (xy 100.876735 -59.716571)
			(xy 100.893652 -59.71032) (xy 100.900738 -59.704732) (xy 100.900738 -59.704478) (xy 100.900992 -59.704478)
			(xy 100.921925 -59.686837) (xy 100.967893 -59.657113) (xy 101.017639 -59.634267) (xy 101.070141 -59.618771)
			(xy 101.124319 -59.610942) (xy 101.179061 -59.610942) (xy 101.233239 -59.618771) (xy 101.285741 -59.634267)
			(xy 101.335487 -59.657113) (xy 101.381455 -59.686837) (xy 101.402388 -59.704478) (xy 101.402642 -59.704732)
			(xy 101.409738 -59.710304) (xy 101.426648 -59.716558) (xy 101.435662 -59.716924) (xy 101.502718 -59.716924)
			(xy 101.511735 -59.716571) (xy 101.528652 -59.71032) (xy 101.535738 -59.704732) (xy 101.535738 -59.704478)
			(xy 101.535992 -59.704478) (xy 101.556913 -59.686826) (xy 101.60289 -59.657117) (xy 101.65264 -59.634284)
			(xy 101.705143 -59.618796) (xy 101.75932 -59.61097) (xy 101.78669 -59.610498) (xy 101.813944 -59.610949)
			(xy 101.867897 -59.618705) (xy 101.920196 -59.63406) (xy 101.969779 -59.656702) (xy 102.015634 -59.68617)
			(xy 102.056828 -59.721865) (xy 102.092524 -59.763058) (xy 102.121993 -59.808913) (xy 102.144636 -59.858494)
			(xy 102.159993 -59.910794) (xy 102.167751 -59.964746) (xy 102.167751 -59.974734) (xy 121.1867 -59.974734)
			(xy 121.190771 -59.919112) (xy 121.202897 -59.864675) (xy 121.22282 -59.812584) (xy 121.250116 -59.763949)
			(xy 121.284202 -59.719806) (xy 121.324351 -59.681097) (xy 121.369709 -59.648646) (xy 121.419309 -59.623145)
			(xy 121.472093 -59.605138) (xy 121.526936 -59.595008) (xy 121.58267 -59.592971) (xy 121.638107 -59.599071)
			(xy 121.692064 -59.613177) (xy 121.743393 -59.634989) (xy 121.790999 -59.664043) (xy 121.833867 -59.699718)
			(xy 121.871084 -59.741255) (xy 121.901857 -59.787768) (xy 121.925529 -59.838265) (xy 121.941597 -59.891672)
			(xy 121.949717 -59.946848) (xy 121.950226 -59.974734) (xy 121.949717 -60.00262) (xy 121.941597 -60.057796)
			(xy 121.925529 -60.111203) (xy 121.91838 -60.126453) (xy 133.280349 -60.126453) (xy 133.280349 -60.071947)
			(xy 133.288107 -60.017994) (xy 133.303463 -59.965695) (xy 133.326106 -59.916114) (xy 133.355575 -59.87026)
			(xy 133.39127 -59.829067) (xy 133.432463 -59.793373) (xy 133.478318 -59.763904) (xy 133.527899 -59.741262)
			(xy 133.580198 -59.725906) (xy 133.634151 -59.718149) (xy 133.661404 -59.717686) (xy 133.688774 -59.718153)
			(xy 133.742953 -59.725971) (xy 133.795456 -59.74146) (xy 133.845203 -59.764302) (xy 133.89117 -59.794025)
			(xy 133.912102 -59.811666) (xy 133.912356 -59.81192) (xy 133.919449 -59.817497) (xy 133.936361 -59.823749)
			(xy 133.945376 -59.824112) (xy 134.012432 -59.824112) (xy 134.02145 -59.823768) (xy 134.038367 -59.817511)
			(xy 134.045452 -59.81192) (xy 134.045452 -59.811666) (xy 134.045706 -59.811666) (xy 134.066639 -59.794025)
			(xy 134.112607 -59.764301) (xy 134.162353 -59.741455) (xy 134.214855 -59.725959) (xy 134.269033 -59.71813)
			(xy 134.323775 -59.71813) (xy 134.377953 -59.725959) (xy 134.430455 -59.741455) (xy 134.480201 -59.764301)
			(xy 134.526169 -59.794025) (xy 134.547102 -59.811666) (xy 134.547356 -59.81192) (xy 134.554449 -59.817497)
			(xy 134.571361 -59.823749) (xy 134.580376 -59.824112) (xy 134.647432 -59.824112) (xy 134.65645 -59.823768)
			(xy 134.673367 -59.817511) (xy 134.680452 -59.81192) (xy 134.680452 -59.811666) (xy 134.680706 -59.811666)
			(xy 134.701621 -59.794005) (xy 134.747599 -59.764298) (xy 134.797351 -59.741467) (xy 134.849855 -59.725981)
			(xy 134.904034 -59.718157) (xy 134.931404 -59.717686) (xy 134.958655 -59.718184) (xy 135.012601 -59.725941)
			(xy 135.064895 -59.741296) (xy 135.11447 -59.763937) (xy 135.16032 -59.793403) (xy 135.201509 -59.829094)
			(xy 135.237199 -59.870284) (xy 135.266665 -59.916133) (xy 135.289305 -59.965709) (xy 135.30466 -60.018003)
			(xy 135.30484 -60.019254) (xy 138.235861 -60.019254) (xy 138.235861 -59.964746) (xy 138.243619 -59.910792)
			(xy 138.258977 -59.858491) (xy 138.281623 -59.808909) (xy 138.311094 -59.763054) (xy 138.346792 -59.721861)
			(xy 138.38799 -59.686168) (xy 138.433848 -59.656702) (xy 138.483432 -59.634062) (xy 138.535735 -59.61871)
			(xy 138.58969 -59.610958) (xy 138.616944 -59.610498) (xy 138.644313 -59.610997) (xy 138.698491 -59.618807)
			(xy 138.750993 -59.634289) (xy 138.800741 -59.657123) (xy 138.846709 -59.68684) (xy 138.867642 -59.704478)
			(xy 138.867896 -59.704732) (xy 138.874977 -59.710327) (xy 138.891898 -59.716567) (xy 138.900916 -59.716924)
			(xy 138.967972 -59.716924) (xy 138.976987 -59.716548) (xy 138.993904 -59.710313) (xy 139.000992 -59.704732)
			(xy 139.000992 -59.704478) (xy 139.001246 -59.704478) (xy 139.022179 -59.686837) (xy 139.068147 -59.657113)
			(xy 139.117893 -59.634267) (xy 139.170395 -59.618771) (xy 139.224573 -59.610942) (xy 139.279315 -59.610942)
			(xy 139.333493 -59.618771) (xy 139.385995 -59.634267) (xy 139.435741 -59.657113) (xy 139.481709 -59.686837)
			(xy 139.502642 -59.704478) (xy 139.502896 -59.704732) (xy 139.509977 -59.710327) (xy 139.526898 -59.716567)
			(xy 139.535916 -59.716924) (xy 139.602972 -59.716924) (xy 139.611987 -59.716548) (xy 139.628904 -59.710313)
			(xy 139.635992 -59.704732) (xy 139.635992 -59.704478) (xy 139.636246 -59.704478) (xy 139.657185 -59.686847)
			(xy 139.703156 -59.657135) (xy 139.752902 -59.634298) (xy 139.805401 -59.618805) (xy 139.859575 -59.610974)
			(xy 139.886944 -59.610498) (xy 139.914194 -59.610975) (xy 139.968137 -59.618737) (xy 140.020428 -59.634096)
			(xy 140.07 -59.65674) (xy 140.115846 -59.686208) (xy 140.157031 -59.7219) (xy 140.192719 -59.763089)
			(xy 140.222181 -59.808938) (xy 140.24482 -59.858514) (xy 140.260173 -59.910806) (xy 140.267928 -59.96475)
			(xy 140.267928 -59.974734) (xy 147.186648 -59.974734) (xy 147.190719 -59.919112) (xy 147.202845 -59.864675)
			(xy 147.222768 -59.812584) (xy 147.250064 -59.763949) (xy 147.28415 -59.719806) (xy 147.324299 -59.681097)
			(xy 147.369657 -59.648646) (xy 147.419257 -59.623145) (xy 147.472041 -59.605138) (xy 147.526884 -59.595008)
			(xy 147.582618 -59.592971) (xy 147.638055 -59.599071) (xy 147.692012 -59.613177) (xy 147.743341 -59.634989)
			(xy 147.790947 -59.664043) (xy 147.833815 -59.699718) (xy 147.871032 -59.741255) (xy 147.901805 -59.787768)
			(xy 147.925477 -59.838265) (xy 147.941545 -59.891672) (xy 147.949665 -59.946848) (xy 147.950174 -59.974734)
			(xy 147.949665 -60.00262) (xy 147.941545 -60.057796) (xy 147.925477 -60.111203) (xy 147.91833 -60.126449)
			(xy 159.280372 -60.126449) (xy 159.280372 -60.071951) (xy 159.288127 -60.018006) (xy 159.30348 -59.965714)
			(xy 159.326118 -59.91614) (xy 159.35558 -59.870291) (xy 159.391267 -59.829101) (xy 159.432452 -59.793409)
			(xy 159.478297 -59.763941) (xy 159.527869 -59.741297) (xy 159.580159 -59.725937) (xy 159.634103 -59.718175)
			(xy 159.661352 -59.717686) (xy 159.688721 -59.718184) (xy 159.742899 -59.725994) (xy 159.795401 -59.741476)
			(xy 159.845149 -59.764311) (xy 159.891117 -59.794028) (xy 159.91205 -59.811666) (xy 159.912304 -59.81192)
			(xy 159.919384 -59.817517) (xy 159.936306 -59.823757) (xy 159.945324 -59.824112) (xy 160.01238 -59.824112)
			(xy 160.021396 -59.823743) (xy 160.038313 -59.817503) (xy 160.0454 -59.81192) (xy 160.0454 -59.811666)
			(xy 160.045654 -59.811666) (xy 160.066587 -59.794025) (xy 160.112555 -59.764301) (xy 160.162301 -59.741455)
			(xy 160.214803 -59.725959) (xy 160.268981 -59.71813) (xy 160.323723 -59.71813) (xy 160.377901 -59.725959)
			(xy 160.430403 -59.741455) (xy 160.480149 -59.764301) (xy 160.526117 -59.794025) (xy 160.54705 -59.811666)
			(xy 160.547304 -59.81192) (xy 160.554384 -59.817517) (xy 160.571306 -59.823757) (xy 160.580324 -59.824112)
			(xy 160.64738 -59.824112) (xy 160.656396 -59.823743) (xy 160.673313 -59.817503) (xy 160.6804 -59.81192)
			(xy 160.6804 -59.811666) (xy 160.680654 -59.811666) (xy 160.701588 -59.79403) (xy 160.747561 -59.764319)
			(xy 160.797308 -59.741483) (xy 160.849808 -59.725991) (xy 160.903983 -59.718161) (xy 160.931352 -59.717686)
			(xy 160.958607 -59.718158) (xy 161.012562 -59.725909) (xy 161.064865 -59.741261) (xy 161.11445 -59.7639)
			(xy 161.160309 -59.793367) (xy 161.201506 -59.82906) (xy 161.237205 -59.870253) (xy 161.266677 -59.916108)
			(xy 161.289322 -59.96569) (xy 161.30468 -60.017991) (xy 161.304861 -60.01925) (xy 164.235884 -60.01925)
			(xy 164.235884 -59.96475) (xy 164.24364 -59.910803) (xy 164.258994 -59.85851) (xy 164.281635 -59.808934)
			(xy 164.3111 -59.763085) (xy 164.34679 -59.721895) (xy 164.387978 -59.686204) (xy 164.433827 -59.656738)
			(xy 164.483403 -59.634097) (xy 164.535696 -59.618742) (xy 164.589642 -59.610984) (xy 164.616892 -59.610498)
			(xy 164.644262 -59.610969) (xy 164.698441 -59.618786) (xy 164.750944 -59.634274) (xy 164.800691 -59.657114)
			(xy 164.846658 -59.686837) (xy 164.86759 -59.704478) (xy 164.867844 -59.704732) (xy 164.87494 -59.710305)
			(xy 164.89185 -59.716559) (xy 164.900864 -59.716924) (xy 164.96792 -59.716924) (xy 164.976937 -59.716572)
			(xy 164.993854 -59.71032) (xy 165.00094 -59.704732) (xy 165.00094 -59.704478) (xy 165.001194 -59.704478)
			(xy 165.022127 -59.686837) (xy 165.068095 -59.657113) (xy 165.117841 -59.634267) (xy 165.170343 -59.618771)
			(xy 165.224521 -59.610942) (xy 165.279263 -59.610942) (xy 165.333441 -59.618771) (xy 165.385943 -59.634267)
			(xy 165.435689 -59.657113) (xy 165.481657 -59.686837) (xy 165.50259 -59.704478) (xy 165.502844 -59.704732)
			(xy 165.50994 -59.710305) (xy 165.52685 -59.716559) (xy 165.535864 -59.716924) (xy 165.60292 -59.716924)
			(xy 165.611937 -59.716572) (xy 165.628854 -59.71032) (xy 165.63594 -59.704732) (xy 165.63594 -59.704478)
			(xy 165.636194 -59.704478) (xy 165.657115 -59.686825) (xy 165.703091 -59.657116) (xy 165.752841 -59.634283)
			(xy 165.805344 -59.618795) (xy 165.859522 -59.61097) (xy 165.886892 -59.610498) (xy 165.914146 -59.610949)
			(xy 165.968098 -59.618705) (xy 166.020398 -59.634061) (xy 166.06998 -59.656703) (xy 166.115835 -59.686171)
			(xy 166.157029 -59.721865) (xy 166.192724 -59.763059) (xy 166.222193 -59.808913) (xy 166.244837 -59.858495)
			(xy 166.260193 -59.910794) (xy 166.267951 -59.964746) (xy 166.267951 -59.974734) (xy 173.186596 -59.974734)
			(xy 173.190667 -59.919112) (xy 173.202793 -59.864675) (xy 173.222716 -59.812584) (xy 173.250012 -59.763949)
			(xy 173.284098 -59.719806) (xy 173.324247 -59.681097) (xy 173.369605 -59.648646) (xy 173.419205 -59.623145)
			(xy 173.471989 -59.605138) (xy 173.526832 -59.595008) (xy 173.582566 -59.592971) (xy 173.638003 -59.599071)
			(xy 173.69196 -59.613177) (xy 173.743289 -59.634989) (xy 173.790895 -59.664043) (xy 173.833763 -59.699718)
			(xy 173.87098 -59.741255) (xy 173.901753 -59.787768) (xy 173.925425 -59.838265) (xy 173.941493 -59.891672)
			(xy 173.949613 -59.946848) (xy 173.950122 -59.974734) (xy 173.949613 -60.00262) (xy 173.941493 -60.057796)
			(xy 173.925425 -60.111203) (xy 173.918277 -60.126452) (xy 185.280272 -60.126452) (xy 185.280272 -60.071948)
			(xy 185.288028 -60.018) (xy 185.303384 -59.965704) (xy 185.326025 -59.916126) (xy 185.355492 -59.870275)
			(xy 185.391184 -59.829084) (xy 185.432375 -59.793392) (xy 185.478226 -59.763925) (xy 185.527804 -59.741284)
			(xy 185.5801 -59.725928) (xy 185.634048 -59.718172) (xy 185.6613 -59.717686) (xy 185.68867 -59.718155)
			(xy 185.742849 -59.725973) (xy 185.795352 -59.741461) (xy 185.845099 -59.764302) (xy 185.891066 -59.794026)
			(xy 185.911998 -59.811666) (xy 185.912252 -59.81192) (xy 185.919347 -59.817495) (xy 185.936257 -59.823748)
			(xy 185.945272 -59.824112) (xy 186.012328 -59.824112) (xy 186.021346 -59.823766) (xy 186.038263 -59.81751)
			(xy 186.045348 -59.81192) (xy 186.045348 -59.811666) (xy 186.045602 -59.811666) (xy 186.066535 -59.794025)
			(xy 186.112503 -59.764301) (xy 186.162249 -59.741455) (xy 186.214751 -59.725959) (xy 186.268929 -59.71813)
			(xy 186.323671 -59.71813) (xy 186.377849 -59.725959) (xy 186.430351 -59.741455) (xy 186.480097 -59.764301)
			(xy 186.526065 -59.794025) (xy 186.546998 -59.811666) (xy 186.547252 -59.81192) (xy 186.554347 -59.817495)
			(xy 186.571257 -59.823748) (xy 186.580272 -59.824112) (xy 186.647328 -59.824112) (xy 186.656346 -59.823766)
			(xy 186.673263 -59.81751) (xy 186.680348 -59.81192) (xy 186.680348 -59.811666) (xy 186.680602 -59.811666)
			(xy 186.701518 -59.794007) (xy 186.747496 -59.764299) (xy 186.797247 -59.741468) (xy 186.849751 -59.725981)
			(xy 186.90393 -59.718158) (xy 186.9313 -59.717686) (xy 186.958551 -59.718184) (xy 187.012498 -59.72594)
			(xy 187.064792 -59.741295) (xy 187.114368 -59.763936) (xy 187.160218 -59.793402) (xy 187.201407 -59.829093)
			(xy 187.237098 -59.870282) (xy 187.266564 -59.916132) (xy 187.289205 -59.965708) (xy 187.30456 -60.018002)
			(xy 187.30474 -60.019254) (xy 190.235761 -60.019254) (xy 190.235761 -59.964746) (xy 190.243519 -59.910792)
			(xy 190.258877 -59.858492) (xy 190.281522 -59.80891) (xy 190.310993 -59.763056) (xy 190.346691 -59.721863)
			(xy 190.387888 -59.686169) (xy 190.433745 -59.656703) (xy 190.483329 -59.634063) (xy 190.535631 -59.618711)
			(xy 190.589586 -59.610959) (xy 190.61684 -59.610498) (xy 190.644209 -59.611) (xy 190.698386 -59.618809)
			(xy 190.750889 -59.63429) (xy 190.800637 -59.657124) (xy 190.846605 -59.68684) (xy 190.867538 -59.704478)
			(xy 190.867792 -59.704732) (xy 190.874874 -59.710325) (xy 190.891794 -59.716567) (xy 190.900812 -59.716924)
			(xy 190.967868 -59.716924) (xy 190.976883 -59.716546) (xy 190.9938 -59.710313) (xy 191.000888 -59.704732)
			(xy 191.000888 -59.704478) (xy 191.001142 -59.704478) (xy 191.022075 -59.686837) (xy 191.068043 -59.657113)
			(xy 191.117789 -59.634267) (xy 191.170291 -59.618771) (xy 191.224469 -59.610942) (xy 191.279211 -59.610942)
			(xy 191.333389 -59.618771) (xy 191.385891 -59.634267) (xy 191.435637 -59.657113) (xy 191.481605 -59.686837)
			(xy 191.502538 -59.704478) (xy 191.502792 -59.704732) (xy 191.509874 -59.710325) (xy 191.526794 -59.716567)
			(xy 191.535812 -59.716924) (xy 191.602868 -59.716924) (xy 191.611883 -59.716546) (xy 191.6288 -59.710313)
			(xy 191.635888 -59.704732) (xy 191.635888 -59.704478) (xy 191.636142 -59.704478) (xy 191.657082 -59.686849)
			(xy 191.703053 -59.657137) (xy 191.752799 -59.634299) (xy 191.805297 -59.618805) (xy 191.859471 -59.610974)
			(xy 191.88684 -59.610498) (xy 191.91409 -59.610975) (xy 191.968034 -59.618736) (xy 192.020325 -59.634095)
			(xy 192.069898 -59.656738) (xy 192.115744 -59.686206) (xy 192.15693 -59.721898) (xy 192.192618 -59.763088)
			(xy 192.222081 -59.808937) (xy 192.244719 -59.858513) (xy 192.260073 -59.910805) (xy 192.267828 -59.96475)
			(xy 192.267828 -59.974734) (xy 199.186544 -59.974734) (xy 199.190615 -59.919112) (xy 199.202741 -59.864675)
			(xy 199.222664 -59.812584) (xy 199.24996 -59.763949) (xy 199.284046 -59.719806) (xy 199.324195 -59.681097)
			(xy 199.369553 -59.648646) (xy 199.419153 -59.623145) (xy 199.471937 -59.605138) (xy 199.52678 -59.595008)
			(xy 199.582514 -59.592971) (xy 199.637951 -59.599071) (xy 199.691908 -59.613177) (xy 199.743237 -59.634989)
			(xy 199.790843 -59.664043) (xy 199.833711 -59.699718) (xy 199.870928 -59.741255) (xy 199.901701 -59.787768)
			(xy 199.925373 -59.838265) (xy 199.941441 -59.891672) (xy 199.949561 -59.946848) (xy 199.95007 -59.974734)
			(xy 199.949561 -60.00262) (xy 199.941441 -60.057796) (xy 199.925373 -60.111203) (xy 199.918223 -60.126455)
			(xy 211.28015 -60.126455) (xy 211.28015 -60.071945) (xy 211.287908 -60.017989) (xy 211.303267 -59.965686)
			(xy 211.325913 -59.916102) (xy 211.355386 -59.870246) (xy 211.391085 -59.829051) (xy 211.432284 -59.793357)
			(xy 211.478144 -59.76389) (xy 211.527731 -59.74125) (xy 211.580036 -59.725898) (xy 211.633992 -59.718146)
			(xy 211.661248 -59.717686) (xy 211.688617 -59.718186) (xy 211.742794 -59.725996) (xy 211.795297 -59.741477)
			(xy 211.845044 -59.764312) (xy 211.891013 -59.794028) (xy 211.911946 -59.811666) (xy 211.9122 -59.81192)
			(xy 211.919281 -59.817515) (xy 211.936202 -59.823756) (xy 211.94522 -59.824112) (xy 212.012276 -59.824112)
			(xy 212.021291 -59.823741) (xy 212.038208 -59.817503) (xy 212.045296 -59.81192) (xy 212.045296 -59.811666)
			(xy 212.04555 -59.811666) (xy 212.066483 -59.794025) (xy 212.112451 -59.764301) (xy 212.162197 -59.741455)
			(xy 212.214699 -59.725959) (xy 212.268877 -59.71813) (xy 212.323619 -59.71813) (xy 212.377797 -59.725959)
			(xy 212.430299 -59.741455) (xy 212.480045 -59.764301) (xy 212.526013 -59.794025) (xy 212.546946 -59.811666)
			(xy 212.5472 -59.81192) (xy 212.554281 -59.817515) (xy 212.571202 -59.823756) (xy 212.58022 -59.824112)
			(xy 212.647276 -59.824112) (xy 212.656291 -59.823741) (xy 212.673208 -59.817503) (xy 212.680296 -59.81192)
			(xy 212.680296 -59.811666) (xy 212.68055 -59.811666) (xy 212.701486 -59.794032) (xy 212.747458 -59.76432)
			(xy 212.797205 -59.741484) (xy 212.849704 -59.725992) (xy 212.903879 -59.718161) (xy 212.931248 -59.717686)
			(xy 212.958497 -59.718187) (xy 213.012438 -59.725949) (xy 213.064726 -59.741308) (xy 213.114297 -59.763952)
			(xy 213.160141 -59.793419) (xy 213.201324 -59.82911) (xy 213.23701 -59.870298) (xy 213.266471 -59.916145)
			(xy 213.289109 -59.965719) (xy 213.304461 -60.018009) (xy 213.304639 -60.01925) (xy 216.235784 -60.01925)
			(xy 216.235784 -59.96475) (xy 216.24354 -59.910804) (xy 216.258894 -59.858511) (xy 216.281534 -59.808935)
			(xy 216.310999 -59.763086) (xy 216.346688 -59.721897) (xy 216.387877 -59.686206) (xy 216.433725 -59.65674)
			(xy 216.4833 -59.634098) (xy 216.535592 -59.618742) (xy 216.589538 -59.610985) (xy 216.616788 -59.610498)
			(xy 216.644158 -59.610972) (xy 216.698337 -59.618788) (xy 216.75084 -59.634275) (xy 216.800587 -59.657115)
			(xy 216.846554 -59.686838) (xy 216.867486 -59.704478) (xy 216.86774 -59.704732) (xy 216.874837 -59.710303)
			(xy 216.891746 -59.716558) (xy 216.90076 -59.716924) (xy 216.967816 -59.716924) (xy 216.976833 -59.716569)
			(xy 216.99375 -59.710319) (xy 217.000836 -59.704732) (xy 217.000836 -59.704478) (xy 217.00109 -59.704478)
			(xy 217.022023 -59.686837) (xy 217.067991 -59.657113) (xy 217.117737 -59.634267) (xy 217.170239 -59.618771)
			(xy 217.224417 -59.610942) (xy 217.279159 -59.610942) (xy 217.333337 -59.618771) (xy 217.385839 -59.634267)
			(xy 217.435585 -59.657113) (xy 217.481553 -59.686837) (xy 217.502486 -59.704478) (xy 217.50274 -59.704732)
			(xy 217.509837 -59.710303) (xy 217.526746 -59.716558) (xy 217.53576 -59.716924) (xy 217.602816 -59.716924)
			(xy 217.611833 -59.716569) (xy 217.62875 -59.710319) (xy 217.635836 -59.704732) (xy 217.635836 -59.704478)
			(xy 217.63609 -59.704478) (xy 217.657012 -59.686827) (xy 217.702988 -59.657117) (xy 217.752738 -59.634284)
			(xy 217.805241 -59.618796) (xy 217.859418 -59.610971) (xy 217.886788 -59.610498) (xy 217.914042 -59.610949)
			(xy 217.967995 -59.618704) (xy 218.020295 -59.634059) (xy 218.069877 -59.656702) (xy 218.115733 -59.68617)
			(xy 218.156928 -59.721864) (xy 218.192623 -59.763058) (xy 218.222093 -59.808912) (xy 218.244736 -59.858494)
			(xy 218.260093 -59.910793) (xy 218.267851 -59.964746) (xy 218.267851 -60.019254) (xy 218.260093 -60.073207)
			(xy 218.244736 -60.125506) (xy 218.222093 -60.175088) (xy 218.192623 -60.220942) (xy 218.156928 -60.262136)
			(xy 218.115733 -60.29783) (xy 218.069877 -60.327298) (xy 218.020295 -60.349941) (xy 217.967995 -60.365296)
			(xy 217.914042 -60.373051) (xy 217.886788 -60.373514) (xy 217.859418 -60.373052) (xy 217.805239 -60.365232)
			(xy 217.752736 -60.349742) (xy 217.702989 -60.3269) (xy 217.657022 -60.297175) (xy 217.63609 -60.279534)
			(xy 217.635836 -60.27928) (xy 217.628745 -60.2737) (xy 217.611832 -60.26745) (xy 217.602816 -60.267088)
			(xy 217.53576 -60.267088) (xy 217.526741 -60.267428) (xy 217.509825 -60.273688) (xy 217.50274 -60.27928)
			(xy 217.502486 -60.279534) (xy 217.481553 -60.297175) (xy 217.435585 -60.326899) (xy 217.385839 -60.349745)
			(xy 217.333337 -60.365241) (xy 217.279159 -60.37307) (xy 217.224417 -60.37307) (xy 217.170239 -60.365241)
			(xy 217.117737 -60.349745) (xy 217.067991 -60.326899) (xy 217.022023 -60.297175) (xy 217.00109 -60.279534)
			(xy 217.000836 -60.27928) (xy 216.993745 -60.2737) (xy 216.976832 -60.26745) (xy 216.967816 -60.267088)
			(xy 216.90076 -60.267088) (xy 216.891741 -60.267428) (xy 216.874825 -60.273688) (xy 216.86774 -60.27928)
			(xy 216.86774 -60.279534) (xy 216.867486 -60.279534) (xy 216.846537 -60.297152) (xy 216.800568 -60.326865)
			(xy 216.750825 -60.349705) (xy 216.698328 -60.365201) (xy 216.644156 -60.373036) (xy 216.616788 -60.373514)
			(xy 216.589538 -60.373015) (xy 216.535592 -60.365258) (xy 216.4833 -60.349902) (xy 216.433725 -60.32726)
			(xy 216.387877 -60.297794) (xy 216.346688 -60.262103) (xy 216.310999 -60.220914) (xy 216.281534 -60.175065)
			(xy 216.258894 -60.125489) (xy 216.24354 -60.073196) (xy 216.235784 -60.01925) (xy 213.304639 -60.01925)
			(xy 213.312216 -60.071951) (xy 213.312216 -60.126449) (xy 213.304461 -60.180391) (xy 213.289109 -60.232681)
			(xy 213.266471 -60.282255) (xy 213.23701 -60.328102) (xy 213.201324 -60.36929) (xy 213.160141 -60.404981)
			(xy 213.114297 -60.434448) (xy 213.064726 -60.457092) (xy 213.012438 -60.472451) (xy 212.958497 -60.480213)
			(xy 212.931248 -60.480702) (xy 212.903879 -60.480207) (xy 212.849701 -60.472396) (xy 212.797198 -60.456914)
			(xy 212.747451 -60.434079) (xy 212.701483 -60.40436) (xy 212.68055 -60.386722) (xy 212.680296 -60.386468)
			(xy 212.673217 -60.38087) (xy 212.656294 -60.374631) (xy 212.647276 -60.374276) (xy 212.58022 -60.374276)
			(xy 212.571205 -60.374648) (xy 212.554288 -60.380886) (xy 212.5472 -60.386468) (xy 212.546946 -60.386722)
			(xy 212.526013 -60.404363) (xy 212.480045 -60.434087) (xy 212.430299 -60.456933) (xy 212.377797 -60.472429)
			(xy 212.323619 -60.480258) (xy 212.268877 -60.480258) (xy 212.214699 -60.472429) (xy 212.162197 -60.456933)
			(xy 212.112451 -60.434087) (xy 212.066483 -60.404363) (xy 212.04555 -60.386722) (xy 212.045296 -60.386468)
			(xy 212.038217 -60.38087) (xy 212.021294 -60.374631) (xy 212.012276 -60.374276) (xy 211.94522 -60.374276)
			(xy 211.936205 -60.374648) (xy 211.919288 -60.380886) (xy 211.9122 -60.386468) (xy 211.9122 -60.386722)
			(xy 211.911946 -60.386722) (xy 211.89101 -60.404356) (xy 211.845038 -60.434068) (xy 211.795291 -60.456905)
			(xy 211.742792 -60.472397) (xy 211.688617 -60.480227) (xy 211.661248 -60.480702) (xy 211.633992 -60.480254)
			(xy 211.580036 -60.472502) (xy 211.527731 -60.45715) (xy 211.478144 -60.43451) (xy 211.432284 -60.405043)
			(xy 211.391085 -60.369349) (xy 211.355386 -60.328154) (xy 211.325913 -60.282298) (xy 211.303267 -60.232714)
			(xy 211.287908 -60.180411) (xy 211.28015 -60.126455) (xy 199.918223 -60.126455) (xy 199.901701 -60.1617)
			(xy 199.870928 -60.208213) (xy 199.833711 -60.24975) (xy 199.790843 -60.285425) (xy 199.743237 -60.314479)
			(xy 199.691908 -60.336291) (xy 199.637951 -60.350397) (xy 199.582514 -60.356497) (xy 199.52678 -60.35446)
			(xy 199.471937 -60.34433) (xy 199.419153 -60.326323) (xy 199.369553 -60.300822) (xy 199.324195 -60.268371)
			(xy 199.284046 -60.229662) (xy 199.24996 -60.185519) (xy 199.222664 -60.136884) (xy 199.202741 -60.084793)
			(xy 199.190615 -60.030356) (xy 199.186544 -59.974734) (xy 192.267828 -59.974734) (xy 192.267828 -60.01925)
			(xy 192.260073 -60.073195) (xy 192.244719 -60.125487) (xy 192.222081 -60.175063) (xy 192.192618 -60.220912)
			(xy 192.15693 -60.262102) (xy 192.115744 -60.297794) (xy 192.069898 -60.327262) (xy 192.020325 -60.349905)
			(xy 191.968034 -60.365264) (xy 191.91409 -60.373025) (xy 191.88684 -60.373514) (xy 191.859471 -60.373021)
			(xy 191.805293 -60.365209) (xy 191.75279 -60.349726) (xy 191.703043 -60.326891) (xy 191.657075 -60.297172)
			(xy 191.636142 -60.279534) (xy 191.635888 -60.27928) (xy 191.628811 -60.27368) (xy 191.611887 -60.267442)
			(xy 191.602868 -60.267088) (xy 191.535812 -60.267088) (xy 191.526796 -60.267453) (xy 191.509879 -60.273695)
			(xy 191.502792 -60.27928) (xy 191.502538 -60.279534) (xy 191.481605 -60.297175) (xy 191.435637 -60.326899)
			(xy 191.385891 -60.349745) (xy 191.333389 -60.365241) (xy 191.279211 -60.37307) (xy 191.224469 -60.37307)
			(xy 191.170291 -60.365241) (xy 191.117789 -60.349745) (xy 191.068043 -60.326899) (xy 191.022075 -60.297175)
			(xy 191.001142 -60.279534) (xy 191.000888 -60.27928) (xy 190.993811 -60.27368) (xy 190.976887 -60.267442)
			(xy 190.967868 -60.267088) (xy 190.900812 -60.267088) (xy 190.891796 -60.267453) (xy 190.874879 -60.273695)
			(xy 190.867792 -60.27928) (xy 190.867792 -60.279534) (xy 190.867538 -60.279534) (xy 190.846607 -60.297174)
			(xy 190.800633 -60.326885) (xy 190.750885 -60.34972) (xy 190.698385 -60.365211) (xy 190.644209 -60.373039)
			(xy 190.61684 -60.373514) (xy 190.589586 -60.373041) (xy 190.535631 -60.365289) (xy 190.483329 -60.349937)
			(xy 190.433745 -60.327297) (xy 190.387888 -60.297831) (xy 190.346691 -60.262137) (xy 190.310993 -60.220944)
			(xy 190.281522 -60.17509) (xy 190.258877 -60.125508) (xy 190.243519 -60.073208) (xy 190.235761 -60.019254)
			(xy 187.30474 -60.019254) (xy 187.312316 -60.071949) (xy 187.312316 -60.126451) (xy 187.30456 -60.180398)
			(xy 187.289205 -60.232692) (xy 187.266564 -60.282268) (xy 187.237098 -60.328118) (xy 187.201407 -60.369307)
			(xy 187.160218 -60.404998) (xy 187.114368 -60.434464) (xy 187.064792 -60.457105) (xy 187.012498 -60.47246)
			(xy 186.958551 -60.480216) (xy 186.9313 -60.480702) (xy 186.90393 -60.480235) (xy 186.849751 -60.472418)
			(xy 186.797248 -60.456929) (xy 186.747501 -60.434087) (xy 186.701534 -60.404363) (xy 186.680602 -60.386722)
			(xy 186.680348 -60.386468) (xy 186.673254 -60.380892) (xy 186.656343 -60.37464) (xy 186.647328 -60.374276)
			(xy 186.580272 -60.374276) (xy 186.571254 -60.374625) (xy 186.554338 -60.380878) (xy 186.547252 -60.386468)
			(xy 186.546998 -60.386722) (xy 186.526065 -60.404363) (xy 186.480097 -60.434087) (xy 186.430351 -60.456933)
			(xy 186.377849 -60.472429) (xy 186.323671 -60.480258) (xy 186.268929 -60.480258) (xy 186.214751 -60.472429)
			(xy 186.162249 -60.456933) (xy 186.112503 -60.434087) (xy 186.066535 -60.404363) (xy 186.045602 -60.386722)
			(xy 186.045348 -60.386468) (xy 186.038254 -60.380892) (xy 186.021343 -60.37464) (xy 186.012328 -60.374276)
			(xy 185.945272 -60.374276) (xy 185.936254 -60.374625) (xy 185.919338 -60.380878) (xy 185.912252 -60.386468)
			(xy 185.912252 -60.386722) (xy 185.911998 -60.386722) (xy 185.89108 -60.404379) (xy 185.845103 -60.434087)
			(xy 185.795352 -60.456919) (xy 185.742848 -60.472406) (xy 185.68867 -60.48023) (xy 185.6613 -60.480702)
			(xy 185.634048 -60.480228) (xy 185.5801 -60.472472) (xy 185.527804 -60.457116) (xy 185.478226 -60.434475)
			(xy 185.432375 -60.405008) (xy 185.391184 -60.369316) (xy 185.355492 -60.328125) (xy 185.326025 -60.282274)
			(xy 185.303384 -60.232696) (xy 185.288028 -60.1804) (xy 185.280272 -60.126452) (xy 173.918277 -60.126452)
			(xy 173.901753 -60.1617) (xy 173.87098 -60.208213) (xy 173.833763 -60.24975) (xy 173.790895 -60.285425)
			(xy 173.743289 -60.314479) (xy 173.69196 -60.336291) (xy 173.638003 -60.350397) (xy 173.582566 -60.356497)
			(xy 173.526832 -60.35446) (xy 173.471989 -60.34433) (xy 173.419205 -60.326323) (xy 173.369605 -60.300822)
			(xy 173.324247 -60.268371) (xy 173.284098 -60.229662) (xy 173.250012 -60.185519) (xy 173.222716 -60.136884)
			(xy 173.202793 -60.084793) (xy 173.190667 -60.030356) (xy 173.186596 -59.974734) (xy 166.267951 -59.974734)
			(xy 166.267951 -60.019254) (xy 166.260193 -60.073206) (xy 166.244837 -60.125505) (xy 166.222193 -60.175087)
			(xy 166.192724 -60.220941) (xy 166.157029 -60.262135) (xy 166.115835 -60.297829) (xy 166.06998 -60.327297)
			(xy 166.020398 -60.349939) (xy 165.968098 -60.365295) (xy 165.914146 -60.373051) (xy 165.886892 -60.373514)
			(xy 165.859522 -60.373049) (xy 165.805343 -60.365231) (xy 165.75284 -60.349741) (xy 165.703093 -60.326899)
			(xy 165.657126 -60.297175) (xy 165.636194 -60.279534) (xy 165.63594 -60.27928) (xy 165.628848 -60.273702)
			(xy 165.611935 -60.267451) (xy 165.60292 -60.267088) (xy 165.535864 -60.267088) (xy 165.526846 -60.26743)
			(xy 165.509929 -60.273688) (xy 165.502844 -60.27928) (xy 165.50259 -60.279534) (xy 165.481657 -60.297175)
			(xy 165.435689 -60.326899) (xy 165.385943 -60.349745) (xy 165.333441 -60.365241) (xy 165.279263 -60.37307)
			(xy 165.224521 -60.37307) (xy 165.170343 -60.365241) (xy 165.117841 -60.349745) (xy 165.068095 -60.326899)
			(xy 165.022127 -60.297175) (xy 165.001194 -60.279534) (xy 165.00094 -60.27928) (xy 164.993848 -60.273702)
			(xy 164.976935 -60.267451) (xy 164.96792 -60.267088) (xy 164.900864 -60.267088) (xy 164.891846 -60.26743)
			(xy 164.874929 -60.273688) (xy 164.867844 -60.27928) (xy 164.867844 -60.279534) (xy 164.86759 -60.279534)
			(xy 164.846677 -60.297197) (xy 164.800698 -60.326904) (xy 164.750946 -60.349735) (xy 164.698441 -60.36522)
			(xy 164.644262 -60.373043) (xy 164.616892 -60.373514) (xy 164.589642 -60.373016) (xy 164.535696 -60.365258)
			(xy 164.483403 -60.349903) (xy 164.433827 -60.327262) (xy 164.387978 -60.297796) (xy 164.34679 -60.262105)
			(xy 164.3111 -60.220915) (xy 164.281635 -60.175066) (xy 164.258994 -60.12549) (xy 164.24364 -60.073197)
			(xy 164.235884 -60.01925) (xy 161.304861 -60.01925) (xy 161.312439 -60.071945) (xy 161.312439 -60.126455)
			(xy 161.30468 -60.180409) (xy 161.289322 -60.23271) (xy 161.266677 -60.282292) (xy 161.237205 -60.328147)
			(xy 161.201506 -60.36934) (xy 161.160309 -60.405033) (xy 161.11445 -60.4345) (xy 161.064865 -60.457139)
			(xy 161.012562 -60.472491) (xy 160.958607 -60.480242) (xy 160.931352 -60.480702) (xy 160.903983 -60.480205)
			(xy 160.849805 -60.472395) (xy 160.797302 -60.456913) (xy 160.747555 -60.434078) (xy 160.701587 -60.40436)
			(xy 160.680654 -60.386722) (xy 160.6804 -60.386468) (xy 160.67332 -60.380872) (xy 160.656398 -60.374632)
			(xy 160.64738 -60.374276) (xy 160.580324 -60.374276) (xy 160.571309 -60.37465) (xy 160.554392 -60.380886)
			(xy 160.547304 -60.386468) (xy 160.54705 -60.386722) (xy 160.526117 -60.404363) (xy 160.480149 -60.434087)
			(xy 160.430403 -60.456933) (xy 160.377901 -60.472429) (xy 160.323723 -60.480258) (xy 160.268981 -60.480258)
			(xy 160.214803 -60.472429) (xy 160.162301 -60.456933) (xy 160.112555 -60.434087) (xy 160.066587 -60.404363)
			(xy 160.045654 -60.386722) (xy 160.0454 -60.386468) (xy 160.03832 -60.380872) (xy 160.021398 -60.374632)
			(xy 160.01238 -60.374276) (xy 159.945324 -60.374276) (xy 159.936309 -60.37465) (xy 159.919392 -60.380886)
			(xy 159.912304 -60.386468) (xy 159.912304 -60.386722) (xy 159.91205 -60.386722) (xy 159.891113 -60.404355)
			(xy 159.845141 -60.434067) (xy 159.795395 -60.456903) (xy 159.742895 -60.472396) (xy 159.688721 -60.480227)
			(xy 159.661352 -60.480702) (xy 159.634103 -60.480225) (xy 159.580159 -60.472463) (xy 159.527869 -60.457103)
			(xy 159.478297 -60.434459) (xy 159.432452 -60.404991) (xy 159.391267 -60.369299) (xy 159.35558 -60.328109)
			(xy 159.326118 -60.28226) (xy 159.30348 -60.232686) (xy 159.288127 -60.180394) (xy 159.280372 -60.126449)
			(xy 147.91833 -60.126449) (xy 147.901805 -60.1617) (xy 147.871032 -60.208213) (xy 147.833815 -60.24975)
			(xy 147.790947 -60.285425) (xy 147.743341 -60.314479) (xy 147.692012 -60.336291) (xy 147.638055 -60.350397)
			(xy 147.582618 -60.356497) (xy 147.526884 -60.35446) (xy 147.472041 -60.34433) (xy 147.419257 -60.326323)
			(xy 147.369657 -60.300822) (xy 147.324299 -60.268371) (xy 147.28415 -60.229662) (xy 147.250064 -60.185519)
			(xy 147.222768 -60.136884) (xy 147.202845 -60.084793) (xy 147.190719 -60.030356) (xy 147.186648 -59.974734)
			(xy 140.267928 -59.974734) (xy 140.267928 -60.01925) (xy 140.260173 -60.073194) (xy 140.24482 -60.125486)
			(xy 140.222181 -60.175062) (xy 140.192719 -60.220911) (xy 140.157031 -60.2621) (xy 140.115846 -60.297792)
			(xy 140.07 -60.32726) (xy 140.020428 -60.349904) (xy 139.968137 -60.365263) (xy 139.914194 -60.373025)
			(xy 139.886944 -60.373514) (xy 139.859575 -60.373019) (xy 139.805397 -60.365207) (xy 139.752894 -60.349725)
			(xy 139.703147 -60.32689) (xy 139.657179 -60.297172) (xy 139.636246 -60.279534) (xy 139.635992 -60.27928)
			(xy 139.628914 -60.273682) (xy 139.61199 -60.267443) (xy 139.602972 -60.267088) (xy 139.535916 -60.267088)
			(xy 139.5269 -60.267455) (xy 139.509983 -60.273696) (xy 139.502896 -60.27928) (xy 139.502642 -60.279534)
			(xy 139.481709 -60.297175) (xy 139.435741 -60.326899) (xy 139.385995 -60.349745) (xy 139.333493 -60.365241)
			(xy 139.279315 -60.37307) (xy 139.224573 -60.37307) (xy 139.170395 -60.365241) (xy 139.117893 -60.349745)
			(xy 139.068147 -60.326899) (xy 139.022179 -60.297175) (xy 139.001246 -60.279534) (xy 139.000992 -60.27928)
			(xy 138.993914 -60.273682) (xy 138.97699 -60.267443) (xy 138.967972 -60.267088) (xy 138.900916 -60.267088)
			(xy 138.8919 -60.267455) (xy 138.874983 -60.273696) (xy 138.867896 -60.27928) (xy 138.867896 -60.279534)
			(xy 138.867642 -60.279534) (xy 138.846709 -60.297172) (xy 138.800736 -60.326883) (xy 138.750989 -60.349719)
			(xy 138.698488 -60.36521) (xy 138.644313 -60.373039) (xy 138.616944 -60.373514) (xy 138.58969 -60.373042)
			(xy 138.535735 -60.36529) (xy 138.483432 -60.349938) (xy 138.433847 -60.327298) (xy 138.38799 -60.297832)
			(xy 138.346792 -60.262139) (xy 138.311094 -60.220946) (xy 138.281623 -60.175091) (xy 138.258977 -60.125509)
			(xy 138.243619 -60.073208) (xy 138.235861 -60.019254) (xy 135.30484 -60.019254) (xy 135.312416 -60.071949)
			(xy 135.312416 -60.126451) (xy 135.30466 -60.180397) (xy 135.289305 -60.232691) (xy 135.266665 -60.282267)
			(xy 135.237199 -60.328116) (xy 135.201509 -60.369306) (xy 135.16032 -60.404997) (xy 135.11447 -60.434463)
			(xy 135.064895 -60.457104) (xy 135.012601 -60.472459) (xy 134.958655 -60.480216) (xy 134.931404 -60.480702)
			(xy 134.904034 -60.480233) (xy 134.849855 -60.472416) (xy 134.797352 -60.456927) (xy 134.747605 -60.434086)
			(xy 134.701638 -60.404363) (xy 134.680706 -60.386722) (xy 134.680452 -60.386468) (xy 134.673357 -60.380893)
			(xy 134.656447 -60.374641) (xy 134.647432 -60.374276) (xy 134.580376 -60.374276) (xy 134.571359 -60.374627)
			(xy 134.554442 -60.380879) (xy 134.547356 -60.386468) (xy 134.547102 -60.386722) (xy 134.526169 -60.404363)
			(xy 134.480201 -60.434087) (xy 134.430455 -60.456933) (xy 134.377953 -60.472429) (xy 134.323775 -60.480258)
			(xy 134.269033 -60.480258) (xy 134.214855 -60.472429) (xy 134.162353 -60.456933) (xy 134.112607 -60.434087)
			(xy 134.066639 -60.404363) (xy 134.045706 -60.386722) (xy 134.045452 -60.386468) (xy 134.038357 -60.380893)
			(xy 134.021447 -60.374641) (xy 134.012432 -60.374276) (xy 133.945376 -60.374276) (xy 133.936359 -60.374627)
			(xy 133.919442 -60.380879) (xy 133.912356 -60.386468) (xy 133.912356 -60.386722) (xy 133.912102 -60.386722)
			(xy 133.891183 -60.404377) (xy 133.845206 -60.434086) (xy 133.795455 -60.456918) (xy 133.742952 -60.472406)
			(xy 133.688774 -60.48023) (xy 133.661404 -60.480702) (xy 133.634151 -60.480251) (xy 133.580198 -60.472494)
			(xy 133.527899 -60.457138) (xy 133.478318 -60.434496) (xy 133.432463 -60.405027) (xy 133.39127 -60.369333)
			(xy 133.355575 -60.32814) (xy 133.326106 -60.282286) (xy 133.303463 -60.232705) (xy 133.288107 -60.180406)
			(xy 133.280349 -60.126453) (xy 121.91838 -60.126453) (xy 121.901857 -60.1617) (xy 121.871084 -60.208213)
			(xy 121.833867 -60.24975) (xy 121.790999 -60.285425) (xy 121.743393 -60.314479) (xy 121.692064 -60.336291)
			(xy 121.638107 -60.350397) (xy 121.58267 -60.356497) (xy 121.526936 -60.35446) (xy 121.472093 -60.34433)
			(xy 121.419309 -60.326323) (xy 121.369709 -60.300822) (xy 121.324351 -60.268371) (xy 121.284202 -60.229662)
			(xy 121.250116 -60.185519) (xy 121.22282 -60.136884) (xy 121.202897 -60.084793) (xy 121.190771 -60.030356)
			(xy 121.1867 -59.974734) (xy 102.167751 -59.974734) (xy 102.167751 -60.019254) (xy 102.159993 -60.073206)
			(xy 102.144636 -60.125506) (xy 102.121993 -60.175087) (xy 102.092524 -60.220942) (xy 102.056828 -60.262135)
			(xy 102.015634 -60.29783) (xy 101.969779 -60.327298) (xy 101.920196 -60.34994) (xy 101.867897 -60.365295)
			(xy 101.813944 -60.373051) (xy 101.78669 -60.373514) (xy 101.75932 -60.37305) (xy 101.705141 -60.365231)
			(xy 101.652638 -60.349742) (xy 101.602891 -60.326899) (xy 101.556924 -60.297175) (xy 101.535992 -60.279534)
			(xy 101.535738 -60.27928) (xy 101.528646 -60.273701) (xy 101.511733 -60.26745) (xy 101.502718 -60.267088)
			(xy 101.435662 -60.267088) (xy 101.426644 -60.267429) (xy 101.409727 -60.273688) (xy 101.402642 -60.27928)
			(xy 101.402388 -60.279534) (xy 101.381455 -60.297175) (xy 101.335487 -60.326899) (xy 101.285741 -60.349745)
			(xy 101.233239 -60.365241) (xy 101.179061 -60.37307) (xy 101.124319 -60.37307) (xy 101.070141 -60.365241)
			(xy 101.017639 -60.349745) (xy 100.967893 -60.326899) (xy 100.921925 -60.297175) (xy 100.900992 -60.279534)
			(xy 100.900738 -60.27928) (xy 100.893646 -60.273701) (xy 100.876733 -60.26745) (xy 100.867718 -60.267088)
			(xy 100.800662 -60.267088) (xy 100.791644 -60.267429) (xy 100.774727 -60.273688) (xy 100.767642 -60.27928)
			(xy 100.767642 -60.279534) (xy 100.767388 -60.279534) (xy 100.746438 -60.297151) (xy 100.70047 -60.326865)
			(xy 100.650727 -60.349704) (xy 100.59823 -60.365201) (xy 100.544058 -60.373036) (xy 100.51669 -60.373514)
			(xy 100.48944 -60.373016) (xy 100.435494 -60.365258) (xy 100.383201 -60.349902) (xy 100.333626 -60.327261)
			(xy 100.287777 -60.297795) (xy 100.246589 -60.262104) (xy 100.210899 -60.220914) (xy 100.181434 -60.175065)
			(xy 100.158794 -60.12549) (xy 100.14344 -60.073196) (xy 100.135684 -60.01925) (xy 97.204661 -60.01925)
			(xy 97.212239 -60.071945) (xy 97.212239 -60.126455) (xy 97.20448 -60.180409) (xy 97.189122 -60.23271)
			(xy 97.166476 -60.282293) (xy 97.137004 -60.328148) (xy 97.101306 -60.369341) (xy 97.060108 -60.405034)
			(xy 97.014249 -60.4345) (xy 96.964663 -60.45714) (xy 96.91236 -60.472491) (xy 96.858405 -60.480242)
			(xy 96.83115 -60.480702) (xy 96.803781 -60.480206) (xy 96.749603 -60.472395) (xy 96.6971 -60.456913)
			(xy 96.647353 -60.434078) (xy 96.601385 -60.40436) (xy 96.580452 -60.386722) (xy 96.580198 -60.386468)
			(xy 96.573119 -60.380871) (xy 96.556196 -60.374632) (xy 96.547178 -60.374276) (xy 96.480122 -60.374276)
			(xy 96.471107 -60.374649) (xy 96.45419 -60.380886) (xy 96.447102 -60.386468) (xy 96.446848 -60.386722)
			(xy 96.425915 -60.404363) (xy 96.379947 -60.434087) (xy 96.330201 -60.456933) (xy 96.277699 -60.472429)
			(xy 96.223521 -60.480258) (xy 96.168779 -60.480258) (xy 96.114601 -60.472429) (xy 96.062099 -60.456933)
			(xy 96.012353 -60.434087) (xy 95.966385 -60.404363) (xy 95.945452 -60.386722) (xy 95.945198 -60.386468)
			(xy 95.938119 -60.380871) (xy 95.921196 -60.374632) (xy 95.912178 -60.374276) (xy 95.845122 -60.374276)
			(xy 95.836107 -60.374649) (xy 95.81919 -60.380886) (xy 95.812102 -60.386468) (xy 95.812102 -60.386722)
			(xy 95.811848 -60.386722) (xy 95.790911 -60.404355) (xy 95.74494 -60.434067) (xy 95.695193 -60.456904)
			(xy 95.642694 -60.472397) (xy 95.588519 -60.480227) (xy 95.56115 -60.480702) (xy 95.533901 -60.480225)
			(xy 95.479957 -60.472462) (xy 95.427668 -60.457103) (xy 95.378096 -60.434458) (xy 95.332251 -60.40499)
			(xy 95.291066 -60.369298) (xy 95.25538 -60.328109) (xy 95.225918 -60.28226) (xy 95.20328 -60.232685)
			(xy 95.187927 -60.180394) (xy 95.180172 -60.126449) (xy 83.818128 -60.126449) (xy 83.801603 -60.1617)
			(xy 83.77083 -60.208213) (xy 83.733613 -60.24975) (xy 83.690745 -60.285425) (xy 83.643139 -60.314479)
			(xy 83.59181 -60.336291) (xy 83.537853 -60.350397) (xy 83.482416 -60.356497) (xy 83.426682 -60.35446)
			(xy 83.371839 -60.34433) (xy 83.319055 -60.326323) (xy 83.269455 -60.300822) (xy 83.224097 -60.268371)
			(xy 83.183948 -60.229662) (xy 83.149862 -60.185519) (xy 83.122566 -60.136884) (xy 83.102643 -60.084793)
			(xy 83.090517 -60.030356) (xy 83.086446 -59.974734) (xy 76.167728 -59.974734) (xy 76.167728 -60.01925)
			(xy 76.159973 -60.073195) (xy 76.14462 -60.125487) (xy 76.121981 -60.175062) (xy 76.092518 -60.220911)
			(xy 76.056831 -60.262101) (xy 76.015645 -60.297793) (xy 75.969799 -60.327261) (xy 75.920226 -60.349905)
			(xy 75.867936 -60.365264) (xy 75.813992 -60.373025) (xy 75.786742 -60.373514) (xy 75.759373 -60.37302)
			(xy 75.705195 -60.365208) (xy 75.652692 -60.349726) (xy 75.602945 -60.32689) (xy 75.556977 -60.297172)
			(xy 75.536044 -60.279534) (xy 75.53579 -60.27928) (xy 75.528712 -60.273681) (xy 75.511789 -60.267442)
			(xy 75.50277 -60.267088) (xy 75.435714 -60.267088) (xy 75.426698 -60.267454) (xy 75.409781 -60.273696)
			(xy 75.402694 -60.27928) (xy 75.40244 -60.279534) (xy 75.381507 -60.297175) (xy 75.335539 -60.326899)
			(xy 75.285793 -60.349745) (xy 75.233291 -60.365241) (xy 75.179113 -60.37307) (xy 75.124371 -60.37307)
			(xy 75.070193 -60.365241) (xy 75.017691 -60.349745) (xy 74.967945 -60.326899) (xy 74.921977 -60.297175)
			(xy 74.901044 -60.279534) (xy 74.90079 -60.27928) (xy 74.893712 -60.273681) (xy 74.876789 -60.267442)
			(xy 74.86777 -60.267088) (xy 74.800714 -60.267088) (xy 74.791698 -60.267454) (xy 74.774781 -60.273696)
			(xy 74.767694 -60.27928) (xy 74.767694 -60.279534) (xy 74.76744 -60.279534) (xy 74.746508 -60.297173)
			(xy 74.700535 -60.326884) (xy 74.650787 -60.349719) (xy 74.598287 -60.36521) (xy 74.544111 -60.373039)
			(xy 74.516742 -60.373514) (xy 74.489488 -60.373042) (xy 74.435533 -60.36529) (xy 74.383231 -60.349937)
			(xy 74.333646 -60.327298) (xy 74.287789 -60.297831) (xy 74.246592 -60.262138) (xy 74.210894 -60.220945)
			(xy 74.181423 -60.175091) (xy 74.158777 -60.125508) (xy 74.143419 -60.073208) (xy 74.135661 -60.019254)
			(xy 71.20464 -60.019254) (xy 71.212216 -60.071949) (xy 71.212216 -60.126451) (xy 71.20446 -60.180397)
			(xy 71.189105 -60.232691) (xy 71.166464 -60.282268) (xy 71.136999 -60.328117) (xy 71.101308 -60.369307)
			(xy 71.060119 -60.404998) (xy 71.014269 -60.434464) (xy 70.964693 -60.457104) (xy 70.912399 -60.472459)
			(xy 70.858453 -60.480216) (xy 70.831202 -60.480702) (xy 70.803832 -60.480234) (xy 70.749653 -60.472417)
			(xy 70.69715 -60.456928) (xy 70.647403 -60.434087) (xy 70.601436 -60.404363) (xy 70.580504 -60.386722)
			(xy 70.58025 -60.386468) (xy 70.573156 -60.380893) (xy 70.556245 -60.37464) (xy 70.54723 -60.374276)
			(xy 70.480174 -60.374276) (xy 70.471156 -60.374626) (xy 70.45424 -60.380879) (xy 70.447154 -60.386468)
			(xy 70.4469 -60.386722) (xy 70.425967 -60.404363) (xy 70.379999 -60.434087) (xy 70.330253 -60.456933)
			(xy 70.277751 -60.472429) (xy 70.223573 -60.480258) (xy 70.168831 -60.480258) (xy 70.114653 -60.472429)
			(xy 70.062151 -60.456933) (xy 70.012405 -60.434087) (xy 69.966437 -60.404363) (xy 69.945504 -60.386722)
			(xy 69.94525 -60.386468) (xy 69.938156 -60.380893) (xy 69.921245 -60.37464) (xy 69.91223 -60.374276)
			(xy 69.845174 -60.374276) (xy 69.836156 -60.374626) (xy 69.81924 -60.380879) (xy 69.812154 -60.386468)
			(xy 69.812154 -60.386722) (xy 69.8119 -60.386722) (xy 69.790982 -60.404378) (xy 69.745005 -60.434087)
			(xy 69.695254 -60.456919) (xy 69.64275 -60.472406) (xy 69.588572 -60.48023) (xy 69.561202 -60.480702)
			(xy 69.533949 -60.480251) (xy 69.479997 -60.472494) (xy 69.427698 -60.457138) (xy 69.378117 -60.434495)
			(xy 69.332262 -60.405027) (xy 69.291069 -60.369332) (xy 69.255375 -60.328139) (xy 69.225906 -60.282285)
			(xy 69.203263 -60.232704) (xy 69.187907 -60.180405) (xy 69.180149 -60.126453) (xy 57.818178 -60.126453)
			(xy 57.801655 -60.1617) (xy 57.770882 -60.208213) (xy 57.733665 -60.24975) (xy 57.690797 -60.285425)
			(xy 57.643191 -60.314479) (xy 57.591862 -60.336291) (xy 57.537905 -60.350397) (xy 57.482468 -60.356497)
			(xy 57.426734 -60.35446) (xy 57.371891 -60.34433) (xy 57.319107 -60.326323) (xy 57.269507 -60.300822)
			(xy 57.224149 -60.268371) (xy 57.184 -60.229662) (xy 57.149914 -60.185519) (xy 57.122618 -60.136884)
			(xy 57.102695 -60.084793) (xy 57.090569 -60.030356) (xy 57.086498 -59.974734) (xy 50.167851 -59.974734)
			(xy 50.167851 -60.019254) (xy 50.160093 -60.073206) (xy 50.144737 -60.125505) (xy 50.122094 -60.175086)
			(xy 50.092624 -60.22094) (xy 50.05693 -60.262134) (xy 50.015736 -60.297828) (xy 49.969881 -60.327296)
			(xy 49.920299 -60.349939) (xy 49.868 -60.365295) (xy 49.814048 -60.373051) (xy 49.786794 -60.373514)
			(xy 49.759424 -60.373048) (xy 49.705245 -60.36523) (xy 49.652742 -60.34974) (xy 49.602995 -60.326899)
			(xy 49.557028 -60.297175) (xy 49.536096 -60.279534) (xy 49.535842 -60.27928) (xy 49.528749 -60.273703)
			(xy 49.511837 -60.267451) (xy 49.502822 -60.267088) (xy 49.435766 -60.267088) (xy 49.426748 -60.267431)
			(xy 49.409831 -60.273688) (xy 49.402746 -60.27928) (xy 49.402492 -60.279534) (xy 49.381559 -60.297175)
			(xy 49.335591 -60.326899) (xy 49.285845 -60.349745) (xy 49.233343 -60.365241) (xy 49.179165 -60.37307)
			(xy 49.124423 -60.37307) (xy 49.070245 -60.365241) (xy 49.017743 -60.349745) (xy 48.967997 -60.326899)
			(xy 48.922029 -60.297175) (xy 48.901096 -60.279534) (xy 48.900842 -60.27928) (xy 48.893749 -60.273703)
			(xy 48.876837 -60.267451) (xy 48.867822 -60.267088) (xy 48.800766 -60.267088) (xy 48.791748 -60.267431)
			(xy 48.774831 -60.273688) (xy 48.767746 -60.27928) (xy 48.767746 -60.279534) (xy 48.767492 -60.279534)
			(xy 48.746578 -60.297196) (xy 48.7006 -60.326903) (xy 48.650848 -60.349734) (xy 48.598343 -60.36522)
			(xy 48.544164 -60.373043) (xy 48.516794 -60.373514) (xy 48.489543 -60.373016) (xy 48.435597 -60.365259)
			(xy 48.383304 -60.349903) (xy 48.333728 -60.327262) (xy 48.287879 -60.297796) (xy 48.246691 -60.262105)
			(xy 48.211 -60.220916) (xy 48.181535 -60.175066) (xy 48.158895 -60.12549) (xy 48.14354 -60.073197)
			(xy 48.135784 -60.019251) (xy 45.204761 -60.019251) (xy 45.212339 -60.071945) (xy 45.212339 -60.126455)
			(xy 45.20458 -60.180409) (xy 45.189222 -60.232709) (xy 45.166577 -60.282292) (xy 45.137105 -60.328146)
			(xy 45.101407 -60.36934) (xy 45.060209 -60.405033) (xy 45.014351 -60.434499) (xy 44.964766 -60.457138)
			(xy 44.912464 -60.47249) (xy 44.858509 -60.480242) (xy 44.831254 -60.480702) (xy 44.803885 -60.480204)
			(xy 44.749707 -60.472394) (xy 44.697205 -60.456912) (xy 44.647457 -60.434077) (xy 44.601489 -60.40436)
			(xy 44.580556 -60.386722) (xy 44.580302 -60.386468) (xy 44.573222 -60.380873) (xy 44.5563 -60.374632)
			(xy 44.547282 -60.374276) (xy 44.480226 -60.374276) (xy 44.471211 -60.374651) (xy 44.454294 -60.380887)
			(xy 44.447206 -60.386468) (xy 44.446952 -60.386722) (xy 44.426019 -60.404363) (xy 44.380051 -60.434087)
			(xy 44.330305 -60.456933) (xy 44.277803 -60.472429) (xy 44.223625 -60.480258) (xy 44.168883 -60.480258)
			(xy 44.114705 -60.472429) (xy 44.062203 -60.456933) (xy 44.012457 -60.434087) (xy 43.966489 -60.404363)
			(xy 43.945556 -60.386722) (xy 43.945302 -60.386468) (xy 43.938222 -60.380873) (xy 43.9213 -60.374632)
			(xy 43.912282 -60.374276) (xy 43.845226 -60.374276) (xy 43.836211 -60.374651) (xy 43.819294 -60.380887)
			(xy 43.812206 -60.386468) (xy 43.812206 -60.386722) (xy 43.811952 -60.386722) (xy 43.791014 -60.404354)
			(xy 43.745042 -60.434066) (xy 43.695296 -60.456903) (xy 43.642797 -60.472396) (xy 43.588623 -60.480226)
			(xy 43.561254 -60.480702) (xy 43.534004 -60.480225) (xy 43.480061 -60.472463) (xy 43.427771 -60.457104)
			(xy 43.378199 -60.43446) (xy 43.332353 -60.404992) (xy 43.291168 -60.3693) (xy 43.255481 -60.32811)
			(xy 43.226018 -60.282261) (xy 43.20338 -60.232686) (xy 43.188027 -60.180394) (xy 43.180272 -60.12645)
			(xy 31.818232 -60.12645) (xy 31.801707 -60.1617) (xy 31.770934 -60.208213) (xy 31.733717 -60.24975)
			(xy 31.690849 -60.285425) (xy 31.643243 -60.314479) (xy 31.591914 -60.336291) (xy 31.537957 -60.350397)
			(xy 31.48252 -60.356497) (xy 31.426786 -60.35446) (xy 31.371943 -60.34433) (xy 31.319159 -60.326323)
			(xy 31.269559 -60.300822) (xy 31.224201 -60.268371) (xy 31.184052 -60.229662) (xy 31.149966 -60.185519)
			(xy 31.12267 -60.136884) (xy 31.102747 -60.084793) (xy 31.090621 -60.030356) (xy 31.08655 -59.974734)
			(xy 24.167891 -59.974734) (xy 24.167891 -60.019263) (xy 24.160134 -60.073213) (xy 24.144778 -60.125511)
			(xy 24.122135 -60.175091) (xy 24.092667 -60.220944) (xy 24.056973 -60.262136) (xy 24.015781 -60.297829)
			(xy 23.969927 -60.327297) (xy 23.920347 -60.349939) (xy 23.86805 -60.365295) (xy 23.814099 -60.373051)
			(xy 23.786846 -60.373514) (xy 23.759477 -60.373018) (xy 23.705299 -60.365207) (xy 23.652797 -60.349724)
			(xy 23.603049 -60.32689) (xy 23.557081 -60.297172) (xy 23.536148 -60.279534) (xy 23.535894 -60.27928)
			(xy 23.528815 -60.273683) (xy 23.511892 -60.267443) (xy 23.502874 -60.267088) (xy 23.435818 -60.267088)
			(xy 23.426802 -60.267456) (xy 23.409885 -60.273696) (xy 23.402798 -60.27928) (xy 23.402544 -60.279534)
			(xy 23.381611 -60.297175) (xy 23.335643 -60.326899) (xy 23.285897 -60.349745) (xy 23.233395 -60.365241)
			(xy 23.179217 -60.37307) (xy 23.124475 -60.37307) (xy 23.070297 -60.365241) (xy 23.017795 -60.349745)
			(xy 22.968049 -60.326899) (xy 22.922081 -60.297175) (xy 22.901148 -60.279534) (xy 22.900894 -60.27928)
			(xy 22.893815 -60.273683) (xy 22.876892 -60.267443) (xy 22.867874 -60.267088) (xy 22.800818 -60.267088)
			(xy 22.791802 -60.267456) (xy 22.774885 -60.273696) (xy 22.767798 -60.27928) (xy 22.767798 -60.279534)
			(xy 22.767544 -60.279534) (xy 22.746611 -60.297171) (xy 22.700638 -60.326882) (xy 22.65089 -60.349718)
			(xy 22.59839 -60.36521) (xy 22.544215 -60.373039) (xy 22.516846 -60.373514) (xy 22.489595 -60.373036)
			(xy 22.435647 -60.365279) (xy 22.383352 -60.349923) (xy 22.333775 -60.327282) (xy 22.287924 -60.297815)
			(xy 22.246734 -60.262123) (xy 22.211043 -60.220932) (xy 22.181576 -60.175082) (xy 22.158935 -60.125504)
			(xy 22.14358 -60.073209) (xy 22.135824 -60.019261) (xy 19.204741 -60.019261) (xy 19.212316 -60.071949)
			(xy 19.212316 -60.126451) (xy 19.20456 -60.180397) (xy 19.189205 -60.23269) (xy 19.166565 -60.282266)
			(xy 19.1371 -60.328116) (xy 19.101409 -60.369305) (xy 19.060221 -60.404996) (xy 19.014372 -60.434462)
			(xy 18.964796 -60.457103) (xy 18.912503 -60.472459) (xy 18.858557 -60.480216) (xy 18.831306 -60.480702)
			(xy 18.803936 -60.480232) (xy 18.749757 -60.472415) (xy 18.697254 -60.456927) (xy 18.647507 -60.434086)
			(xy 18.60154 -60.404363) (xy 18.580608 -60.386722) (xy 18.580354 -60.386468) (xy 18.573259 -60.380894)
			(xy 18.556349 -60.374641) (xy 18.547334 -60.374276) (xy 18.480278 -60.374276) (xy 18.471261 -60.374627)
			(xy 18.454344 -60.380879) (xy 18.447258 -60.386468) (xy 18.447004 -60.386722) (xy 18.426071 -60.404363)
			(xy 18.380103 -60.434087) (xy 18.330357 -60.456933) (xy 18.277855 -60.472429) (xy 18.223677 -60.480258)
			(xy 18.168935 -60.480258) (xy 18.114757 -60.472429) (xy 18.062255 -60.456933) (xy 18.012509 -60.434087)
			(xy 17.966541 -60.404363) (xy 17.945608 -60.386722) (xy 17.945354 -60.386468) (xy 17.938259 -60.380894)
			(xy 17.921349 -60.374641) (xy 17.912334 -60.374276) (xy 17.845278 -60.374276) (xy 17.836261 -60.374627)
			(xy 17.819344 -60.380879) (xy 17.812258 -60.386468) (xy 17.812258 -60.386722) (xy 17.812004 -60.386722)
			(xy 17.791084 -60.404376) (xy 17.745108 -60.434085) (xy 17.695357 -60.456918) (xy 17.642854 -60.472405)
			(xy 17.588676 -60.48023) (xy 17.561306 -60.480702) (xy 17.534052 -60.480251) (xy 17.4801 -60.472495)
			(xy 17.427801 -60.457139) (xy 17.378219 -60.434496) (xy 17.332364 -60.405028) (xy 17.29117 -60.369334)
			(xy 17.255476 -60.32814) (xy 17.226006 -60.282286) (xy 17.203363 -60.232705) (xy 17.188007 -60.180406)
			(xy 17.180249 -60.126454) (xy 5.818282 -60.126454) (xy 5.801759 -60.1617) (xy 5.770986 -60.208213)
			(xy 5.733769 -60.24975) (xy 5.690901 -60.285425) (xy 5.643295 -60.314479) (xy 5.591966 -60.336291)
			(xy 5.538009 -60.350397) (xy 5.482572 -60.356497) (xy 5.426838 -60.35446) (xy 5.371995 -60.34433)
			(xy 5.319211 -60.326323) (xy 5.269611 -60.300822) (xy 5.224253 -60.268371) (xy 5.184104 -60.229662)
			(xy 5.150018 -60.185519) (xy 5.122722 -60.136884) (xy 5.102799 -60.084793) (xy 5.090673 -60.030356)
			(xy 5.086602 -59.974734) (xy 2.875788 -59.974734) (xy 2.875788 -60.601606) (xy 4.333238 -60.601606)
			(xy 4.337309 -60.545984) (xy 4.349435 -60.491547) (xy 4.369358 -60.439456) (xy 4.396654 -60.390821)
			(xy 4.43074 -60.346678) (xy 4.470889 -60.307969) (xy 4.516247 -60.275518) (xy 4.565847 -60.250017)
			(xy 4.618631 -60.23201) (xy 4.673474 -60.22188) (xy 4.729208 -60.219843) (xy 4.784645 -60.225943)
			(xy 4.838602 -60.240049) (xy 4.889931 -60.261861) (xy 4.937537 -60.290915) (xy 4.980405 -60.32659)
			(xy 5.017622 -60.368127) (xy 5.048395 -60.41464) (xy 5.072067 -60.465137) (xy 5.088135 -60.518544)
			(xy 5.096255 -60.57372) (xy 5.096764 -60.601606) (xy 5.096255 -60.629492) (xy 5.088135 -60.684668)
			(xy 5.072067 -60.738075) (xy 5.051501 -60.781946) (xy 5.674358 -60.781946) (xy 5.678429 -60.726324)
			(xy 5.690555 -60.671887) (xy 5.710478 -60.619796) (xy 5.737774 -60.571161) (xy 5.77186 -60.527018)
			(xy 5.812009 -60.488309) (xy 5.857367 -60.455858) (xy 5.906967 -60.430357) (xy 5.959751 -60.41235)
			(xy 6.014594 -60.40222) (xy 6.070328 -60.400183) (xy 6.125765 -60.406283) (xy 6.179722 -60.420389)
			(xy 6.231051 -60.442201) (xy 6.278657 -60.471255) (xy 6.321525 -60.50693) (xy 6.358742 -60.548467)
			(xy 6.389515 -60.59498) (xy 6.404528 -60.627006) (xy 6.721346 -60.627006) (xy 6.725417 -60.571384)
			(xy 6.737543 -60.516947) (xy 6.757466 -60.464856) (xy 6.784762 -60.416221) (xy 6.818848 -60.372078)
			(xy 6.858997 -60.333369) (xy 6.904355 -60.300918) (xy 6.953955 -60.275417) (xy 7.006739 -60.25741)
			(xy 7.061582 -60.24728) (xy 7.117316 -60.245243) (xy 7.172753 -60.251343) (xy 7.22671 -60.265449)
			(xy 7.278039 -60.287261) (xy 7.325645 -60.316315) (xy 7.368513 -60.35199) (xy 7.40573 -60.393527)
			(xy 7.436503 -60.44004) (xy 7.460175 -60.490537) (xy 7.476243 -60.543944) (xy 7.484363 -60.59912)
			(xy 7.484872 -60.627006) (xy 7.484756 -60.633356) (xy 7.797036 -60.633356) (xy 7.801107 -60.577734)
			(xy 7.813233 -60.523297) (xy 7.833156 -60.471206) (xy 7.860452 -60.422571) (xy 7.894538 -60.378428)
			(xy 7.934687 -60.339719) (xy 7.980045 -60.307268) (xy 8.029645 -60.281767) (xy 8.082429 -60.26376)
			(xy 8.137272 -60.25363) (xy 8.193006 -60.251593) (xy 8.248443 -60.257693) (xy 8.3024 -60.271799)
			(xy 8.353729 -60.293611) (xy 8.401335 -60.322665) (xy 8.444203 -60.35834) (xy 8.48142 -60.399877)
			(xy 8.512193 -60.44639) (xy 8.535865 -60.496887) (xy 8.551933 -60.550294) (xy 8.560053 -60.60547)
			(xy 8.560562 -60.633356) (xy 8.813036 -60.633356) (xy 8.817107 -60.577734) (xy 8.829233 -60.523297)
			(xy 8.849156 -60.471206) (xy 8.876452 -60.422571) (xy 8.910538 -60.378428) (xy 8.950687 -60.339719)
			(xy 8.996045 -60.307268) (xy 9.045645 -60.281767) (xy 9.098429 -60.26376) (xy 9.153272 -60.25363)
			(xy 9.209006 -60.251593) (xy 9.264443 -60.257693) (xy 9.3184 -60.271799) (xy 9.369729 -60.293611)
			(xy 9.417335 -60.322665) (xy 9.460203 -60.35834) (xy 9.49742 -60.399877) (xy 9.528193 -60.44639)
			(xy 9.551865 -60.496887) (xy 9.567933 -60.550294) (xy 9.575484 -60.601606) (xy 30.333186 -60.601606)
			(xy 30.337257 -60.545984) (xy 30.349383 -60.491547) (xy 30.369306 -60.439456) (xy 30.396602 -60.390821)
			(xy 30.430688 -60.346678) (xy 30.470837 -60.307969) (xy 30.516195 -60.275518) (xy 30.565795 -60.250017)
			(xy 30.618579 -60.23201) (xy 30.673422 -60.22188) (xy 30.729156 -60.219843) (xy 30.784593 -60.225943)
			(xy 30.83855 -60.240049) (xy 30.889879 -60.261861) (xy 30.937485 -60.290915) (xy 30.980353 -60.32659)
			(xy 31.01757 -60.368127) (xy 31.048343 -60.41464) (xy 31.072015 -60.465137) (xy 31.088083 -60.518544)
			(xy 31.096203 -60.57372) (xy 31.096712 -60.601606) (xy 31.096248 -60.627006) (xy 32.721294 -60.627006)
			(xy 32.725365 -60.571384) (xy 32.737491 -60.516947) (xy 32.757414 -60.464856) (xy 32.78471 -60.416221)
			(xy 32.818796 -60.372078) (xy 32.858945 -60.333369) (xy 32.904303 -60.300918) (xy 32.953903 -60.275417)
			(xy 33.006687 -60.25741) (xy 33.06153 -60.24728) (xy 33.117264 -60.245243) (xy 33.172701 -60.251343)
			(xy 33.226658 -60.265449) (xy 33.277987 -60.287261) (xy 33.325593 -60.316315) (xy 33.368461 -60.35199)
			(xy 33.405678 -60.393527) (xy 33.436451 -60.44004) (xy 33.460123 -60.490537) (xy 33.476191 -60.543944)
			(xy 33.484311 -60.59912) (xy 33.48482 -60.627006) (xy 33.484704 -60.633356) (xy 33.796984 -60.633356)
			(xy 33.801055 -60.577734) (xy 33.813181 -60.523297) (xy 33.833104 -60.471206) (xy 33.8604 -60.422571)
			(xy 33.894486 -60.378428) (xy 33.934635 -60.339719) (xy 33.979993 -60.307268) (xy 34.029593 -60.281767)
			(xy 34.082377 -60.26376) (xy 34.13722 -60.25363) (xy 34.192954 -60.251593) (xy 34.248391 -60.257693)
			(xy 34.302348 -60.271799) (xy 34.353677 -60.293611) (xy 34.401283 -60.322665) (xy 34.444151 -60.35834)
			(xy 34.481368 -60.399877) (xy 34.512141 -60.44639) (xy 34.535813 -60.496887) (xy 34.551881 -60.550294)
			(xy 34.560001 -60.60547) (xy 34.56051 -60.633356) (xy 34.813494 -60.633356) (xy 34.81398 -60.606105)
			(xy 34.821736 -60.552157) (xy 34.837091 -60.499862) (xy 34.859733 -60.450285) (xy 34.889199 -60.404435)
			(xy 34.92489 -60.363244) (xy 34.966081 -60.327553) (xy 35.011931 -60.298087) (xy 35.061508 -60.275445)
			(xy 35.113803 -60.26009) (xy 35.167751 -60.252334) (xy 35.222253 -60.252334) (xy 35.276201 -60.26009)
			(xy 35.328496 -60.275445) (xy 35.378073 -60.298087) (xy 35.423923 -60.327553) (xy 35.465114 -60.363244)
			(xy 35.500805 -60.404435) (xy 35.530271 -60.450285) (xy 35.552913 -60.499862) (xy 35.568268 -60.552157)
			(xy 35.575377 -60.601606) (xy 56.333134 -60.601606) (xy 56.337205 -60.545984) (xy 56.349331 -60.491547)
			(xy 56.369254 -60.439456) (xy 56.39655 -60.390821) (xy 56.430636 -60.346678) (xy 56.470785 -60.307969)
			(xy 56.516143 -60.275518) (xy 56.565743 -60.250017) (xy 56.618527 -60.23201) (xy 56.67337 -60.22188)
			(xy 56.729104 -60.219843) (xy 56.784541 -60.225943) (xy 56.838498 -60.240049) (xy 56.889827 -60.261861)
			(xy 56.937433 -60.290915) (xy 56.980301 -60.32659) (xy 57.017518 -60.368127) (xy 57.048291 -60.41464)
			(xy 57.071963 -60.465137) (xy 57.088031 -60.518544) (xy 57.096151 -60.57372) (xy 57.09666 -60.601606)
			(xy 57.096196 -60.627006) (xy 58.721242 -60.627006) (xy 58.725313 -60.571384) (xy 58.737439 -60.516947)
			(xy 58.757362 -60.464856) (xy 58.784658 -60.416221) (xy 58.818744 -60.372078) (xy 58.858893 -60.333369)
			(xy 58.904251 -60.300918) (xy 58.953851 -60.275417) (xy 59.006635 -60.25741) (xy 59.061478 -60.24728)
			(xy 59.117212 -60.245243) (xy 59.172649 -60.251343) (xy 59.226606 -60.265449) (xy 59.277935 -60.287261)
			(xy 59.325541 -60.316315) (xy 59.368409 -60.35199) (xy 59.405626 -60.393527) (xy 59.436399 -60.44004)
			(xy 59.460071 -60.490537) (xy 59.476139 -60.543944) (xy 59.484259 -60.59912) (xy 59.484768 -60.627006)
			(xy 59.484652 -60.633356) (xy 59.796932 -60.633356) (xy 59.801003 -60.577734) (xy 59.813129 -60.523297)
			(xy 59.833052 -60.471206) (xy 59.860348 -60.422571) (xy 59.894434 -60.378428) (xy 59.934583 -60.339719)
			(xy 59.979941 -60.307268) (xy 60.029541 -60.281767) (xy 60.082325 -60.26376) (xy 60.137168 -60.25363)
			(xy 60.192902 -60.251593) (xy 60.248339 -60.257693) (xy 60.302296 -60.271799) (xy 60.353625 -60.293611)
			(xy 60.401231 -60.322665) (xy 60.444099 -60.35834) (xy 60.481316 -60.399877) (xy 60.512089 -60.44639)
			(xy 60.535761 -60.496887) (xy 60.551829 -60.550294) (xy 60.559949 -60.60547) (xy 60.560458 -60.633356)
			(xy 60.812932 -60.633356) (xy 60.817003 -60.577734) (xy 60.829129 -60.523297) (xy 60.849052 -60.471206)
			(xy 60.876348 -60.422571) (xy 60.910434 -60.378428) (xy 60.950583 -60.339719) (xy 60.995941 -60.307268)
			(xy 61.045541 -60.281767) (xy 61.098325 -60.26376) (xy 61.153168 -60.25363) (xy 61.208902 -60.251593)
			(xy 61.264339 -60.257693) (xy 61.318296 -60.271799) (xy 61.369625 -60.293611) (xy 61.417231 -60.322665)
			(xy 61.460099 -60.35834) (xy 61.497316 -60.399877) (xy 61.528089 -60.44639) (xy 61.551761 -60.496887)
			(xy 61.567829 -60.550294) (xy 61.57538 -60.601606) (xy 82.333082 -60.601606) (xy 82.337153 -60.545984)
			(xy 82.349279 -60.491547) (xy 82.369202 -60.439456) (xy 82.396498 -60.390821) (xy 82.430584 -60.346678)
			(xy 82.470733 -60.307969) (xy 82.516091 -60.275518) (xy 82.565691 -60.250017) (xy 82.618475 -60.23201)
			(xy 82.673318 -60.22188) (xy 82.729052 -60.219843) (xy 82.784489 -60.225943) (xy 82.838446 -60.240049)
			(xy 82.889775 -60.261861) (xy 82.937381 -60.290915) (xy 82.980249 -60.32659) (xy 83.017466 -60.368127)
			(xy 83.048239 -60.41464) (xy 83.071911 -60.465137) (xy 83.087979 -60.518544) (xy 83.096099 -60.57372)
			(xy 83.096608 -60.601606) (xy 83.096144 -60.627006) (xy 84.72119 -60.627006) (xy 84.725261 -60.571384)
			(xy 84.737387 -60.516947) (xy 84.75731 -60.464856) (xy 84.784606 -60.416221) (xy 84.818692 -60.372078)
			(xy 84.858841 -60.333369) (xy 84.904199 -60.300918) (xy 84.953799 -60.275417) (xy 85.006583 -60.25741)
			(xy 85.061426 -60.24728) (xy 85.11716 -60.245243) (xy 85.172597 -60.251343) (xy 85.226554 -60.265449)
			(xy 85.277883 -60.287261) (xy 85.325489 -60.316315) (xy 85.368357 -60.35199) (xy 85.405574 -60.393527)
			(xy 85.436347 -60.44004) (xy 85.460019 -60.490537) (xy 85.476087 -60.543944) (xy 85.484207 -60.59912)
			(xy 85.484716 -60.627006) (xy 85.4846 -60.633356) (xy 85.79688 -60.633356) (xy 85.800951 -60.577734)
			(xy 85.813077 -60.523297) (xy 85.833 -60.471206) (xy 85.860296 -60.422571) (xy 85.894382 -60.378428)
			(xy 85.934531 -60.339719) (xy 85.979889 -60.307268) (xy 86.029489 -60.281767) (xy 86.082273 -60.26376)
			(xy 86.137116 -60.25363) (xy 86.19285 -60.251593) (xy 86.248287 -60.257693) (xy 86.302244 -60.271799)
			(xy 86.353573 -60.293611) (xy 86.401179 -60.322665) (xy 86.444047 -60.35834) (xy 86.481264 -60.399877)
			(xy 86.512037 -60.44639) (xy 86.535709 -60.496887) (xy 86.551777 -60.550294) (xy 86.559897 -60.60547)
			(xy 86.560406 -60.633356) (xy 86.81288 -60.633356) (xy 86.816951 -60.577734) (xy 86.829077 -60.523297)
			(xy 86.849 -60.471206) (xy 86.876296 -60.422571) (xy 86.910382 -60.378428) (xy 86.950531 -60.339719)
			(xy 86.995889 -60.307268) (xy 87.045489 -60.281767) (xy 87.098273 -60.26376) (xy 87.153116 -60.25363)
			(xy 87.20885 -60.251593) (xy 87.264287 -60.257693) (xy 87.318244 -60.271799) (xy 87.369573 -60.293611)
			(xy 87.417179 -60.322665) (xy 87.460047 -60.35834) (xy 87.497264 -60.399877) (xy 87.528037 -60.44639)
			(xy 87.551709 -60.496887) (xy 87.567777 -60.550294) (xy 87.575328 -60.601606) (xy 120.433336 -60.601606)
			(xy 120.437407 -60.545984) (xy 120.449533 -60.491547) (xy 120.469456 -60.439456) (xy 120.496752 -60.390821)
			(xy 120.530838 -60.346678) (xy 120.570987 -60.307969) (xy 120.616345 -60.275518) (xy 120.665945 -60.250017)
			(xy 120.718729 -60.23201) (xy 120.773572 -60.22188) (xy 120.829306 -60.219843) (xy 120.884743 -60.225943)
			(xy 120.9387 -60.240049) (xy 120.990029 -60.261861) (xy 121.037635 -60.290915) (xy 121.080503 -60.32659)
			(xy 121.11772 -60.368127) (xy 121.148493 -60.41464) (xy 121.172165 -60.465137) (xy 121.188233 -60.518544)
			(xy 121.196353 -60.57372) (xy 121.196862 -60.601606) (xy 121.196398 -60.627006) (xy 122.821444 -60.627006)
			(xy 122.825515 -60.571384) (xy 122.837641 -60.516947) (xy 122.857564 -60.464856) (xy 122.88486 -60.416221)
			(xy 122.918946 -60.372078) (xy 122.959095 -60.333369) (xy 123.004453 -60.300918) (xy 123.054053 -60.275417)
			(xy 123.106837 -60.25741) (xy 123.16168 -60.24728) (xy 123.217414 -60.245243) (xy 123.272851 -60.251343)
			(xy 123.326808 -60.265449) (xy 123.378137 -60.287261) (xy 123.425743 -60.316315) (xy 123.468611 -60.35199)
			(xy 123.505828 -60.393527) (xy 123.536601 -60.44004) (xy 123.560273 -60.490537) (xy 123.576341 -60.543944)
			(xy 123.584461 -60.59912) (xy 123.58497 -60.627006) (xy 123.584854 -60.633356) (xy 123.897134 -60.633356)
			(xy 123.901205 -60.577734) (xy 123.913331 -60.523297) (xy 123.933254 -60.471206) (xy 123.96055 -60.422571)
			(xy 123.994636 -60.378428) (xy 124.034785 -60.339719) (xy 124.080143 -60.307268) (xy 124.129743 -60.281767)
			(xy 124.182527 -60.26376) (xy 124.23737 -60.25363) (xy 124.293104 -60.251593) (xy 124.348541 -60.257693)
			(xy 124.402498 -60.271799) (xy 124.453827 -60.293611) (xy 124.501433 -60.322665) (xy 124.544301 -60.35834)
			(xy 124.581518 -60.399877) (xy 124.612291 -60.44639) (xy 124.635963 -60.496887) (xy 124.652031 -60.550294)
			(xy 124.660151 -60.60547) (xy 124.66066 -60.633356) (xy 124.913134 -60.633356) (xy 124.917205 -60.577734)
			(xy 124.929331 -60.523297) (xy 124.949254 -60.471206) (xy 124.97655 -60.422571) (xy 125.010636 -60.378428)
			(xy 125.050785 -60.339719) (xy 125.096143 -60.307268) (xy 125.145743 -60.281767) (xy 125.198527 -60.26376)
			(xy 125.25337 -60.25363) (xy 125.309104 -60.251593) (xy 125.364541 -60.257693) (xy 125.418498 -60.271799)
			(xy 125.469827 -60.293611) (xy 125.517433 -60.322665) (xy 125.560301 -60.35834) (xy 125.597518 -60.399877)
			(xy 125.628291 -60.44639) (xy 125.651963 -60.496887) (xy 125.668031 -60.550294) (xy 125.675582 -60.601606)
			(xy 146.433284 -60.601606) (xy 146.437355 -60.545984) (xy 146.449481 -60.491547) (xy 146.469404 -60.439456)
			(xy 146.4967 -60.390821) (xy 146.530786 -60.346678) (xy 146.570935 -60.307969) (xy 146.616293 -60.275518)
			(xy 146.665893 -60.250017) (xy 146.718677 -60.23201) (xy 146.77352 -60.22188) (xy 146.829254 -60.219843)
			(xy 146.884691 -60.225943) (xy 146.938648 -60.240049) (xy 146.989977 -60.261861) (xy 147.037583 -60.290915)
			(xy 147.080451 -60.32659) (xy 147.117668 -60.368127) (xy 147.148441 -60.41464) (xy 147.172113 -60.465137)
			(xy 147.188181 -60.518544) (xy 147.196301 -60.57372) (xy 147.19681 -60.601606) (xy 147.196346 -60.627006)
			(xy 148.821392 -60.627006) (xy 148.825463 -60.571384) (xy 148.837589 -60.516947) (xy 148.857512 -60.464856)
			(xy 148.884808 -60.416221) (xy 148.918894 -60.372078) (xy 148.959043 -60.333369) (xy 149.004401 -60.300918)
			(xy 149.054001 -60.275417) (xy 149.106785 -60.25741) (xy 149.161628 -60.24728) (xy 149.217362 -60.245243)
			(xy 149.272799 -60.251343) (xy 149.326756 -60.265449) (xy 149.378085 -60.287261) (xy 149.425691 -60.316315)
			(xy 149.468559 -60.35199) (xy 149.505776 -60.393527) (xy 149.536549 -60.44004) (xy 149.560221 -60.490537)
			(xy 149.576289 -60.543944) (xy 149.584409 -60.59912) (xy 149.584918 -60.627006) (xy 149.584802 -60.633356)
			(xy 149.897082 -60.633356) (xy 149.901153 -60.577734) (xy 149.913279 -60.523297) (xy 149.933202 -60.471206)
			(xy 149.960498 -60.422571) (xy 149.994584 -60.378428) (xy 150.034733 -60.339719) (xy 150.080091 -60.307268)
			(xy 150.129691 -60.281767) (xy 150.182475 -60.26376) (xy 150.237318 -60.25363) (xy 150.293052 -60.251593)
			(xy 150.348489 -60.257693) (xy 150.402446 -60.271799) (xy 150.453775 -60.293611) (xy 150.501381 -60.322665)
			(xy 150.544249 -60.35834) (xy 150.581466 -60.399877) (xy 150.612239 -60.44639) (xy 150.635911 -60.496887)
			(xy 150.651979 -60.550294) (xy 150.660099 -60.60547) (xy 150.660608 -60.633356) (xy 150.913082 -60.633356)
			(xy 150.917153 -60.577734) (xy 150.929279 -60.523297) (xy 150.949202 -60.471206) (xy 150.976498 -60.422571)
			(xy 151.010584 -60.378428) (xy 151.050733 -60.339719) (xy 151.096091 -60.307268) (xy 151.145691 -60.281767)
			(xy 151.198475 -60.26376) (xy 151.253318 -60.25363) (xy 151.309052 -60.251593) (xy 151.364489 -60.257693)
			(xy 151.418446 -60.271799) (xy 151.469775 -60.293611) (xy 151.517381 -60.322665) (xy 151.560249 -60.35834)
			(xy 151.597466 -60.399877) (xy 151.628239 -60.44639) (xy 151.651911 -60.496887) (xy 151.667979 -60.550294)
			(xy 151.67553 -60.601606) (xy 172.433232 -60.601606) (xy 172.437303 -60.545984) (xy 172.449429 -60.491547)
			(xy 172.469352 -60.439456) (xy 172.496648 -60.390821) (xy 172.530734 -60.346678) (xy 172.570883 -60.307969)
			(xy 172.616241 -60.275518) (xy 172.665841 -60.250017) (xy 172.718625 -60.23201) (xy 172.773468 -60.22188)
			(xy 172.829202 -60.219843) (xy 172.884639 -60.225943) (xy 172.938596 -60.240049) (xy 172.989925 -60.261861)
			(xy 173.037531 -60.290915) (xy 173.080399 -60.32659) (xy 173.117616 -60.368127) (xy 173.148389 -60.41464)
			(xy 173.172061 -60.465137) (xy 173.188129 -60.518544) (xy 173.196249 -60.57372) (xy 173.196758 -60.601606)
			(xy 173.196294 -60.627006) (xy 174.82134 -60.627006) (xy 174.825411 -60.571384) (xy 174.837537 -60.516947)
			(xy 174.85746 -60.464856) (xy 174.884756 -60.416221) (xy 174.918842 -60.372078) (xy 174.958991 -60.333369)
			(xy 175.004349 -60.300918) (xy 175.053949 -60.275417) (xy 175.106733 -60.25741) (xy 175.161576 -60.24728)
			(xy 175.21731 -60.245243) (xy 175.272747 -60.251343) (xy 175.326704 -60.265449) (xy 175.378033 -60.287261)
			(xy 175.425639 -60.316315) (xy 175.468507 -60.35199) (xy 175.505724 -60.393527) (xy 175.536497 -60.44004)
			(xy 175.560169 -60.490537) (xy 175.576237 -60.543944) (xy 175.584357 -60.59912) (xy 175.584866 -60.627006)
			(xy 175.58475 -60.633356) (xy 175.89703 -60.633356) (xy 175.901101 -60.577734) (xy 175.913227 -60.523297)
			(xy 175.93315 -60.471206) (xy 175.960446 -60.422571) (xy 175.994532 -60.378428) (xy 176.034681 -60.339719)
			(xy 176.080039 -60.307268) (xy 176.129639 -60.281767) (xy 176.182423 -60.26376) (xy 176.237266 -60.25363)
			(xy 176.293 -60.251593) (xy 176.348437 -60.257693) (xy 176.402394 -60.271799) (xy 176.453723 -60.293611)
			(xy 176.501329 -60.322665) (xy 176.544197 -60.35834) (xy 176.581414 -60.399877) (xy 176.612187 -60.44639)
			(xy 176.635859 -60.496887) (xy 176.651927 -60.550294) (xy 176.660047 -60.60547) (xy 176.660556 -60.633356)
			(xy 176.91303 -60.633356) (xy 176.917101 -60.577734) (xy 176.929227 -60.523297) (xy 176.94915 -60.471206)
			(xy 176.976446 -60.422571) (xy 177.010532 -60.378428) (xy 177.050681 -60.339719) (xy 177.096039 -60.307268)
			(xy 177.145639 -60.281767) (xy 177.198423 -60.26376) (xy 177.253266 -60.25363) (xy 177.309 -60.251593)
			(xy 177.364437 -60.257693) (xy 177.418394 -60.271799) (xy 177.469723 -60.293611) (xy 177.517329 -60.322665)
			(xy 177.560197 -60.35834) (xy 177.597414 -60.399877) (xy 177.628187 -60.44639) (xy 177.651859 -60.496887)
			(xy 177.667927 -60.550294) (xy 177.675478 -60.601606) (xy 198.43318 -60.601606) (xy 198.437251 -60.545984)
			(xy 198.449377 -60.491547) (xy 198.4693 -60.439456) (xy 198.496596 -60.390821) (xy 198.530682 -60.346678)
			(xy 198.570831 -60.307969) (xy 198.616189 -60.275518) (xy 198.665789 -60.250017) (xy 198.718573 -60.23201)
			(xy 198.773416 -60.22188) (xy 198.82915 -60.219843) (xy 198.884587 -60.225943) (xy 198.938544 -60.240049)
			(xy 198.989873 -60.261861) (xy 199.037479 -60.290915) (xy 199.080347 -60.32659) (xy 199.117564 -60.368127)
			(xy 199.148337 -60.41464) (xy 199.172009 -60.465137) (xy 199.188077 -60.518544) (xy 199.196197 -60.57372)
			(xy 199.196706 -60.601606) (xy 199.196242 -60.627006) (xy 200.821288 -60.627006) (xy 200.825359 -60.571384)
			(xy 200.837485 -60.516947) (xy 200.857408 -60.464856) (xy 200.884704 -60.416221) (xy 200.91879 -60.372078)
			(xy 200.958939 -60.333369) (xy 201.004297 -60.300918) (xy 201.053897 -60.275417) (xy 201.106681 -60.25741)
			(xy 201.161524 -60.24728) (xy 201.217258 -60.245243) (xy 201.272695 -60.251343) (xy 201.326652 -60.265449)
			(xy 201.377981 -60.287261) (xy 201.425587 -60.316315) (xy 201.468455 -60.35199) (xy 201.505672 -60.393527)
			(xy 201.536445 -60.44004) (xy 201.560117 -60.490537) (xy 201.576185 -60.543944) (xy 201.584305 -60.59912)
			(xy 201.584814 -60.627006) (xy 201.584698 -60.633356) (xy 201.896978 -60.633356) (xy 201.901049 -60.577734)
			(xy 201.913175 -60.523297) (xy 201.933098 -60.471206) (xy 201.960394 -60.422571) (xy 201.99448 -60.378428)
			(xy 202.034629 -60.339719) (xy 202.079987 -60.307268) (xy 202.129587 -60.281767) (xy 202.182371 -60.26376)
			(xy 202.237214 -60.25363) (xy 202.292948 -60.251593) (xy 202.348385 -60.257693) (xy 202.402342 -60.271799)
			(xy 202.453671 -60.293611) (xy 202.501277 -60.322665) (xy 202.544145 -60.35834) (xy 202.581362 -60.399877)
			(xy 202.612135 -60.44639) (xy 202.635807 -60.496887) (xy 202.651875 -60.550294) (xy 202.659995 -60.60547)
			(xy 202.660504 -60.633356) (xy 202.912978 -60.633356) (xy 202.917049 -60.577734) (xy 202.929175 -60.523297)
			(xy 202.949098 -60.471206) (xy 202.976394 -60.422571) (xy 203.01048 -60.378428) (xy 203.050629 -60.339719)
			(xy 203.095987 -60.307268) (xy 203.145587 -60.281767) (xy 203.198371 -60.26376) (xy 203.253214 -60.25363)
			(xy 203.308948 -60.251593) (xy 203.364385 -60.257693) (xy 203.418342 -60.271799) (xy 203.469671 -60.293611)
			(xy 203.517277 -60.322665) (xy 203.560145 -60.35834) (xy 203.597362 -60.399877) (xy 203.628135 -60.44639)
			(xy 203.651807 -60.496887) (xy 203.667875 -60.550294) (xy 203.675995 -60.60547) (xy 203.676504 -60.633356)
			(xy 203.675995 -60.661242) (xy 203.667875 -60.716418) (xy 203.651807 -60.769825) (xy 203.628135 -60.820322)
			(xy 203.597362 -60.866835) (xy 203.560145 -60.908372) (xy 203.517277 -60.944047) (xy 203.469671 -60.973101)
			(xy 203.418342 -60.994913) (xy 203.364385 -61.009019) (xy 203.308948 -61.015119) (xy 203.253214 -61.013082)
			(xy 203.198371 -61.002952) (xy 203.145587 -60.984945) (xy 203.095987 -60.959444) (xy 203.050629 -60.926993)
			(xy 203.01048 -60.888284) (xy 202.976394 -60.844141) (xy 202.949098 -60.795506) (xy 202.929175 -60.743415)
			(xy 202.917049 -60.688978) (xy 202.912978 -60.633356) (xy 202.660504 -60.633356) (xy 202.659995 -60.661242)
			(xy 202.651875 -60.716418) (xy 202.635807 -60.769825) (xy 202.612135 -60.820322) (xy 202.581362 -60.866835)
			(xy 202.544145 -60.908372) (xy 202.501277 -60.944047) (xy 202.453671 -60.973101) (xy 202.402342 -60.994913)
			(xy 202.348385 -61.009019) (xy 202.292948 -61.015119) (xy 202.237214 -61.013082) (xy 202.182371 -61.002952)
			(xy 202.129587 -60.984945) (xy 202.079987 -60.959444) (xy 202.034629 -60.926993) (xy 201.99448 -60.888284)
			(xy 201.960394 -60.844141) (xy 201.933098 -60.795506) (xy 201.913175 -60.743415) (xy 201.901049 -60.688978)
			(xy 201.896978 -60.633356) (xy 201.584698 -60.633356) (xy 201.584305 -60.654892) (xy 201.576185 -60.710068)
			(xy 201.560117 -60.763475) (xy 201.536445 -60.813972) (xy 201.505672 -60.860485) (xy 201.468455 -60.902022)
			(xy 201.425587 -60.937697) (xy 201.377981 -60.966751) (xy 201.326652 -60.988563) (xy 201.272695 -61.002669)
			(xy 201.217258 -61.008769) (xy 201.161524 -61.006732) (xy 201.106681 -60.996602) (xy 201.053897 -60.978595)
			(xy 201.004297 -60.953094) (xy 200.958939 -60.920643) (xy 200.91879 -60.881934) (xy 200.884704 -60.837791)
			(xy 200.857408 -60.789156) (xy 200.837485 -60.737065) (xy 200.825359 -60.682628) (xy 200.821288 -60.627006)
			(xy 199.196242 -60.627006) (xy 199.196197 -60.629492) (xy 199.188077 -60.684668) (xy 199.172009 -60.738075)
			(xy 199.148337 -60.788572) (xy 199.117564 -60.835085) (xy 199.080347 -60.876622) (xy 199.037479 -60.912297)
			(xy 198.989873 -60.941351) (xy 198.938544 -60.963163) (xy 198.884587 -60.977269) (xy 198.82915 -60.983369)
			(xy 198.773416 -60.981332) (xy 198.718573 -60.971202) (xy 198.665789 -60.953195) (xy 198.616189 -60.927694)
			(xy 198.570831 -60.895243) (xy 198.530682 -60.856534) (xy 198.496596 -60.812391) (xy 198.4693 -60.763756)
			(xy 198.449377 -60.711665) (xy 198.437251 -60.657228) (xy 198.43318 -60.601606) (xy 177.675478 -60.601606)
			(xy 177.676047 -60.60547) (xy 177.676556 -60.633356) (xy 177.676047 -60.661242) (xy 177.667927 -60.716418)
			(xy 177.651859 -60.769825) (xy 177.628187 -60.820322) (xy 177.597414 -60.866835) (xy 177.560197 -60.908372)
			(xy 177.517329 -60.944047) (xy 177.469723 -60.973101) (xy 177.418394 -60.994913) (xy 177.364437 -61.009019)
			(xy 177.309 -61.015119) (xy 177.253266 -61.013082) (xy 177.198423 -61.002952) (xy 177.145639 -60.984945)
			(xy 177.096039 -60.959444) (xy 177.050681 -60.926993) (xy 177.010532 -60.888284) (xy 176.976446 -60.844141)
			(xy 176.94915 -60.795506) (xy 176.929227 -60.743415) (xy 176.917101 -60.688978) (xy 176.91303 -60.633356)
			(xy 176.660556 -60.633356) (xy 176.660047 -60.661242) (xy 176.651927 -60.716418) (xy 176.635859 -60.769825)
			(xy 176.612187 -60.820322) (xy 176.581414 -60.866835) (xy 176.544197 -60.908372) (xy 176.501329 -60.944047)
			(xy 176.453723 -60.973101) (xy 176.402394 -60.994913) (xy 176.348437 -61.009019) (xy 176.293 -61.015119)
			(xy 176.237266 -61.013082) (xy 176.182423 -61.002952) (xy 176.129639 -60.984945) (xy 176.080039 -60.959444)
			(xy 176.034681 -60.926993) (xy 175.994532 -60.888284) (xy 175.960446 -60.844141) (xy 175.93315 -60.795506)
			(xy 175.913227 -60.743415) (xy 175.901101 -60.688978) (xy 175.89703 -60.633356) (xy 175.58475 -60.633356)
			(xy 175.584357 -60.654892) (xy 175.576237 -60.710068) (xy 175.560169 -60.763475) (xy 175.536497 -60.813972)
			(xy 175.505724 -60.860485) (xy 175.468507 -60.902022) (xy 175.425639 -60.937697) (xy 175.378033 -60.966751)
			(xy 175.326704 -60.988563) (xy 175.272747 -61.002669) (xy 175.21731 -61.008769) (xy 175.161576 -61.006732)
			(xy 175.106733 -60.996602) (xy 175.053949 -60.978595) (xy 175.004349 -60.953094) (xy 174.958991 -60.920643)
			(xy 174.918842 -60.881934) (xy 174.884756 -60.837791) (xy 174.85746 -60.789156) (xy 174.837537 -60.737065)
			(xy 174.825411 -60.682628) (xy 174.82134 -60.627006) (xy 173.196294 -60.627006) (xy 173.196249 -60.629492)
			(xy 173.188129 -60.684668) (xy 173.172061 -60.738075) (xy 173.148389 -60.788572) (xy 173.117616 -60.835085)
			(xy 173.080399 -60.876622) (xy 173.037531 -60.912297) (xy 172.989925 -60.941351) (xy 172.938596 -60.963163)
			(xy 172.884639 -60.977269) (xy 172.829202 -60.983369) (xy 172.773468 -60.981332) (xy 172.718625 -60.971202)
			(xy 172.665841 -60.953195) (xy 172.616241 -60.927694) (xy 172.570883 -60.895243) (xy 172.530734 -60.856534)
			(xy 172.496648 -60.812391) (xy 172.469352 -60.763756) (xy 172.449429 -60.711665) (xy 172.437303 -60.657228)
			(xy 172.433232 -60.601606) (xy 151.67553 -60.601606) (xy 151.676099 -60.60547) (xy 151.676608 -60.633356)
			(xy 151.676099 -60.661242) (xy 151.667979 -60.716418) (xy 151.651911 -60.769825) (xy 151.628239 -60.820322)
			(xy 151.597466 -60.866835) (xy 151.560249 -60.908372) (xy 151.517381 -60.944047) (xy 151.469775 -60.973101)
			(xy 151.418446 -60.994913) (xy 151.364489 -61.009019) (xy 151.309052 -61.015119) (xy 151.253318 -61.013082)
			(xy 151.198475 -61.002952) (xy 151.145691 -60.984945) (xy 151.096091 -60.959444) (xy 151.050733 -60.926993)
			(xy 151.010584 -60.888284) (xy 150.976498 -60.844141) (xy 150.949202 -60.795506) (xy 150.929279 -60.743415)
			(xy 150.917153 -60.688978) (xy 150.913082 -60.633356) (xy 150.660608 -60.633356) (xy 150.660099 -60.661242)
			(xy 150.651979 -60.716418) (xy 150.635911 -60.769825) (xy 150.612239 -60.820322) (xy 150.581466 -60.866835)
			(xy 150.544249 -60.908372) (xy 150.501381 -60.944047) (xy 150.453775 -60.973101) (xy 150.402446 -60.994913)
			(xy 150.348489 -61.009019) (xy 150.293052 -61.015119) (xy 150.237318 -61.013082) (xy 150.182475 -61.002952)
			(xy 150.129691 -60.984945) (xy 150.080091 -60.959444) (xy 150.034733 -60.926993) (xy 149.994584 -60.888284)
			(xy 149.960498 -60.844141) (xy 149.933202 -60.795506) (xy 149.913279 -60.743415) (xy 149.901153 -60.688978)
			(xy 149.897082 -60.633356) (xy 149.584802 -60.633356) (xy 149.584409 -60.654892) (xy 149.576289 -60.710068)
			(xy 149.560221 -60.763475) (xy 149.536549 -60.813972) (xy 149.505776 -60.860485) (xy 149.468559 -60.902022)
			(xy 149.425691 -60.937697) (xy 149.378085 -60.966751) (xy 149.326756 -60.988563) (xy 149.272799 -61.002669)
			(xy 149.217362 -61.008769) (xy 149.161628 -61.006732) (xy 149.106785 -60.996602) (xy 149.054001 -60.978595)
			(xy 149.004401 -60.953094) (xy 148.959043 -60.920643) (xy 148.918894 -60.881934) (xy 148.884808 -60.837791)
			(xy 148.857512 -60.789156) (xy 148.837589 -60.737065) (xy 148.825463 -60.682628) (xy 148.821392 -60.627006)
			(xy 147.196346 -60.627006) (xy 147.196301 -60.629492) (xy 147.188181 -60.684668) (xy 147.172113 -60.738075)
			(xy 147.148441 -60.788572) (xy 147.117668 -60.835085) (xy 147.080451 -60.876622) (xy 147.037583 -60.912297)
			(xy 146.989977 -60.941351) (xy 146.938648 -60.963163) (xy 146.884691 -60.977269) (xy 146.829254 -60.983369)
			(xy 146.77352 -60.981332) (xy 146.718677 -60.971202) (xy 146.665893 -60.953195) (xy 146.616293 -60.927694)
			(xy 146.570935 -60.895243) (xy 146.530786 -60.856534) (xy 146.4967 -60.812391) (xy 146.469404 -60.763756)
			(xy 146.449481 -60.711665) (xy 146.437355 -60.657228) (xy 146.433284 -60.601606) (xy 125.675582 -60.601606)
			(xy 125.676151 -60.60547) (xy 125.67666 -60.633356) (xy 125.676151 -60.661242) (xy 125.668031 -60.716418)
			(xy 125.651963 -60.769825) (xy 125.628291 -60.820322) (xy 125.597518 -60.866835) (xy 125.560301 -60.908372)
			(xy 125.517433 -60.944047) (xy 125.469827 -60.973101) (xy 125.418498 -60.994913) (xy 125.364541 -61.009019)
			(xy 125.309104 -61.015119) (xy 125.25337 -61.013082) (xy 125.198527 -61.002952) (xy 125.145743 -60.984945)
			(xy 125.096143 -60.959444) (xy 125.050785 -60.926993) (xy 125.010636 -60.888284) (xy 124.97655 -60.844141)
			(xy 124.949254 -60.795506) (xy 124.929331 -60.743415) (xy 124.917205 -60.688978) (xy 124.913134 -60.633356)
			(xy 124.66066 -60.633356) (xy 124.660151 -60.661242) (xy 124.652031 -60.716418) (xy 124.635963 -60.769825)
			(xy 124.612291 -60.820322) (xy 124.581518 -60.866835) (xy 124.544301 -60.908372) (xy 124.501433 -60.944047)
			(xy 124.453827 -60.973101) (xy 124.402498 -60.994913) (xy 124.348541 -61.009019) (xy 124.293104 -61.015119)
			(xy 124.23737 -61.013082) (xy 124.182527 -61.002952) (xy 124.129743 -60.984945) (xy 124.080143 -60.959444)
			(xy 124.034785 -60.926993) (xy 123.994636 -60.888284) (xy 123.96055 -60.844141) (xy 123.933254 -60.795506)
			(xy 123.913331 -60.743415) (xy 123.901205 -60.688978) (xy 123.897134 -60.633356) (xy 123.584854 -60.633356)
			(xy 123.584461 -60.654892) (xy 123.576341 -60.710068) (xy 123.560273 -60.763475) (xy 123.536601 -60.813972)
			(xy 123.505828 -60.860485) (xy 123.468611 -60.902022) (xy 123.425743 -60.937697) (xy 123.378137 -60.966751)
			(xy 123.326808 -60.988563) (xy 123.272851 -61.002669) (xy 123.217414 -61.008769) (xy 123.16168 -61.006732)
			(xy 123.106837 -60.996602) (xy 123.054053 -60.978595) (xy 123.004453 -60.953094) (xy 122.959095 -60.920643)
			(xy 122.918946 -60.881934) (xy 122.88486 -60.837791) (xy 122.857564 -60.789156) (xy 122.837641 -60.737065)
			(xy 122.825515 -60.682628) (xy 122.821444 -60.627006) (xy 121.196398 -60.627006) (xy 121.196353 -60.629492)
			(xy 121.188233 -60.684668) (xy 121.172165 -60.738075) (xy 121.148493 -60.788572) (xy 121.11772 -60.835085)
			(xy 121.080503 -60.876622) (xy 121.037635 -60.912297) (xy 120.990029 -60.941351) (xy 120.9387 -60.963163)
			(xy 120.884743 -60.977269) (xy 120.829306 -60.983369) (xy 120.773572 -60.981332) (xy 120.718729 -60.971202)
			(xy 120.665945 -60.953195) (xy 120.616345 -60.927694) (xy 120.570987 -60.895243) (xy 120.530838 -60.856534)
			(xy 120.496752 -60.812391) (xy 120.469456 -60.763756) (xy 120.449533 -60.711665) (xy 120.437407 -60.657228)
			(xy 120.433336 -60.601606) (xy 87.575328 -60.601606) (xy 87.575897 -60.60547) (xy 87.576406 -60.633356)
			(xy 87.575897 -60.661242) (xy 87.567777 -60.716418) (xy 87.551709 -60.769825) (xy 87.528037 -60.820322)
			(xy 87.497264 -60.866835) (xy 87.460047 -60.908372) (xy 87.417179 -60.944047) (xy 87.369573 -60.973101)
			(xy 87.318244 -60.994913) (xy 87.264287 -61.009019) (xy 87.20885 -61.015119) (xy 87.153116 -61.013082)
			(xy 87.098273 -61.002952) (xy 87.045489 -60.984945) (xy 86.995889 -60.959444) (xy 86.950531 -60.926993)
			(xy 86.910382 -60.888284) (xy 86.876296 -60.844141) (xy 86.849 -60.795506) (xy 86.829077 -60.743415)
			(xy 86.816951 -60.688978) (xy 86.81288 -60.633356) (xy 86.560406 -60.633356) (xy 86.559897 -60.661242)
			(xy 86.551777 -60.716418) (xy 86.535709 -60.769825) (xy 86.512037 -60.820322) (xy 86.481264 -60.866835)
			(xy 86.444047 -60.908372) (xy 86.401179 -60.944047) (xy 86.353573 -60.973101) (xy 86.302244 -60.994913)
			(xy 86.248287 -61.009019) (xy 86.19285 -61.015119) (xy 86.137116 -61.013082) (xy 86.082273 -61.002952)
			(xy 86.029489 -60.984945) (xy 85.979889 -60.959444) (xy 85.934531 -60.926993) (xy 85.894382 -60.888284)
			(xy 85.860296 -60.844141) (xy 85.833 -60.795506) (xy 85.813077 -60.743415) (xy 85.800951 -60.688978)
			(xy 85.79688 -60.633356) (xy 85.4846 -60.633356) (xy 85.484207 -60.654892) (xy 85.476087 -60.710068)
			(xy 85.460019 -60.763475) (xy 85.436347 -60.813972) (xy 85.405574 -60.860485) (xy 85.368357 -60.902022)
			(xy 85.325489 -60.937697) (xy 85.277883 -60.966751) (xy 85.226554 -60.988563) (xy 85.172597 -61.002669)
			(xy 85.11716 -61.008769) (xy 85.061426 -61.006732) (xy 85.006583 -60.996602) (xy 84.953799 -60.978595)
			(xy 84.904199 -60.953094) (xy 84.858841 -60.920643) (xy 84.818692 -60.881934) (xy 84.784606 -60.837791)
			(xy 84.75731 -60.789156) (xy 84.737387 -60.737065) (xy 84.725261 -60.682628) (xy 84.72119 -60.627006)
			(xy 83.096144 -60.627006) (xy 83.096099 -60.629492) (xy 83.087979 -60.684668) (xy 83.071911 -60.738075)
			(xy 83.048239 -60.788572) (xy 83.017466 -60.835085) (xy 82.980249 -60.876622) (xy 82.937381 -60.912297)
			(xy 82.889775 -60.941351) (xy 82.838446 -60.963163) (xy 82.784489 -60.977269) (xy 82.729052 -60.983369)
			(xy 82.673318 -60.981332) (xy 82.618475 -60.971202) (xy 82.565691 -60.953195) (xy 82.516091 -60.927694)
			(xy 82.470733 -60.895243) (xy 82.430584 -60.856534) (xy 82.396498 -60.812391) (xy 82.369202 -60.763756)
			(xy 82.349279 -60.711665) (xy 82.337153 -60.657228) (xy 82.333082 -60.601606) (xy 61.57538 -60.601606)
			(xy 61.575949 -60.60547) (xy 61.576458 -60.633356) (xy 61.575949 -60.661242) (xy 61.567829 -60.716418)
			(xy 61.551761 -60.769825) (xy 61.528089 -60.820322) (xy 61.497316 -60.866835) (xy 61.460099 -60.908372)
			(xy 61.417231 -60.944047) (xy 61.369625 -60.973101) (xy 61.318296 -60.994913) (xy 61.264339 -61.009019)
			(xy 61.208902 -61.015119) (xy 61.153168 -61.013082) (xy 61.098325 -61.002952) (xy 61.045541 -60.984945)
			(xy 60.995941 -60.959444) (xy 60.950583 -60.926993) (xy 60.910434 -60.888284) (xy 60.876348 -60.844141)
			(xy 60.849052 -60.795506) (xy 60.829129 -60.743415) (xy 60.817003 -60.688978) (xy 60.812932 -60.633356)
			(xy 60.560458 -60.633356) (xy 60.559949 -60.661242) (xy 60.551829 -60.716418) (xy 60.535761 -60.769825)
			(xy 60.512089 -60.820322) (xy 60.481316 -60.866835) (xy 60.444099 -60.908372) (xy 60.401231 -60.944047)
			(xy 60.353625 -60.973101) (xy 60.302296 -60.994913) (xy 60.248339 -61.009019) (xy 60.192902 -61.015119)
			(xy 60.137168 -61.013082) (xy 60.082325 -61.002952) (xy 60.029541 -60.984945) (xy 59.979941 -60.959444)
			(xy 59.934583 -60.926993) (xy 59.894434 -60.888284) (xy 59.860348 -60.844141) (xy 59.833052 -60.795506)
			(xy 59.813129 -60.743415) (xy 59.801003 -60.688978) (xy 59.796932 -60.633356) (xy 59.484652 -60.633356)
			(xy 59.484259 -60.654892) (xy 59.476139 -60.710068) (xy 59.460071 -60.763475) (xy 59.436399 -60.813972)
			(xy 59.405626 -60.860485) (xy 59.368409 -60.902022) (xy 59.325541 -60.937697) (xy 59.277935 -60.966751)
			(xy 59.226606 -60.988563) (xy 59.172649 -61.002669) (xy 59.117212 -61.008769) (xy 59.061478 -61.006732)
			(xy 59.006635 -60.996602) (xy 58.953851 -60.978595) (xy 58.904251 -60.953094) (xy 58.858893 -60.920643)
			(xy 58.818744 -60.881934) (xy 58.784658 -60.837791) (xy 58.757362 -60.789156) (xy 58.737439 -60.737065)
			(xy 58.725313 -60.682628) (xy 58.721242 -60.627006) (xy 57.096196 -60.627006) (xy 57.096151 -60.629492)
			(xy 57.088031 -60.684668) (xy 57.071963 -60.738075) (xy 57.048291 -60.788572) (xy 57.017518 -60.835085)
			(xy 56.980301 -60.876622) (xy 56.937433 -60.912297) (xy 56.889827 -60.941351) (xy 56.838498 -60.963163)
			(xy 56.784541 -60.977269) (xy 56.729104 -60.983369) (xy 56.67337 -60.981332) (xy 56.618527 -60.971202)
			(xy 56.565743 -60.953195) (xy 56.516143 -60.927694) (xy 56.470785 -60.895243) (xy 56.430636 -60.856534)
			(xy 56.39655 -60.812391) (xy 56.369254 -60.763756) (xy 56.349331 -60.711665) (xy 56.337205 -60.657228)
			(xy 56.333134 -60.601606) (xy 35.575377 -60.601606) (xy 35.576024 -60.606105) (xy 35.57651 -60.633356)
			(xy 35.576032 -60.660993) (xy 35.568072 -60.715691) (xy 35.552298 -60.768667) (xy 35.52904 -60.81881)
			(xy 35.498786 -60.865069) (xy 35.46217 -60.906476) (xy 35.441382 -60.924694) (xy 35.432855 -60.932578)
			(xy 35.42332 -60.953725) (xy 35.423094 -60.965334) (xy 35.426142 -61.04509) (xy 35.427187 -61.056443)
			(xy 35.437733 -61.07662) (xy 35.446462 -61.083952) (xy 35.446716 -61.084206) (xy 35.470353 -61.102351)
			(xy 35.512278 -61.144688) (xy 35.547113 -61.193028) (xy 35.57401 -61.246195) (xy 35.592317 -61.302896)
			(xy 35.601587 -61.361754) (xy 35.602164 -61.391546) (xy 35.601678 -61.418797) (xy 35.593922 -61.472745)
			(xy 35.589498 -61.487812) (xy 58.304428 -61.487812) (xy 58.308499 -61.43219) (xy 58.320625 -61.377753)
			(xy 58.340548 -61.325662) (xy 58.367844 -61.277027) (xy 58.40193 -61.232884) (xy 58.442079 -61.194175)
			(xy 58.487437 -61.161724) (xy 58.537037 -61.136223) (xy 58.589821 -61.118216) (xy 58.644664 -61.108086)
			(xy 58.700398 -61.106049) (xy 58.755835 -61.112149) (xy 58.809792 -61.126255) (xy 58.861121 -61.148067)
			(xy 58.908727 -61.177121) (xy 58.951595 -61.212796) (xy 58.988812 -61.254333) (xy 59.019585 -61.300846)
			(xy 59.043257 -61.351343) (xy 59.059325 -61.40475) (xy 59.067445 -61.459926) (xy 59.067954 -61.487812)
			(xy 84.304376 -61.487812) (xy 84.308447 -61.43219) (xy 84.320573 -61.377753) (xy 84.340496 -61.325662)
			(xy 84.367792 -61.277027) (xy 84.401878 -61.232884) (xy 84.442027 -61.194175) (xy 84.487385 -61.161724)
			(xy 84.536985 -61.136223) (xy 84.589769 -61.118216) (xy 84.644612 -61.108086) (xy 84.700346 -61.106049)
			(xy 84.755783 -61.112149) (xy 84.80974 -61.126255) (xy 84.861069 -61.148067) (xy 84.908675 -61.177121)
			(xy 84.951543 -61.212796) (xy 84.98876 -61.254333) (xy 85.019533 -61.300846) (xy 85.043205 -61.351343)
			(xy 85.059273 -61.40475) (xy 85.067393 -61.459926) (xy 85.067902 -61.487812) (xy 122.40463 -61.487812)
			(xy 122.408701 -61.43219) (xy 122.420827 -61.377753) (xy 122.44075 -61.325662) (xy 122.468046 -61.277027)
			(xy 122.502132 -61.232884) (xy 122.542281 -61.194175) (xy 122.587639 -61.161724) (xy 122.637239 -61.136223)
			(xy 122.690023 -61.118216) (xy 122.744866 -61.108086) (xy 122.8006 -61.106049) (xy 122.856037 -61.112149)
			(xy 122.909994 -61.126255) (xy 122.961323 -61.148067) (xy 123.008929 -61.177121) (xy 123.051797 -61.212796)
			(xy 123.089014 -61.254333) (xy 123.119787 -61.300846) (xy 123.143459 -61.351343) (xy 123.159527 -61.40475)
			(xy 123.167647 -61.459926) (xy 123.168156 -61.487812) (xy 148.404578 -61.487812) (xy 148.408649 -61.43219)
			(xy 148.420775 -61.377753) (xy 148.440698 -61.325662) (xy 148.467994 -61.277027) (xy 148.50208 -61.232884)
			(xy 148.542229 -61.194175) (xy 148.587587 -61.161724) (xy 148.637187 -61.136223) (xy 148.689971 -61.118216)
			(xy 148.744814 -61.108086) (xy 148.800548 -61.106049) (xy 148.855985 -61.112149) (xy 148.909942 -61.126255)
			(xy 148.961271 -61.148067) (xy 149.008877 -61.177121) (xy 149.051745 -61.212796) (xy 149.088962 -61.254333)
			(xy 149.119735 -61.300846) (xy 149.143407 -61.351343) (xy 149.159475 -61.40475) (xy 149.167595 -61.459926)
			(xy 149.168104 -61.487812) (xy 174.404526 -61.487812) (xy 174.408597 -61.43219) (xy 174.420723 -61.377753)
			(xy 174.440646 -61.325662) (xy 174.467942 -61.277027) (xy 174.502028 -61.232884) (xy 174.542177 -61.194175)
			(xy 174.587535 -61.161724) (xy 174.637135 -61.136223) (xy 174.689919 -61.118216) (xy 174.744762 -61.108086)
			(xy 174.800496 -61.106049) (xy 174.855933 -61.112149) (xy 174.90989 -61.126255) (xy 174.961219 -61.148067)
			(xy 175.008825 -61.177121) (xy 175.051693 -61.212796) (xy 175.08891 -61.254333) (xy 175.119683 -61.300846)
			(xy 175.143355 -61.351343) (xy 175.159423 -61.40475) (xy 175.167543 -61.459926) (xy 175.168052 -61.487812)
			(xy 200.404474 -61.487812) (xy 200.408545 -61.43219) (xy 200.420671 -61.377753) (xy 200.440594 -61.325662)
			(xy 200.46789 -61.277027) (xy 200.501976 -61.232884) (xy 200.542125 -61.194175) (xy 200.587483 -61.161724)
			(xy 200.637083 -61.136223) (xy 200.689867 -61.118216) (xy 200.74471 -61.108086) (xy 200.800444 -61.106049)
			(xy 200.855881 -61.112149) (xy 200.909838 -61.126255) (xy 200.961167 -61.148067) (xy 201.008773 -61.177121)
			(xy 201.051641 -61.212796) (xy 201.088858 -61.254333) (xy 201.119631 -61.300846) (xy 201.143303 -61.351343)
			(xy 201.159371 -61.40475) (xy 201.167491 -61.459926) (xy 201.168 -61.487812) (xy 201.167491 -61.515698)
			(xy 201.159371 -61.570874) (xy 201.143303 -61.624281) (xy 201.119631 -61.674778) (xy 201.088858 -61.721291)
			(xy 201.051641 -61.762828) (xy 201.008773 -61.798503) (xy 200.961167 -61.827557) (xy 200.909838 -61.849369)
			(xy 200.855881 -61.863475) (xy 200.800444 -61.869575) (xy 200.74471 -61.867538) (xy 200.689867 -61.857408)
			(xy 200.637083 -61.839401) (xy 200.587483 -61.8139) (xy 200.542125 -61.781449) (xy 200.501976 -61.74274)
			(xy 200.46789 -61.698597) (xy 200.440594 -61.649962) (xy 200.420671 -61.597871) (xy 200.408545 -61.543434)
			(xy 200.404474 -61.487812) (xy 175.168052 -61.487812) (xy 175.167543 -61.515698) (xy 175.159423 -61.570874)
			(xy 175.143355 -61.624281) (xy 175.119683 -61.674778) (xy 175.08891 -61.721291) (xy 175.051693 -61.762828)
			(xy 175.008825 -61.798503) (xy 174.961219 -61.827557) (xy 174.90989 -61.849369) (xy 174.855933 -61.863475)
			(xy 174.800496 -61.869575) (xy 174.744762 -61.867538) (xy 174.689919 -61.857408) (xy 174.637135 -61.839401)
			(xy 174.587535 -61.8139) (xy 174.542177 -61.781449) (xy 174.502028 -61.74274) (xy 174.467942 -61.698597)
			(xy 174.440646 -61.649962) (xy 174.420723 -61.597871) (xy 174.408597 -61.543434) (xy 174.404526 -61.487812)
			(xy 149.168104 -61.487812) (xy 149.167595 -61.515698) (xy 149.159475 -61.570874) (xy 149.143407 -61.624281)
			(xy 149.119735 -61.674778) (xy 149.088962 -61.721291) (xy 149.051745 -61.762828) (xy 149.008877 -61.798503)
			(xy 148.961271 -61.827557) (xy 148.909942 -61.849369) (xy 148.855985 -61.863475) (xy 148.800548 -61.869575)
			(xy 148.744814 -61.867538) (xy 148.689971 -61.857408) (xy 148.637187 -61.839401) (xy 148.587587 -61.8139)
			(xy 148.542229 -61.781449) (xy 148.50208 -61.74274) (xy 148.467994 -61.698597) (xy 148.440698 -61.649962)
			(xy 148.420775 -61.597871) (xy 148.408649 -61.543434) (xy 148.404578 -61.487812) (xy 123.168156 -61.487812)
			(xy 123.167647 -61.515698) (xy 123.159527 -61.570874) (xy 123.143459 -61.624281) (xy 123.119787 -61.674778)
			(xy 123.089014 -61.721291) (xy 123.051797 -61.762828) (xy 123.008929 -61.798503) (xy 122.961323 -61.827557)
			(xy 122.909994 -61.849369) (xy 122.856037 -61.863475) (xy 122.8006 -61.869575) (xy 122.744866 -61.867538)
			(xy 122.690023 -61.857408) (xy 122.637239 -61.839401) (xy 122.587639 -61.8139) (xy 122.542281 -61.781449)
			(xy 122.502132 -61.74274) (xy 122.468046 -61.698597) (xy 122.44075 -61.649962) (xy 122.420827 -61.597871)
			(xy 122.408701 -61.543434) (xy 122.40463 -61.487812) (xy 85.067902 -61.487812) (xy 85.067393 -61.515698)
			(xy 85.059273 -61.570874) (xy 85.043205 -61.624281) (xy 85.019533 -61.674778) (xy 84.98876 -61.721291)
			(xy 84.951543 -61.762828) (xy 84.908675 -61.798503) (xy 84.861069 -61.827557) (xy 84.80974 -61.849369)
			(xy 84.755783 -61.863475) (xy 84.700346 -61.869575) (xy 84.644612 -61.867538) (xy 84.589769 -61.857408)
			(xy 84.536985 -61.839401) (xy 84.487385 -61.8139) (xy 84.442027 -61.781449) (xy 84.401878 -61.74274)
			(xy 84.367792 -61.698597) (xy 84.340496 -61.649962) (xy 84.320573 -61.597871) (xy 84.308447 -61.543434)
			(xy 84.304376 -61.487812) (xy 59.067954 -61.487812) (xy 59.067445 -61.515698) (xy 59.059325 -61.570874)
			(xy 59.043257 -61.624281) (xy 59.019585 -61.674778) (xy 58.988812 -61.721291) (xy 58.951595 -61.762828)
			(xy 58.908727 -61.798503) (xy 58.861121 -61.827557) (xy 58.809792 -61.849369) (xy 58.755835 -61.863475)
			(xy 58.700398 -61.869575) (xy 58.644664 -61.867538) (xy 58.589821 -61.857408) (xy 58.537037 -61.839401)
			(xy 58.487437 -61.8139) (xy 58.442079 -61.781449) (xy 58.40193 -61.74274) (xy 58.367844 -61.698597)
			(xy 58.340548 -61.649962) (xy 58.320625 -61.597871) (xy 58.308499 -61.543434) (xy 58.304428 -61.487812)
			(xy 35.589498 -61.487812) (xy 35.578567 -61.52504) (xy 35.555925 -61.574617) (xy 35.526459 -61.620467)
			(xy 35.490768 -61.661658) (xy 35.449577 -61.697349) (xy 35.403727 -61.726815) (xy 35.35415 -61.749457)
			(xy 35.301855 -61.764812) (xy 35.247907 -61.772568) (xy 35.193405 -61.772568) (xy 35.139457 -61.764812)
			(xy 35.087162 -61.749457) (xy 35.037585 -61.726815) (xy 34.991735 -61.697349) (xy 34.950544 -61.661658)
			(xy 34.914853 -61.620467) (xy 34.885387 -61.574617) (xy 34.862745 -61.52504) (xy 34.84739 -61.472745)
			(xy 34.839634 -61.418797) (xy 34.839148 -61.391546) (xy 34.839642 -61.363909) (xy 34.847601 -61.309213)
			(xy 34.863373 -61.256238) (xy 34.886628 -61.206096) (xy 34.916878 -61.159836) (xy 34.95349 -61.118428)
			(xy 34.974276 -61.100208) (xy 34.982842 -61.092359) (xy 34.992358 -61.071186) (xy 34.992564 -61.059568)
			(xy 34.989516 -60.979812) (xy 34.988485 -60.968457) (xy 34.977931 -60.948279) (xy 34.969196 -60.94095)
			(xy 34.968942 -60.940696) (xy 34.945297 -60.922562) (xy 34.903374 -60.880221) (xy 34.868542 -60.831879)
			(xy 34.841646 -60.77871) (xy 34.823341 -60.722007) (xy 34.814071 -60.663148) (xy 34.813494 -60.633356)
			(xy 34.56051 -60.633356) (xy 34.560001 -60.661242) (xy 34.551881 -60.716418) (xy 34.535813 -60.769825)
			(xy 34.512141 -60.820322) (xy 34.481368 -60.866835) (xy 34.444151 -60.908372) (xy 34.401283 -60.944047)
			(xy 34.353677 -60.973101) (xy 34.302348 -60.994913) (xy 34.248391 -61.009019) (xy 34.192954 -61.015119)
			(xy 34.13722 -61.013082) (xy 34.082377 -61.002952) (xy 34.029593 -60.984945) (xy 33.979993 -60.959444)
			(xy 33.934635 -60.926993) (xy 33.894486 -60.888284) (xy 33.8604 -60.844141) (xy 33.833104 -60.795506)
			(xy 33.813181 -60.743415) (xy 33.801055 -60.688978) (xy 33.796984 -60.633356) (xy 33.484704 -60.633356)
			(xy 33.484311 -60.654892) (xy 33.476191 -60.710068) (xy 33.460123 -60.763475) (xy 33.436451 -60.813972)
			(xy 33.405678 -60.860485) (xy 33.368461 -60.902022) (xy 33.325593 -60.937697) (xy 33.277987 -60.966751)
			(xy 33.226658 -60.988563) (xy 33.172701 -61.002669) (xy 33.117264 -61.008769) (xy 33.06153 -61.006732)
			(xy 33.006687 -60.996602) (xy 32.953903 -60.978595) (xy 32.904303 -60.953094) (xy 32.858945 -60.920643)
			(xy 32.818796 -60.881934) (xy 32.78471 -60.837791) (xy 32.757414 -60.789156) (xy 32.737491 -60.737065)
			(xy 32.725365 -60.682628) (xy 32.721294 -60.627006) (xy 31.096248 -60.627006) (xy 31.096203 -60.629492)
			(xy 31.088083 -60.684668) (xy 31.072015 -60.738075) (xy 31.048343 -60.788572) (xy 31.01757 -60.835085)
			(xy 30.980353 -60.876622) (xy 30.937485 -60.912297) (xy 30.889879 -60.941351) (xy 30.83855 -60.963163)
			(xy 30.784593 -60.977269) (xy 30.729156 -60.983369) (xy 30.673422 -60.981332) (xy 30.618579 -60.971202)
			(xy 30.565795 -60.953195) (xy 30.516195 -60.927694) (xy 30.470837 -60.895243) (xy 30.430688 -60.856534)
			(xy 30.396602 -60.812391) (xy 30.369306 -60.763756) (xy 30.349383 -60.711665) (xy 30.337257 -60.657228)
			(xy 30.333186 -60.601606) (xy 9.575484 -60.601606) (xy 9.576053 -60.60547) (xy 9.576562 -60.633356)
			(xy 9.576053 -60.661242) (xy 9.567933 -60.716418) (xy 9.551865 -60.769825) (xy 9.528193 -60.820322)
			(xy 9.49742 -60.866835) (xy 9.460203 -60.908372) (xy 9.417335 -60.944047) (xy 9.369729 -60.973101)
			(xy 9.3184 -60.994913) (xy 9.264443 -61.009019) (xy 9.209006 -61.015119) (xy 9.153272 -61.013082)
			(xy 9.098429 -61.002952) (xy 9.045645 -60.984945) (xy 8.996045 -60.959444) (xy 8.950687 -60.926993)
			(xy 8.910538 -60.888284) (xy 8.876452 -60.844141) (xy 8.849156 -60.795506) (xy 8.829233 -60.743415)
			(xy 8.817107 -60.688978) (xy 8.813036 -60.633356) (xy 8.560562 -60.633356) (xy 8.560053 -60.661242)
			(xy 8.551933 -60.716418) (xy 8.535865 -60.769825) (xy 8.512193 -60.820322) (xy 8.48142 -60.866835)
			(xy 8.444203 -60.908372) (xy 8.401335 -60.944047) (xy 8.353729 -60.973101) (xy 8.3024 -60.994913)
			(xy 8.248443 -61.009019) (xy 8.193006 -61.015119) (xy 8.137272 -61.013082) (xy 8.082429 -61.002952)
			(xy 8.029645 -60.984945) (xy 7.980045 -60.959444) (xy 7.934687 -60.926993) (xy 7.894538 -60.888284)
			(xy 7.860452 -60.844141) (xy 7.833156 -60.795506) (xy 7.813233 -60.743415) (xy 7.801107 -60.688978)
			(xy 7.797036 -60.633356) (xy 7.484756 -60.633356) (xy 7.484363 -60.654892) (xy 7.476243 -60.710068)
			(xy 7.460175 -60.763475) (xy 7.436503 -60.813972) (xy 7.40573 -60.860485) (xy 7.368513 -60.902022)
			(xy 7.325645 -60.937697) (xy 7.278039 -60.966751) (xy 7.22671 -60.988563) (xy 7.172753 -61.002669)
			(xy 7.117316 -61.008769) (xy 7.061582 -61.006732) (xy 7.006739 -60.996602) (xy 6.953955 -60.978595)
			(xy 6.904355 -60.953094) (xy 6.858997 -60.920643) (xy 6.818848 -60.881934) (xy 6.784762 -60.837791)
			(xy 6.757466 -60.789156) (xy 6.737543 -60.737065) (xy 6.725417 -60.682628) (xy 6.721346 -60.627006)
			(xy 6.404528 -60.627006) (xy 6.413187 -60.645477) (xy 6.429255 -60.698884) (xy 6.437375 -60.75406)
			(xy 6.437884 -60.781946) (xy 6.437375 -60.809832) (xy 6.429255 -60.865008) (xy 6.413187 -60.918415)
			(xy 6.389515 -60.968912) (xy 6.358742 -61.015425) (xy 6.321525 -61.056962) (xy 6.278657 -61.092637)
			(xy 6.231051 -61.121691) (xy 6.179722 -61.143503) (xy 6.125765 -61.157609) (xy 6.070328 -61.163709)
			(xy 6.014594 -61.161672) (xy 5.959751 -61.151542) (xy 5.906967 -61.133535) (xy 5.857367 -61.108034)
			(xy 5.812009 -61.075583) (xy 5.77186 -61.036874) (xy 5.737774 -60.992731) (xy 5.710478 -60.944096)
			(xy 5.690555 -60.892005) (xy 5.678429 -60.837568) (xy 5.674358 -60.781946) (xy 5.051501 -60.781946)
			(xy 5.048395 -60.788572) (xy 5.017622 -60.835085) (xy 4.980405 -60.876622) (xy 4.937537 -60.912297)
			(xy 4.889931 -60.941351) (xy 4.838602 -60.963163) (xy 4.784645 -60.977269) (xy 4.729208 -60.983369)
			(xy 4.673474 -60.981332) (xy 4.618631 -60.971202) (xy 4.565847 -60.953195) (xy 4.516247 -60.927694)
			(xy 4.470889 -60.895243) (xy 4.43074 -60.856534) (xy 4.396654 -60.812391) (xy 4.369358 -60.763756)
			(xy 4.349435 -60.711665) (xy 4.337309 -60.657228) (xy 4.333238 -60.601606) (xy 2.875788 -60.601606)
			(xy 2.875788 -61.487812) (xy 32.30448 -61.487812) (xy 32.308551 -61.43219) (xy 32.320677 -61.377753)
			(xy 32.3406 -61.325662) (xy 32.367896 -61.277027) (xy 32.401982 -61.232884) (xy 32.442131 -61.194175)
			(xy 32.487489 -61.161724) (xy 32.537089 -61.136223) (xy 32.589873 -61.118216) (xy 32.644716 -61.108086)
			(xy 32.70045 -61.106049) (xy 32.755887 -61.112149) (xy 32.809844 -61.126255) (xy 32.861173 -61.148067)
			(xy 32.908779 -61.177121) (xy 32.951647 -61.212796) (xy 32.988864 -61.254333) (xy 33.019637 -61.300846)
			(xy 33.043309 -61.351343) (xy 33.059377 -61.40475) (xy 33.067497 -61.459926) (xy 33.068006 -61.487812)
			(xy 33.067497 -61.515698) (xy 33.059377 -61.570874) (xy 33.043309 -61.624281) (xy 33.019637 -61.674778)
			(xy 32.988864 -61.721291) (xy 32.951647 -61.762828) (xy 32.908779 -61.798503) (xy 32.861173 -61.827557)
			(xy 32.809844 -61.849369) (xy 32.755887 -61.863475) (xy 32.70045 -61.869575) (xy 32.644716 -61.867538)
			(xy 32.589873 -61.857408) (xy 32.537089 -61.839401) (xy 32.487489 -61.8139) (xy 32.442131 -61.781449)
			(xy 32.401982 -61.74274) (xy 32.367896 -61.698597) (xy 32.3406 -61.649962) (xy 32.320677 -61.597871)
			(xy 32.308551 -61.543434) (xy 32.30448 -61.487812) (xy 2.875788 -61.487812) (xy 2.875788 -62.151002)
			(xy 4.167106 -62.151002) (xy 4.167106 -62.091066) (xy 4.174929 -62.031644) (xy 4.190442 -61.973751)
			(xy 4.213378 -61.918378) (xy 4.243345 -61.866472) (xy 4.279832 -61.818922) (xy 4.322212 -61.776542)
			(xy 4.369762 -61.740055) (xy 4.421668 -61.710088) (xy 4.477041 -61.687152) (xy 4.534934 -61.671639)
			(xy 4.594356 -61.663816) (xy 4.654292 -61.663816) (xy 4.713714 -61.671639) (xy 4.771607 -61.687152)
			(xy 4.82698 -61.710088) (xy 4.878886 -61.740055) (xy 4.926436 -61.776542) (xy 4.968816 -61.818922)
			(xy 5.005303 -61.866472) (xy 5.03527 -61.918378) (xy 5.058206 -61.973751) (xy 5.073719 -62.031644)
			(xy 5.076325 -62.051438) (xy 8.22909 -62.051438) (xy 8.233161 -61.995816) (xy 8.245287 -61.941379)
			(xy 8.26521 -61.889288) (xy 8.292506 -61.840653) (xy 8.326592 -61.79651) (xy 8.366741 -61.757801)
			(xy 8.412099 -61.72535) (xy 8.461699 -61.699849) (xy 8.514483 -61.681842) (xy 8.569326 -61.671712)
			(xy 8.62506 -61.669675) (xy 8.680497 -61.675775) (xy 8.734454 -61.689881) (xy 8.785783 -61.711693)
			(xy 8.833389 -61.740747) (xy 8.876257 -61.776422) (xy 8.913474 -61.817959) (xy 8.944247 -61.864472)
			(xy 8.967919 -61.914969) (xy 8.983987 -61.968376) (xy 8.992107 -62.023552) (xy 8.992616 -62.051438)
			(xy 8.992107 -62.079324) (xy 8.983987 -62.1345) (xy 8.979022 -62.151002) (xy 30.167054 -62.151002)
			(xy 30.167054 -62.091066) (xy 30.174877 -62.031644) (xy 30.19039 -61.973751) (xy 30.213326 -61.918378)
			(xy 30.243293 -61.866472) (xy 30.27978 -61.818922) (xy 30.32216 -61.776542) (xy 30.36971 -61.740055)
			(xy 30.421616 -61.710088) (xy 30.476989 -61.687152) (xy 30.534882 -61.671639) (xy 30.594304 -61.663816)
			(xy 30.65424 -61.663816) (xy 30.713662 -61.671639) (xy 30.771555 -61.687152) (xy 30.826928 -61.710088)
			(xy 30.878834 -61.740055) (xy 30.926384 -61.776542) (xy 30.968764 -61.818922) (xy 31.005251 -61.866472)
			(xy 31.035218 -61.918378) (xy 31.058154 -61.973751) (xy 31.073667 -62.031644) (xy 31.08149 -62.091066)
			(xy 31.08198 -62.121034) (xy 31.08149 -62.151002) (xy 56.167002 -62.151002) (xy 56.167002 -62.091066)
			(xy 56.174825 -62.031644) (xy 56.190338 -61.973751) (xy 56.213274 -61.918378) (xy 56.243241 -61.866472)
			(xy 56.279728 -61.818922) (xy 56.322108 -61.776542) (xy 56.369658 -61.740055) (xy 56.421564 -61.710088)
			(xy 56.476937 -61.687152) (xy 56.53483 -61.671639) (xy 56.594252 -61.663816) (xy 56.654188 -61.663816)
			(xy 56.71361 -61.671639) (xy 56.771503 -61.687152) (xy 56.826876 -61.710088) (xy 56.878782 -61.740055)
			(xy 56.926332 -61.776542) (xy 56.968712 -61.818922) (xy 57.005199 -61.866472) (xy 57.035166 -61.918378)
			(xy 57.058102 -61.973751) (xy 57.073615 -62.031644) (xy 57.076221 -62.051438) (xy 60.228986 -62.051438)
			(xy 60.233057 -61.995816) (xy 60.245183 -61.941379) (xy 60.265106 -61.889288) (xy 60.292402 -61.840653)
			(xy 60.326488 -61.79651) (xy 60.366637 -61.757801) (xy 60.411995 -61.72535) (xy 60.461595 -61.699849)
			(xy 60.514379 -61.681842) (xy 60.569222 -61.671712) (xy 60.624956 -61.669675) (xy 60.680393 -61.675775)
			(xy 60.73435 -61.689881) (xy 60.785679 -61.711693) (xy 60.833285 -61.740747) (xy 60.876153 -61.776422)
			(xy 60.91337 -61.817959) (xy 60.944143 -61.864472) (xy 60.967815 -61.914969) (xy 60.983883 -61.968376)
			(xy 60.992003 -62.023552) (xy 60.992512 -62.051438) (xy 60.992003 -62.079324) (xy 60.983883 -62.1345)
			(xy 60.978918 -62.151002) (xy 82.16695 -62.151002) (xy 82.16695 -62.091066) (xy 82.174773 -62.031644)
			(xy 82.190286 -61.973751) (xy 82.213222 -61.918378) (xy 82.243189 -61.866472) (xy 82.279676 -61.818922)
			(xy 82.322056 -61.776542) (xy 82.369606 -61.740055) (xy 82.421512 -61.710088) (xy 82.476885 -61.687152)
			(xy 82.534778 -61.671639) (xy 82.5942 -61.663816) (xy 82.654136 -61.663816) (xy 82.713558 -61.671639)
			(xy 82.771451 -61.687152) (xy 82.826824 -61.710088) (xy 82.87873 -61.740055) (xy 82.92628 -61.776542)
			(xy 82.96866 -61.818922) (xy 83.005147 -61.866472) (xy 83.035114 -61.918378) (xy 83.05805 -61.973751)
			(xy 83.073563 -62.031644) (xy 83.080114 -62.081406) (xy 86.153734 -62.081406) (xy 86.153734 -62.02147)
			(xy 86.161557 -61.962048) (xy 86.17707 -61.904155) (xy 86.200006 -61.848782) (xy 86.229973 -61.796876)
			(xy 86.26646 -61.749326) (xy 86.30884 -61.706946) (xy 86.35639 -61.670459) (xy 86.408296 -61.640492)
			(xy 86.463669 -61.617556) (xy 86.521562 -61.602043) (xy 86.580984 -61.59422) (xy 86.64092 -61.59422)
			(xy 86.700342 -61.602043) (xy 86.758235 -61.617556) (xy 86.813608 -61.640492) (xy 86.865514 -61.670459)
			(xy 86.913064 -61.706946) (xy 86.955444 -61.749326) (xy 86.991931 -61.796876) (xy 87.021898 -61.848782)
			(xy 87.044834 -61.904155) (xy 87.060347 -61.962048) (xy 87.06817 -62.02147) (xy 87.06866 -62.051438)
			(xy 87.06817 -62.081406) (xy 87.060347 -62.140828) (xy 87.057621 -62.151002) (xy 120.267204 -62.151002)
			(xy 120.267204 -62.091066) (xy 120.275027 -62.031644) (xy 120.29054 -61.973751) (xy 120.313476 -61.918378)
			(xy 120.343443 -61.866472) (xy 120.37993 -61.818922) (xy 120.42231 -61.776542) (xy 120.46986 -61.740055)
			(xy 120.521766 -61.710088) (xy 120.577139 -61.687152) (xy 120.635032 -61.671639) (xy 120.694454 -61.663816)
			(xy 120.75439 -61.663816) (xy 120.813812 -61.671639) (xy 120.871705 -61.687152) (xy 120.927078 -61.710088)
			(xy 120.978984 -61.740055) (xy 121.026534 -61.776542) (xy 121.068914 -61.818922) (xy 121.105401 -61.866472)
			(xy 121.135368 -61.918378) (xy 121.158304 -61.973751) (xy 121.173817 -62.031644) (xy 121.180368 -62.081406)
			(xy 124.253988 -62.081406) (xy 124.253988 -62.02147) (xy 124.261811 -61.962048) (xy 124.277324 -61.904155)
			(xy 124.30026 -61.848782) (xy 124.330227 -61.796876) (xy 124.366714 -61.749326) (xy 124.409094 -61.706946)
			(xy 124.456644 -61.670459) (xy 124.50855 -61.640492) (xy 124.563923 -61.617556) (xy 124.621816 -61.602043)
			(xy 124.681238 -61.59422) (xy 124.741174 -61.59422) (xy 124.800596 -61.602043) (xy 124.858489 -61.617556)
			(xy 124.913862 -61.640492) (xy 124.965768 -61.670459) (xy 125.013318 -61.706946) (xy 125.055698 -61.749326)
			(xy 125.092185 -61.796876) (xy 125.122152 -61.848782) (xy 125.145088 -61.904155) (xy 125.160601 -61.962048)
			(xy 125.168424 -62.02147) (xy 125.168914 -62.051438) (xy 125.168424 -62.081406) (xy 125.160601 -62.140828)
			(xy 125.157875 -62.151002) (xy 146.267152 -62.151002) (xy 146.267152 -62.091066) (xy 146.274975 -62.031644)
			(xy 146.290488 -61.973751) (xy 146.313424 -61.918378) (xy 146.343391 -61.866472) (xy 146.379878 -61.818922)
			(xy 146.422258 -61.776542) (xy 146.469808 -61.740055) (xy 146.521714 -61.710088) (xy 146.577087 -61.687152)
			(xy 146.63498 -61.671639) (xy 146.694402 -61.663816) (xy 146.754338 -61.663816) (xy 146.81376 -61.671639)
			(xy 146.871653 -61.687152) (xy 146.927026 -61.710088) (xy 146.978932 -61.740055) (xy 147.026482 -61.776542)
			(xy 147.068862 -61.818922) (xy 147.105349 -61.866472) (xy 147.135316 -61.918378) (xy 147.158252 -61.973751)
			(xy 147.173765 -62.031644) (xy 147.180316 -62.081406) (xy 150.253936 -62.081406) (xy 150.253936 -62.02147)
			(xy 150.261759 -61.962048) (xy 150.277272 -61.904155) (xy 150.300208 -61.848782) (xy 150.330175 -61.796876)
			(xy 150.366662 -61.749326) (xy 150.409042 -61.706946) (xy 150.456592 -61.670459) (xy 150.508498 -61.640492)
			(xy 150.563871 -61.617556) (xy 150.621764 -61.602043) (xy 150.681186 -61.59422) (xy 150.741122 -61.59422)
			(xy 150.800544 -61.602043) (xy 150.858437 -61.617556) (xy 150.91381 -61.640492) (xy 150.965716 -61.670459)
			(xy 151.013266 -61.706946) (xy 151.055646 -61.749326) (xy 151.092133 -61.796876) (xy 151.1221 -61.848782)
			(xy 151.145036 -61.904155) (xy 151.160549 -61.962048) (xy 151.168372 -62.02147) (xy 151.168862 -62.051438)
			(xy 151.168372 -62.081406) (xy 151.160549 -62.140828) (xy 151.157823 -62.151002) (xy 172.2671 -62.151002)
			(xy 172.2671 -62.091066) (xy 172.274923 -62.031644) (xy 172.290436 -61.973751) (xy 172.313372 -61.918378)
			(xy 172.343339 -61.866472) (xy 172.379826 -61.818922) (xy 172.422206 -61.776542) (xy 172.469756 -61.740055)
			(xy 172.521662 -61.710088) (xy 172.577035 -61.687152) (xy 172.634928 -61.671639) (xy 172.69435 -61.663816)
			(xy 172.754286 -61.663816) (xy 172.813708 -61.671639) (xy 172.871601 -61.687152) (xy 172.926974 -61.710088)
			(xy 172.97888 -61.740055) (xy 173.02643 -61.776542) (xy 173.06881 -61.818922) (xy 173.105297 -61.866472)
			(xy 173.135264 -61.918378) (xy 173.1582 -61.973751) (xy 173.173713 -62.031644) (xy 173.180264 -62.081406)
			(xy 176.253884 -62.081406) (xy 176.253884 -62.02147) (xy 176.261707 -61.962048) (xy 176.27722 -61.904155)
			(xy 176.300156 -61.848782) (xy 176.330123 -61.796876) (xy 176.36661 -61.749326) (xy 176.40899 -61.706946)
			(xy 176.45654 -61.670459) (xy 176.508446 -61.640492) (xy 176.563819 -61.617556) (xy 176.621712 -61.602043)
			(xy 176.681134 -61.59422) (xy 176.74107 -61.59422) (xy 176.800492 -61.602043) (xy 176.858385 -61.617556)
			(xy 176.913758 -61.640492) (xy 176.965664 -61.670459) (xy 177.013214 -61.706946) (xy 177.055594 -61.749326)
			(xy 177.092081 -61.796876) (xy 177.122048 -61.848782) (xy 177.144984 -61.904155) (xy 177.160497 -61.962048)
			(xy 177.16832 -62.02147) (xy 177.16881 -62.051438) (xy 177.16832 -62.081406) (xy 177.160497 -62.140828)
			(xy 177.157771 -62.151002) (xy 198.267048 -62.151002) (xy 198.267048 -62.091066) (xy 198.274871 -62.031644)
			(xy 198.290384 -61.973751) (xy 198.31332 -61.918378) (xy 198.343287 -61.866472) (xy 198.379774 -61.818922)
			(xy 198.422154 -61.776542) (xy 198.469704 -61.740055) (xy 198.52161 -61.710088) (xy 198.576983 -61.687152)
			(xy 198.634876 -61.671639) (xy 198.694298 -61.663816) (xy 198.754234 -61.663816) (xy 198.813656 -61.671639)
			(xy 198.871549 -61.687152) (xy 198.926922 -61.710088) (xy 198.978828 -61.740055) (xy 199.026378 -61.776542)
			(xy 199.068758 -61.818922) (xy 199.105245 -61.866472) (xy 199.135212 -61.918378) (xy 199.158148 -61.973751)
			(xy 199.173661 -62.031644) (xy 199.180212 -62.081406) (xy 202.253832 -62.081406) (xy 202.253832 -62.02147)
			(xy 202.261655 -61.962048) (xy 202.277168 -61.904155) (xy 202.300104 -61.848782) (xy 202.330071 -61.796876)
			(xy 202.366558 -61.749326) (xy 202.408938 -61.706946) (xy 202.456488 -61.670459) (xy 202.508394 -61.640492)
			(xy 202.563767 -61.617556) (xy 202.62166 -61.602043) (xy 202.681082 -61.59422) (xy 202.741018 -61.59422)
			(xy 202.80044 -61.602043) (xy 202.858333 -61.617556) (xy 202.913706 -61.640492) (xy 202.965612 -61.670459)
			(xy 203.013162 -61.706946) (xy 203.055542 -61.749326) (xy 203.074139 -61.773562) (xy 226.029264 -61.773562)
			(xy 226.033335 -61.71794) (xy 226.045461 -61.663503) (xy 226.065384 -61.611412) (xy 226.09268 -61.562777)
			(xy 226.126766 -61.518634) (xy 226.166915 -61.479925) (xy 226.212273 -61.447474) (xy 226.261873 -61.421973)
			(xy 226.314657 -61.403966) (xy 226.3695 -61.393836) (xy 226.425234 -61.391799) (xy 226.480671 -61.397899)
			(xy 226.534628 -61.412005) (xy 226.585957 -61.433817) (xy 226.633563 -61.462871) (xy 226.676431 -61.498546)
			(xy 226.713648 -61.540083) (xy 226.744421 -61.586596) (xy 226.768093 -61.637093) (xy 226.784161 -61.6905)
			(xy 226.792281 -61.745676) (xy 226.79279 -61.773562) (xy 226.792308 -61.799978) (xy 227.210618 -61.799978)
			(xy 227.214689 -61.744356) (xy 227.226815 -61.689919) (xy 227.246738 -61.637828) (xy 227.274034 -61.589193)
			(xy 227.30812 -61.54505) (xy 227.348269 -61.506341) (xy 227.393627 -61.47389) (xy 227.443227 -61.448389)
			(xy 227.496011 -61.430382) (xy 227.550854 -61.420252) (xy 227.606588 -61.418215) (xy 227.662025 -61.424315)
			(xy 227.715982 -61.438421) (xy 227.767311 -61.460233) (xy 227.814917 -61.489287) (xy 227.857785 -61.524962)
			(xy 227.895002 -61.566499) (xy 227.925775 -61.613012) (xy 227.949447 -61.663509) (xy 227.965515 -61.716916)
			(xy 227.973635 -61.772092) (xy 227.974144 -61.799978) (xy 227.973635 -61.827864) (xy 227.965515 -61.88304)
			(xy 227.949447 -61.936447) (xy 227.925775 -61.986944) (xy 227.895002 -62.033457) (xy 227.857785 -62.074994)
			(xy 227.814917 -62.110669) (xy 227.767311 -62.139723) (xy 227.715982 -62.161535) (xy 227.662025 -62.175641)
			(xy 227.606588 -62.181741) (xy 227.550854 -62.179704) (xy 227.496011 -62.169574) (xy 227.443227 -62.151567)
			(xy 227.393627 -62.126066) (xy 227.348269 -62.093615) (xy 227.30812 -62.054906) (xy 227.274034 -62.010763)
			(xy 227.246738 -61.962128) (xy 227.226815 -61.910037) (xy 227.214689 -61.8556) (xy 227.210618 -61.799978)
			(xy 226.792308 -61.799978) (xy 226.792281 -61.801448) (xy 226.784161 -61.856624) (xy 226.768093 -61.910031)
			(xy 226.744421 -61.960528) (xy 226.713648 -62.007041) (xy 226.676431 -62.048578) (xy 226.633563 -62.084253)
			(xy 226.585957 -62.113307) (xy 226.534628 -62.135119) (xy 226.480671 -62.149225) (xy 226.425234 -62.155325)
			(xy 226.3695 -62.153288) (xy 226.314657 -62.143158) (xy 226.261873 -62.125151) (xy 226.212273 -62.09965)
			(xy 226.166915 -62.067199) (xy 226.126766 -62.02849) (xy 226.09268 -61.984347) (xy 226.065384 -61.935712)
			(xy 226.045461 -61.883621) (xy 226.033335 -61.829184) (xy 226.029264 -61.773562) (xy 203.074139 -61.773562)
			(xy 203.092029 -61.796876) (xy 203.121996 -61.848782) (xy 203.144932 -61.904155) (xy 203.160445 -61.962048)
			(xy 203.168268 -62.02147) (xy 203.168758 -62.051438) (xy 203.168268 -62.081406) (xy 203.160445 -62.140828)
			(xy 203.144932 -62.198721) (xy 203.121996 -62.254094) (xy 203.092029 -62.306) (xy 203.055542 -62.35355)
			(xy 203.013162 -62.39593) (xy 202.965612 -62.432417) (xy 202.913706 -62.462384) (xy 202.858333 -62.48532)
			(xy 202.80044 -62.500833) (xy 202.741018 -62.508656) (xy 202.681082 -62.508656) (xy 202.62166 -62.500833)
			(xy 202.563767 -62.48532) (xy 202.508394 -62.462384) (xy 202.456488 -62.432417) (xy 202.408938 -62.39593)
			(xy 202.366558 -62.35355) (xy 202.330071 -62.306) (xy 202.300104 -62.254094) (xy 202.277168 -62.198721)
			(xy 202.261655 -62.140828) (xy 202.253832 -62.081406) (xy 199.180212 -62.081406) (xy 199.181484 -62.091066)
			(xy 199.181974 -62.121034) (xy 199.181484 -62.151002) (xy 199.173661 -62.210424) (xy 199.158148 -62.268317)
			(xy 199.135212 -62.32369) (xy 199.105245 -62.375596) (xy 199.068758 -62.423146) (xy 199.026378 -62.465526)
			(xy 198.978828 -62.502013) (xy 198.926922 -62.53198) (xy 198.871549 -62.554916) (xy 198.813656 -62.570429)
			(xy 198.754234 -62.578252) (xy 198.694298 -62.578252) (xy 198.634876 -62.570429) (xy 198.576983 -62.554916)
			(xy 198.52161 -62.53198) (xy 198.469704 -62.502013) (xy 198.422154 -62.465526) (xy 198.379774 -62.423146)
			(xy 198.343287 -62.375596) (xy 198.31332 -62.32369) (xy 198.290384 -62.268317) (xy 198.274871 -62.210424)
			(xy 198.267048 -62.151002) (xy 177.157771 -62.151002) (xy 177.144984 -62.198721) (xy 177.122048 -62.254094)
			(xy 177.092081 -62.306) (xy 177.055594 -62.35355) (xy 177.013214 -62.39593) (xy 176.965664 -62.432417)
			(xy 176.913758 -62.462384) (xy 176.858385 -62.48532) (xy 176.800492 -62.500833) (xy 176.74107 -62.508656)
			(xy 176.681134 -62.508656) (xy 176.621712 -62.500833) (xy 176.563819 -62.48532) (xy 176.508446 -62.462384)
			(xy 176.45654 -62.432417) (xy 176.40899 -62.39593) (xy 176.36661 -62.35355) (xy 176.330123 -62.306)
			(xy 176.300156 -62.254094) (xy 176.27722 -62.198721) (xy 176.261707 -62.140828) (xy 176.253884 -62.081406)
			(xy 173.180264 -62.081406) (xy 173.181536 -62.091066) (xy 173.182026 -62.121034) (xy 173.181536 -62.151002)
			(xy 173.173713 -62.210424) (xy 173.1582 -62.268317) (xy 173.135264 -62.32369) (xy 173.105297 -62.375596)
			(xy 173.06881 -62.423146) (xy 173.02643 -62.465526) (xy 172.97888 -62.502013) (xy 172.926974 -62.53198)
			(xy 172.871601 -62.554916) (xy 172.813708 -62.570429) (xy 172.754286 -62.578252) (xy 172.69435 -62.578252)
			(xy 172.634928 -62.570429) (xy 172.577035 -62.554916) (xy 172.521662 -62.53198) (xy 172.469756 -62.502013)
			(xy 172.422206 -62.465526) (xy 172.379826 -62.423146) (xy 172.343339 -62.375596) (xy 172.313372 -62.32369)
			(xy 172.290436 -62.268317) (xy 172.274923 -62.210424) (xy 172.2671 -62.151002) (xy 151.157823 -62.151002)
			(xy 151.145036 -62.198721) (xy 151.1221 -62.254094) (xy 151.092133 -62.306) (xy 151.055646 -62.35355)
			(xy 151.013266 -62.39593) (xy 150.965716 -62.432417) (xy 150.91381 -62.462384) (xy 150.858437 -62.48532)
			(xy 150.800544 -62.500833) (xy 150.741122 -62.508656) (xy 150.681186 -62.508656) (xy 150.621764 -62.500833)
			(xy 150.563871 -62.48532) (xy 150.508498 -62.462384) (xy 150.456592 -62.432417) (xy 150.409042 -62.39593)
			(xy 150.366662 -62.35355) (xy 150.330175 -62.306) (xy 150.300208 -62.254094) (xy 150.277272 -62.198721)
			(xy 150.261759 -62.140828) (xy 150.253936 -62.081406) (xy 147.180316 -62.081406) (xy 147.181588 -62.091066)
			(xy 147.182078 -62.121034) (xy 147.181588 -62.151002) (xy 147.173765 -62.210424) (xy 147.158252 -62.268317)
			(xy 147.135316 -62.32369) (xy 147.105349 -62.375596) (xy 147.068862 -62.423146) (xy 147.026482 -62.465526)
			(xy 146.978932 -62.502013) (xy 146.927026 -62.53198) (xy 146.871653 -62.554916) (xy 146.81376 -62.570429)
			(xy 146.754338 -62.578252) (xy 146.694402 -62.578252) (xy 146.63498 -62.570429) (xy 146.577087 -62.554916)
			(xy 146.521714 -62.53198) (xy 146.469808 -62.502013) (xy 146.422258 -62.465526) (xy 146.379878 -62.423146)
			(xy 146.343391 -62.375596) (xy 146.313424 -62.32369) (xy 146.290488 -62.268317) (xy 146.274975 -62.210424)
			(xy 146.267152 -62.151002) (xy 125.157875 -62.151002) (xy 125.145088 -62.198721) (xy 125.122152 -62.254094)
			(xy 125.092185 -62.306) (xy 125.055698 -62.35355) (xy 125.013318 -62.39593) (xy 124.965768 -62.432417)
			(xy 124.913862 -62.462384) (xy 124.858489 -62.48532) (xy 124.800596 -62.500833) (xy 124.741174 -62.508656)
			(xy 124.681238 -62.508656) (xy 124.621816 -62.500833) (xy 124.563923 -62.48532) (xy 124.50855 -62.462384)
			(xy 124.456644 -62.432417) (xy 124.409094 -62.39593) (xy 124.366714 -62.35355) (xy 124.330227 -62.306)
			(xy 124.30026 -62.254094) (xy 124.277324 -62.198721) (xy 124.261811 -62.140828) (xy 124.253988 -62.081406)
			(xy 121.180368 -62.081406) (xy 121.18164 -62.091066) (xy 121.18213 -62.121034) (xy 121.18164 -62.151002)
			(xy 121.173817 -62.210424) (xy 121.158304 -62.268317) (xy 121.135368 -62.32369) (xy 121.105401 -62.375596)
			(xy 121.068914 -62.423146) (xy 121.026534 -62.465526) (xy 120.978984 -62.502013) (xy 120.927078 -62.53198)
			(xy 120.871705 -62.554916) (xy 120.813812 -62.570429) (xy 120.75439 -62.578252) (xy 120.694454 -62.578252)
			(xy 120.635032 -62.570429) (xy 120.577139 -62.554916) (xy 120.521766 -62.53198) (xy 120.46986 -62.502013)
			(xy 120.42231 -62.465526) (xy 120.37993 -62.423146) (xy 120.343443 -62.375596) (xy 120.313476 -62.32369)
			(xy 120.29054 -62.268317) (xy 120.275027 -62.210424) (xy 120.267204 -62.151002) (xy 87.057621 -62.151002)
			(xy 87.044834 -62.198721) (xy 87.021898 -62.254094) (xy 86.991931 -62.306) (xy 86.955444 -62.35355)
			(xy 86.913064 -62.39593) (xy 86.865514 -62.432417) (xy 86.813608 -62.462384) (xy 86.758235 -62.48532)
			(xy 86.700342 -62.500833) (xy 86.64092 -62.508656) (xy 86.580984 -62.508656) (xy 86.521562 -62.500833)
			(xy 86.463669 -62.48532) (xy 86.408296 -62.462384) (xy 86.35639 -62.432417) (xy 86.30884 -62.39593)
			(xy 86.26646 -62.35355) (xy 86.229973 -62.306) (xy 86.200006 -62.254094) (xy 86.17707 -62.198721)
			(xy 86.161557 -62.140828) (xy 86.153734 -62.081406) (xy 83.080114 -62.081406) (xy 83.081386 -62.091066)
			(xy 83.081876 -62.121034) (xy 83.081386 -62.151002) (xy 83.073563 -62.210424) (xy 83.05805 -62.268317)
			(xy 83.035114 -62.32369) (xy 83.005147 -62.375596) (xy 82.96866 -62.423146) (xy 82.92628 -62.465526)
			(xy 82.87873 -62.502013) (xy 82.826824 -62.53198) (xy 82.771451 -62.554916) (xy 82.713558 -62.570429)
			(xy 82.654136 -62.578252) (xy 82.5942 -62.578252) (xy 82.534778 -62.570429) (xy 82.476885 -62.554916)
			(xy 82.421512 -62.53198) (xy 82.369606 -62.502013) (xy 82.322056 -62.465526) (xy 82.279676 -62.423146)
			(xy 82.243189 -62.375596) (xy 82.213222 -62.32369) (xy 82.190286 -62.268317) (xy 82.174773 -62.210424)
			(xy 82.16695 -62.151002) (xy 60.978918 -62.151002) (xy 60.967815 -62.187907) (xy 60.944143 -62.238404)
			(xy 60.91337 -62.284917) (xy 60.876153 -62.326454) (xy 60.833285 -62.362129) (xy 60.785679 -62.391183)
			(xy 60.73435 -62.412995) (xy 60.680393 -62.427101) (xy 60.624956 -62.433201) (xy 60.569222 -62.431164)
			(xy 60.514379 -62.421034) (xy 60.461595 -62.403027) (xy 60.411995 -62.377526) (xy 60.366637 -62.345075)
			(xy 60.326488 -62.306366) (xy 60.292402 -62.262223) (xy 60.265106 -62.213588) (xy 60.245183 -62.161497)
			(xy 60.233057 -62.10706) (xy 60.228986 -62.051438) (xy 57.076221 -62.051438) (xy 57.081438 -62.091066)
			(xy 57.081928 -62.121034) (xy 57.081438 -62.151002) (xy 57.073615 -62.210424) (xy 57.058102 -62.268317)
			(xy 57.035166 -62.32369) (xy 57.005199 -62.375596) (xy 56.968712 -62.423146) (xy 56.926332 -62.465526)
			(xy 56.878782 -62.502013) (xy 56.826876 -62.53198) (xy 56.771503 -62.554916) (xy 56.71361 -62.570429)
			(xy 56.654188 -62.578252) (xy 56.594252 -62.578252) (xy 56.53483 -62.570429) (xy 56.476937 -62.554916)
			(xy 56.421564 -62.53198) (xy 56.369658 -62.502013) (xy 56.322108 -62.465526) (xy 56.279728 -62.423146)
			(xy 56.243241 -62.375596) (xy 56.213274 -62.32369) (xy 56.190338 -62.268317) (xy 56.174825 -62.210424)
			(xy 56.167002 -62.151002) (xy 31.08149 -62.151002) (xy 31.073667 -62.210424) (xy 31.058154 -62.268317)
			(xy 31.035218 -62.32369) (xy 31.005251 -62.375596) (xy 30.968764 -62.423146) (xy 30.926384 -62.465526)
			(xy 30.878834 -62.502013) (xy 30.826928 -62.53198) (xy 30.771555 -62.554916) (xy 30.713662 -62.570429)
			(xy 30.65424 -62.578252) (xy 30.594304 -62.578252) (xy 30.534882 -62.570429) (xy 30.476989 -62.554916)
			(xy 30.421616 -62.53198) (xy 30.36971 -62.502013) (xy 30.32216 -62.465526) (xy 30.27978 -62.423146)
			(xy 30.243293 -62.375596) (xy 30.213326 -62.32369) (xy 30.19039 -62.268317) (xy 30.174877 -62.210424)
			(xy 30.167054 -62.151002) (xy 8.979022 -62.151002) (xy 8.967919 -62.187907) (xy 8.944247 -62.238404)
			(xy 8.913474 -62.284917) (xy 8.876257 -62.326454) (xy 8.833389 -62.362129) (xy 8.785783 -62.391183)
			(xy 8.734454 -62.412995) (xy 8.680497 -62.427101) (xy 8.62506 -62.433201) (xy 8.569326 -62.431164)
			(xy 8.514483 -62.421034) (xy 8.461699 -62.403027) (xy 8.412099 -62.377526) (xy 8.366741 -62.345075)
			(xy 8.326592 -62.306366) (xy 8.292506 -62.262223) (xy 8.26521 -62.213588) (xy 8.245287 -62.161497)
			(xy 8.233161 -62.10706) (xy 8.22909 -62.051438) (xy 5.076325 -62.051438) (xy 5.081542 -62.091066)
			(xy 5.082032 -62.121034) (xy 5.081542 -62.151002) (xy 5.073719 -62.210424) (xy 5.058206 -62.268317)
			(xy 5.03527 -62.32369) (xy 5.005303 -62.375596) (xy 4.968816 -62.423146) (xy 4.926436 -62.465526)
			(xy 4.878886 -62.502013) (xy 4.82698 -62.53198) (xy 4.771607 -62.554916) (xy 4.713714 -62.570429)
			(xy 4.654292 -62.578252) (xy 4.594356 -62.578252) (xy 4.534934 -62.570429) (xy 4.477041 -62.554916)
			(xy 4.421668 -62.53198) (xy 4.369762 -62.502013) (xy 4.322212 -62.465526) (xy 4.279832 -62.423146)
			(xy 4.243345 -62.375596) (xy 4.213378 -62.32369) (xy 4.190442 -62.268317) (xy 4.174929 -62.210424)
			(xy 4.167106 -62.151002) (xy 2.875788 -62.151002) (xy 2.875788 -62.812168) (xy 6.917942 -62.812168)
			(xy 6.922013 -62.756546) (xy 6.934139 -62.702109) (xy 6.954062 -62.650018) (xy 6.981358 -62.601383)
			(xy 7.015444 -62.55724) (xy 7.055593 -62.518531) (xy 7.100951 -62.48608) (xy 7.150551 -62.460579)
			(xy 7.203335 -62.442572) (xy 7.258178 -62.432442) (xy 7.313912 -62.430405) (xy 7.369349 -62.436505)
			(xy 7.423306 -62.450611) (xy 7.474635 -62.472423) (xy 7.522241 -62.501477) (xy 7.565109 -62.537152)
			(xy 7.602326 -62.578689) (xy 7.633099 -62.625202) (xy 7.656771 -62.675699) (xy 7.672839 -62.729106)
			(xy 7.680959 -62.784282) (xy 7.681468 -62.812168) (xy 7.680959 -62.840054) (xy 7.672839 -62.89523)
			(xy 7.656771 -62.948637) (xy 7.633099 -62.999134) (xy 7.602326 -63.045647) (xy 7.565109 -63.087184)
			(xy 7.522241 -63.122859) (xy 7.474635 -63.151913) (xy 7.423306 -63.173725) (xy 7.369349 -63.187831)
			(xy 7.313912 -63.193931) (xy 7.258178 -63.191894) (xy 7.203335 -63.181764) (xy 7.150551 -63.163757)
			(xy 7.100951 -63.138256) (xy 7.055593 -63.105805) (xy 7.015444 -63.067096) (xy 6.981358 -63.022953)
			(xy 6.954062 -62.974318) (xy 6.934139 -62.922227) (xy 6.922013 -62.86779) (xy 6.917942 -62.812168)
			(xy 2.875788 -62.812168) (xy 2.875788 -63.3034) (xy 3.501626 -63.3034) (xy 3.501626 -63.243464) (xy 3.509449 -63.184042)
			(xy 3.524962 -63.126149) (xy 3.547898 -63.070776) (xy 3.577865 -63.01887) (xy 3.614352 -62.97132)
			(xy 3.656732 -62.92894) (xy 3.704282 -62.892453) (xy 3.756188 -62.862486) (xy 3.811561 -62.83955)
			(xy 3.869454 -62.824037) (xy 3.928876 -62.816214) (xy 3.988812 -62.816214) (xy 4.048234 -62.824037)
			(xy 4.106127 -62.83955) (xy 4.1615 -62.862486) (xy 4.213406 -62.892453) (xy 4.260956 -62.92894) (xy 4.303336 -62.97132)
			(xy 4.339823 -63.01887) (xy 4.36979 -63.070776) (xy 4.392726 -63.126149) (xy 4.408239 -63.184042)
			(xy 4.416062 -63.243464) (xy 4.416096 -63.245552) (xy 17.104569 -63.245552) (xy 17.104569 -63.191048)
			(xy 17.112326 -63.137097) (xy 17.127683 -63.0848) (xy 17.150325 -63.035221) (xy 17.179793 -62.989369)
			(xy 17.215487 -62.948177) (xy 17.25668 -62.912485) (xy 17.302533 -62.883019) (xy 17.352113 -62.860378)
			(xy 17.404411 -62.845023) (xy 17.458361 -62.837268) (xy 17.485614 -62.836806) (xy 17.512985 -62.837262)
			(xy 17.567164 -62.845082) (xy 17.619667 -62.860574) (xy 17.669414 -62.883417) (xy 17.715381 -62.913144)
			(xy 17.736312 -62.930786) (xy 17.736566 -62.93104) (xy 17.743655 -62.936623) (xy 17.76057 -62.942871)
			(xy 17.769586 -62.943232) (xy 17.836642 -62.943232) (xy 17.845655 -62.94284) (xy 17.862572 -62.936616)
			(xy 17.869662 -62.93104) (xy 17.869662 -62.930786) (xy 17.869916 -62.930786) (xy 17.890849 -62.913145)
			(xy 17.936817 -62.883421) (xy 17.986563 -62.860575) (xy 18.039065 -62.845079) (xy 18.093243 -62.83725)
			(xy 18.147985 -62.83725) (xy 18.202163 -62.845079) (xy 18.254665 -62.860575) (xy 18.304411 -62.883421)
			(xy 18.350379 -62.913145) (xy 18.371312 -62.930786) (xy 18.371566 -62.93104) (xy 18.378655 -62.936623)
			(xy 18.39557 -62.942871) (xy 18.404586 -62.943232) (xy 18.471642 -62.943232) (xy 18.480655 -62.94284)
			(xy 18.497572 -62.936616) (xy 18.504662 -62.93104) (xy 18.504662 -62.930786) (xy 18.504916 -62.930786)
			(xy 18.525867 -62.913171) (xy 18.571835 -62.883456) (xy 18.621578 -62.860615) (xy 18.674074 -62.845119)
			(xy 18.728246 -62.837284) (xy 18.755614 -62.836806) (xy 18.782866 -62.837265) (xy 18.836814 -62.845023)
			(xy 18.889109 -62.86038) (xy 18.938686 -62.883023) (xy 18.984536 -62.912491) (xy 19.025726 -62.948183)
			(xy 19.061418 -62.989375) (xy 19.090884 -63.035226) (xy 19.113525 -63.084804) (xy 19.12888 -63.1371)
			(xy 19.136636 -63.191048) (xy 19.136636 -63.213549) (xy 22.120888 -63.213549) (xy 22.120888 -63.159051)
			(xy 22.128643 -63.105109) (xy 22.143996 -63.052818) (xy 22.166634 -63.003245) (xy 22.196095 -62.957398)
			(xy 22.231782 -62.91621) (xy 22.272966 -62.880519) (xy 22.31881 -62.851053) (xy 22.368381 -62.82841)
			(xy 22.420669 -62.813052) (xy 22.474611 -62.805291) (xy 22.50186 -62.804802) (xy 22.529229 -62.805291)
			(xy 22.583408 -62.813103) (xy 22.63591 -62.828587) (xy 22.685658 -62.851424) (xy 22.731626 -62.881143)
			(xy 22.752558 -62.898782) (xy 22.752812 -62.899036) (xy 22.759888 -62.904638) (xy 22.776813 -62.910874)
			(xy 22.785832 -62.911228) (xy 22.852888 -62.911228) (xy 22.861904 -62.910859) (xy 22.87882 -62.904619)
			(xy 22.885908 -62.899036) (xy 22.885908 -62.898782) (xy 22.886162 -62.898782) (xy 22.907095 -62.881141)
			(xy 22.953063 -62.851417) (xy 23.002809 -62.828571) (xy 23.055311 -62.813075) (xy 23.109489 -62.805246)
			(xy 23.164231 -62.805246) (xy 23.218409 -62.813075) (xy 23.270911 -62.828571) (xy 23.320657 -62.851417)
			(xy 23.366625 -62.881141) (xy 23.387558 -62.898782) (xy 23.387812 -62.899036) (xy 23.394888 -62.904638)
			(xy 23.411813 -62.910874) (xy 23.420832 -62.911228) (xy 23.487888 -62.911228) (xy 23.496904 -62.910859)
			(xy 23.51382 -62.904619) (xy 23.520908 -62.899036) (xy 23.520908 -62.898782) (xy 23.521162 -62.898782)
			(xy 23.542095 -62.881144) (xy 23.588068 -62.851433) (xy 23.637815 -62.828597) (xy 23.690316 -62.813106)
			(xy 23.744491 -62.805277) (xy 23.77186 -62.804802) (xy 23.799115 -62.805242) (xy 23.853072 -62.812995)
			(xy 23.905376 -62.828348) (xy 23.954963 -62.850989) (xy 24.000822 -62.880456) (xy 24.042021 -62.916151)
			(xy 24.07772 -62.957346) (xy 24.107192 -63.003202) (xy 24.129838 -63.052786) (xy 24.13966 -63.086234)
			(xy 27.387548 -63.086234) (xy 27.391619 -63.030612) (xy 27.403745 -62.976175) (xy 27.423668 -62.924084)
			(xy 27.450964 -62.875449) (xy 27.48505 -62.831306) (xy 27.525199 -62.792597) (xy 27.570557 -62.760146)
			(xy 27.620157 -62.734645) (xy 27.672941 -62.716638) (xy 27.727784 -62.706508) (xy 27.783518 -62.704471)
			(xy 27.838955 -62.710571) (xy 27.892912 -62.724677) (xy 27.944241 -62.746489) (xy 27.991847 -62.775543)
			(xy 28.034715 -62.811218) (xy 28.035566 -62.812168) (xy 32.91789 -62.812168) (xy 32.921961 -62.756546)
			(xy 32.934087 -62.702109) (xy 32.95401 -62.650018) (xy 32.981306 -62.601383) (xy 33.015392 -62.55724)
			(xy 33.055541 -62.518531) (xy 33.100899 -62.48608) (xy 33.150499 -62.460579) (xy 33.203283 -62.442572)
			(xy 33.258126 -62.432442) (xy 33.31386 -62.430405) (xy 33.369297 -62.436505) (xy 33.423254 -62.450611)
			(xy 33.474583 -62.472423) (xy 33.522189 -62.501477) (xy 33.565057 -62.537152) (xy 33.602274 -62.578689)
			(xy 33.633047 -62.625202) (xy 33.656719 -62.675699) (xy 33.672787 -62.729106) (xy 33.680907 -62.784282)
			(xy 33.681416 -62.812168) (xy 33.680907 -62.840054) (xy 33.672787 -62.89523) (xy 33.656719 -62.948637)
			(xy 33.633047 -62.999134) (xy 33.602274 -63.045647) (xy 33.565057 -63.087184) (xy 33.522189 -63.122859)
			(xy 33.474583 -63.151913) (xy 33.423254 -63.173725) (xy 33.369297 -63.187831) (xy 33.31386 -63.193931)
			(xy 33.258126 -63.191894) (xy 33.203283 -63.181764) (xy 33.150499 -63.163757) (xy 33.100899 -63.138256)
			(xy 33.055541 -63.105805) (xy 33.015392 -63.067096) (xy 32.981306 -63.022953) (xy 32.95401 -62.974318)
			(xy 32.934087 -62.922227) (xy 32.921961 -62.86779) (xy 32.91789 -62.812168) (xy 28.035566 -62.812168)
			(xy 28.071932 -62.852755) (xy 28.102705 -62.899268) (xy 28.126377 -62.949765) (xy 28.142445 -63.003172)
			(xy 28.150565 -63.058348) (xy 28.151074 -63.086234) (xy 28.150565 -63.11412) (xy 28.142445 -63.169296)
			(xy 28.126377 -63.222703) (xy 28.102705 -63.2732) (xy 28.082725 -63.3034) (xy 29.501574 -63.3034)
			(xy 29.501574 -63.243464) (xy 29.509397 -63.184042) (xy 29.52491 -63.126149) (xy 29.547846 -63.070776)
			(xy 29.577813 -63.01887) (xy 29.6143 -62.97132) (xy 29.65668 -62.92894) (xy 29.70423 -62.892453)
			(xy 29.756136 -62.862486) (xy 29.811509 -62.83955) (xy 29.869402 -62.824037) (xy 29.928824 -62.816214)
			(xy 29.98876 -62.816214) (xy 30.048182 -62.824037) (xy 30.106075 -62.83955) (xy 30.161448 -62.862486)
			(xy 30.213354 -62.892453) (xy 30.260904 -62.92894) (xy 30.303284 -62.97132) (xy 30.339771 -63.01887)
			(xy 30.369738 -63.070776) (xy 30.392674 -63.126149) (xy 30.408187 -63.184042) (xy 30.41601 -63.243464)
			(xy 30.416044 -63.245548) (xy 43.104592 -63.245548) (xy 43.104592 -63.191052) (xy 43.112347 -63.137109)
			(xy 43.1277 -63.084819) (xy 43.150337 -63.035247) (xy 43.179799 -62.9894) (xy 43.215485 -62.948212)
			(xy 43.256669 -62.912522) (xy 43.302513 -62.883056) (xy 43.352084 -62.860413) (xy 43.404372 -62.845055)
			(xy 43.458314 -62.837295) (xy 43.485562 -62.836806) (xy 43.512931 -62.837293) (xy 43.56711 -62.845105)
			(xy 43.619613 -62.86059) (xy 43.66936 -62.883427) (xy 43.715328 -62.913147) (xy 43.73626 -62.930786)
			(xy 43.736514 -62.93104) (xy 43.743589 -62.936643) (xy 43.760515 -62.942879) (xy 43.769534 -62.943232)
			(xy 43.83659 -62.943232) (xy 43.845606 -62.942863) (xy 43.862522 -62.936623) (xy 43.86961 -62.93104)
			(xy 43.86961 -62.930786) (xy 43.869864 -62.930786) (xy 43.890797 -62.913145) (xy 43.936765 -62.883421)
			(xy 43.986511 -62.860575) (xy 44.039013 -62.845079) (xy 44.093191 -62.83725) (xy 44.147933 -62.83725)
			(xy 44.202111 -62.845079) (xy 44.254613 -62.860575) (xy 44.304359 -62.883421) (xy 44.350327 -62.913145)
			(xy 44.37126 -62.930786) (xy 44.371514 -62.93104) (xy 44.378589 -62.936643) (xy 44.395515 -62.942879)
			(xy 44.404534 -62.943232) (xy 44.47159 -62.943232) (xy 44.480606 -62.942863) (xy 44.497522 -62.936623)
			(xy 44.50461 -62.93104) (xy 44.50461 -62.930786) (xy 44.504864 -62.930786) (xy 44.525797 -62.913148)
			(xy 44.57177 -62.883437) (xy 44.621517 -62.860601) (xy 44.674017 -62.845109) (xy 44.728193 -62.83728)
			(xy 44.755562 -62.836806) (xy 44.782818 -62.837238) (xy 44.836775 -62.844991) (xy 44.889079 -62.860344)
			(xy 44.938666 -62.882986) (xy 44.984526 -62.912454) (xy 45.025724 -62.948149) (xy 45.061423 -62.989344)
			(xy 45.090896 -63.035201) (xy 45.113542 -63.084785) (xy 45.128901 -63.137088) (xy 45.136659 -63.191044)
			(xy 45.136659 -63.213553) (xy 48.120765 -63.213553) (xy 48.120765 -63.159047) (xy 48.128522 -63.105097)
			(xy 48.143878 -63.0528) (xy 48.166521 -63.003221) (xy 48.195989 -62.957369) (xy 48.231682 -62.916177)
			(xy 48.272875 -62.880484) (xy 48.318728 -62.851017) (xy 48.368308 -62.828376) (xy 48.420605 -62.813021)
			(xy 48.474555 -62.805265) (xy 48.501808 -62.804802) (xy 48.529178 -62.805263) (xy 48.583358 -62.813082)
			(xy 48.635861 -62.828572) (xy 48.685608 -62.851415) (xy 48.731574 -62.88114) (xy 48.752506 -62.898782)
			(xy 48.75276 -62.899036) (xy 48.759851 -62.904616) (xy 48.776765 -62.910866) (xy 48.78578 -62.911228)
			(xy 48.852836 -62.911228) (xy 48.861854 -62.910882) (xy 48.87877 -62.904626) (xy 48.885856 -62.899036)
			(xy 48.885856 -62.898782) (xy 48.88611 -62.898782) (xy 48.907043 -62.881141) (xy 48.953011 -62.851417)
			(xy 49.002757 -62.828571) (xy 49.055259 -62.813075) (xy 49.109437 -62.805246) (xy 49.164179 -62.805246)
			(xy 49.218357 -62.813075) (xy 49.270859 -62.828571) (xy 49.320605 -62.851417) (xy 49.366573 -62.881141)
			(xy 49.387506 -62.898782) (xy 49.38776 -62.899036) (xy 49.394851 -62.904616) (xy 49.411765 -62.910866)
			(xy 49.42078 -62.911228) (xy 49.487836 -62.911228) (xy 49.496854 -62.910882) (xy 49.51377 -62.904626)
			(xy 49.520856 -62.899036) (xy 49.520856 -62.898782) (xy 49.52111 -62.898782) (xy 49.542025 -62.881122)
			(xy 49.588003 -62.851414) (xy 49.637755 -62.828582) (xy 49.690259 -62.813096) (xy 49.744438 -62.805273)
			(xy 49.771808 -62.804802) (xy 49.79906 -62.805268) (xy 49.853008 -62.813026) (xy 49.905303 -62.828382)
			(xy 49.954881 -62.851024) (xy 50.000731 -62.880492) (xy 50.041922 -62.916184) (xy 50.077613 -62.957375)
			(xy 50.107079 -63.003226) (xy 50.129721 -63.052804) (xy 50.139537 -63.086234) (xy 53.387496 -63.086234)
			(xy 53.391567 -63.030612) (xy 53.403693 -62.976175) (xy 53.423616 -62.924084) (xy 53.450912 -62.875449)
			(xy 53.484998 -62.831306) (xy 53.525147 -62.792597) (xy 53.570505 -62.760146) (xy 53.620105 -62.734645)
			(xy 53.672889 -62.716638) (xy 53.727732 -62.706508) (xy 53.783466 -62.704471) (xy 53.838903 -62.710571)
			(xy 53.89286 -62.724677) (xy 53.944189 -62.746489) (xy 53.991795 -62.775543) (xy 54.034663 -62.811218)
			(xy 54.035514 -62.812168) (xy 58.917838 -62.812168) (xy 58.921909 -62.756546) (xy 58.934035 -62.702109)
			(xy 58.953958 -62.650018) (xy 58.981254 -62.601383) (xy 59.01534 -62.55724) (xy 59.055489 -62.518531)
			(xy 59.100847 -62.48608) (xy 59.150447 -62.460579) (xy 59.203231 -62.442572) (xy 59.258074 -62.432442)
			(xy 59.313808 -62.430405) (xy 59.369245 -62.436505) (xy 59.423202 -62.450611) (xy 59.474531 -62.472423)
			(xy 59.522137 -62.501477) (xy 59.565005 -62.537152) (xy 59.602222 -62.578689) (xy 59.632995 -62.625202)
			(xy 59.656667 -62.675699) (xy 59.672735 -62.729106) (xy 59.680855 -62.784282) (xy 59.681364 -62.812168)
			(xy 59.680855 -62.840054) (xy 59.672735 -62.89523) (xy 59.656667 -62.948637) (xy 59.632995 -62.999134)
			(xy 59.602222 -63.045647) (xy 59.565005 -63.087184) (xy 59.522137 -63.122859) (xy 59.474531 -63.151913)
			(xy 59.423202 -63.173725) (xy 59.369245 -63.187831) (xy 59.313808 -63.193931) (xy 59.258074 -63.191894)
			(xy 59.203231 -63.181764) (xy 59.150447 -63.163757) (xy 59.100847 -63.138256) (xy 59.055489 -63.105805)
			(xy 59.01534 -63.067096) (xy 58.981254 -63.022953) (xy 58.953958 -62.974318) (xy 58.934035 -62.922227)
			(xy 58.921909 -62.86779) (xy 58.917838 -62.812168) (xy 54.035514 -62.812168) (xy 54.07188 -62.852755)
			(xy 54.102653 -62.899268) (xy 54.126325 -62.949765) (xy 54.142393 -63.003172) (xy 54.150513 -63.058348)
			(xy 54.151022 -63.086234) (xy 54.150513 -63.11412) (xy 54.142393 -63.169296) (xy 54.126325 -63.222703)
			(xy 54.102653 -63.2732) (xy 54.082673 -63.3034) (xy 55.501522 -63.3034) (xy 55.501522 -63.243464)
			(xy 55.509345 -63.184042) (xy 55.524858 -63.126149) (xy 55.547794 -63.070776) (xy 55.577761 -63.01887)
			(xy 55.614248 -62.97132) (xy 55.656628 -62.92894) (xy 55.704178 -62.892453) (xy 55.756084 -62.862486)
			(xy 55.811457 -62.83955) (xy 55.86935 -62.824037) (xy 55.928772 -62.816214) (xy 55.988708 -62.816214)
			(xy 56.04813 -62.824037) (xy 56.106023 -62.83955) (xy 56.161396 -62.862486) (xy 56.213302 -62.892453)
			(xy 56.260852 -62.92894) (xy 56.303232 -62.97132) (xy 56.339719 -63.01887) (xy 56.369686 -63.070776)
			(xy 56.392622 -63.126149) (xy 56.408135 -63.184042) (xy 56.415958 -63.243464) (xy 56.415992 -63.245552)
			(xy 69.104469 -63.245552) (xy 69.104469 -63.191048) (xy 69.112226 -63.137098) (xy 69.127582 -63.084801)
			(xy 69.150225 -63.035222) (xy 69.179692 -62.98937) (xy 69.215386 -62.948179) (xy 69.256578 -62.912486)
			(xy 69.302431 -62.88302) (xy 69.352011 -62.860379) (xy 69.404308 -62.845024) (xy 69.458258 -62.837269)
			(xy 69.48551 -62.836806) (xy 69.512881 -62.837265) (xy 69.56706 -62.845084) (xy 69.619563 -62.860575)
			(xy 69.66931 -62.883418) (xy 69.715276 -62.913144) (xy 69.736208 -62.930786) (xy 69.736462 -62.93104)
			(xy 69.743552 -62.936622) (xy 69.760466 -62.94287) (xy 69.769482 -62.943232) (xy 69.836538 -62.943232)
			(xy 69.845556 -62.942886) (xy 69.862472 -62.93663) (xy 69.869558 -62.93104) (xy 69.869558 -62.930786)
			(xy 69.869812 -62.930786) (xy 69.890745 -62.913145) (xy 69.936713 -62.883421) (xy 69.986459 -62.860575)
			(xy 70.038961 -62.845079) (xy 70.093139 -62.83725) (xy 70.147881 -62.83725) (xy 70.202059 -62.845079)
			(xy 70.254561 -62.860575) (xy 70.304307 -62.883421) (xy 70.350275 -62.913145) (xy 70.371208 -62.930786)
			(xy 70.371462 -62.93104) (xy 70.378552 -62.936622) (xy 70.395466 -62.94287) (xy 70.404482 -62.943232)
			(xy 70.471538 -62.943232) (xy 70.480556 -62.942886) (xy 70.497472 -62.93663) (xy 70.504558 -62.93104)
			(xy 70.504558 -62.930786) (xy 70.504812 -62.930786) (xy 70.525765 -62.913173) (xy 70.571732 -62.883457)
			(xy 70.621474 -62.860617) (xy 70.67397 -62.84512) (xy 70.728142 -62.837284) (xy 70.75551 -62.836806)
			(xy 70.782762 -62.837264) (xy 70.83671 -62.845022) (xy 70.889006 -62.860379) (xy 70.938584 -62.883022)
			(xy 70.984434 -62.912489) (xy 71.025625 -62.948182) (xy 71.061317 -62.989374) (xy 71.090783 -63.035225)
			(xy 71.113424 -63.084803) (xy 71.12878 -63.137099) (xy 71.136536 -63.191048) (xy 71.136536 -63.213549)
			(xy 74.120788 -63.213549) (xy 74.120788 -63.159052) (xy 74.128543 -63.105109) (xy 74.143896 -63.052819)
			(xy 74.166533 -63.003246) (xy 74.195994 -62.957399) (xy 74.23168 -62.916211) (xy 74.272864 -62.880521)
			(xy 74.318708 -62.851054) (xy 74.368278 -62.828411) (xy 74.420566 -62.813053) (xy 74.474508 -62.805291)
			(xy 74.501756 -62.804802) (xy 74.529125 -62.805293) (xy 74.583303 -62.813105) (xy 74.635806 -62.828588)
			(xy 74.685553 -62.851424) (xy 74.731521 -62.881143) (xy 74.752454 -62.898782) (xy 74.752708 -62.899036)
			(xy 74.759785 -62.904636) (xy 74.776709 -62.910874) (xy 74.785728 -62.911228) (xy 74.852784 -62.911228)
			(xy 74.861799 -62.910857) (xy 74.878716 -62.904618) (xy 74.885804 -62.899036) (xy 74.885804 -62.898782)
			(xy 74.886058 -62.898782) (xy 74.906991 -62.881141) (xy 74.952959 -62.851417) (xy 75.002705 -62.828571)
			(xy 75.055207 -62.813075) (xy 75.109385 -62.805246) (xy 75.164127 -62.805246) (xy 75.218305 -62.813075)
			(xy 75.270807 -62.828571) (xy 75.320553 -62.851417) (xy 75.366521 -62.881141) (xy 75.387454 -62.898782)
			(xy 75.387708 -62.899036) (xy 75.394785 -62.904636) (xy 75.411709 -62.910874) (xy 75.420728 -62.911228)
			(xy 75.487784 -62.911228) (xy 75.496799 -62.910857) (xy 75.513716 -62.904618) (xy 75.520804 -62.899036)
			(xy 75.520804 -62.898782) (xy 75.521058 -62.898782) (xy 75.541993 -62.881146) (xy 75.587965 -62.851435)
			(xy 75.637712 -62.828598) (xy 75.690212 -62.813106) (xy 75.744387 -62.805277) (xy 75.771756 -62.804802)
			(xy 75.799012 -62.805242) (xy 75.852969 -62.812994) (xy 75.905273 -62.828347) (xy 75.95486 -62.850987)
			(xy 76.00072 -62.880455) (xy 76.041919 -62.916149) (xy 76.077619 -62.957344) (xy 76.107092 -63.003201)
			(xy 76.129738 -63.052785) (xy 76.13956 -63.086234) (xy 79.387444 -63.086234) (xy 79.391515 -63.030612)
			(xy 79.403641 -62.976175) (xy 79.423564 -62.924084) (xy 79.45086 -62.875449) (xy 79.484946 -62.831306)
			(xy 79.525095 -62.792597) (xy 79.570453 -62.760146) (xy 79.620053 -62.734645) (xy 79.672837 -62.716638)
			(xy 79.72768 -62.706508) (xy 79.783414 -62.704471) (xy 79.838851 -62.710571) (xy 79.892808 -62.724677)
			(xy 79.944137 -62.746489) (xy 79.991743 -62.775543) (xy 80.034611 -62.811218) (xy 80.035462 -62.812168)
			(xy 84.917786 -62.812168) (xy 84.921857 -62.756546) (xy 84.933983 -62.702109) (xy 84.953906 -62.650018)
			(xy 84.981202 -62.601383) (xy 85.015288 -62.55724) (xy 85.055437 -62.518531) (xy 85.100795 -62.48608)
			(xy 85.150395 -62.460579) (xy 85.203179 -62.442572) (xy 85.258022 -62.432442) (xy 85.313756 -62.430405)
			(xy 85.369193 -62.436505) (xy 85.42315 -62.450611) (xy 85.474479 -62.472423) (xy 85.522085 -62.501477)
			(xy 85.564953 -62.537152) (xy 85.60217 -62.578689) (xy 85.632943 -62.625202) (xy 85.656615 -62.675699)
			(xy 85.672683 -62.729106) (xy 85.680803 -62.784282) (xy 85.681312 -62.812168) (xy 85.680803 -62.840054)
			(xy 85.672683 -62.89523) (xy 85.656615 -62.948637) (xy 85.632943 -62.999134) (xy 85.60217 -63.045647)
			(xy 85.564953 -63.087184) (xy 85.522085 -63.122859) (xy 85.474479 -63.151913) (xy 85.42315 -63.173725)
			(xy 85.369193 -63.187831) (xy 85.313756 -63.193931) (xy 85.258022 -63.191894) (xy 85.203179 -63.181764)
			(xy 85.150395 -63.163757) (xy 85.100795 -63.138256) (xy 85.055437 -63.105805) (xy 85.015288 -63.067096)
			(xy 84.981202 -63.022953) (xy 84.953906 -62.974318) (xy 84.933983 -62.922227) (xy 84.921857 -62.86779)
			(xy 84.917786 -62.812168) (xy 80.035462 -62.812168) (xy 80.071828 -62.852755) (xy 80.102601 -62.899268)
			(xy 80.126273 -62.949765) (xy 80.142341 -63.003172) (xy 80.150461 -63.058348) (xy 80.15097 -63.086234)
			(xy 80.150461 -63.11412) (xy 80.142341 -63.169296) (xy 80.126273 -63.222703) (xy 80.102601 -63.2732)
			(xy 80.082621 -63.3034) (xy 81.50147 -63.3034) (xy 81.50147 -63.243464) (xy 81.509293 -63.184042)
			(xy 81.524806 -63.126149) (xy 81.547742 -63.070776) (xy 81.577709 -63.01887) (xy 81.614196 -62.97132)
			(xy 81.656576 -62.92894) (xy 81.704126 -62.892453) (xy 81.756032 -62.862486) (xy 81.811405 -62.83955)
			(xy 81.869298 -62.824037) (xy 81.92872 -62.816214) (xy 81.988656 -62.816214) (xy 82.048078 -62.824037)
			(xy 82.105971 -62.83955) (xy 82.161344 -62.862486) (xy 82.21325 -62.892453) (xy 82.2608 -62.92894)
			(xy 82.30318 -62.97132) (xy 82.339667 -63.01887) (xy 82.369634 -63.070776) (xy 82.39257 -63.126149)
			(xy 82.408083 -63.184042) (xy 82.415906 -63.243464) (xy 82.41594 -63.245548) (xy 95.104492 -63.245548)
			(xy 95.104492 -63.191052) (xy 95.112247 -63.13711) (xy 95.1276 -63.08482) (xy 95.150237 -63.035248)
			(xy 95.179698 -62.989401) (xy 95.215384 -62.948214) (xy 95.256567 -62.912523) (xy 95.302411 -62.883057)
			(xy 95.351981 -62.860414) (xy 95.404269 -62.845056) (xy 95.45821 -62.837295) (xy 95.485458 -62.836806)
			(xy 95.512827 -62.837295) (xy 95.567006 -62.845107) (xy 95.619508 -62.860591) (xy 95.669256 -62.883427)
			(xy 95.715224 -62.913147) (xy 95.736156 -62.930786) (xy 95.73641 -62.93104) (xy 95.743486 -62.936642)
			(xy 95.760411 -62.942878) (xy 95.76943 -62.943232) (xy 95.836486 -62.943232) (xy 95.845501 -62.942861)
			(xy 95.862418 -62.936622) (xy 95.869506 -62.93104) (xy 95.869506 -62.930786) (xy 95.86976 -62.930786)
			(xy 95.890693 -62.913145) (xy 95.936661 -62.883421) (xy 95.986407 -62.860575) (xy 96.038909 -62.845079)
			(xy 96.093087 -62.83725) (xy 96.147829 -62.83725) (xy 96.202007 -62.845079) (xy 96.254509 -62.860575)
			(xy 96.304255 -62.883421) (xy 96.350223 -62.913145) (xy 96.371156 -62.930786) (xy 96.37141 -62.93104)
			(xy 96.378486 -62.936642) (xy 96.395411 -62.942878) (xy 96.40443 -62.943232) (xy 96.471486 -62.943232)
			(xy 96.480501 -62.942861) (xy 96.497418 -62.936622) (xy 96.504506 -62.93104) (xy 96.504506 -62.930786)
			(xy 96.50476 -62.930786) (xy 96.525695 -62.91315) (xy 96.571667 -62.883438) (xy 96.621414 -62.860602)
			(xy 96.673914 -62.84511) (xy 96.728089 -62.837281) (xy 96.755458 -62.836806) (xy 96.782714 -62.837238)
			(xy 96.836671 -62.84499) (xy 96.888976 -62.860343) (xy 96.938564 -62.882984) (xy 96.984424 -62.912452)
			(xy 97.025623 -62.948147) (xy 97.061322 -62.989343) (xy 97.090795 -63.0352) (xy 97.113442 -63.084784)
			(xy 97.128801 -63.137088) (xy 97.136559 -63.191044) (xy 97.136559 -63.213552) (xy 100.120665 -63.213552)
			(xy 100.120665 -63.159048) (xy 100.128422 -63.105098) (xy 100.143778 -63.052801) (xy 100.16642 -63.003222)
			(xy 100.195888 -62.95737) (xy 100.231581 -62.916178) (xy 100.272773 -62.880485) (xy 100.318625 -62.851018)
			(xy 100.368205 -62.828377) (xy 100.420502 -62.813021) (xy 100.474452 -62.805265) (xy 100.501704 -62.804802)
			(xy 100.529074 -62.805265) (xy 100.583254 -62.813084) (xy 100.635757 -62.828573) (xy 100.685504 -62.851416)
			(xy 100.73147 -62.881141) (xy 100.752402 -62.898782) (xy 100.752656 -62.899036) (xy 100.759748 -62.904614)
			(xy 100.776661 -62.910865) (xy 100.785676 -62.911228) (xy 100.852732 -62.911228) (xy 100.86175 -62.91088)
			(xy 100.878666 -62.904626) (xy 100.885752 -62.899036) (xy 100.885752 -62.898782) (xy 100.886006 -62.898782)
			(xy 100.906939 -62.881141) (xy 100.952907 -62.851417) (xy 101.002653 -62.828571) (xy 101.055155 -62.813075)
			(xy 101.109333 -62.805246) (xy 101.164075 -62.805246) (xy 101.218253 -62.813075) (xy 101.270755 -62.828571)
			(xy 101.320501 -62.851417) (xy 101.366469 -62.881141) (xy 101.387402 -62.898782) (xy 101.387656 -62.899036)
			(xy 101.394748 -62.904614) (xy 101.411661 -62.910865) (xy 101.420676 -62.911228) (xy 101.487732 -62.911228)
			(xy 101.49675 -62.91088) (xy 101.513666 -62.904626) (xy 101.520752 -62.899036) (xy 101.520752 -62.898782)
			(xy 101.521006 -62.898782) (xy 101.541923 -62.881124) (xy 101.5879 -62.851415) (xy 101.637651 -62.828583)
			(xy 101.690155 -62.813097) (xy 101.744334 -62.805273) (xy 101.771704 -62.804802) (xy 101.798956 -62.805268)
			(xy 101.852904 -62.813025) (xy 101.9052 -62.828381) (xy 101.954778 -62.851023) (xy 102.000629 -62.88049)
			(xy 102.04182 -62.916183) (xy 102.077512 -62.957374) (xy 102.106979 -63.003225) (xy 102.12962 -63.052804)
			(xy 102.139436 -63.086234) (xy 117.487698 -63.086234) (xy 117.491769 -63.030612) (xy 117.503895 -62.976175)
			(xy 117.523818 -62.924084) (xy 117.551114 -62.875449) (xy 117.5852 -62.831306) (xy 117.625349 -62.792597)
			(xy 117.670707 -62.760146) (xy 117.720307 -62.734645) (xy 117.773091 -62.716638) (xy 117.827934 -62.706508)
			(xy 117.883668 -62.704471) (xy 117.939105 -62.710571) (xy 117.993062 -62.724677) (xy 118.044391 -62.746489)
			(xy 118.091997 -62.775543) (xy 118.134865 -62.811218) (xy 118.135716 -62.812168) (xy 123.01804 -62.812168)
			(xy 123.022111 -62.756546) (xy 123.034237 -62.702109) (xy 123.05416 -62.650018) (xy 123.081456 -62.601383)
			(xy 123.115542 -62.55724) (xy 123.155691 -62.518531) (xy 123.201049 -62.48608) (xy 123.250649 -62.460579)
			(xy 123.303433 -62.442572) (xy 123.358276 -62.432442) (xy 123.41401 -62.430405) (xy 123.469447 -62.436505)
			(xy 123.523404 -62.450611) (xy 123.574733 -62.472423) (xy 123.622339 -62.501477) (xy 123.665207 -62.537152)
			(xy 123.702424 -62.578689) (xy 123.733197 -62.625202) (xy 123.756869 -62.675699) (xy 123.772937 -62.729106)
			(xy 123.781057 -62.784282) (xy 123.781566 -62.812168) (xy 123.781057 -62.840054) (xy 123.772937 -62.89523)
			(xy 123.756869 -62.948637) (xy 123.733197 -62.999134) (xy 123.702424 -63.045647) (xy 123.665207 -63.087184)
			(xy 123.622339 -63.122859) (xy 123.574733 -63.151913) (xy 123.523404 -63.173725) (xy 123.469447 -63.187831)
			(xy 123.41401 -63.193931) (xy 123.358276 -63.191894) (xy 123.303433 -63.181764) (xy 123.250649 -63.163757)
			(xy 123.201049 -63.138256) (xy 123.155691 -63.105805) (xy 123.115542 -63.067096) (xy 123.081456 -63.022953)
			(xy 123.05416 -62.974318) (xy 123.034237 -62.922227) (xy 123.022111 -62.86779) (xy 123.01804 -62.812168)
			(xy 118.135716 -62.812168) (xy 118.172082 -62.852755) (xy 118.202855 -62.899268) (xy 118.226527 -62.949765)
			(xy 118.242595 -63.003172) (xy 118.250715 -63.058348) (xy 118.251224 -63.086234) (xy 118.250715 -63.11412)
			(xy 118.242595 -63.169296) (xy 118.226527 -63.222703) (xy 118.202855 -63.2732) (xy 118.182875 -63.3034)
			(xy 119.601724 -63.3034) (xy 119.601724 -63.243464) (xy 119.609547 -63.184042) (xy 119.62506 -63.126149)
			(xy 119.647996 -63.070776) (xy 119.677963 -63.01887) (xy 119.71445 -62.97132) (xy 119.75683 -62.92894)
			(xy 119.80438 -62.892453) (xy 119.856286 -62.862486) (xy 119.911659 -62.83955) (xy 119.969552 -62.824037)
			(xy 120.028974 -62.816214) (xy 120.08891 -62.816214) (xy 120.148332 -62.824037) (xy 120.206225 -62.83955)
			(xy 120.261598 -62.862486) (xy 120.313504 -62.892453) (xy 120.361054 -62.92894) (xy 120.403434 -62.97132)
			(xy 120.439921 -63.01887) (xy 120.469888 -63.070776) (xy 120.492824 -63.126149) (xy 120.508337 -63.184042)
			(xy 120.51616 -63.243464) (xy 120.516194 -63.245552) (xy 133.204669 -63.245552) (xy 133.204669 -63.191048)
			(xy 133.212426 -63.137098) (xy 133.227782 -63.084801) (xy 133.250425 -63.035222) (xy 133.279893 -62.98937)
			(xy 133.315587 -62.948178) (xy 133.356779 -62.912486) (xy 133.402632 -62.883019) (xy 133.452212 -62.860378)
			(xy 133.504509 -62.845024) (xy 133.55846 -62.837268) (xy 133.585712 -62.836806) (xy 133.613083 -62.837264)
			(xy 133.667262 -62.845083) (xy 133.719765 -62.860574) (xy 133.769512 -62.883418) (xy 133.815479 -62.913144)
			(xy 133.83641 -62.930786) (xy 133.836664 -62.93104) (xy 133.843753 -62.936623) (xy 133.860668 -62.942871)
			(xy 133.869684 -62.943232) (xy 133.93674 -62.943232) (xy 133.945758 -62.942887) (xy 133.962675 -62.93663)
			(xy 133.96976 -62.93104) (xy 133.96976 -62.930786) (xy 133.970014 -62.930786) (xy 133.990947 -62.913145)
			(xy 134.036915 -62.883421) (xy 134.086661 -62.860575) (xy 134.139163 -62.845079) (xy 134.193341 -62.83725)
			(xy 134.248083 -62.83725) (xy 134.302261 -62.845079) (xy 134.354763 -62.860575) (xy 134.404509 -62.883421)
			(xy 134.450477 -62.913145) (xy 134.47141 -62.930786) (xy 134.471664 -62.93104) (xy 134.478753 -62.936623)
			(xy 134.495668 -62.942871) (xy 134.504684 -62.943232) (xy 134.57174 -62.943232) (xy 134.580758 -62.942887)
			(xy 134.597675 -62.93663) (xy 134.60476 -62.93104) (xy 134.60476 -62.930786) (xy 134.605014 -62.930786)
			(xy 134.625966 -62.913172) (xy 134.671933 -62.883457) (xy 134.721676 -62.860616) (xy 134.774172 -62.845119)
			(xy 134.828344 -62.837284) (xy 134.855712 -62.836806) (xy 134.882964 -62.837265) (xy 134.936912 -62.845023)
			(xy 134.989207 -62.86038) (xy 135.038785 -62.883022) (xy 135.084635 -62.91249) (xy 135.125826 -62.948183)
			(xy 135.161517 -62.989374) (xy 135.190984 -63.035226) (xy 135.213625 -63.084804) (xy 135.22898 -63.1371)
			(xy 135.236736 -63.191048) (xy 135.236736 -63.213549) (xy 138.220988 -63.213549) (xy 138.220988 -63.159051)
			(xy 138.228743 -63.105109) (xy 138.244096 -63.052819) (xy 138.266733 -63.003246) (xy 138.296195 -62.957399)
			(xy 138.331881 -62.916211) (xy 138.373065 -62.88052) (xy 138.418909 -62.851054) (xy 138.468479 -62.828411)
			(xy 138.520768 -62.813052) (xy 138.574709 -62.805291) (xy 138.601958 -62.804802) (xy 138.629327 -62.805292)
			(xy 138.683505 -62.813104) (xy 138.736008 -62.828588) (xy 138.785756 -62.851424) (xy 138.831723 -62.881143)
			(xy 138.852656 -62.898782) (xy 138.85291 -62.899036) (xy 138.859987 -62.904637) (xy 138.876911 -62.910874)
			(xy 138.88593 -62.911228) (xy 138.952986 -62.911228) (xy 138.962001 -62.910858) (xy 138.978918 -62.904619)
			(xy 138.986006 -62.899036) (xy 138.986006 -62.898782) (xy 138.98626 -62.898782) (xy 139.007193 -62.881141)
			(xy 139.053161 -62.851417) (xy 139.102907 -62.828571) (xy 139.155409 -62.813075) (xy 139.209587 -62.805246)
			(xy 139.264329 -62.805246) (xy 139.318507 -62.813075) (xy 139.371009 -62.828571) (xy 139.420755 -62.851417)
			(xy 139.466723 -62.881141) (xy 139.487656 -62.898782) (xy 139.48791 -62.899036) (xy 139.494987 -62.904637)
			(xy 139.511911 -62.910874) (xy 139.52093 -62.911228) (xy 139.587986 -62.911228) (xy 139.597001 -62.910858)
			(xy 139.613918 -62.904619) (xy 139.621006 -62.899036) (xy 139.621006 -62.898782) (xy 139.62126 -62.898782)
			(xy 139.642194 -62.881145) (xy 139.688167 -62.851434) (xy 139.737914 -62.828598) (xy 139.790414 -62.813106)
			(xy 139.844589 -62.805277) (xy 139.871958 -62.804802) (xy 139.899214 -62.805242) (xy 139.953171 -62.812994)
			(xy 140.005475 -62.828347) (xy 140.055062 -62.850988) (xy 140.100921 -62.880456) (xy 140.14212 -62.91615)
			(xy 140.177819 -62.957345) (xy 140.207292 -63.003201) (xy 140.229938 -63.052786) (xy 140.23976 -63.086234)
			(xy 143.487646 -63.086234) (xy 143.491717 -63.030612) (xy 143.503843 -62.976175) (xy 143.523766 -62.924084)
			(xy 143.551062 -62.875449) (xy 143.585148 -62.831306) (xy 143.625297 -62.792597) (xy 143.670655 -62.760146)
			(xy 143.720255 -62.734645) (xy 143.773039 -62.716638) (xy 143.827882 -62.706508) (xy 143.883616 -62.704471)
			(xy 143.939053 -62.710571) (xy 143.99301 -62.724677) (xy 144.044339 -62.746489) (xy 144.091945 -62.775543)
			(xy 144.134813 -62.811218) (xy 144.135664 -62.812168) (xy 149.017988 -62.812168) (xy 149.022059 -62.756546)
			(xy 149.034185 -62.702109) (xy 149.054108 -62.650018) (xy 149.081404 -62.601383) (xy 149.11549 -62.55724)
			(xy 149.155639 -62.518531) (xy 149.200997 -62.48608) (xy 149.250597 -62.460579) (xy 149.303381 -62.442572)
			(xy 149.358224 -62.432442) (xy 149.413958 -62.430405) (xy 149.469395 -62.436505) (xy 149.523352 -62.450611)
			(xy 149.574681 -62.472423) (xy 149.622287 -62.501477) (xy 149.665155 -62.537152) (xy 149.702372 -62.578689)
			(xy 149.733145 -62.625202) (xy 149.756817 -62.675699) (xy 149.772885 -62.729106) (xy 149.781005 -62.784282)
			(xy 149.781514 -62.812168) (xy 149.781005 -62.840054) (xy 149.772885 -62.89523) (xy 149.756817 -62.948637)
			(xy 149.733145 -62.999134) (xy 149.702372 -63.045647) (xy 149.665155 -63.087184) (xy 149.622287 -63.122859)
			(xy 149.574681 -63.151913) (xy 149.523352 -63.173725) (xy 149.469395 -63.187831) (xy 149.413958 -63.193931)
			(xy 149.358224 -63.191894) (xy 149.303381 -63.181764) (xy 149.250597 -63.163757) (xy 149.200997 -63.138256)
			(xy 149.155639 -63.105805) (xy 149.11549 -63.067096) (xy 149.081404 -63.022953) (xy 149.054108 -62.974318)
			(xy 149.034185 -62.922227) (xy 149.022059 -62.86779) (xy 149.017988 -62.812168) (xy 144.135664 -62.812168)
			(xy 144.17203 -62.852755) (xy 144.202803 -62.899268) (xy 144.226475 -62.949765) (xy 144.242543 -63.003172)
			(xy 144.250663 -63.058348) (xy 144.251172 -63.086234) (xy 144.250663 -63.11412) (xy 144.242543 -63.169296)
			(xy 144.226475 -63.222703) (xy 144.202803 -63.2732) (xy 144.182823 -63.3034) (xy 145.601672 -63.3034)
			(xy 145.601672 -63.243464) (xy 145.609495 -63.184042) (xy 145.625008 -63.126149) (xy 145.647944 -63.070776)
			(xy 145.677911 -63.01887) (xy 145.714398 -62.97132) (xy 145.756778 -62.92894) (xy 145.804328 -62.892453)
			(xy 145.856234 -62.862486) (xy 145.911607 -62.83955) (xy 145.9695 -62.824037) (xy 146.028922 -62.816214)
			(xy 146.088858 -62.816214) (xy 146.14828 -62.824037) (xy 146.206173 -62.83955) (xy 146.261546 -62.862486)
			(xy 146.313452 -62.892453) (xy 146.361002 -62.92894) (xy 146.403382 -62.97132) (xy 146.439869 -63.01887)
			(xy 146.469836 -63.070776) (xy 146.492772 -63.126149) (xy 146.508285 -63.184042) (xy 146.516108 -63.243464)
			(xy 146.516142 -63.245548) (xy 159.204692 -63.245548) (xy 159.204692 -63.191052) (xy 159.212447 -63.137109)
			(xy 159.2278 -63.08482) (xy 159.250437 -63.035247) (xy 159.279899 -62.9894) (xy 159.315584 -62.948213)
			(xy 159.356768 -62.912523) (xy 159.402612 -62.883056) (xy 159.452182 -62.860414) (xy 159.50447 -62.845056)
			(xy 159.558412 -62.837295) (xy 159.58566 -62.836806) (xy 159.613029 -62.837294) (xy 159.667208 -62.845106)
			(xy 159.719711 -62.86059) (xy 159.769458 -62.883427) (xy 159.815426 -62.913147) (xy 159.836358 -62.930786)
			(xy 159.836612 -62.93104) (xy 159.843687 -62.936643) (xy 159.860613 -62.942879) (xy 159.869632 -62.943232)
			(xy 159.936688 -62.943232) (xy 159.945703 -62.942862) (xy 159.96262 -62.936623) (xy 159.969708 -62.93104)
			(xy 159.969708 -62.930786) (xy 159.969962 -62.930786) (xy 159.990895 -62.913145) (xy 160.036863 -62.883421)
			(xy 160.086609 -62.860575) (xy 160.139111 -62.845079) (xy 160.193289 -62.83725) (xy 160.248031 -62.83725)
			(xy 160.302209 -62.845079) (xy 160.354711 -62.860575) (xy 160.404457 -62.883421) (xy 160.450425 -62.913145)
			(xy 160.471358 -62.930786) (xy 160.471612 -62.93104) (xy 160.478687 -62.936643) (xy 160.495613 -62.942879)
			(xy 160.504632 -62.943232) (xy 160.571688 -62.943232) (xy 160.580703 -62.942862) (xy 160.59762 -62.936623)
			(xy 160.604708 -62.93104) (xy 160.604708 -62.930786) (xy 160.604962 -62.930786) (xy 160.625896 -62.913149)
			(xy 160.671868 -62.883437) (xy 160.721615 -62.860601) (xy 160.774116 -62.84511) (xy 160.828291 -62.837281)
			(xy 160.85566 -62.836806) (xy 160.882916 -62.837238) (xy 160.936873 -62.844991) (xy 160.989178 -62.860344)
			(xy 161.038765 -62.882985) (xy 161.084625 -62.912453) (xy 161.125824 -62.948148) (xy 161.161523 -62.989343)
			(xy 161.190996 -63.0352) (xy 161.213642 -63.084785) (xy 161.229001 -63.137088) (xy 161.236759 -63.191044)
			(xy 161.236759 -63.213552) (xy 164.220865 -63.213552) (xy 164.220865 -63.159048) (xy 164.228622 -63.105098)
			(xy 164.243978 -63.052801) (xy 164.266621 -63.003221) (xy 164.296088 -62.957369) (xy 164.331782 -62.916177)
			(xy 164.372974 -62.880485) (xy 164.418827 -62.851018) (xy 164.468406 -62.828376) (xy 164.520703 -62.813021)
			(xy 164.574654 -62.805265) (xy 164.601906 -62.804802) (xy 164.629276 -62.805264) (xy 164.683456 -62.813083)
			(xy 164.735959 -62.828573) (xy 164.785706 -62.851415) (xy 164.831672 -62.881141) (xy 164.852604 -62.898782)
			(xy 164.852858 -62.899036) (xy 164.859949 -62.904615) (xy 164.876863 -62.910865) (xy 164.885878 -62.911228)
			(xy 164.952934 -62.911228) (xy 164.961952 -62.910881) (xy 164.978868 -62.904626) (xy 164.985954 -62.899036)
			(xy 164.985954 -62.898782) (xy 164.986208 -62.898782) (xy 165.007141 -62.881141) (xy 165.053109 -62.851417)
			(xy 165.102855 -62.828571) (xy 165.155357 -62.813075) (xy 165.209535 -62.805246) (xy 165.264277 -62.805246)
			(xy 165.318455 -62.813075) (xy 165.370957 -62.828571) (xy 165.420703 -62.851417) (xy 165.466671 -62.881141)
			(xy 165.487604 -62.898782) (xy 165.487858 -62.899036) (xy 165.494949 -62.904615) (xy 165.511863 -62.910865)
			(xy 165.520878 -62.911228) (xy 165.587934 -62.911228) (xy 165.596952 -62.910881) (xy 165.613868 -62.904626)
			(xy 165.620954 -62.899036) (xy 165.620954 -62.898782) (xy 165.621208 -62.898782) (xy 165.642124 -62.881123)
			(xy 165.688101 -62.851415) (xy 165.737853 -62.828583) (xy 165.790357 -62.813096) (xy 165.844536 -62.805273)
			(xy 165.871906 -62.804802) (xy 165.899158 -62.805268) (xy 165.953106 -62.813026) (xy 166.005402 -62.828382)
			(xy 166.054979 -62.851024) (xy 166.10083 -62.880491) (xy 166.142021 -62.916183) (xy 166.177713 -62.957375)
			(xy 166.207179 -63.003226) (xy 166.22982 -63.052804) (xy 166.239636 -63.086234) (xy 169.515026 -63.086234)
			(xy 169.519097 -63.030612) (xy 169.531223 -62.976175) (xy 169.551146 -62.924084) (xy 169.578442 -62.875449)
			(xy 169.612528 -62.831306) (xy 169.652677 -62.792597) (xy 169.698035 -62.760146) (xy 169.747635 -62.734645)
			(xy 169.800419 -62.716638) (xy 169.855262 -62.706508) (xy 169.910996 -62.704471) (xy 169.966433 -62.710571)
			(xy 170.02039 -62.724677) (xy 170.071719 -62.746489) (xy 170.119325 -62.775543) (xy 170.162193 -62.811218)
			(xy 170.163044 -62.812168) (xy 175.017936 -62.812168) (xy 175.022007 -62.756546) (xy 175.034133 -62.702109)
			(xy 175.054056 -62.650018) (xy 175.081352 -62.601383) (xy 175.115438 -62.55724) (xy 175.155587 -62.518531)
			(xy 175.200945 -62.48608) (xy 175.250545 -62.460579) (xy 175.303329 -62.442572) (xy 175.358172 -62.432442)
			(xy 175.413906 -62.430405) (xy 175.469343 -62.436505) (xy 175.5233 -62.450611) (xy 175.574629 -62.472423)
			(xy 175.622235 -62.501477) (xy 175.665103 -62.537152) (xy 175.70232 -62.578689) (xy 175.733093 -62.625202)
			(xy 175.756765 -62.675699) (xy 175.772833 -62.729106) (xy 175.780953 -62.784282) (xy 175.781462 -62.812168)
			(xy 175.780953 -62.840054) (xy 175.772833 -62.89523) (xy 175.756765 -62.948637) (xy 175.733093 -62.999134)
			(xy 175.70232 -63.045647) (xy 175.665103 -63.087184) (xy 175.622235 -63.122859) (xy 175.574629 -63.151913)
			(xy 175.5233 -63.173725) (xy 175.469343 -63.187831) (xy 175.413906 -63.193931) (xy 175.358172 -63.191894)
			(xy 175.303329 -63.181764) (xy 175.250545 -63.163757) (xy 175.200945 -63.138256) (xy 175.155587 -63.105805)
			(xy 175.115438 -63.067096) (xy 175.081352 -63.022953) (xy 175.054056 -62.974318) (xy 175.034133 -62.922227)
			(xy 175.022007 -62.86779) (xy 175.017936 -62.812168) (xy 170.163044 -62.812168) (xy 170.19941 -62.852755)
			(xy 170.230183 -62.899268) (xy 170.253855 -62.949765) (xy 170.269923 -63.003172) (xy 170.278043 -63.058348)
			(xy 170.278552 -63.086234) (xy 170.278043 -63.11412) (xy 170.269923 -63.169296) (xy 170.253855 -63.222703)
			(xy 170.230183 -63.2732) (xy 170.210203 -63.3034) (xy 171.60162 -63.3034) (xy 171.60162 -63.243464)
			(xy 171.609443 -63.184042) (xy 171.624956 -63.126149) (xy 171.647892 -63.070776) (xy 171.677859 -63.01887)
			(xy 171.714346 -62.97132) (xy 171.756726 -62.92894) (xy 171.804276 -62.892453) (xy 171.856182 -62.862486)
			(xy 171.911555 -62.83955) (xy 171.969448 -62.824037) (xy 172.02887 -62.816214) (xy 172.088806 -62.816214)
			(xy 172.148228 -62.824037) (xy 172.206121 -62.83955) (xy 172.261494 -62.862486) (xy 172.3134 -62.892453)
			(xy 172.36095 -62.92894) (xy 172.40333 -62.97132) (xy 172.439817 -63.01887) (xy 172.469784 -63.070776)
			(xy 172.49272 -63.126149) (xy 172.508233 -63.184042) (xy 172.516056 -63.243464) (xy 172.51609 -63.245552)
			(xy 185.204569 -63.245552) (xy 185.204569 -63.191048) (xy 185.212326 -63.137098) (xy 185.227682 -63.084802)
			(xy 185.250324 -63.035223) (xy 185.279792 -62.989371) (xy 185.315485 -62.94818) (xy 185.356677 -62.912487)
			(xy 185.40253 -62.88302) (xy 185.452109 -62.860379) (xy 185.504406 -62.845025) (xy 185.558356 -62.837269)
			(xy 185.585608 -62.836806) (xy 185.612978 -62.837266) (xy 185.667158 -62.845085) (xy 185.719661 -62.860575)
			(xy 185.769408 -62.883419) (xy 185.815374 -62.913144) (xy 185.836306 -62.930786) (xy 185.83656 -62.93104)
			(xy 185.84365 -62.936621) (xy 185.860564 -62.94287) (xy 185.86958 -62.943232) (xy 185.936636 -62.943232)
			(xy 185.945654 -62.942885) (xy 185.96257 -62.93663) (xy 185.969656 -62.93104) (xy 185.969656 -62.930786)
			(xy 185.96991 -62.930786) (xy 185.990843 -62.913145) (xy 186.036811 -62.883421) (xy 186.086557 -62.860575)
			(xy 186.139059 -62.845079) (xy 186.193237 -62.83725) (xy 186.247979 -62.83725) (xy 186.302157 -62.845079)
			(xy 186.354659 -62.860575) (xy 186.404405 -62.883421) (xy 186.450373 -62.913145) (xy 186.471306 -62.930786)
			(xy 186.47156 -62.93104) (xy 186.47865 -62.936621) (xy 186.495564 -62.94287) (xy 186.50458 -62.943232)
			(xy 186.571636 -62.943232) (xy 186.580654 -62.942885) (xy 186.59757 -62.93663) (xy 186.604656 -62.93104)
			(xy 186.604656 -62.930786) (xy 186.60491 -62.930786) (xy 186.625826 -62.913127) (xy 186.671803 -62.883418)
			(xy 186.721555 -62.860586) (xy 186.774059 -62.8451) (xy 186.828238 -62.837277) (xy 186.855608 -62.836806)
			(xy 186.88286 -62.837264) (xy 186.936809 -62.845022) (xy 186.989104 -62.860378) (xy 187.038682 -62.883021)
			(xy 187.084534 -62.912488) (xy 187.125724 -62.948181) (xy 187.161416 -62.989373) (xy 187.190883 -63.035225)
			(xy 187.213524 -63.084803) (xy 187.22888 -63.137099) (xy 187.236636 -63.191048) (xy 187.236636 -63.213548)
			(xy 190.220888 -63.213548) (xy 190.220888 -63.159052) (xy 190.228643 -63.105109) (xy 190.243996 -63.05282)
			(xy 190.266633 -63.003247) (xy 190.296094 -62.9574) (xy 190.33178 -62.916212) (xy 190.372963 -62.880522)
			(xy 190.418807 -62.851055) (xy 190.468377 -62.828412) (xy 190.520664 -62.813053) (xy 190.574606 -62.805291)
			(xy 190.601854 -62.804802) (xy 190.629223 -62.805295) (xy 190.683401 -62.813106) (xy 190.735904 -62.828589)
			(xy 190.785651 -62.851425) (xy 190.831619 -62.881143) (xy 190.852552 -62.898782) (xy 190.852806 -62.899036)
			(xy 190.859884 -62.904635) (xy 190.876807 -62.910873) (xy 190.885826 -62.911228) (xy 190.952882 -62.911228)
			(xy 190.961897 -62.910856) (xy 190.978814 -62.904618) (xy 190.985902 -62.899036) (xy 190.985902 -62.898782)
			(xy 190.986156 -62.898782) (xy 191.007089 -62.881141) (xy 191.053057 -62.851417) (xy 191.102803 -62.828571)
			(xy 191.155305 -62.813075) (xy 191.209483 -62.805246) (xy 191.264225 -62.805246) (xy 191.318403 -62.813075)
			(xy 191.370905 -62.828571) (xy 191.420651 -62.851417) (xy 191.466619 -62.881141) (xy 191.487552 -62.898782)
			(xy 191.487806 -62.899036) (xy 191.494884 -62.904635) (xy 191.511807 -62.910873) (xy 191.520826 -62.911228)
			(xy 191.587882 -62.911228) (xy 191.596897 -62.910856) (xy 191.613814 -62.904618) (xy 191.620902 -62.899036)
			(xy 191.620902 -62.898782) (xy 191.621156 -62.898782) (xy 191.642092 -62.881147) (xy 191.688064 -62.851435)
			(xy 191.73781 -62.828599) (xy 191.79031 -62.813107) (xy 191.844485 -62.805277) (xy 191.871854 -62.804802)
			(xy 191.89911 -62.805242) (xy 191.953067 -62.812994) (xy 192.005372 -62.828346) (xy 192.054959 -62.850987)
			(xy 192.100819 -62.880454) (xy 192.142019 -62.916149) (xy 192.177718 -62.957344) (xy 192.207191 -63.0032)
			(xy 192.229838 -63.052785) (xy 192.23966 -63.086234) (xy 195.487542 -63.086234) (xy 195.491613 -63.030612)
			(xy 195.503739 -62.976175) (xy 195.523662 -62.924084) (xy 195.550958 -62.875449) (xy 195.585044 -62.831306)
			(xy 195.625193 -62.792597) (xy 195.670551 -62.760146) (xy 195.720151 -62.734645) (xy 195.772935 -62.716638)
			(xy 195.827778 -62.706508) (xy 195.883512 -62.704471) (xy 195.938949 -62.710571) (xy 195.992906 -62.724677)
			(xy 196.044235 -62.746489) (xy 196.091841 -62.775543) (xy 196.134709 -62.811218) (xy 196.13556 -62.812168)
			(xy 201.017884 -62.812168) (xy 201.021955 -62.756546) (xy 201.034081 -62.702109) (xy 201.054004 -62.650018)
			(xy 201.0813 -62.601383) (xy 201.115386 -62.55724) (xy 201.155535 -62.518531) (xy 201.200893 -62.48608)
			(xy 201.250493 -62.460579) (xy 201.303277 -62.442572) (xy 201.35812 -62.432442) (xy 201.413854 -62.430405)
			(xy 201.469291 -62.436505) (xy 201.523248 -62.450611) (xy 201.574577 -62.472423) (xy 201.622183 -62.501477)
			(xy 201.665051 -62.537152) (xy 201.702268 -62.578689) (xy 201.733041 -62.625202) (xy 201.756713 -62.675699)
			(xy 201.772781 -62.729106) (xy 201.780901 -62.784282) (xy 201.78141 -62.812168) (xy 201.780901 -62.840054)
			(xy 201.772781 -62.89523) (xy 201.756713 -62.948637) (xy 201.733041 -62.999134) (xy 201.702268 -63.045647)
			(xy 201.665051 -63.087184) (xy 201.622183 -63.122859) (xy 201.574577 -63.151913) (xy 201.523248 -63.173725)
			(xy 201.469291 -63.187831) (xy 201.413854 -63.193931) (xy 201.35812 -63.191894) (xy 201.303277 -63.181764)
			(xy 201.250493 -63.163757) (xy 201.200893 -63.138256) (xy 201.155535 -63.105805) (xy 201.115386 -63.067096)
			(xy 201.0813 -63.022953) (xy 201.054004 -62.974318) (xy 201.034081 -62.922227) (xy 201.021955 -62.86779)
			(xy 201.017884 -62.812168) (xy 196.13556 -62.812168) (xy 196.171926 -62.852755) (xy 196.202699 -62.899268)
			(xy 196.226371 -62.949765) (xy 196.242439 -63.003172) (xy 196.250559 -63.058348) (xy 196.251068 -63.086234)
			(xy 196.250559 -63.11412) (xy 196.242439 -63.169296) (xy 196.226371 -63.222703) (xy 196.202699 -63.2732)
			(xy 196.182719 -63.3034) (xy 197.601568 -63.3034) (xy 197.601568 -63.243464) (xy 197.609391 -63.184042)
			(xy 197.624904 -63.126149) (xy 197.64784 -63.070776) (xy 197.677807 -63.01887) (xy 197.714294 -62.97132)
			(xy 197.756674 -62.92894) (xy 197.804224 -62.892453) (xy 197.85613 -62.862486) (xy 197.911503 -62.83955)
			(xy 197.969396 -62.824037) (xy 198.028818 -62.816214) (xy 198.088754 -62.816214) (xy 198.148176 -62.824037)
			(xy 198.206069 -62.83955) (xy 198.261442 -62.862486) (xy 198.313348 -62.892453) (xy 198.360898 -62.92894)
			(xy 198.403278 -62.97132) (xy 198.439765 -63.01887) (xy 198.469732 -63.070776) (xy 198.492668 -63.126149)
			(xy 198.508181 -63.184042) (xy 198.516004 -63.243464) (xy 198.516038 -63.245548) (xy 211.204592 -63.245548)
			(xy 211.204592 -63.191052) (xy 211.212347 -63.13711) (xy 211.2277 -63.084821) (xy 211.250337 -63.035248)
			(xy 211.279798 -62.989402) (xy 211.315483 -62.948214) (xy 211.356666 -62.912524) (xy 211.40251 -62.883058)
			(xy 211.452079 -62.860415) (xy 211.504367 -62.845057) (xy 211.558308 -62.837295) (xy 211.585556 -62.836806)
			(xy 211.612925 -62.837296) (xy 211.667103 -62.845108) (xy 211.719606 -62.860591) (xy 211.769354 -62.883428)
			(xy 211.815322 -62.913147) (xy 211.836254 -62.930786) (xy 211.836508 -62.93104) (xy 211.843585 -62.936641)
			(xy 211.860509 -62.942878) (xy 211.869528 -62.943232) (xy 211.936584 -62.943232) (xy 211.945599 -62.94286)
			(xy 211.962516 -62.936622) (xy 211.969604 -62.93104) (xy 211.969604 -62.930786) (xy 211.969858 -62.930786)
			(xy 211.990791 -62.913145) (xy 212.036759 -62.883421) (xy 212.086505 -62.860575) (xy 212.139007 -62.845079)
			(xy 212.193185 -62.83725) (xy 212.247927 -62.83725) (xy 212.302105 -62.845079) (xy 212.354607 -62.860575)
			(xy 212.404353 -62.883421) (xy 212.450321 -62.913145) (xy 212.471254 -62.930786) (xy 212.471508 -62.93104)
			(xy 212.478585 -62.936641) (xy 212.495509 -62.942878) (xy 212.504528 -62.943232) (xy 212.571584 -62.943232)
			(xy 212.580599 -62.94286) (xy 212.597516 -62.936622) (xy 212.604604 -62.93104) (xy 212.604604 -62.930786)
			(xy 212.604858 -62.930786) (xy 212.625793 -62.913151) (xy 212.671765 -62.883439) (xy 212.721512 -62.860602)
			(xy 212.774012 -62.84511) (xy 212.828187 -62.837281) (xy 212.855556 -62.836806) (xy 212.882812 -62.837238)
			(xy 212.93677 -62.84499) (xy 212.989075 -62.860343) (xy 213.038662 -62.882984) (xy 213.084523 -62.912452)
			(xy 213.125722 -62.948147) (xy 213.161422 -62.989342) (xy 213.190895 -63.035199) (xy 213.213542 -63.084784)
			(xy 213.228901 -63.137087) (xy 213.236659 -63.191044) (xy 213.236659 -63.213552) (xy 216.220765 -63.213552)
			(xy 216.220765 -63.159048) (xy 216.228522 -63.105098) (xy 216.243878 -63.052801) (xy 216.26652 -63.003222)
			(xy 216.295987 -62.95737) (xy 216.33168 -62.916179) (xy 216.372872 -62.880486) (xy 216.418724 -62.851019)
			(xy 216.468303 -62.828377) (xy 216.5206 -62.813022) (xy 216.57455 -62.805265) (xy 216.601802 -62.804802)
			(xy 216.629172 -62.805266) (xy 216.683351 -62.813085) (xy 216.735855 -62.828574) (xy 216.785601 -62.851416)
			(xy 216.831568 -62.881141) (xy 216.8525 -62.898782) (xy 216.852754 -62.899036) (xy 216.859847 -62.904613)
			(xy 216.876759 -62.910865) (xy 216.885774 -62.911228) (xy 216.95283 -62.911228) (xy 216.961848 -62.910879)
			(xy 216.978764 -62.904625) (xy 216.98585 -62.899036) (xy 216.98585 -62.898782) (xy 216.986104 -62.898782)
			(xy 217.007037 -62.881141) (xy 217.053005 -62.851417) (xy 217.102751 -62.828571) (xy 217.155253 -62.813075)
			(xy 217.209431 -62.805246) (xy 217.264173 -62.805246) (xy 217.318351 -62.813075) (xy 217.370853 -62.828571)
			(xy 217.420599 -62.851417) (xy 217.466567 -62.881141) (xy 217.4875 -62.898782) (xy 217.487754 -62.899036)
			(xy 217.494847 -62.904613) (xy 217.511759 -62.910865) (xy 217.520774 -62.911228) (xy 217.58783 -62.911228)
			(xy 217.596848 -62.910879) (xy 217.613764 -62.904625) (xy 217.62085 -62.899036) (xy 217.62085 -62.898782)
			(xy 217.621104 -62.898782) (xy 217.642021 -62.881125) (xy 217.687999 -62.851416) (xy 217.73775 -62.828584)
			(xy 217.790254 -62.813097) (xy 217.844432 -62.805274) (xy 217.871802 -62.804802) (xy 217.899054 -62.805268)
			(xy 217.953003 -62.813025) (xy 218.005299 -62.828381) (xy 218.054877 -62.851022) (xy 218.100728 -62.88049)
			(xy 218.141919 -62.916182) (xy 218.177612 -62.957373) (xy 218.207079 -63.003225) (xy 218.22972 -63.052803)
			(xy 218.245076 -63.105099) (xy 218.252832 -63.159048) (xy 218.252832 -63.213552) (xy 218.245076 -63.267501)
			(xy 218.22972 -63.319797) (xy 218.207079 -63.369375) (xy 218.177612 -63.415227) (xy 218.141919 -63.456418)
			(xy 218.100728 -63.49211) (xy 218.054877 -63.521578) (xy 218.005299 -63.544219) (xy 217.953003 -63.559575)
			(xy 217.899054 -63.567332) (xy 217.871802 -63.567818) (xy 217.844431 -63.567371) (xy 217.79025 -63.559551)
			(xy 217.737746 -63.544059) (xy 217.687999 -63.521213) (xy 217.642034 -63.491482) (xy 217.621104 -63.473838)
			(xy 217.62085 -63.473584) (xy 217.613755 -63.46801) (xy 217.596845 -63.461756) (xy 217.58783 -63.461392)
			(xy 217.520774 -63.461392) (xy 217.511756 -63.461739) (xy 217.494839 -63.467994) (xy 217.487754 -63.473584)
			(xy 217.4875 -63.473838) (xy 217.466567 -63.491479) (xy 217.420599 -63.521203) (xy 217.370853 -63.544049)
			(xy 217.318351 -63.559545) (xy 217.264173 -63.567374) (xy 217.209431 -63.567374) (xy 217.155253 -63.559545)
			(xy 217.102751 -63.544049) (xy 217.053005 -63.521203) (xy 217.007037 -63.491479) (xy 216.986104 -63.473838)
			(xy 216.98585 -63.473584) (xy 216.978755 -63.46801) (xy 216.961845 -63.461756) (xy 216.95283 -63.461392)
			(xy 216.885774 -63.461392) (xy 216.876756 -63.461739) (xy 216.859839 -63.467994) (xy 216.852754 -63.473584)
			(xy 216.852754 -63.473838) (xy 216.8525 -63.473838) (xy 216.831584 -63.491497) (xy 216.785606 -63.521205)
			(xy 216.735855 -63.544036) (xy 216.683351 -63.559523) (xy 216.629172 -63.567347) (xy 216.601802 -63.567818)
			(xy 216.57455 -63.567335) (xy 216.5206 -63.559578) (xy 216.468303 -63.544223) (xy 216.418724 -63.521581)
			(xy 216.372872 -63.492114) (xy 216.33168 -63.456421) (xy 216.295987 -63.41523) (xy 216.26652 -63.369378)
			(xy 216.243878 -63.319799) (xy 216.228522 -63.267502) (xy 216.220765 -63.213552) (xy 213.236659 -63.213552)
			(xy 213.236659 -63.245556) (xy 213.228901 -63.299513) (xy 213.213542 -63.351816) (xy 213.190895 -63.401401)
			(xy 213.161422 -63.447258) (xy 213.125722 -63.488453) (xy 213.084523 -63.524148) (xy 213.038662 -63.553616)
			(xy 212.989075 -63.576257) (xy 212.93677 -63.59161) (xy 212.882812 -63.599362) (xy 212.855556 -63.599822)
			(xy 212.828186 -63.599342) (xy 212.774007 -63.591531) (xy 212.721503 -63.576046) (xy 212.671756 -63.553207)
			(xy 212.625789 -63.523483) (xy 212.604858 -63.505842) (xy 212.604604 -63.505588) (xy 212.597521 -63.499996)
			(xy 212.580602 -63.493753) (xy 212.571584 -63.493396) (xy 212.504528 -63.493396) (xy 212.495513 -63.493767)
			(xy 212.478596 -63.500005) (xy 212.471508 -63.505588) (xy 212.471254 -63.505842) (xy 212.450321 -63.523483)
			(xy 212.404353 -63.553207) (xy 212.354607 -63.576053) (xy 212.302105 -63.591549) (xy 212.247927 -63.599378)
			(xy 212.193185 -63.599378) (xy 212.139007 -63.591549) (xy 212.086505 -63.576053) (xy 212.036759 -63.553207)
			(xy 211.990791 -63.523483) (xy 211.969858 -63.505842) (xy 211.969604 -63.505588) (xy 211.962521 -63.499996)
			(xy 211.945602 -63.493753) (xy 211.936584 -63.493396) (xy 211.869528 -63.493396) (xy 211.860513 -63.493767)
			(xy 211.843596 -63.500005) (xy 211.836508 -63.505588) (xy 211.836508 -63.505842) (xy 211.836254 -63.505842)
			(xy 211.815318 -63.523476) (xy 211.769346 -63.553187) (xy 211.719599 -63.576024) (xy 211.6671 -63.591516)
			(xy 211.612925 -63.599347) (xy 211.585556 -63.599822) (xy 211.558308 -63.599305) (xy 211.504367 -63.591543)
			(xy 211.452079 -63.576185) (xy 211.40251 -63.553542) (xy 211.356666 -63.524076) (xy 211.315483 -63.488386)
			(xy 211.279798 -63.447198) (xy 211.250337 -63.401352) (xy 211.2277 -63.351779) (xy 211.212347 -63.29949)
			(xy 211.204592 -63.245548) (xy 198.516038 -63.245548) (xy 198.516494 -63.273432) (xy 198.516004 -63.3034)
			(xy 198.508181 -63.362822) (xy 198.492668 -63.420715) (xy 198.469732 -63.476088) (xy 198.439765 -63.527994)
			(xy 198.403278 -63.575544) (xy 198.360898 -63.617924) (xy 198.313348 -63.654411) (xy 198.261442 -63.684378)
			(xy 198.206069 -63.707314) (xy 198.148176 -63.722827) (xy 198.088754 -63.73065) (xy 198.028818 -63.73065)
			(xy 197.969396 -63.722827) (xy 197.911503 -63.707314) (xy 197.85613 -63.684378) (xy 197.804224 -63.654411)
			(xy 197.756674 -63.617924) (xy 197.714294 -63.575544) (xy 197.677807 -63.527994) (xy 197.64784 -63.476088)
			(xy 197.624904 -63.420715) (xy 197.609391 -63.362822) (xy 197.601568 -63.3034) (xy 196.182719 -63.3034)
			(xy 196.171926 -63.319713) (xy 196.134709 -63.36125) (xy 196.091841 -63.396925) (xy 196.044235 -63.425979)
			(xy 195.992906 -63.447791) (xy 195.938949 -63.461897) (xy 195.883512 -63.467997) (xy 195.827778 -63.46596)
			(xy 195.772935 -63.45583) (xy 195.720151 -63.437823) (xy 195.670551 -63.412322) (xy 195.625193 -63.379871)
			(xy 195.585044 -63.341162) (xy 195.550958 -63.297019) (xy 195.523662 -63.248384) (xy 195.503739 -63.196293)
			(xy 195.491613 -63.141856) (xy 195.487542 -63.086234) (xy 192.23966 -63.086234) (xy 192.245197 -63.105088)
			(xy 192.252955 -63.159044) (xy 192.252955 -63.213556) (xy 192.245197 -63.267512) (xy 192.229838 -63.319815)
			(xy 192.207191 -63.3694) (xy 192.177718 -63.415256) (xy 192.142019 -63.456451) (xy 192.100819 -63.492146)
			(xy 192.054959 -63.521613) (xy 192.005372 -63.544254) (xy 191.953067 -63.559606) (xy 191.89911 -63.567358)
			(xy 191.871854 -63.567818) (xy 191.844484 -63.56734) (xy 191.790305 -63.559528) (xy 191.737801 -63.544043)
			(xy 191.688054 -63.521203) (xy 191.642087 -63.491479) (xy 191.621156 -63.473838) (xy 191.620902 -63.473584)
			(xy 191.61382 -63.46799) (xy 191.5969 -63.461748) (xy 191.587882 -63.461392) (xy 191.520826 -63.461392)
			(xy 191.511811 -63.461763) (xy 191.494894 -63.468001) (xy 191.487806 -63.473584) (xy 191.487552 -63.473838)
			(xy 191.466619 -63.491479) (xy 191.420651 -63.521203) (xy 191.370905 -63.544049) (xy 191.318403 -63.559545)
			(xy 191.264225 -63.567374) (xy 191.209483 -63.567374) (xy 191.155305 -63.559545) (xy 191.102803 -63.544049)
			(xy 191.053057 -63.521203) (xy 191.007089 -63.491479) (xy 190.986156 -63.473838) (xy 190.985902 -63.473584)
			(xy 190.97882 -63.46799) (xy 190.9619 -63.461748) (xy 190.952882 -63.461392) (xy 190.885826 -63.461392)
			(xy 190.876811 -63.461763) (xy 190.859894 -63.468001) (xy 190.852806 -63.473584) (xy 190.852806 -63.473838)
			(xy 190.852552 -63.473838) (xy 190.831616 -63.491472) (xy 190.785644 -63.521184) (xy 190.735897 -63.54402)
			(xy 190.683398 -63.559513) (xy 190.629223 -63.567343) (xy 190.601854 -63.567818) (xy 190.574606 -63.567309)
			(xy 190.520664 -63.559547) (xy 190.468377 -63.544188) (xy 190.418807 -63.521545) (xy 190.372963 -63.492078)
			(xy 190.33178 -63.456388) (xy 190.296094 -63.4152) (xy 190.266633 -63.369353) (xy 190.243996 -63.31978)
			(xy 190.228643 -63.267491) (xy 190.220888 -63.213548) (xy 187.236636 -63.213548) (xy 187.236636 -63.245552)
			(xy 187.22888 -63.299501) (xy 187.213524 -63.351797) (xy 187.190883 -63.401375) (xy 187.161416 -63.447227)
			(xy 187.125724 -63.488419) (xy 187.084534 -63.524112) (xy 187.038682 -63.553579) (xy 186.989104 -63.576222)
			(xy 186.936809 -63.591578) (xy 186.88286 -63.599336) (xy 186.855608 -63.599822) (xy 186.828237 -63.59937)
			(xy 186.774057 -63.591552) (xy 186.721553 -63.576061) (xy 186.671806 -63.553215) (xy 186.62584 -63.523486)
			(xy 186.60491 -63.505842) (xy 186.604656 -63.505588) (xy 186.597559 -63.500017) (xy 186.58065 -63.493761)
			(xy 186.571636 -63.493396) (xy 186.50458 -63.493396) (xy 186.495562 -63.493744) (xy 186.478645 -63.499998)
			(xy 186.47156 -63.505588) (xy 186.471306 -63.505842) (xy 186.450373 -63.523483) (xy 186.404405 -63.553207)
			(xy 186.354659 -63.576053) (xy 186.302157 -63.591549) (xy 186.247979 -63.599378) (xy 186.193237 -63.599378)
			(xy 186.139059 -63.591549) (xy 186.086557 -63.576053) (xy 186.036811 -63.553207) (xy 185.990843 -63.523483)
			(xy 185.96991 -63.505842) (xy 185.969656 -63.505588) (xy 185.962559 -63.500017) (xy 185.94565 -63.493761)
			(xy 185.936636 -63.493396) (xy 185.86958 -63.493396) (xy 185.860562 -63.493744) (xy 185.843645 -63.499998)
			(xy 185.83656 -63.505588) (xy 185.83656 -63.505842) (xy 185.836306 -63.505842) (xy 185.815388 -63.523499)
			(xy 185.769411 -63.553207) (xy 185.71966 -63.576039) (xy 185.667156 -63.591526) (xy 185.612978 -63.59935)
			(xy 185.585608 -63.599822) (xy 185.558356 -63.599331) (xy 185.504406 -63.591575) (xy 185.452109 -63.576221)
			(xy 185.40253 -63.55358) (xy 185.356677 -63.524113) (xy 185.315485 -63.48842) (xy 185.279792 -63.447229)
			(xy 185.250324 -63.401377) (xy 185.227682 -63.351798) (xy 185.212326 -63.299502) (xy 185.204569 -63.245552)
			(xy 172.51609 -63.245552) (xy 172.516546 -63.273432) (xy 172.516056 -63.3034) (xy 172.508233 -63.362822)
			(xy 172.49272 -63.420715) (xy 172.469784 -63.476088) (xy 172.439817 -63.527994) (xy 172.40333 -63.575544)
			(xy 172.36095 -63.617924) (xy 172.3134 -63.654411) (xy 172.261494 -63.684378) (xy 172.206121 -63.707314)
			(xy 172.148228 -63.722827) (xy 172.088806 -63.73065) (xy 172.02887 -63.73065) (xy 171.969448 -63.722827)
			(xy 171.911555 -63.707314) (xy 171.856182 -63.684378) (xy 171.804276 -63.654411) (xy 171.756726 -63.617924)
			(xy 171.714346 -63.575544) (xy 171.677859 -63.527994) (xy 171.647892 -63.476088) (xy 171.624956 -63.420715)
			(xy 171.609443 -63.362822) (xy 171.60162 -63.3034) (xy 170.210203 -63.3034) (xy 170.19941 -63.319713)
			(xy 170.162193 -63.36125) (xy 170.119325 -63.396925) (xy 170.071719 -63.425979) (xy 170.02039 -63.447791)
			(xy 169.966433 -63.461897) (xy 169.910996 -63.467997) (xy 169.855262 -63.46596) (xy 169.800419 -63.45583)
			(xy 169.747635 -63.437823) (xy 169.698035 -63.412322) (xy 169.652677 -63.379871) (xy 169.612528 -63.341162)
			(xy 169.578442 -63.297019) (xy 169.551146 -63.248384) (xy 169.531223 -63.196293) (xy 169.519097 -63.141856)
			(xy 169.515026 -63.086234) (xy 166.239636 -63.086234) (xy 166.245176 -63.1051) (xy 166.252932 -63.159048)
			(xy 166.252932 -63.213552) (xy 166.245176 -63.2675) (xy 166.22982 -63.319796) (xy 166.207179 -63.369374)
			(xy 166.177713 -63.415225) (xy 166.142021 -63.456417) (xy 166.10083 -63.492109) (xy 166.054979 -63.521576)
			(xy 166.005402 -63.544218) (xy 165.953106 -63.559574) (xy 165.899158 -63.567332) (xy 165.871906 -63.567818)
			(xy 165.844535 -63.567368) (xy 165.790354 -63.55955) (xy 165.73785 -63.544058) (xy 165.688104 -63.521212)
			(xy 165.642138 -63.491482) (xy 165.621208 -63.473838) (xy 165.620954 -63.473584) (xy 165.613857 -63.468012)
			(xy 165.596948 -63.461757) (xy 165.587934 -63.461392) (xy 165.520878 -63.461392) (xy 165.51186 -63.46174)
			(xy 165.494944 -63.467994) (xy 165.487858 -63.473584) (xy 165.487604 -63.473838) (xy 165.466671 -63.491479)
			(xy 165.420703 -63.521203) (xy 165.370957 -63.544049) (xy 165.318455 -63.559545) (xy 165.264277 -63.567374)
			(xy 165.209535 -63.567374) (xy 165.155357 -63.559545) (xy 165.102855 -63.544049) (xy 165.053109 -63.521203)
			(xy 165.007141 -63.491479) (xy 164.986208 -63.473838) (xy 164.985954 -63.473584) (xy 164.978857 -63.468012)
			(xy 164.961948 -63.461757) (xy 164.952934 -63.461392) (xy 164.885878 -63.461392) (xy 164.87686 -63.46174)
			(xy 164.859944 -63.467994) (xy 164.852858 -63.473584) (xy 164.852858 -63.473838) (xy 164.852604 -63.473838)
			(xy 164.831686 -63.491495) (xy 164.785709 -63.521203) (xy 164.735958 -63.544035) (xy 164.683454 -63.559522)
			(xy 164.629276 -63.567346) (xy 164.601906 -63.567818) (xy 164.574654 -63.567335) (xy 164.520703 -63.559579)
			(xy 164.468406 -63.544224) (xy 164.418827 -63.521582) (xy 164.372974 -63.492115) (xy 164.331782 -63.456423)
			(xy 164.296088 -63.415231) (xy 164.266621 -63.369379) (xy 164.243978 -63.319799) (xy 164.228622 -63.267502)
			(xy 164.220865 -63.213552) (xy 161.236759 -63.213552) (xy 161.236759 -63.245556) (xy 161.229001 -63.299512)
			(xy 161.213642 -63.351815) (xy 161.190996 -63.4014) (xy 161.161523 -63.447257) (xy 161.125824 -63.488452)
			(xy 161.084625 -63.524147) (xy 161.038765 -63.553615) (xy 160.989178 -63.576256) (xy 160.936873 -63.591609)
			(xy 160.882916 -63.599362) (xy 160.85566 -63.599822) (xy 160.82829 -63.59934) (xy 160.774111 -63.591529)
			(xy 160.721607 -63.576045) (xy 160.67186 -63.553206) (xy 160.625893 -63.523483) (xy 160.604962 -63.505842)
			(xy 160.604708 -63.505588) (xy 160.597624 -63.499997) (xy 160.580705 -63.493753) (xy 160.571688 -63.493396)
			(xy 160.504632 -63.493396) (xy 160.495617 -63.493769) (xy 160.4787 -63.500006) (xy 160.471612 -63.505588)
			(xy 160.471358 -63.505842) (xy 160.450425 -63.523483) (xy 160.404457 -63.553207) (xy 160.354711 -63.576053)
			(xy 160.302209 -63.591549) (xy 160.248031 -63.599378) (xy 160.193289 -63.599378) (xy 160.139111 -63.591549)
			(xy 160.086609 -63.576053) (xy 160.036863 -63.553207) (xy 159.990895 -63.523483) (xy 159.969962 -63.505842)
			(xy 159.969708 -63.505588) (xy 159.962624 -63.499997) (xy 159.945705 -63.493753) (xy 159.936688 -63.493396)
			(xy 159.869632 -63.493396) (xy 159.860617 -63.493769) (xy 159.8437 -63.500006) (xy 159.836612 -63.505588)
			(xy 159.836612 -63.505842) (xy 159.836358 -63.505842) (xy 159.815421 -63.523474) (xy 159.769449 -63.553186)
			(xy 159.719702 -63.576022) (xy 159.667203 -63.591515) (xy 159.613029 -63.599347) (xy 159.58566 -63.599822)
			(xy 159.558412 -63.599305) (xy 159.50447 -63.591544) (xy 159.452182 -63.576186) (xy 159.402612 -63.553544)
			(xy 159.356768 -63.524077) (xy 159.315584 -63.488387) (xy 159.279899 -63.4472) (xy 159.250437 -63.401353)
			(xy 159.2278 -63.35178) (xy 159.212447 -63.299491) (xy 159.204692 -63.245548) (xy 146.516142 -63.245548)
			(xy 146.516598 -63.273432) (xy 146.516108 -63.3034) (xy 146.508285 -63.362822) (xy 146.492772 -63.420715)
			(xy 146.469836 -63.476088) (xy 146.439869 -63.527994) (xy 146.403382 -63.575544) (xy 146.361002 -63.617924)
			(xy 146.313452 -63.654411) (xy 146.261546 -63.684378) (xy 146.206173 -63.707314) (xy 146.14828 -63.722827)
			(xy 146.088858 -63.73065) (xy 146.028922 -63.73065) (xy 145.9695 -63.722827) (xy 145.911607 -63.707314)
			(xy 145.856234 -63.684378) (xy 145.804328 -63.654411) (xy 145.756778 -63.617924) (xy 145.714398 -63.575544)
			(xy 145.677911 -63.527994) (xy 145.647944 -63.476088) (xy 145.625008 -63.420715) (xy 145.609495 -63.362822)
			(xy 145.601672 -63.3034) (xy 144.182823 -63.3034) (xy 144.17203 -63.319713) (xy 144.134813 -63.36125)
			(xy 144.091945 -63.396925) (xy 144.044339 -63.425979) (xy 143.99301 -63.447791) (xy 143.939053 -63.461897)
			(xy 143.883616 -63.467997) (xy 143.827882 -63.46596) (xy 143.773039 -63.45583) (xy 143.720255 -63.437823)
			(xy 143.670655 -63.412322) (xy 143.625297 -63.379871) (xy 143.585148 -63.341162) (xy 143.551062 -63.297019)
			(xy 143.523766 -63.248384) (xy 143.503843 -63.196293) (xy 143.491717 -63.141856) (xy 143.487646 -63.086234)
			(xy 140.23976 -63.086234) (xy 140.245297 -63.105088) (xy 140.253055 -63.159044) (xy 140.253055 -63.213556)
			(xy 140.245297 -63.267512) (xy 140.229938 -63.319814) (xy 140.207292 -63.369399) (xy 140.177819 -63.415255)
			(xy 140.14212 -63.45645) (xy 140.100921 -63.492144) (xy 140.055062 -63.521612) (xy 140.005475 -63.544253)
			(xy 139.953171 -63.559606) (xy 139.899214 -63.567358) (xy 139.871958 -63.567818) (xy 139.844588 -63.567338)
			(xy 139.790409 -63.559527) (xy 139.737905 -63.544042) (xy 139.688158 -63.521203) (xy 139.642191 -63.491479)
			(xy 139.62126 -63.473838) (xy 139.621006 -63.473584) (xy 139.613923 -63.467992) (xy 139.597003 -63.461749)
			(xy 139.587986 -63.461392) (xy 139.52093 -63.461392) (xy 139.511915 -63.461765) (xy 139.494998 -63.468002)
			(xy 139.48791 -63.473584) (xy 139.487656 -63.473838) (xy 139.466723 -63.491479) (xy 139.420755 -63.521203)
			(xy 139.371009 -63.544049) (xy 139.318507 -63.559545) (xy 139.264329 -63.567374) (xy 139.209587 -63.567374)
			(xy 139.155409 -63.559545) (xy 139.102907 -63.544049) (xy 139.053161 -63.521203) (xy 139.007193 -63.491479)
			(xy 138.98626 -63.473838) (xy 138.986006 -63.473584) (xy 138.978923 -63.467992) (xy 138.962003 -63.461749)
			(xy 138.952986 -63.461392) (xy 138.88593 -63.461392) (xy 138.876915 -63.461765) (xy 138.859998 -63.468002)
			(xy 138.85291 -63.473584) (xy 138.85291 -63.473838) (xy 138.852656 -63.473838) (xy 138.831719 -63.491471)
			(xy 138.785747 -63.521182) (xy 138.736001 -63.544019) (xy 138.683501 -63.559512) (xy 138.629327 -63.567343)
			(xy 138.601958 -63.567818) (xy 138.574709 -63.567309) (xy 138.520768 -63.559548) (xy 138.468479 -63.544189)
			(xy 138.418909 -63.521546) (xy 138.373065 -63.49208) (xy 138.331881 -63.456389) (xy 138.296195 -63.415201)
			(xy 138.266733 -63.369354) (xy 138.244096 -63.319781) (xy 138.228743 -63.267491) (xy 138.220988 -63.213549)
			(xy 135.236736 -63.213549) (xy 135.236736 -63.245552) (xy 135.22898 -63.2995) (xy 135.213625 -63.351796)
			(xy 135.190984 -63.401374) (xy 135.161517 -63.447226) (xy 135.125826 -63.488417) (xy 135.084635 -63.52411)
			(xy 135.038785 -63.553578) (xy 134.989207 -63.57622) (xy 134.936912 -63.591577) (xy 134.882964 -63.599335)
			(xy 134.855712 -63.599822) (xy 134.828341 -63.599368) (xy 134.774161 -63.59155) (xy 134.721657 -63.576059)
			(xy 134.67191 -63.553214) (xy 134.625944 -63.523486) (xy 134.605014 -63.505842) (xy 134.60476 -63.505588)
			(xy 134.597661 -63.500019) (xy 134.580754 -63.493762) (xy 134.57174 -63.493396) (xy 134.504684 -63.493396)
			(xy 134.495666 -63.493746) (xy 134.47875 -63.499999) (xy 134.471664 -63.505588) (xy 134.47141 -63.505842)
			(xy 134.450477 -63.523483) (xy 134.404509 -63.553207) (xy 134.354763 -63.576053) (xy 134.302261 -63.591549)
			(xy 134.248083 -63.599378) (xy 134.193341 -63.599378) (xy 134.139163 -63.591549) (xy 134.086661 -63.576053)
			(xy 134.036915 -63.553207) (xy 133.990947 -63.523483) (xy 133.970014 -63.505842) (xy 133.96976 -63.505588)
			(xy 133.962661 -63.500019) (xy 133.945754 -63.493762) (xy 133.93674 -63.493396) (xy 133.869684 -63.493396)
			(xy 133.860666 -63.493746) (xy 133.84375 -63.499999) (xy 133.836664 -63.505588) (xy 133.836664 -63.505842)
			(xy 133.83641 -63.505842) (xy 133.815491 -63.523497) (xy 133.769514 -63.553205) (xy 133.719763 -63.576037)
			(xy 133.66726 -63.591525) (xy 133.613082 -63.59935) (xy 133.585712 -63.599822) (xy 133.55846 -63.599332)
			(xy 133.504509 -63.591576) (xy 133.452212 -63.576222) (xy 133.402632 -63.553581) (xy 133.356779 -63.524114)
			(xy 133.315587 -63.488422) (xy 133.279893 -63.44723) (xy 133.250425 -63.401378) (xy 133.227782 -63.351799)
			(xy 133.212426 -63.299502) (xy 133.204669 -63.245552) (xy 120.516194 -63.245552) (xy 120.51665 -63.273432)
			(xy 120.51616 -63.3034) (xy 120.508337 -63.362822) (xy 120.492824 -63.420715) (xy 120.469888 -63.476088)
			(xy 120.439921 -63.527994) (xy 120.403434 -63.575544) (xy 120.361054 -63.617924) (xy 120.313504 -63.654411)
			(xy 120.261598 -63.684378) (xy 120.206225 -63.707314) (xy 120.148332 -63.722827) (xy 120.08891 -63.73065)
			(xy 120.028974 -63.73065) (xy 119.969552 -63.722827) (xy 119.911659 -63.707314) (xy 119.856286 -63.684378)
			(xy 119.80438 -63.654411) (xy 119.75683 -63.617924) (xy 119.71445 -63.575544) (xy 119.677963 -63.527994)
			(xy 119.647996 -63.476088) (xy 119.62506 -63.420715) (xy 119.609547 -63.362822) (xy 119.601724 -63.3034)
			(xy 118.182875 -63.3034) (xy 118.172082 -63.319713) (xy 118.134865 -63.36125) (xy 118.091997 -63.396925)
			(xy 118.044391 -63.425979) (xy 117.993062 -63.447791) (xy 117.939105 -63.461897) (xy 117.883668 -63.467997)
			(xy 117.827934 -63.46596) (xy 117.773091 -63.45583) (xy 117.720307 -63.437823) (xy 117.670707 -63.412322)
			(xy 117.625349 -63.379871) (xy 117.5852 -63.341162) (xy 117.551114 -63.297019) (xy 117.523818 -63.248384)
			(xy 117.503895 -63.196293) (xy 117.491769 -63.141856) (xy 117.487698 -63.086234) (xy 102.139436 -63.086234)
			(xy 102.144976 -63.105099) (xy 102.152732 -63.159048) (xy 102.152732 -63.213552) (xy 102.144976 -63.267501)
			(xy 102.12962 -63.319796) (xy 102.106979 -63.369375) (xy 102.077512 -63.415226) (xy 102.04182 -63.456417)
			(xy 102.000629 -63.49211) (xy 101.954778 -63.521577) (xy 101.9052 -63.544219) (xy 101.852904 -63.559575)
			(xy 101.798956 -63.567332) (xy 101.771704 -63.567818) (xy 101.744333 -63.56737) (xy 101.690152 -63.559551)
			(xy 101.637648 -63.544058) (xy 101.587902 -63.521212) (xy 101.541936 -63.491482) (xy 101.521006 -63.473838)
			(xy 101.520752 -63.473584) (xy 101.513656 -63.468011) (xy 101.496746 -63.461757) (xy 101.487732 -63.461392)
			(xy 101.420676 -63.461392) (xy 101.411658 -63.461739) (xy 101.394741 -63.467994) (xy 101.387656 -63.473584)
			(xy 101.387402 -63.473838) (xy 101.366469 -63.491479) (xy 101.320501 -63.521203) (xy 101.270755 -63.544049)
			(xy 101.218253 -63.559545) (xy 101.164075 -63.567374) (xy 101.109333 -63.567374) (xy 101.055155 -63.559545)
			(xy 101.002653 -63.544049) (xy 100.952907 -63.521203) (xy 100.906939 -63.491479) (xy 100.886006 -63.473838)
			(xy 100.885752 -63.473584) (xy 100.878656 -63.468011) (xy 100.861746 -63.461757) (xy 100.852732 -63.461392)
			(xy 100.785676 -63.461392) (xy 100.776658 -63.461739) (xy 100.759741 -63.467994) (xy 100.752656 -63.473584)
			(xy 100.752656 -63.473838) (xy 100.752402 -63.473838) (xy 100.731485 -63.491496) (xy 100.685508 -63.521204)
			(xy 100.635756 -63.544036) (xy 100.583252 -63.559522) (xy 100.529074 -63.567346) (xy 100.501704 -63.567818)
			(xy 100.474452 -63.567335) (xy 100.420502 -63.559579) (xy 100.368205 -63.544223) (xy 100.318625 -63.521582)
			(xy 100.272773 -63.492115) (xy 100.231581 -63.456422) (xy 100.195888 -63.41523) (xy 100.16642 -63.369378)
			(xy 100.143778 -63.319799) (xy 100.128422 -63.267502) (xy 100.120665 -63.213552) (xy 97.136559 -63.213552)
			(xy 97.136559 -63.245556) (xy 97.128801 -63.299512) (xy 97.113442 -63.351816) (xy 97.090795 -63.4014)
			(xy 97.061322 -63.447257) (xy 97.025623 -63.488453) (xy 96.984424 -63.524148) (xy 96.938564 -63.553616)
			(xy 96.888976 -63.576257) (xy 96.836671 -63.59161) (xy 96.782714 -63.599362) (xy 96.755458 -63.599822)
			(xy 96.728088 -63.599341) (xy 96.673909 -63.59153) (xy 96.621405 -63.576045) (xy 96.571658 -63.553206)
			(xy 96.525691 -63.523483) (xy 96.50476 -63.505842) (xy 96.504506 -63.505588) (xy 96.497423 -63.499996)
			(xy 96.480503 -63.493753) (xy 96.471486 -63.493396) (xy 96.40443 -63.493396) (xy 96.395415 -63.493768)
			(xy 96.378498 -63.500005) (xy 96.37141 -63.505588) (xy 96.371156 -63.505842) (xy 96.350223 -63.523483)
			(xy 96.304255 -63.553207) (xy 96.254509 -63.576053) (xy 96.202007 -63.591549) (xy 96.147829 -63.599378)
			(xy 96.093087 -63.599378) (xy 96.038909 -63.591549) (xy 95.986407 -63.576053) (xy 95.936661 -63.553207)
			(xy 95.890693 -63.523483) (xy 95.86976 -63.505842) (xy 95.869506 -63.505588) (xy 95.862423 -63.499996)
			(xy 95.845503 -63.493753) (xy 95.836486 -63.493396) (xy 95.76943 -63.493396) (xy 95.760415 -63.493768)
			(xy 95.743498 -63.500005) (xy 95.73641 -63.505588) (xy 95.73641 -63.505842) (xy 95.736156 -63.505842)
			(xy 95.715219 -63.523475) (xy 95.669247 -63.553187) (xy 95.619501 -63.576023) (xy 95.567001 -63.591516)
			(xy 95.512827 -63.599347) (xy 95.485458 -63.599822) (xy 95.45821 -63.599305) (xy 95.404269 -63.591544)
			(xy 95.351981 -63.576186) (xy 95.302411 -63.553543) (xy 95.256567 -63.524077) (xy 95.215384 -63.488386)
			(xy 95.179698 -63.447199) (xy 95.150237 -63.401352) (xy 95.1276 -63.35178) (xy 95.112247 -63.29949)
			(xy 95.104492 -63.245548) (xy 82.41594 -63.245548) (xy 82.416396 -63.273432) (xy 82.415906 -63.3034)
			(xy 82.408083 -63.362822) (xy 82.39257 -63.420715) (xy 82.369634 -63.476088) (xy 82.339667 -63.527994)
			(xy 82.30318 -63.575544) (xy 82.2608 -63.617924) (xy 82.21325 -63.654411) (xy 82.161344 -63.684378)
			(xy 82.105971 -63.707314) (xy 82.048078 -63.722827) (xy 81.988656 -63.73065) (xy 81.92872 -63.73065)
			(xy 81.869298 -63.722827) (xy 81.811405 -63.707314) (xy 81.756032 -63.684378) (xy 81.704126 -63.654411)
			(xy 81.656576 -63.617924) (xy 81.614196 -63.575544) (xy 81.577709 -63.527994) (xy 81.547742 -63.476088)
			(xy 81.524806 -63.420715) (xy 81.509293 -63.362822) (xy 81.50147 -63.3034) (xy 80.082621 -63.3034)
			(xy 80.071828 -63.319713) (xy 80.034611 -63.36125) (xy 79.991743 -63.396925) (xy 79.944137 -63.425979)
			(xy 79.892808 -63.447791) (xy 79.838851 -63.461897) (xy 79.783414 -63.467997) (xy 79.72768 -63.46596)
			(xy 79.672837 -63.45583) (xy 79.620053 -63.437823) (xy 79.570453 -63.412322) (xy 79.525095 -63.379871)
			(xy 79.484946 -63.341162) (xy 79.45086 -63.297019) (xy 79.423564 -63.248384) (xy 79.403641 -63.196293)
			(xy 79.391515 -63.141856) (xy 79.387444 -63.086234) (xy 76.13956 -63.086234) (xy 76.145097 -63.105088)
			(xy 76.152855 -63.159044) (xy 76.152855 -63.213556) (xy 76.145097 -63.267512) (xy 76.129738 -63.319815)
			(xy 76.107092 -63.369399) (xy 76.077619 -63.415256) (xy 76.041919 -63.456451) (xy 76.00072 -63.492145)
			(xy 75.95486 -63.521613) (xy 75.905273 -63.544253) (xy 75.852969 -63.559606) (xy 75.799012 -63.567358)
			(xy 75.771756 -63.567818) (xy 75.744386 -63.567339) (xy 75.690207 -63.559527) (xy 75.637703 -63.544042)
			(xy 75.587956 -63.521203) (xy 75.541989 -63.491479) (xy 75.521058 -63.473838) (xy 75.520804 -63.473584)
			(xy 75.513722 -63.467991) (xy 75.496802 -63.461749) (xy 75.487784 -63.461392) (xy 75.420728 -63.461392)
			(xy 75.411713 -63.461764) (xy 75.394796 -63.468001) (xy 75.387708 -63.473584) (xy 75.387454 -63.473838)
			(xy 75.366521 -63.491479) (xy 75.320553 -63.521203) (xy 75.270807 -63.544049) (xy 75.218305 -63.559545)
			(xy 75.164127 -63.567374) (xy 75.109385 -63.567374) (xy 75.055207 -63.559545) (xy 75.002705 -63.544049)
			(xy 74.952959 -63.521203) (xy 74.906991 -63.491479) (xy 74.886058 -63.473838) (xy 74.885804 -63.473584)
			(xy 74.878722 -63.467991) (xy 74.861802 -63.461749) (xy 74.852784 -63.461392) (xy 74.785728 -63.461392)
			(xy 74.776713 -63.461764) (xy 74.759796 -63.468001) (xy 74.752708 -63.473584) (xy 74.752708 -63.473838)
			(xy 74.752454 -63.473838) (xy 74.731518 -63.491472) (xy 74.685545 -63.521183) (xy 74.635799 -63.54402)
			(xy 74.583299 -63.559512) (xy 74.529125 -63.567343) (xy 74.501756 -63.567818) (xy 74.474508 -63.567309)
			(xy 74.420566 -63.559547) (xy 74.368278 -63.544189) (xy 74.318708 -63.521546) (xy 74.272864 -63.492079)
			(xy 74.23168 -63.456389) (xy 74.195994 -63.415201) (xy 74.166533 -63.369354) (xy 74.143896 -63.319781)
			(xy 74.128543 -63.267491) (xy 74.120788 -63.213549) (xy 71.136536 -63.213549) (xy 71.136536 -63.245552)
			(xy 71.12878 -63.299501) (xy 71.113424 -63.351797) (xy 71.090783 -63.401375) (xy 71.061317 -63.447226)
			(xy 71.025625 -63.488418) (xy 70.984434 -63.524111) (xy 70.938584 -63.553578) (xy 70.889006 -63.576221)
			(xy 70.83671 -63.591578) (xy 70.782762 -63.599336) (xy 70.75551 -63.599822) (xy 70.728139 -63.599369)
			(xy 70.673959 -63.591551) (xy 70.621455 -63.57606) (xy 70.571708 -63.553215) (xy 70.525742 -63.523486)
			(xy 70.504812 -63.505842) (xy 70.504558 -63.505588) (xy 70.49746 -63.500018) (xy 70.480552 -63.493762)
			(xy 70.471538 -63.493396) (xy 70.404482 -63.493396) (xy 70.395464 -63.493745) (xy 70.378548 -63.499998)
			(xy 70.371462 -63.505588) (xy 70.371208 -63.505842) (xy 70.350275 -63.523483) (xy 70.304307 -63.553207)
			(xy 70.254561 -63.576053) (xy 70.202059 -63.591549) (xy 70.147881 -63.599378) (xy 70.093139 -63.599378)
			(xy 70.038961 -63.591549) (xy 69.986459 -63.576053) (xy 69.936713 -63.553207) (xy 69.890745 -63.523483)
			(xy 69.869812 -63.505842) (xy 69.869558 -63.505588) (xy 69.86246 -63.500018) (xy 69.845552 -63.493762)
			(xy 69.836538 -63.493396) (xy 69.769482 -63.493396) (xy 69.760464 -63.493745) (xy 69.743548 -63.499998)
			(xy 69.736462 -63.505588) (xy 69.736462 -63.505842) (xy 69.736208 -63.505842) (xy 69.715289 -63.523498)
			(xy 69.669312 -63.553206) (xy 69.619561 -63.576038) (xy 69.567058 -63.591525) (xy 69.51288 -63.59935)
			(xy 69.48551 -63.599822) (xy 69.458258 -63.599331) (xy 69.404308 -63.591576) (xy 69.352011 -63.576221)
			(xy 69.302431 -63.55358) (xy 69.256578 -63.524114) (xy 69.215386 -63.488421) (xy 69.179692 -63.44723)
			(xy 69.150225 -63.401378) (xy 69.127582 -63.351799) (xy 69.112226 -63.299502) (xy 69.104469 -63.245552)
			(xy 56.415992 -63.245552) (xy 56.416448 -63.273432) (xy 56.415958 -63.3034) (xy 56.408135 -63.362822)
			(xy 56.392622 -63.420715) (xy 56.369686 -63.476088) (xy 56.339719 -63.527994) (xy 56.303232 -63.575544)
			(xy 56.260852 -63.617924) (xy 56.213302 -63.654411) (xy 56.161396 -63.684378) (xy 56.106023 -63.707314)
			(xy 56.04813 -63.722827) (xy 55.988708 -63.73065) (xy 55.928772 -63.73065) (xy 55.86935 -63.722827)
			(xy 55.811457 -63.707314) (xy 55.756084 -63.684378) (xy 55.704178 -63.654411) (xy 55.656628 -63.617924)
			(xy 55.614248 -63.575544) (xy 55.577761 -63.527994) (xy 55.547794 -63.476088) (xy 55.524858 -63.420715)
			(xy 55.509345 -63.362822) (xy 55.501522 -63.3034) (xy 54.082673 -63.3034) (xy 54.07188 -63.319713)
			(xy 54.034663 -63.36125) (xy 53.991795 -63.396925) (xy 53.944189 -63.425979) (xy 53.89286 -63.447791)
			(xy 53.838903 -63.461897) (xy 53.783466 -63.467997) (xy 53.727732 -63.46596) (xy 53.672889 -63.45583)
			(xy 53.620105 -63.437823) (xy 53.570505 -63.412322) (xy 53.525147 -63.379871) (xy 53.484998 -63.341162)
			(xy 53.450912 -63.297019) (xy 53.423616 -63.248384) (xy 53.403693 -63.196293) (xy 53.391567 -63.141856)
			(xy 53.387496 -63.086234) (xy 50.139537 -63.086234) (xy 50.145076 -63.1051) (xy 50.152832 -63.159048)
			(xy 50.152832 -63.213552) (xy 50.145076 -63.2675) (xy 50.129721 -63.319796) (xy 50.107079 -63.369374)
			(xy 50.077613 -63.415225) (xy 50.041922 -63.456416) (xy 50.000731 -63.492108) (xy 49.954881 -63.521576)
			(xy 49.905303 -63.544218) (xy 49.853008 -63.559574) (xy 49.79906 -63.567332) (xy 49.771808 -63.567818)
			(xy 49.744437 -63.567367) (xy 49.690256 -63.559549) (xy 49.637752 -63.544057) (xy 49.588006 -63.521212)
			(xy 49.54204 -63.491482) (xy 49.52111 -63.473838) (xy 49.520856 -63.473584) (xy 49.513759 -63.468013)
			(xy 49.49685 -63.461757) (xy 49.487836 -63.461392) (xy 49.42078 -63.461392) (xy 49.411762 -63.461741)
			(xy 49.394846 -63.467995) (xy 49.38776 -63.473584) (xy 49.387506 -63.473838) (xy 49.366573 -63.491479)
			(xy 49.320605 -63.521203) (xy 49.270859 -63.544049) (xy 49.218357 -63.559545) (xy 49.164179 -63.567374)
			(xy 49.109437 -63.567374) (xy 49.055259 -63.559545) (xy 49.002757 -63.544049) (xy 48.953011 -63.521203)
			(xy 48.907043 -63.491479) (xy 48.88611 -63.473838) (xy 48.885856 -63.473584) (xy 48.878759 -63.468013)
			(xy 48.86185 -63.461757) (xy 48.852836 -63.461392) (xy 48.78578 -63.461392) (xy 48.776762 -63.461741)
			(xy 48.759846 -63.467995) (xy 48.75276 -63.473584) (xy 48.75276 -63.473838) (xy 48.752506 -63.473838)
			(xy 48.731588 -63.491494) (xy 48.685611 -63.521202) (xy 48.635859 -63.544034) (xy 48.583356 -63.559522)
			(xy 48.529178 -63.567346) (xy 48.501808 -63.567818) (xy 48.474555 -63.567335) (xy 48.420605 -63.559579)
			(xy 48.368308 -63.544224) (xy 48.318728 -63.521583) (xy 48.272875 -63.492116) (xy 48.231682 -63.456423)
			(xy 48.195989 -63.415231) (xy 48.166521 -63.369379) (xy 48.143878 -63.3198) (xy 48.128522 -63.267503)
			(xy 48.120765 -63.213553) (xy 45.136659 -63.213553) (xy 45.136659 -63.245556) (xy 45.128901 -63.299512)
			(xy 45.113542 -63.351815) (xy 45.090896 -63.401399) (xy 45.061423 -63.447256) (xy 45.025724 -63.488451)
			(xy 44.984526 -63.524146) (xy 44.938666 -63.553614) (xy 44.889079 -63.576256) (xy 44.836775 -63.591609)
			(xy 44.782818 -63.599362) (xy 44.755562 -63.599822) (xy 44.728192 -63.599339) (xy 44.674013 -63.591528)
			(xy 44.621509 -63.576044) (xy 44.571762 -63.553206) (xy 44.525795 -63.523483) (xy 44.504864 -63.505842)
			(xy 44.50461 -63.505588) (xy 44.497526 -63.499998) (xy 44.480607 -63.493754) (xy 44.47159 -63.493396)
			(xy 44.404534 -63.493396) (xy 44.395519 -63.49377) (xy 44.378602 -63.500006) (xy 44.371514 -63.505588)
			(xy 44.37126 -63.505842) (xy 44.350327 -63.523483) (xy 44.304359 -63.553207) (xy 44.254613 -63.576053)
			(xy 44.202111 -63.591549) (xy 44.147933 -63.599378) (xy 44.093191 -63.599378) (xy 44.039013 -63.591549)
			(xy 43.986511 -63.576053) (xy 43.936765 -63.553207) (xy 43.890797 -63.523483) (xy 43.869864 -63.505842)
			(xy 43.86961 -63.505588) (xy 43.862526 -63.499998) (xy 43.845607 -63.493754) (xy 43.83659 -63.493396)
			(xy 43.769534 -63.493396) (xy 43.760519 -63.49377) (xy 43.743602 -63.500006) (xy 43.736514 -63.505588)
			(xy 43.736514 -63.505842) (xy 43.73626 -63.505842) (xy 43.715322 -63.523473) (xy 43.66935 -63.553185)
			(xy 43.619604 -63.576022) (xy 43.567105 -63.591515) (xy 43.512931 -63.599346) (xy 43.485562 -63.599822)
			(xy 43.458314 -63.599305) (xy 43.404372 -63.591545) (xy 43.352084 -63.576187) (xy 43.302513 -63.553544)
			(xy 43.256669 -63.524078) (xy 43.215485 -63.488388) (xy 43.179799 -63.4472) (xy 43.150337 -63.401353)
			(xy 43.1277 -63.351781) (xy 43.112347 -63.299491) (xy 43.104592 -63.245548) (xy 30.416044 -63.245548)
			(xy 30.4165 -63.273432) (xy 30.41601 -63.3034) (xy 30.408187 -63.362822) (xy 30.392674 -63.420715)
			(xy 30.369738 -63.476088) (xy 30.339771 -63.527994) (xy 30.303284 -63.575544) (xy 30.260904 -63.617924)
			(xy 30.213354 -63.654411) (xy 30.161448 -63.684378) (xy 30.106075 -63.707314) (xy 30.048182 -63.722827)
			(xy 29.98876 -63.73065) (xy 29.928824 -63.73065) (xy 29.869402 -63.722827) (xy 29.811509 -63.707314)
			(xy 29.756136 -63.684378) (xy 29.70423 -63.654411) (xy 29.65668 -63.617924) (xy 29.6143 -63.575544)
			(xy 29.577813 -63.527994) (xy 29.547846 -63.476088) (xy 29.52491 -63.420715) (xy 29.509397 -63.362822)
			(xy 29.501574 -63.3034) (xy 28.082725 -63.3034) (xy 28.071932 -63.319713) (xy 28.034715 -63.36125)
			(xy 27.991847 -63.396925) (xy 27.944241 -63.425979) (xy 27.892912 -63.447791) (xy 27.838955 -63.461897)
			(xy 27.783518 -63.467997) (xy 27.727784 -63.46596) (xy 27.672941 -63.45583) (xy 27.620157 -63.437823)
			(xy 27.570557 -63.412322) (xy 27.525199 -63.379871) (xy 27.48505 -63.341162) (xy 27.450964 -63.297019)
			(xy 27.423668 -63.248384) (xy 27.403745 -63.196293) (xy 27.391619 -63.141856) (xy 27.387548 -63.086234)
			(xy 24.13966 -63.086234) (xy 24.145197 -63.105089) (xy 24.152955 -63.159045) (xy 24.152955 -63.213555)
			(xy 24.145197 -63.267511) (xy 24.129838 -63.319814) (xy 24.107192 -63.369398) (xy 24.07772 -63.415254)
			(xy 24.042021 -63.456449) (xy 24.000822 -63.492144) (xy 23.954963 -63.521611) (xy 23.905376 -63.544252)
			(xy 23.853072 -63.559605) (xy 23.799115 -63.567358) (xy 23.77186 -63.567818) (xy 23.74449 -63.567337)
			(xy 23.690311 -63.559526) (xy 23.637807 -63.544041) (xy 23.58806 -63.521202) (xy 23.542093 -63.491479)
			(xy 23.521162 -63.473838) (xy 23.520908 -63.473584) (xy 23.513825 -63.467993) (xy 23.496905 -63.461749)
			(xy 23.487888 -63.461392) (xy 23.420832 -63.461392) (xy 23.411817 -63.461766) (xy 23.3949 -63.468002)
			(xy 23.387812 -63.473584) (xy 23.387558 -63.473838) (xy 23.366625 -63.491479) (xy 23.320657 -63.521203)
			(xy 23.270911 -63.544049) (xy 23.218409 -63.559545) (xy 23.164231 -63.567374) (xy 23.109489 -63.567374)
			(xy 23.055311 -63.559545) (xy 23.002809 -63.544049) (xy 22.953063 -63.521203) (xy 22.907095 -63.491479)
			(xy 22.886162 -63.473838) (xy 22.885908 -63.473584) (xy 22.878825 -63.467993) (xy 22.861905 -63.461749)
			(xy 22.852888 -63.461392) (xy 22.785832 -63.461392) (xy 22.776817 -63.461766) (xy 22.7599 -63.468002)
			(xy 22.752812 -63.473584) (xy 22.752812 -63.473838) (xy 22.752558 -63.473838) (xy 22.73162 -63.49147)
			(xy 22.685648 -63.521181) (xy 22.635902 -63.544018) (xy 22.583403 -63.559511) (xy 22.529229 -63.567343)
			(xy 22.50186 -63.567818) (xy 22.474611 -63.567309) (xy 22.420669 -63.559548) (xy 22.368381 -63.54419)
			(xy 22.31881 -63.521547) (xy 22.272966 -63.492081) (xy 22.231782 -63.45639) (xy 22.196095 -63.415202)
			(xy 22.166634 -63.369355) (xy 22.143996 -63.319782) (xy 22.128643 -63.267491) (xy 22.120888 -63.213549)
			(xy 19.136636 -63.213549) (xy 19.136636 -63.245552) (xy 19.12888 -63.2995) (xy 19.113525 -63.351796)
			(xy 19.090884 -63.401374) (xy 19.061418 -63.447225) (xy 19.025726 -63.488417) (xy 18.984536 -63.524109)
			(xy 18.938686 -63.553577) (xy 18.889109 -63.57622) (xy 18.836814 -63.591577) (xy 18.782866 -63.599335)
			(xy 18.755614 -63.599822) (xy 18.728243 -63.599367) (xy 18.674063 -63.591549) (xy 18.621559 -63.576059)
			(xy 18.571812 -63.553214) (xy 18.525847 -63.523486) (xy 18.504916 -63.505842) (xy 18.504662 -63.505588)
			(xy 18.497563 -63.50002) (xy 18.480656 -63.493762) (xy 18.471642 -63.493396) (xy 18.404586 -63.493396)
			(xy 18.395569 -63.493747) (xy 18.378652 -63.499999) (xy 18.371566 -63.505588) (xy 18.371312 -63.505842)
			(xy 18.350379 -63.523483) (xy 18.304411 -63.553207) (xy 18.254665 -63.576053) (xy 18.202163 -63.591549)
			(xy 18.147985 -63.599378) (xy 18.093243 -63.599378) (xy 18.039065 -63.591549) (xy 17.986563 -63.576053)
			(xy 17.936817 -63.553207) (xy 17.890849 -63.523483) (xy 17.869916 -63.505842) (xy 17.869662 -63.505588)
			(xy 17.862563 -63.50002) (xy 17.845656 -63.493762) (xy 17.836642 -63.493396) (xy 17.769586 -63.493396)
			(xy 17.760569 -63.493747) (xy 17.743652 -63.499999) (xy 17.736566 -63.505588) (xy 17.736566 -63.505842)
			(xy 17.736312 -63.505842) (xy 17.715392 -63.523496) (xy 17.669415 -63.553204) (xy 17.619665 -63.576037)
			(xy 17.567161 -63.591525) (xy 17.512984 -63.59935) (xy 17.485614 -63.599822) (xy 17.458361 -63.599332)
			(xy 17.404411 -63.591577) (xy 17.352113 -63.576222) (xy 17.302533 -63.553581) (xy 17.25668 -63.524115)
			(xy 17.215487 -63.488423) (xy 17.179793 -63.447231) (xy 17.150325 -63.401379) (xy 17.127683 -63.3518)
			(xy 17.112326 -63.299503) (xy 17.104569 -63.245552) (xy 4.416096 -63.245552) (xy 4.416552 -63.273432)
			(xy 4.416062 -63.3034) (xy 4.408239 -63.362822) (xy 4.392726 -63.420715) (xy 4.36979 -63.476088)
			(xy 4.339823 -63.527994) (xy 4.303336 -63.575544) (xy 4.260956 -63.617924) (xy 4.213406 -63.654411)
			(xy 4.1615 -63.684378) (xy 4.106127 -63.707314) (xy 4.048234 -63.722827) (xy 3.988812 -63.73065)
			(xy 3.928876 -63.73065) (xy 3.869454 -63.722827) (xy 3.811561 -63.707314) (xy 3.756188 -63.684378)
			(xy 3.704282 -63.654411) (xy 3.656732 -63.617924) (xy 3.614352 -63.575544) (xy 3.577865 -63.527994)
			(xy 3.547898 -63.476088) (xy 3.524962 -63.420715) (xy 3.509449 -63.362822) (xy 3.501626 -63.3034)
			(xy 2.875788 -63.3034) (xy 2.875788 -64.17818) (xy 2.876204 -64.188205) (xy 2.88387 -64.206731) (xy 2.898042 -64.220912)
			(xy 2.916563 -64.22859) (xy 2.926588 -64.22898) (xy 3.29311 -64.22898) (xy 3.326388 -64.229524) (xy 3.392375 -64.23821)
			(xy 3.456664 -64.255432) (xy 3.518156 -64.280896) (xy 3.572552 -64.312292) (xy 5.066028 -64.312292)
			(xy 5.070099 -64.25667) (xy 5.082225 -64.202233) (xy 5.102148 -64.150142) (xy 5.129444 -64.101507)
			(xy 5.16353 -64.057364) (xy 5.203679 -64.018655) (xy 5.249037 -63.986204) (xy 5.298637 -63.960703)
			(xy 5.351421 -63.942696) (xy 5.406264 -63.932566) (xy 5.461998 -63.930529) (xy 5.517435 -63.936629)
			(xy 5.571392 -63.950735) (xy 5.622721 -63.972547) (xy 5.670327 -64.001601) (xy 5.713195 -64.037276)
			(xy 5.750412 -64.078813) (xy 5.765907 -64.102234) (xy 27.387548 -64.102234) (xy 27.391619 -64.046612)
			(xy 27.403745 -63.992175) (xy 27.423668 -63.940084) (xy 27.450964 -63.891449) (xy 27.48505 -63.847306)
			(xy 27.525199 -63.808597) (xy 27.570557 -63.776146) (xy 27.620157 -63.750645) (xy 27.672941 -63.732638)
			(xy 27.727784 -63.722508) (xy 27.783518 -63.720471) (xy 27.838955 -63.726571) (xy 27.892912 -63.740677)
			(xy 27.944241 -63.762489) (xy 27.991847 -63.791543) (xy 28.034715 -63.827218) (xy 28.071932 -63.868755)
			(xy 28.102705 -63.915268) (xy 28.126377 -63.965765) (xy 28.142445 -64.019172) (xy 28.150565 -64.074348)
			(xy 28.151074 -64.102234) (xy 28.150565 -64.13012) (xy 28.142445 -64.185296) (xy 28.126377 -64.238703)
			(xy 28.102705 -64.2892) (xy 28.087427 -64.312292) (xy 31.065976 -64.312292) (xy 31.070047 -64.25667)
			(xy 31.082173 -64.202233) (xy 31.102096 -64.150142) (xy 31.129392 -64.101507) (xy 31.163478 -64.057364)
			(xy 31.203627 -64.018655) (xy 31.248985 -63.986204) (xy 31.298585 -63.960703) (xy 31.351369 -63.942696)
			(xy 31.406212 -63.932566) (xy 31.461946 -63.930529) (xy 31.517383 -63.936629) (xy 31.57134 -63.950735)
			(xy 31.622669 -63.972547) (xy 31.670275 -64.001601) (xy 31.713143 -64.037276) (xy 31.75036 -64.078813)
			(xy 31.765855 -64.102234) (xy 53.387496 -64.102234) (xy 53.391567 -64.046612) (xy 53.403693 -63.992175)
			(xy 53.423616 -63.940084) (xy 53.450912 -63.891449) (xy 53.484998 -63.847306) (xy 53.525147 -63.808597)
			(xy 53.570505 -63.776146) (xy 53.620105 -63.750645) (xy 53.672889 -63.732638) (xy 53.727732 -63.722508)
			(xy 53.783466 -63.720471) (xy 53.838903 -63.726571) (xy 53.89286 -63.740677) (xy 53.944189 -63.762489)
			(xy 53.991795 -63.791543) (xy 54.034663 -63.827218) (xy 54.07188 -63.868755) (xy 54.102653 -63.915268)
			(xy 54.126325 -63.965765) (xy 54.142393 -64.019172) (xy 54.150513 -64.074348) (xy 54.151022 -64.102234)
			(xy 54.150513 -64.13012) (xy 54.142393 -64.185296) (xy 54.126325 -64.238703) (xy 54.102653 -64.2892)
			(xy 54.087375 -64.312292) (xy 57.065924 -64.312292) (xy 57.069995 -64.25667) (xy 57.082121 -64.202233)
			(xy 57.102044 -64.150142) (xy 57.12934 -64.101507) (xy 57.163426 -64.057364) (xy 57.203575 -64.018655)
			(xy 57.248933 -63.986204) (xy 57.298533 -63.960703) (xy 57.351317 -63.942696) (xy 57.40616 -63.932566)
			(xy 57.461894 -63.930529) (xy 57.517331 -63.936629) (xy 57.571288 -63.950735) (xy 57.622617 -63.972547)
			(xy 57.670223 -64.001601) (xy 57.713091 -64.037276) (xy 57.750308 -64.078813) (xy 57.781081 -64.125326)
			(xy 57.804753 -64.175823) (xy 57.820821 -64.22923) (xy 57.828941 -64.284406) (xy 57.82945 -64.312292)
			(xy 57.828941 -64.340178) (xy 57.828635 -64.34226) (xy 58.8307 -64.34226) (xy 58.8307 -64.282324)
			(xy 58.838523 -64.222902) (xy 58.854036 -64.165009) (xy 58.876972 -64.109636) (xy 58.906939 -64.05773)
			(xy 58.943426 -64.01018) (xy 58.985806 -63.9678) (xy 59.033356 -63.931313) (xy 59.085262 -63.901346)
			(xy 59.140635 -63.87841) (xy 59.198528 -63.862897) (xy 59.25795 -63.855074) (xy 59.317886 -63.855074)
			(xy 59.377308 -63.862897) (xy 59.435201 -63.87841) (xy 59.490574 -63.901346) (xy 59.54248 -63.931313)
			(xy 59.59003 -63.9678) (xy 59.63241 -64.01018) (xy 59.668897 -64.05773) (xy 59.694591 -64.102234)
			(xy 79.387444 -64.102234) (xy 79.391515 -64.046612) (xy 79.403641 -63.992175) (xy 79.423564 -63.940084)
			(xy 79.45086 -63.891449) (xy 79.484946 -63.847306) (xy 79.525095 -63.808597) (xy 79.570453 -63.776146)
			(xy 79.620053 -63.750645) (xy 79.672837 -63.732638) (xy 79.72768 -63.722508) (xy 79.783414 -63.720471)
			(xy 79.838851 -63.726571) (xy 79.892808 -63.740677) (xy 79.944137 -63.762489) (xy 79.991743 -63.791543)
			(xy 80.034611 -63.827218) (xy 80.071828 -63.868755) (xy 80.102601 -63.915268) (xy 80.126273 -63.965765)
			(xy 80.142341 -64.019172) (xy 80.150461 -64.074348) (xy 80.15097 -64.102234) (xy 80.150461 -64.13012)
			(xy 80.142341 -64.185296) (xy 80.126273 -64.238703) (xy 80.102601 -64.2892) (xy 80.087323 -64.312292)
			(xy 83.065872 -64.312292) (xy 83.069943 -64.25667) (xy 83.082069 -64.202233) (xy 83.101992 -64.150142)
			(xy 83.129288 -64.101507) (xy 83.163374 -64.057364) (xy 83.203523 -64.018655) (xy 83.248881 -63.986204)
			(xy 83.298481 -63.960703) (xy 83.351265 -63.942696) (xy 83.406108 -63.932566) (xy 83.461842 -63.930529)
			(xy 83.517279 -63.936629) (xy 83.571236 -63.950735) (xy 83.622565 -63.972547) (xy 83.670171 -64.001601)
			(xy 83.713039 -64.037276) (xy 83.750256 -64.078813) (xy 83.765751 -64.102234) (xy 117.487698 -64.102234)
			(xy 117.491769 -64.046612) (xy 117.503895 -63.992175) (xy 117.523818 -63.940084) (xy 117.551114 -63.891449)
			(xy 117.5852 -63.847306) (xy 117.625349 -63.808597) (xy 117.670707 -63.776146) (xy 117.720307 -63.750645)
			(xy 117.773091 -63.732638) (xy 117.827934 -63.722508) (xy 117.883668 -63.720471) (xy 117.939105 -63.726571)
			(xy 117.993062 -63.740677) (xy 118.044391 -63.762489) (xy 118.091997 -63.791543) (xy 118.134865 -63.827218)
			(xy 118.172082 -63.868755) (xy 118.202855 -63.915268) (xy 118.226527 -63.965765) (xy 118.242595 -64.019172)
			(xy 118.250715 -64.074348) (xy 118.251224 -64.102234) (xy 118.250715 -64.13012) (xy 118.242595 -64.185296)
			(xy 118.226527 -64.238703) (xy 118.202855 -64.2892) (xy 118.187577 -64.312292) (xy 121.166126 -64.312292)
			(xy 121.170197 -64.25667) (xy 121.182323 -64.202233) (xy 121.202246 -64.150142) (xy 121.229542 -64.101507)
			(xy 121.263628 -64.057364) (xy 121.303777 -64.018655) (xy 121.349135 -63.986204) (xy 121.398735 -63.960703)
			(xy 121.451519 -63.942696) (xy 121.506362 -63.932566) (xy 121.562096 -63.930529) (xy 121.617533 -63.936629)
			(xy 121.67149 -63.950735) (xy 121.722819 -63.972547) (xy 121.770425 -64.001601) (xy 121.813293 -64.037276)
			(xy 121.85051 -64.078813) (xy 121.866005 -64.102234) (xy 143.487646 -64.102234) (xy 143.491717 -64.046612)
			(xy 143.503843 -63.992175) (xy 143.523766 -63.940084) (xy 143.551062 -63.891449) (xy 143.585148 -63.847306)
			(xy 143.625297 -63.808597) (xy 143.670655 -63.776146) (xy 143.720255 -63.750645) (xy 143.773039 -63.732638)
			(xy 143.827882 -63.722508) (xy 143.883616 -63.720471) (xy 143.939053 -63.726571) (xy 143.99301 -63.740677)
			(xy 144.044339 -63.762489) (xy 144.091945 -63.791543) (xy 144.134813 -63.827218) (xy 144.17203 -63.868755)
			(xy 144.202803 -63.915268) (xy 144.226475 -63.965765) (xy 144.242543 -64.019172) (xy 144.250663 -64.074348)
			(xy 144.251172 -64.102234) (xy 144.250663 -64.13012) (xy 144.242543 -64.185296) (xy 144.226475 -64.238703)
			(xy 144.202803 -64.2892) (xy 144.187525 -64.312292) (xy 147.166074 -64.312292) (xy 147.170145 -64.25667)
			(xy 147.182271 -64.202233) (xy 147.202194 -64.150142) (xy 147.22949 -64.101507) (xy 147.263576 -64.057364)
			(xy 147.303725 -64.018655) (xy 147.349083 -63.986204) (xy 147.398683 -63.960703) (xy 147.451467 -63.942696)
			(xy 147.50631 -63.932566) (xy 147.562044 -63.930529) (xy 147.617481 -63.936629) (xy 147.671438 -63.950735)
			(xy 147.722767 -63.972547) (xy 147.770373 -64.001601) (xy 147.813241 -64.037276) (xy 147.850458 -64.078813)
			(xy 147.865953 -64.102234) (xy 169.487594 -64.102234) (xy 169.491665 -64.046612) (xy 169.503791 -63.992175)
			(xy 169.523714 -63.940084) (xy 169.55101 -63.891449) (xy 169.585096 -63.847306) (xy 169.625245 -63.808597)
			(xy 169.670603 -63.776146) (xy 169.720203 -63.750645) (xy 169.772987 -63.732638) (xy 169.82783 -63.722508)
			(xy 169.883564 -63.720471) (xy 169.939001 -63.726571) (xy 169.992958 -63.740677) (xy 170.044287 -63.762489)
			(xy 170.091893 -63.791543) (xy 170.134761 -63.827218) (xy 170.171978 -63.868755) (xy 170.202751 -63.915268)
			(xy 170.226423 -63.965765) (xy 170.242491 -64.019172) (xy 170.250611 -64.074348) (xy 170.25112 -64.102234)
			(xy 170.250611 -64.13012) (xy 170.242491 -64.185296) (xy 170.226423 -64.238703) (xy 170.202751 -64.2892)
			(xy 170.187473 -64.312292) (xy 173.166022 -64.312292) (xy 173.170093 -64.25667) (xy 173.182219 -64.202233)
			(xy 173.202142 -64.150142) (xy 173.229438 -64.101507) (xy 173.263524 -64.057364) (xy 173.303673 -64.018655)
			(xy 173.349031 -63.986204) (xy 173.398631 -63.960703) (xy 173.451415 -63.942696) (xy 173.506258 -63.932566)
			(xy 173.561992 -63.930529) (xy 173.617429 -63.936629) (xy 173.671386 -63.950735) (xy 173.722715 -63.972547)
			(xy 173.770321 -64.001601) (xy 173.813189 -64.037276) (xy 173.850406 -64.078813) (xy 173.881179 -64.125326)
			(xy 173.904851 -64.175823) (xy 173.920919 -64.22923) (xy 173.929039 -64.284406) (xy 173.929548 -64.312292)
			(xy 173.929039 -64.340178) (xy 173.928733 -64.34226) (xy 174.930798 -64.34226) (xy 174.930798 -64.282324)
			(xy 174.938621 -64.222902) (xy 174.954134 -64.165009) (xy 174.97707 -64.109636) (xy 175.007037 -64.05773)
			(xy 175.043524 -64.01018) (xy 175.085904 -63.9678) (xy 175.133454 -63.931313) (xy 175.18536 -63.901346)
			(xy 175.240733 -63.87841) (xy 175.298626 -63.862897) (xy 175.358048 -63.855074) (xy 175.417984 -63.855074)
			(xy 175.477406 -63.862897) (xy 175.535299 -63.87841) (xy 175.590672 -63.901346) (xy 175.642578 -63.931313)
			(xy 175.690128 -63.9678) (xy 175.732508 -64.01018) (xy 175.768995 -64.05773) (xy 175.794689 -64.102234)
			(xy 195.487542 -64.102234) (xy 195.491613 -64.046612) (xy 195.503739 -63.992175) (xy 195.523662 -63.940084)
			(xy 195.550958 -63.891449) (xy 195.585044 -63.847306) (xy 195.625193 -63.808597) (xy 195.670551 -63.776146)
			(xy 195.720151 -63.750645) (xy 195.772935 -63.732638) (xy 195.827778 -63.722508) (xy 195.883512 -63.720471)
			(xy 195.938949 -63.726571) (xy 195.992906 -63.740677) (xy 196.044235 -63.762489) (xy 196.091841 -63.791543)
			(xy 196.134709 -63.827218) (xy 196.171926 -63.868755) (xy 196.202699 -63.915268) (xy 196.226371 -63.965765)
			(xy 196.242439 -64.019172) (xy 196.250559 -64.074348) (xy 196.251068 -64.102234) (xy 196.250559 -64.13012)
			(xy 196.242439 -64.185296) (xy 196.226371 -64.238703) (xy 196.202699 -64.2892) (xy 196.187421 -64.312292)
			(xy 199.16597 -64.312292) (xy 199.170041 -64.25667) (xy 199.182167 -64.202233) (xy 199.20209 -64.150142)
			(xy 199.229386 -64.101507) (xy 199.263472 -64.057364) (xy 199.303621 -64.018655) (xy 199.348979 -63.986204)
			(xy 199.398579 -63.960703) (xy 199.451363 -63.942696) (xy 199.506206 -63.932566) (xy 199.56194 -63.930529)
			(xy 199.617377 -63.936629) (xy 199.671334 -63.950735) (xy 199.722663 -63.972547) (xy 199.770269 -64.001601)
			(xy 199.813137 -64.037276) (xy 199.850354 -64.078813) (xy 199.881127 -64.125326) (xy 199.904799 -64.175823)
			(xy 199.920867 -64.22923) (xy 199.928987 -64.284406) (xy 199.929496 -64.312292) (xy 199.928987 -64.340178)
			(xy 199.920867 -64.395354) (xy 199.904799 -64.448761) (xy 199.881127 -64.499258) (xy 199.850354 -64.545771)
			(xy 199.813137 -64.587308) (xy 199.770269 -64.622983) (xy 199.722663 -64.652037) (xy 199.671334 -64.673849)
			(xy 199.617377 -64.687955) (xy 199.56194 -64.694055) (xy 199.506206 -64.692018) (xy 199.451363 -64.681888)
			(xy 199.398579 -64.663881) (xy 199.348979 -64.63838) (xy 199.303621 -64.605929) (xy 199.263472 -64.56722)
			(xy 199.229386 -64.523077) (xy 199.20209 -64.474442) (xy 199.182167 -64.422351) (xy 199.170041 -64.367914)
			(xy 199.16597 -64.312292) (xy 196.187421 -64.312292) (xy 196.171926 -64.335713) (xy 196.134709 -64.37725)
			(xy 196.091841 -64.412925) (xy 196.044235 -64.441979) (xy 195.992906 -64.463791) (xy 195.938949 -64.477897)
			(xy 195.883512 -64.483997) (xy 195.827778 -64.48196) (xy 195.772935 -64.47183) (xy 195.720151 -64.453823)
			(xy 195.670551 -64.428322) (xy 195.625193 -64.395871) (xy 195.585044 -64.357162) (xy 195.550958 -64.313019)
			(xy 195.523662 -64.264384) (xy 195.503739 -64.212293) (xy 195.491613 -64.157856) (xy 195.487542 -64.102234)
			(xy 175.794689 -64.102234) (xy 175.798962 -64.109636) (xy 175.821898 -64.165009) (xy 175.837411 -64.222902)
			(xy 175.845234 -64.282324) (xy 175.845724 -64.312292) (xy 175.845234 -64.34226) (xy 175.837411 -64.401682)
			(xy 175.821898 -64.459575) (xy 175.798962 -64.514948) (xy 175.768995 -64.566854) (xy 175.732508 -64.614404)
			(xy 175.690128 -64.656784) (xy 175.642578 -64.693271) (xy 175.590672 -64.723238) (xy 175.535299 -64.746174)
			(xy 175.477406 -64.761687) (xy 175.417984 -64.76951) (xy 175.358048 -64.76951) (xy 175.298626 -64.761687)
			(xy 175.240733 -64.746174) (xy 175.18536 -64.723238) (xy 175.133454 -64.693271) (xy 175.085904 -64.656784)
			(xy 175.043524 -64.614404) (xy 175.007037 -64.566854) (xy 174.97707 -64.514948) (xy 174.954134 -64.459575)
			(xy 174.938621 -64.401682) (xy 174.930798 -64.34226) (xy 173.928733 -64.34226) (xy 173.920919 -64.395354)
			(xy 173.904851 -64.448761) (xy 173.881179 -64.499258) (xy 173.850406 -64.545771) (xy 173.813189 -64.587308)
			(xy 173.770321 -64.622983) (xy 173.722715 -64.652037) (xy 173.671386 -64.673849) (xy 173.617429 -64.687955)
			(xy 173.561992 -64.694055) (xy 173.506258 -64.692018) (xy 173.451415 -64.681888) (xy 173.398631 -64.663881)
			(xy 173.349031 -64.63838) (xy 173.303673 -64.605929) (xy 173.263524 -64.56722) (xy 173.229438 -64.523077)
			(xy 173.202142 -64.474442) (xy 173.182219 -64.422351) (xy 173.170093 -64.367914) (xy 173.166022 -64.312292)
			(xy 170.187473 -64.312292) (xy 170.171978 -64.335713) (xy 170.134761 -64.37725) (xy 170.091893 -64.412925)
			(xy 170.044287 -64.441979) (xy 169.992958 -64.463791) (xy 169.939001 -64.477897) (xy 169.883564 -64.483997)
			(xy 169.82783 -64.48196) (xy 169.772987 -64.47183) (xy 169.720203 -64.453823) (xy 169.670603 -64.428322)
			(xy 169.625245 -64.395871) (xy 169.585096 -64.357162) (xy 169.55101 -64.313019) (xy 169.523714 -64.264384)
			(xy 169.503791 -64.212293) (xy 169.491665 -64.157856) (xy 169.487594 -64.102234) (xy 147.865953 -64.102234)
			(xy 147.881231 -64.125326) (xy 147.904903 -64.175823) (xy 147.920971 -64.22923) (xy 147.929091 -64.284406)
			(xy 147.9296 -64.312292) (xy 147.929091 -64.340178) (xy 147.920971 -64.395354) (xy 147.904903 -64.448761)
			(xy 147.881231 -64.499258) (xy 147.850458 -64.545771) (xy 147.813241 -64.587308) (xy 147.770373 -64.622983)
			(xy 147.722767 -64.652037) (xy 147.671438 -64.673849) (xy 147.617481 -64.687955) (xy 147.562044 -64.694055)
			(xy 147.50631 -64.692018) (xy 147.451467 -64.681888) (xy 147.398683 -64.663881) (xy 147.349083 -64.63838)
			(xy 147.303725 -64.605929) (xy 147.263576 -64.56722) (xy 147.22949 -64.523077) (xy 147.202194 -64.474442)
			(xy 147.182271 -64.422351) (xy 147.170145 -64.367914) (xy 147.166074 -64.312292) (xy 144.187525 -64.312292)
			(xy 144.17203 -64.335713) (xy 144.134813 -64.37725) (xy 144.091945 -64.412925) (xy 144.044339 -64.441979)
			(xy 143.99301 -64.463791) (xy 143.939053 -64.477897) (xy 143.883616 -64.483997) (xy 143.827882 -64.48196)
			(xy 143.773039 -64.47183) (xy 143.720255 -64.453823) (xy 143.670655 -64.428322) (xy 143.625297 -64.395871)
			(xy 143.585148 -64.357162) (xy 143.551062 -64.313019) (xy 143.523766 -64.264384) (xy 143.503843 -64.212293)
			(xy 143.491717 -64.157856) (xy 143.487646 -64.102234) (xy 121.866005 -64.102234) (xy 121.881283 -64.125326)
			(xy 121.904955 -64.175823) (xy 121.921023 -64.22923) (xy 121.929143 -64.284406) (xy 121.929652 -64.312292)
			(xy 121.929143 -64.340178) (xy 121.921023 -64.395354) (xy 121.904955 -64.448761) (xy 121.881283 -64.499258)
			(xy 121.85051 -64.545771) (xy 121.813293 -64.587308) (xy 121.770425 -64.622983) (xy 121.722819 -64.652037)
			(xy 121.67149 -64.673849) (xy 121.617533 -64.687955) (xy 121.562096 -64.694055) (xy 121.506362 -64.692018)
			(xy 121.451519 -64.681888) (xy 121.398735 -64.663881) (xy 121.349135 -64.63838) (xy 121.303777 -64.605929)
			(xy 121.263628 -64.56722) (xy 121.229542 -64.523077) (xy 121.202246 -64.474442) (xy 121.182323 -64.422351)
			(xy 121.170197 -64.367914) (xy 121.166126 -64.312292) (xy 118.187577 -64.312292) (xy 118.172082 -64.335713)
			(xy 118.134865 -64.37725) (xy 118.091997 -64.412925) (xy 118.044391 -64.441979) (xy 117.993062 -64.463791)
			(xy 117.939105 -64.477897) (xy 117.883668 -64.483997) (xy 117.827934 -64.48196) (xy 117.773091 -64.47183)
			(xy 117.720307 -64.453823) (xy 117.670707 -64.428322) (xy 117.625349 -64.395871) (xy 117.5852 -64.357162)
			(xy 117.551114 -64.313019) (xy 117.523818 -64.264384) (xy 117.503895 -64.212293) (xy 117.491769 -64.157856)
			(xy 117.487698 -64.102234) (xy 83.765751 -64.102234) (xy 83.781029 -64.125326) (xy 83.804701 -64.175823)
			(xy 83.820769 -64.22923) (xy 83.828889 -64.284406) (xy 83.829398 -64.312292) (xy 83.828889 -64.340178)
			(xy 83.820769 -64.395354) (xy 83.804701 -64.448761) (xy 83.781029 -64.499258) (xy 83.750256 -64.545771)
			(xy 83.713039 -64.587308) (xy 83.670171 -64.622983) (xy 83.622565 -64.652037) (xy 83.571236 -64.673849)
			(xy 83.517279 -64.687955) (xy 83.461842 -64.694055) (xy 83.406108 -64.692018) (xy 83.351265 -64.681888)
			(xy 83.298481 -64.663881) (xy 83.248881 -64.63838) (xy 83.203523 -64.605929) (xy 83.163374 -64.56722)
			(xy 83.129288 -64.523077) (xy 83.101992 -64.474442) (xy 83.082069 -64.422351) (xy 83.069943 -64.367914)
			(xy 83.065872 -64.312292) (xy 80.087323 -64.312292) (xy 80.071828 -64.335713) (xy 80.034611 -64.37725)
			(xy 79.991743 -64.412925) (xy 79.944137 -64.441979) (xy 79.892808 -64.463791) (xy 79.838851 -64.477897)
			(xy 79.783414 -64.483997) (xy 79.72768 -64.48196) (xy 79.672837 -64.47183) (xy 79.620053 -64.453823)
			(xy 79.570453 -64.428322) (xy 79.525095 -64.395871) (xy 79.484946 -64.357162) (xy 79.45086 -64.313019)
			(xy 79.423564 -64.264384) (xy 79.403641 -64.212293) (xy 79.391515 -64.157856) (xy 79.387444 -64.102234)
			(xy 59.694591 -64.102234) (xy 59.698864 -64.109636) (xy 59.7218 -64.165009) (xy 59.737313 -64.222902)
			(xy 59.745136 -64.282324) (xy 59.745626 -64.312292) (xy 59.745136 -64.34226) (xy 59.737313 -64.401682)
			(xy 59.7218 -64.459575) (xy 59.698864 -64.514948) (xy 59.668897 -64.566854) (xy 59.63241 -64.614404)
			(xy 59.59003 -64.656784) (xy 59.54248 -64.693271) (xy 59.490574 -64.723238) (xy 59.435201 -64.746174)
			(xy 59.377308 -64.761687) (xy 59.317886 -64.76951) (xy 59.25795 -64.76951) (xy 59.198528 -64.761687)
			(xy 59.140635 -64.746174) (xy 59.085262 -64.723238) (xy 59.033356 -64.693271) (xy 58.985806 -64.656784)
			(xy 58.943426 -64.614404) (xy 58.906939 -64.566854) (xy 58.876972 -64.514948) (xy 58.854036 -64.459575)
			(xy 58.838523 -64.401682) (xy 58.8307 -64.34226) (xy 57.828635 -64.34226) (xy 57.820821 -64.395354)
			(xy 57.804753 -64.448761) (xy 57.781081 -64.499258) (xy 57.750308 -64.545771) (xy 57.713091 -64.587308)
			(xy 57.670223 -64.622983) (xy 57.622617 -64.652037) (xy 57.571288 -64.673849) (xy 57.517331 -64.687955)
			(xy 57.461894 -64.694055) (xy 57.40616 -64.692018) (xy 57.351317 -64.681888) (xy 57.298533 -64.663881)
			(xy 57.248933 -64.63838) (xy 57.203575 -64.605929) (xy 57.163426 -64.56722) (xy 57.12934 -64.523077)
			(xy 57.102044 -64.474442) (xy 57.082121 -64.422351) (xy 57.069995 -64.367914) (xy 57.065924 -64.312292)
			(xy 54.087375 -64.312292) (xy 54.07188 -64.335713) (xy 54.034663 -64.37725) (xy 53.991795 -64.412925)
			(xy 53.944189 -64.441979) (xy 53.89286 -64.463791) (xy 53.838903 -64.477897) (xy 53.783466 -64.483997)
			(xy 53.727732 -64.48196) (xy 53.672889 -64.47183) (xy 53.620105 -64.453823) (xy 53.570505 -64.428322)
			(xy 53.525147 -64.395871) (xy 53.484998 -64.357162) (xy 53.450912 -64.313019) (xy 53.423616 -64.264384)
			(xy 53.403693 -64.212293) (xy 53.391567 -64.157856) (xy 53.387496 -64.102234) (xy 31.765855 -64.102234)
			(xy 31.781133 -64.125326) (xy 31.804805 -64.175823) (xy 31.820873 -64.22923) (xy 31.828993 -64.284406)
			(xy 31.829502 -64.312292) (xy 31.828993 -64.340178) (xy 31.820873 -64.395354) (xy 31.804805 -64.448761)
			(xy 31.781133 -64.499258) (xy 31.75036 -64.545771) (xy 31.713143 -64.587308) (xy 31.670275 -64.622983)
			(xy 31.622669 -64.652037) (xy 31.57134 -64.673849) (xy 31.517383 -64.687955) (xy 31.461946 -64.694055)
			(xy 31.406212 -64.692018) (xy 31.351369 -64.681888) (xy 31.298585 -64.663881) (xy 31.248985 -64.63838)
			(xy 31.203627 -64.605929) (xy 31.163478 -64.56722) (xy 31.129392 -64.523077) (xy 31.102096 -64.474442)
			(xy 31.082173 -64.422351) (xy 31.070047 -64.367914) (xy 31.065976 -64.312292) (xy 28.087427 -64.312292)
			(xy 28.071932 -64.335713) (xy 28.034715 -64.37725) (xy 27.991847 -64.412925) (xy 27.944241 -64.441979)
			(xy 27.892912 -64.463791) (xy 27.838955 -64.477897) (xy 27.783518 -64.483997) (xy 27.727784 -64.48196)
			(xy 27.672941 -64.47183) (xy 27.620157 -64.453823) (xy 27.570557 -64.428322) (xy 27.525199 -64.395871)
			(xy 27.48505 -64.357162) (xy 27.450964 -64.313019) (xy 27.423668 -64.264384) (xy 27.403745 -64.212293)
			(xy 27.391619 -64.157856) (xy 27.387548 -64.102234) (xy 5.765907 -64.102234) (xy 5.781185 -64.125326)
			(xy 5.804857 -64.175823) (xy 5.820925 -64.22923) (xy 5.829045 -64.284406) (xy 5.829554 -64.312292)
			(xy 5.829045 -64.340178) (xy 5.820925 -64.395354) (xy 5.804857 -64.448761) (xy 5.781185 -64.499258)
			(xy 5.750412 -64.545771) (xy 5.713195 -64.587308) (xy 5.670327 -64.622983) (xy 5.622721 -64.652037)
			(xy 5.571392 -64.673849) (xy 5.517435 -64.687955) (xy 5.461998 -64.694055) (xy 5.406264 -64.692018)
			(xy 5.351421 -64.681888) (xy 5.298637 -64.663881) (xy 5.249037 -64.63838) (xy 5.203679 -64.605929)
			(xy 5.16353 -64.56722) (xy 5.129444 -64.523077) (xy 5.102148 -64.474442) (xy 5.082225 -64.422351)
			(xy 5.070099 -64.367914) (xy 5.066028 -64.312292) (xy 3.572552 -64.312292) (xy 3.575799 -64.314166)
			(xy 3.628609 -64.354673) (xy 3.65252 -64.377824) (xy 4.660138 -65.385442) (xy 4.664964 -65.38976)
			(xy 4.671752 -65.394665) (xy 4.687583 -65.4001) (xy 4.695952 -65.400428) (xy 5.957824 -65.400428)
			(xy 5.961494 -65.400383) (xy 5.968762 -65.399365) (xy 5.972302 -65.398396) (xy 5.980104 -65.395752)
			(xy 5.993579 -65.386292) (xy 5.998718 -65.379854) (xy 6.004814 -65.371472) (xy 6.047486 -65.312544)
			(xy 6.050798 -65.30759) (xy 6.055297 -65.29656) (xy 6.056376 -65.2907) (xy 6.058408 -65.278508) (xy 6.054598 -65.267078)
			(xy 6.044108 -65.232905) (xy 6.032629 -65.162352) (xy 6.031738 -65.126616) (xy 6.031738 -65.120266)
			(xy 6.032465 -65.090461) (xy 6.040696 -65.031412) (xy 6.056525 -64.973931) (xy 6.079683 -64.918992)
			(xy 6.109779 -64.867526) (xy 6.146303 -64.820403) (xy 6.188637 -64.778421) (xy 6.236063 -64.742292)
			(xy 6.287779 -64.712626) (xy 6.342909 -64.689927) (xy 6.40052 -64.674578) (xy 6.459636 -64.66684)
			(xy 6.489446 -64.666368) (xy 6.519222 -64.666848) (xy 6.57827 -64.674578) (xy 6.635818 -64.689899)
			(xy 6.690892 -64.712555) (xy 6.742563 -64.742162) (xy 6.789958 -64.778219) (xy 6.832276 -64.820119)
			(xy 6.868803 -64.867154) (xy 6.898922 -64.918528) (xy 6.922124 -64.973374) (xy 6.938017 -65.030766)
			(xy 6.946333 -65.089735) (xy 6.947154 -65.119504) (xy 6.947154 -65.124584) (xy 6.946669 -65.154255)
			(xy 6.945931 -65.15989) (xy 19.116546 -65.15989) (xy 19.120617 -65.104268) (xy 19.132743 -65.049831)
			(xy 19.152666 -64.99774) (xy 19.179962 -64.949105) (xy 19.214048 -64.904962) (xy 19.254197 -64.866253)
			(xy 19.299555 -64.833802) (xy 19.349155 -64.808301) (xy 19.401939 -64.790294) (xy 19.456782 -64.780164)
			(xy 19.512516 -64.778127) (xy 19.567953 -64.784227) (xy 19.62191 -64.798333) (xy 19.673239 -64.820145)
			(xy 19.720845 -64.849199) (xy 19.763713 -64.884874) (xy 19.80093 -64.926411) (xy 19.831703 -64.972924)
			(xy 19.855375 -65.023421) (xy 19.871443 -65.076828) (xy 19.874995 -65.100962) (xy 20.132546 -65.100962)
			(xy 20.136617 -65.04534) (xy 20.148743 -64.990903) (xy 20.168666 -64.938812) (xy 20.195962 -64.890177)
			(xy 20.230048 -64.846034) (xy 20.270197 -64.807325) (xy 20.315555 -64.774874) (xy 20.365155 -64.749373)
			(xy 20.417939 -64.731366) (xy 20.472782 -64.721236) (xy 20.528516 -64.719199) (xy 20.583953 -64.725299)
			(xy 20.63791 -64.739405) (xy 20.689239 -64.761217) (xy 20.736845 -64.790271) (xy 20.779713 -64.825946)
			(xy 20.81693 -64.867483) (xy 20.847703 -64.913996) (xy 20.871375 -64.964493) (xy 20.887443 -65.0179)
			(xy 20.895563 -65.073076) (xy 20.896072 -65.100962) (xy 20.895563 -65.128848) (xy 20.890995 -65.15989)
			(xy 21.148546 -65.15989) (xy 21.152617 -65.104268) (xy 21.164743 -65.049831) (xy 21.184666 -64.99774)
			(xy 21.211962 -64.949105) (xy 21.246048 -64.904962) (xy 21.286197 -64.866253) (xy 21.331555 -64.833802)
			(xy 21.381155 -64.808301) (xy 21.433939 -64.790294) (xy 21.488782 -64.780164) (xy 21.544516 -64.778127)
			(xy 21.599953 -64.784227) (xy 21.65391 -64.798333) (xy 21.705239 -64.820145) (xy 21.752845 -64.849199)
			(xy 21.795713 -64.884874) (xy 21.83293 -64.926411) (xy 21.863703 -64.972924) (xy 21.887375 -65.023421)
			(xy 21.903443 -65.076828) (xy 21.911563 -65.132004) (xy 21.911965 -65.154044) (xy 32.032176 -65.154044)
			(xy 32.032176 -65.094108) (xy 32.039999 -65.034686) (xy 32.055512 -64.976793) (xy 32.078448 -64.92142)
			(xy 32.108415 -64.869514) (xy 32.144902 -64.821964) (xy 32.187282 -64.779584) (xy 32.234832 -64.743097)
			(xy 32.286738 -64.71313) (xy 32.342111 -64.690194) (xy 32.400004 -64.674681) (xy 32.459426 -64.666858)
			(xy 32.519362 -64.666858) (xy 32.578784 -64.674681) (xy 32.636677 -64.690194) (xy 32.69205 -64.71313)
			(xy 32.743956 -64.743097) (xy 32.791506 -64.779584) (xy 32.833886 -64.821964) (xy 32.870373 -64.869514)
			(xy 32.90034 -64.92142) (xy 32.923276 -64.976793) (xy 32.938789 -65.034686) (xy 32.946612 -65.094108)
			(xy 32.947102 -65.124076) (xy 32.946612 -65.154044) (xy 32.945842 -65.15989) (xy 45.116494 -65.15989)
			(xy 45.120565 -65.104268) (xy 45.132691 -65.049831) (xy 45.152614 -64.99774) (xy 45.17991 -64.949105)
			(xy 45.213996 -64.904962) (xy 45.254145 -64.866253) (xy 45.299503 -64.833802) (xy 45.349103 -64.808301)
			(xy 45.401887 -64.790294) (xy 45.45673 -64.780164) (xy 45.512464 -64.778127) (xy 45.567901 -64.784227)
			(xy 45.621858 -64.798333) (xy 45.673187 -64.820145) (xy 45.720793 -64.849199) (xy 45.763661 -64.884874)
			(xy 45.800878 -64.926411) (xy 45.831651 -64.972924) (xy 45.855323 -65.023421) (xy 45.871391 -65.076828)
			(xy 45.874943 -65.100962) (xy 46.132494 -65.100962) (xy 46.136565 -65.04534) (xy 46.148691 -64.990903)
			(xy 46.168614 -64.938812) (xy 46.19591 -64.890177) (xy 46.229996 -64.846034) (xy 46.270145 -64.807325)
			(xy 46.315503 -64.774874) (xy 46.365103 -64.749373) (xy 46.417887 -64.731366) (xy 46.47273 -64.721236)
			(xy 46.528464 -64.719199) (xy 46.583901 -64.725299) (xy 46.637858 -64.739405) (xy 46.689187 -64.761217)
			(xy 46.736793 -64.790271) (xy 46.779661 -64.825946) (xy 46.816878 -64.867483) (xy 46.847651 -64.913996)
			(xy 46.871323 -64.964493) (xy 46.887391 -65.0179) (xy 46.895511 -65.073076) (xy 46.89602 -65.100962)
			(xy 46.895511 -65.128848) (xy 46.890943 -65.15989) (xy 47.148494 -65.15989) (xy 47.152565 -65.104268)
			(xy 47.164691 -65.049831) (xy 47.184614 -64.99774) (xy 47.21191 -64.949105) (xy 47.245996 -64.904962)
			(xy 47.286145 -64.866253) (xy 47.331503 -64.833802) (xy 47.381103 -64.808301) (xy 47.433887 -64.790294)
			(xy 47.48873 -64.780164) (xy 47.544464 -64.778127) (xy 47.599901 -64.784227) (xy 47.653858 -64.798333)
			(xy 47.705187 -64.820145) (xy 47.752793 -64.849199) (xy 47.795661 -64.884874) (xy 47.832878 -64.926411)
			(xy 47.863651 -64.972924) (xy 47.887323 -65.023421) (xy 47.903391 -65.076828) (xy 47.911511 -65.132004)
			(xy 47.91202 -65.15989) (xy 71.116442 -65.15989) (xy 71.120513 -65.104268) (xy 71.132639 -65.049831)
			(xy 71.152562 -64.99774) (xy 71.179858 -64.949105) (xy 71.213944 -64.904962) (xy 71.254093 -64.866253)
			(xy 71.299451 -64.833802) (xy 71.349051 -64.808301) (xy 71.401835 -64.790294) (xy 71.456678 -64.780164)
			(xy 71.512412 -64.778127) (xy 71.567849 -64.784227) (xy 71.621806 -64.798333) (xy 71.673135 -64.820145)
			(xy 71.720741 -64.849199) (xy 71.763609 -64.884874) (xy 71.800826 -64.926411) (xy 71.831599 -64.972924)
			(xy 71.855271 -65.023421) (xy 71.871339 -65.076828) (xy 71.874891 -65.100962) (xy 72.132442 -65.100962)
			(xy 72.136513 -65.04534) (xy 72.148639 -64.990903) (xy 72.168562 -64.938812) (xy 72.195858 -64.890177)
			(xy 72.229944 -64.846034) (xy 72.270093 -64.807325) (xy 72.315451 -64.774874) (xy 72.365051 -64.749373)
			(xy 72.417835 -64.731366) (xy 72.472678 -64.721236) (xy 72.528412 -64.719199) (xy 72.583849 -64.725299)
			(xy 72.637806 -64.739405) (xy 72.689135 -64.761217) (xy 72.736741 -64.790271) (xy 72.779609 -64.825946)
			(xy 72.816826 -64.867483) (xy 72.847599 -64.913996) (xy 72.871271 -64.964493) (xy 72.887339 -65.0179)
			(xy 72.895459 -65.073076) (xy 72.895968 -65.100962) (xy 72.895459 -65.128848) (xy 72.890891 -65.15989)
			(xy 73.148442 -65.15989) (xy 73.152513 -65.104268) (xy 73.164639 -65.049831) (xy 73.184562 -64.99774)
			(xy 73.211858 -64.949105) (xy 73.245944 -64.904962) (xy 73.286093 -64.866253) (xy 73.331451 -64.833802)
			(xy 73.381051 -64.808301) (xy 73.433835 -64.790294) (xy 73.488678 -64.780164) (xy 73.544412 -64.778127)
			(xy 73.599849 -64.784227) (xy 73.653806 -64.798333) (xy 73.705135 -64.820145) (xy 73.752741 -64.849199)
			(xy 73.795609 -64.884874) (xy 73.832826 -64.926411) (xy 73.863599 -64.972924) (xy 73.887271 -65.023421)
			(xy 73.903339 -65.076828) (xy 73.911459 -65.132004) (xy 73.911861 -65.154044) (xy 84.032072 -65.154044)
			(xy 84.032072 -65.094108) (xy 84.039895 -65.034686) (xy 84.055408 -64.976793) (xy 84.078344 -64.92142)
			(xy 84.108311 -64.869514) (xy 84.144798 -64.821964) (xy 84.187178 -64.779584) (xy 84.234728 -64.743097)
			(xy 84.286634 -64.71313) (xy 84.342007 -64.690194) (xy 84.3999 -64.674681) (xy 84.459322 -64.666858)
			(xy 84.519258 -64.666858) (xy 84.57868 -64.674681) (xy 84.636573 -64.690194) (xy 84.691946 -64.71313)
			(xy 84.743852 -64.743097) (xy 84.791402 -64.779584) (xy 84.833782 -64.821964) (xy 84.870269 -64.869514)
			(xy 84.900236 -64.92142) (xy 84.923172 -64.976793) (xy 84.938685 -65.034686) (xy 84.946508 -65.094108)
			(xy 84.946998 -65.124076) (xy 84.946508 -65.154044) (xy 84.945738 -65.15989) (xy 97.11639 -65.15989)
			(xy 97.120461 -65.104268) (xy 97.132587 -65.049831) (xy 97.15251 -64.99774) (xy 97.179806 -64.949105)
			(xy 97.213892 -64.904962) (xy 97.254041 -64.866253) (xy 97.299399 -64.833802) (xy 97.348999 -64.808301)
			(xy 97.401783 -64.790294) (xy 97.456626 -64.780164) (xy 97.51236 -64.778127) (xy 97.567797 -64.784227)
			(xy 97.621754 -64.798333) (xy 97.673083 -64.820145) (xy 97.720689 -64.849199) (xy 97.763557 -64.884874)
			(xy 97.800774 -64.926411) (xy 97.831547 -64.972924) (xy 97.855219 -65.023421) (xy 97.871287 -65.076828)
			(xy 97.874839 -65.100962) (xy 98.13239 -65.100962) (xy 98.136461 -65.04534) (xy 98.148587 -64.990903)
			(xy 98.16851 -64.938812) (xy 98.195806 -64.890177) (xy 98.229892 -64.846034) (xy 98.270041 -64.807325)
			(xy 98.315399 -64.774874) (xy 98.364999 -64.749373) (xy 98.417783 -64.731366) (xy 98.472626 -64.721236)
			(xy 98.52836 -64.719199) (xy 98.583797 -64.725299) (xy 98.637754 -64.739405) (xy 98.689083 -64.761217)
			(xy 98.736689 -64.790271) (xy 98.779557 -64.825946) (xy 98.816774 -64.867483) (xy 98.847547 -64.913996)
			(xy 98.871219 -64.964493) (xy 98.887287 -65.0179) (xy 98.895407 -65.073076) (xy 98.895916 -65.100962)
			(xy 98.895407 -65.128848) (xy 98.890839 -65.15989) (xy 99.14839 -65.15989) (xy 99.152461 -65.104268)
			(xy 99.164587 -65.049831) (xy 99.18451 -64.99774) (xy 99.211806 -64.949105) (xy 99.245892 -64.904962)
			(xy 99.286041 -64.866253) (xy 99.331399 -64.833802) (xy 99.380999 -64.808301) (xy 99.433783 -64.790294)
			(xy 99.488626 -64.780164) (xy 99.54436 -64.778127) (xy 99.599797 -64.784227) (xy 99.653754 -64.798333)
			(xy 99.705083 -64.820145) (xy 99.752689 -64.849199) (xy 99.795557 -64.884874) (xy 99.832774 -64.926411)
			(xy 99.863547 -64.972924) (xy 99.887219 -65.023421) (xy 99.903287 -65.076828) (xy 99.911407 -65.132004)
			(xy 99.911809 -65.154044) (xy 122.132326 -65.154044) (xy 122.132326 -65.094108) (xy 122.140149 -65.034686)
			(xy 122.155662 -64.976793) (xy 122.178598 -64.92142) (xy 122.208565 -64.869514) (xy 122.245052 -64.821964)
			(xy 122.287432 -64.779584) (xy 122.334982 -64.743097) (xy 122.386888 -64.71313) (xy 122.442261 -64.690194)
			(xy 122.500154 -64.674681) (xy 122.559576 -64.666858) (xy 122.619512 -64.666858) (xy 122.678934 -64.674681)
			(xy 122.736827 -64.690194) (xy 122.7922 -64.71313) (xy 122.844106 -64.743097) (xy 122.891656 -64.779584)
			(xy 122.934036 -64.821964) (xy 122.970523 -64.869514) (xy 123.00049 -64.92142) (xy 123.023426 -64.976793)
			(xy 123.038939 -65.034686) (xy 123.046762 -65.094108) (xy 123.047252 -65.124076) (xy 123.046762 -65.154044)
			(xy 123.045992 -65.15989) (xy 135.216644 -65.15989) (xy 135.220715 -65.104268) (xy 135.232841 -65.049831)
			(xy 135.252764 -64.99774) (xy 135.28006 -64.949105) (xy 135.314146 -64.904962) (xy 135.354295 -64.866253)
			(xy 135.399653 -64.833802) (xy 135.449253 -64.808301) (xy 135.502037 -64.790294) (xy 135.55688 -64.780164)
			(xy 135.612614 -64.778127) (xy 135.668051 -64.784227) (xy 135.722008 -64.798333) (xy 135.773337 -64.820145)
			(xy 135.820943 -64.849199) (xy 135.863811 -64.884874) (xy 135.901028 -64.926411) (xy 135.931801 -64.972924)
			(xy 135.955473 -65.023421) (xy 135.971541 -65.076828) (xy 135.975093 -65.100962) (xy 136.232644 -65.100962)
			(xy 136.236715 -65.04534) (xy 136.248841 -64.990903) (xy 136.268764 -64.938812) (xy 136.29606 -64.890177)
			(xy 136.330146 -64.846034) (xy 136.370295 -64.807325) (xy 136.415653 -64.774874) (xy 136.465253 -64.749373)
			(xy 136.518037 -64.731366) (xy 136.57288 -64.721236) (xy 136.628614 -64.719199) (xy 136.684051 -64.725299)
			(xy 136.738008 -64.739405) (xy 136.789337 -64.761217) (xy 136.836943 -64.790271) (xy 136.879811 -64.825946)
			(xy 136.917028 -64.867483) (xy 136.947801 -64.913996) (xy 136.971473 -64.964493) (xy 136.987541 -65.0179)
			(xy 136.995661 -65.073076) (xy 136.99617 -65.100962) (xy 136.995661 -65.128848) (xy 136.991093 -65.15989)
			(xy 137.248644 -65.15989) (xy 137.252715 -65.104268) (xy 137.264841 -65.049831) (xy 137.284764 -64.99774)
			(xy 137.31206 -64.949105) (xy 137.346146 -64.904962) (xy 137.386295 -64.866253) (xy 137.431653 -64.833802)
			(xy 137.481253 -64.808301) (xy 137.534037 -64.790294) (xy 137.58888 -64.780164) (xy 137.644614 -64.778127)
			(xy 137.700051 -64.784227) (xy 137.754008 -64.798333) (xy 137.805337 -64.820145) (xy 137.852943 -64.849199)
			(xy 137.895811 -64.884874) (xy 137.933028 -64.926411) (xy 137.963801 -64.972924) (xy 137.987473 -65.023421)
			(xy 138.003541 -65.076828) (xy 138.011661 -65.132004) (xy 138.012063 -65.154044) (xy 148.132274 -65.154044)
			(xy 148.132274 -65.094108) (xy 148.140097 -65.034686) (xy 148.15561 -64.976793) (xy 148.178546 -64.92142)
			(xy 148.208513 -64.869514) (xy 148.245 -64.821964) (xy 148.28738 -64.779584) (xy 148.33493 -64.743097)
			(xy 148.386836 -64.71313) (xy 148.442209 -64.690194) (xy 148.500102 -64.674681) (xy 148.559524 -64.666858)
			(xy 148.61946 -64.666858) (xy 148.678882 -64.674681) (xy 148.736775 -64.690194) (xy 148.792148 -64.71313)
			(xy 148.844054 -64.743097) (xy 148.891604 -64.779584) (xy 148.933984 -64.821964) (xy 148.970471 -64.869514)
			(xy 149.000438 -64.92142) (xy 149.023374 -64.976793) (xy 149.038887 -65.034686) (xy 149.04671 -65.094108)
			(xy 149.0472 -65.124076) (xy 149.04671 -65.154044) (xy 149.04594 -65.15989) (xy 161.216592 -65.15989)
			(xy 161.220663 -65.104268) (xy 161.232789 -65.049831) (xy 161.252712 -64.99774) (xy 161.280008 -64.949105)
			(xy 161.314094 -64.904962) (xy 161.354243 -64.866253) (xy 161.399601 -64.833802) (xy 161.449201 -64.808301)
			(xy 161.501985 -64.790294) (xy 161.556828 -64.780164) (xy 161.612562 -64.778127) (xy 161.667999 -64.784227)
			(xy 161.721956 -64.798333) (xy 161.773285 -64.820145) (xy 161.820891 -64.849199) (xy 161.863759 -64.884874)
			(xy 161.900976 -64.926411) (xy 161.931749 -64.972924) (xy 161.955421 -65.023421) (xy 161.971489 -65.076828)
			(xy 161.975041 -65.100962) (xy 162.232592 -65.100962) (xy 162.236663 -65.04534) (xy 162.248789 -64.990903)
			(xy 162.268712 -64.938812) (xy 162.296008 -64.890177) (xy 162.330094 -64.846034) (xy 162.370243 -64.807325)
			(xy 162.415601 -64.774874) (xy 162.465201 -64.749373) (xy 162.517985 -64.731366) (xy 162.572828 -64.721236)
			(xy 162.628562 -64.719199) (xy 162.683999 -64.725299) (xy 162.737956 -64.739405) (xy 162.789285 -64.761217)
			(xy 162.836891 -64.790271) (xy 162.879759 -64.825946) (xy 162.916976 -64.867483) (xy 162.947749 -64.913996)
			(xy 162.971421 -64.964493) (xy 162.987489 -65.0179) (xy 162.995609 -65.073076) (xy 162.996118 -65.100962)
			(xy 162.995609 -65.128848) (xy 162.991041 -65.15989) (xy 163.248592 -65.15989) (xy 163.252663 -65.104268)
			(xy 163.264789 -65.049831) (xy 163.284712 -64.99774) (xy 163.312008 -64.949105) (xy 163.346094 -64.904962)
			(xy 163.386243 -64.866253) (xy 163.431601 -64.833802) (xy 163.481201 -64.808301) (xy 163.533985 -64.790294)
			(xy 163.588828 -64.780164) (xy 163.644562 -64.778127) (xy 163.699999 -64.784227) (xy 163.753956 -64.798333)
			(xy 163.805285 -64.820145) (xy 163.852891 -64.849199) (xy 163.895759 -64.884874) (xy 163.932976 -64.926411)
			(xy 163.963749 -64.972924) (xy 163.987421 -65.023421) (xy 164.003489 -65.076828) (xy 164.011609 -65.132004)
			(xy 164.012118 -65.15989) (xy 187.21654 -65.15989) (xy 187.220611 -65.104268) (xy 187.232737 -65.049831)
			(xy 187.25266 -64.99774) (xy 187.279956 -64.949105) (xy 187.314042 -64.904962) (xy 187.354191 -64.866253)
			(xy 187.399549 -64.833802) (xy 187.449149 -64.808301) (xy 187.501933 -64.790294) (xy 187.556776 -64.780164)
			(xy 187.61251 -64.778127) (xy 187.667947 -64.784227) (xy 187.721904 -64.798333) (xy 187.773233 -64.820145)
			(xy 187.820839 -64.849199) (xy 187.863707 -64.884874) (xy 187.900924 -64.926411) (xy 187.931697 -64.972924)
			(xy 187.955369 -65.023421) (xy 187.971437 -65.076828) (xy 187.974989 -65.100962) (xy 188.23254 -65.100962)
			(xy 188.236611 -65.04534) (xy 188.248737 -64.990903) (xy 188.26866 -64.938812) (xy 188.295956 -64.890177)
			(xy 188.330042 -64.846034) (xy 188.370191 -64.807325) (xy 188.415549 -64.774874) (xy 188.465149 -64.749373)
			(xy 188.517933 -64.731366) (xy 188.572776 -64.721236) (xy 188.62851 -64.719199) (xy 188.683947 -64.725299)
			(xy 188.737904 -64.739405) (xy 188.789233 -64.761217) (xy 188.836839 -64.790271) (xy 188.879707 -64.825946)
			(xy 188.916924 -64.867483) (xy 188.947697 -64.913996) (xy 188.971369 -64.964493) (xy 188.987437 -65.0179)
			(xy 188.995557 -65.073076) (xy 188.996066 -65.100962) (xy 188.995557 -65.128848) (xy 188.990989 -65.15989)
			(xy 189.24854 -65.15989) (xy 189.252611 -65.104268) (xy 189.264737 -65.049831) (xy 189.28466 -64.99774)
			(xy 189.311956 -64.949105) (xy 189.346042 -64.904962) (xy 189.386191 -64.866253) (xy 189.431549 -64.833802)
			(xy 189.481149 -64.808301) (xy 189.533933 -64.790294) (xy 189.588776 -64.780164) (xy 189.64451 -64.778127)
			(xy 189.699947 -64.784227) (xy 189.753904 -64.798333) (xy 189.805233 -64.820145) (xy 189.852839 -64.849199)
			(xy 189.895707 -64.884874) (xy 189.932924 -64.926411) (xy 189.963697 -64.972924) (xy 189.987369 -65.023421)
			(xy 190.003437 -65.076828) (xy 190.011557 -65.132004) (xy 190.011959 -65.154044) (xy 200.13217 -65.154044)
			(xy 200.13217 -65.094108) (xy 200.139993 -65.034686) (xy 200.155506 -64.976793) (xy 200.178442 -64.92142)
			(xy 200.208409 -64.869514) (xy 200.244896 -64.821964) (xy 200.287276 -64.779584) (xy 200.334826 -64.743097)
			(xy 200.386732 -64.71313) (xy 200.442105 -64.690194) (xy 200.499998 -64.674681) (xy 200.55942 -64.666858)
			(xy 200.619356 -64.666858) (xy 200.678778 -64.674681) (xy 200.736671 -64.690194) (xy 200.792044 -64.71313)
			(xy 200.84395 -64.743097) (xy 200.8915 -64.779584) (xy 200.93388 -64.821964) (xy 200.970367 -64.869514)
			(xy 201.000334 -64.92142) (xy 201.02327 -64.976793) (xy 201.038783 -65.034686) (xy 201.046606 -65.094108)
			(xy 201.047096 -65.124076) (xy 201.046606 -65.154044) (xy 201.045836 -65.15989) (xy 213.216488 -65.15989)
			(xy 213.220559 -65.104268) (xy 213.232685 -65.049831) (xy 213.252608 -64.99774) (xy 213.279904 -64.949105)
			(xy 213.31399 -64.904962) (xy 213.354139 -64.866253) (xy 213.399497 -64.833802) (xy 213.449097 -64.808301)
			(xy 213.501881 -64.790294) (xy 213.556724 -64.780164) (xy 213.612458 -64.778127) (xy 213.667895 -64.784227)
			(xy 213.721852 -64.798333) (xy 213.773181 -64.820145) (xy 213.820787 -64.849199) (xy 213.863655 -64.884874)
			(xy 213.900872 -64.926411) (xy 213.931645 -64.972924) (xy 213.955317 -65.023421) (xy 213.971385 -65.076828)
			(xy 213.974937 -65.100962) (xy 214.232488 -65.100962) (xy 214.236559 -65.04534) (xy 214.248685 -64.990903)
			(xy 214.268608 -64.938812) (xy 214.295904 -64.890177) (xy 214.32999 -64.846034) (xy 214.370139 -64.807325)
			(xy 214.415497 -64.774874) (xy 214.465097 -64.749373) (xy 214.517881 -64.731366) (xy 214.572724 -64.721236)
			(xy 214.628458 -64.719199) (xy 214.683895 -64.725299) (xy 214.737852 -64.739405) (xy 214.789181 -64.761217)
			(xy 214.836787 -64.790271) (xy 214.879655 -64.825946) (xy 214.916872 -64.867483) (xy 214.947645 -64.913996)
			(xy 214.971317 -64.964493) (xy 214.987385 -65.0179) (xy 214.995505 -65.073076) (xy 214.996014 -65.100962)
			(xy 214.995505 -65.128848) (xy 214.990937 -65.15989) (xy 215.248488 -65.15989) (xy 215.252559 -65.104268)
			(xy 215.264685 -65.049831) (xy 215.284608 -64.99774) (xy 215.311904 -64.949105) (xy 215.34599 -64.904962)
			(xy 215.386139 -64.866253) (xy 215.431497 -64.833802) (xy 215.481097 -64.808301) (xy 215.533881 -64.790294)
			(xy 215.588724 -64.780164) (xy 215.644458 -64.778127) (xy 215.699895 -64.784227) (xy 215.753852 -64.798333)
			(xy 215.757709 -64.799972) (xy 224.556828 -64.799972) (xy 224.557319 -64.770616) (xy 224.56483 -64.712385)
			(xy 224.579725 -64.655593) (xy 224.60176 -64.601172) (xy 224.630573 -64.550015) (xy 224.66569 -64.502962)
			(xy 224.706536 -64.460786) (xy 224.75244 -64.424179) (xy 224.7773 -64.408558) (xy 224.786698 -64.40297)
			(xy 224.79889 -64.385444) (xy 224.816924 -64.28994) (xy 224.812098 -64.269112) (xy 224.805748 -64.260476)
			(xy 224.787675 -64.235502) (xy 224.758952 -64.18096) (xy 224.739359 -64.122514) (xy 224.729404 -64.061681)
			(xy 224.728786 -64.03086) (xy 224.729247 -64.00472) (xy 224.736397 -63.952932) (xy 224.750545 -63.902603)
			(xy 224.771426 -63.854675) (xy 224.79865 -63.810043) (xy 224.831708 -63.769541) (xy 224.869981 -63.733928)
			(xy 224.912755 -63.703868) (xy 224.935796 -63.691516) (xy 224.944178 -63.687198) (xy 224.956878 -63.672974)
			(xy 224.984056 -63.59906) (xy 224.986883 -63.590175) (xy 224.986611 -63.571545) (xy 224.983548 -63.562738)
			(xy 224.983548 -63.562484) (xy 224.98304 -63.561976) (xy 224.973878 -63.538774) (xy 224.960988 -63.490583)
			(xy 224.954489 -63.441123) (xy 224.954084 -63.41618) (xy 224.95457 -63.388929) (xy 224.962326 -63.334981)
			(xy 224.977681 -63.282686) (xy 225.000323 -63.233109) (xy 225.029789 -63.187259) (xy 225.06548 -63.146068)
			(xy 225.106671 -63.110377) (xy 225.152521 -63.080911) (xy 225.202098 -63.058269) (xy 225.254393 -63.042914)
			(xy 225.308341 -63.035158) (xy 225.362843 -63.035158) (xy 225.416791 -63.042914) (xy 225.469086 -63.058269)
			(xy 225.518663 -63.080911) (xy 225.564513 -63.110377) (xy 225.605704 -63.146068) (xy 225.641395 -63.187259)
			(xy 225.670861 -63.233109) (xy 225.693503 -63.282686) (xy 225.708858 -63.334981) (xy 225.716614 -63.388929)
			(xy 225.7171 -63.41618) (xy 225.71668 -63.442321) (xy 225.709524 -63.494111) (xy 225.69537 -63.544442)
			(xy 225.681089 -63.577212) (xy 226.889038 -63.577212) (xy 226.889038 -63.517276) (xy 226.896861 -63.457854)
			(xy 226.912374 -63.399961) (xy 226.93531 -63.344588) (xy 226.965277 -63.292682) (xy 227.001764 -63.245132)
			(xy 227.044144 -63.202752) (xy 227.091694 -63.166265) (xy 227.1436 -63.136298) (xy 227.198973 -63.113362)
			(xy 227.256866 -63.097849) (xy 227.316288 -63.090026) (xy 227.376224 -63.090026) (xy 227.435646 -63.097849)
			(xy 227.493539 -63.113362) (xy 227.548912 -63.136298) (xy 227.600818 -63.166265) (xy 227.648368 -63.202752)
			(xy 227.690748 -63.245132) (xy 227.727235 -63.292682) (xy 227.757202 -63.344588) (xy 227.780138 -63.399961)
			(xy 227.795651 -63.457854) (xy 227.803474 -63.517276) (xy 227.803964 -63.547244) (xy 227.803474 -63.577212)
			(xy 227.795651 -63.636634) (xy 227.780138 -63.694527) (xy 227.757202 -63.7499) (xy 227.727235 -63.801806)
			(xy 227.690748 -63.849356) (xy 227.648368 -63.891736) (xy 227.600818 -63.928223) (xy 227.548912 -63.95819)
			(xy 227.493539 -63.981126) (xy 227.435646 -63.996639) (xy 227.376224 -64.004462) (xy 227.316288 -64.004462)
			(xy 227.256866 -63.996639) (xy 227.198973 -63.981126) (xy 227.1436 -63.95819) (xy 227.091694 -63.928223)
			(xy 227.044144 -63.891736) (xy 227.001764 -63.849356) (xy 226.965277 -63.801806) (xy 226.93531 -63.7499)
			(xy 226.912374 -63.694527) (xy 226.896861 -63.636634) (xy 226.889038 -63.577212) (xy 225.681089 -63.577212)
			(xy 225.674483 -63.592371) (xy 225.647254 -63.637003) (xy 225.61419 -63.677503) (xy 225.575912 -63.713115)
			(xy 225.533133 -63.743173) (xy 225.51009 -63.755524) (xy 225.501708 -63.759842) (xy 225.489008 -63.774066)
			(xy 225.46183 -63.84798) (xy 225.45903 -63.856872) (xy 225.459282 -63.875496) (xy 225.462338 -63.884302)
			(xy 225.462338 -63.884556) (xy 225.462846 -63.885064) (xy 225.471989 -63.908273) (xy 225.484887 -63.956461)
			(xy 225.491394 -64.005918) (xy 225.491802 -64.03086) (xy 225.491235 -64.059291) (xy 225.482794 -64.115522)
			(xy 225.466109 -64.169881) (xy 225.441547 -64.221164) (xy 225.409652 -64.268238) (xy 225.37113 -64.310062)
			(xy 225.349308 -64.328294) (xy 225.340926 -64.334898) (xy 225.33102 -64.353948) (xy 225.325432 -64.450976)
			(xy 225.333052 -64.471042) (xy 225.340672 -64.478662) (xy 225.361185 -64.500102) (xy 225.397012 -64.547403)
			(xy 225.42642 -64.598942) (xy 225.448915 -64.65385) (xy 225.464121 -64.711207) (xy 225.47178 -64.770049)
			(xy 225.472244 -64.799718) (xy 225.472244 -64.799972) (xy 225.471754 -64.82994) (xy 225.463931 -64.889362)
			(xy 225.448418 -64.947255) (xy 225.425482 -65.002628) (xy 225.395515 -65.054534) (xy 225.359028 -65.102084)
			(xy 225.316648 -65.144464) (xy 225.269098 -65.180951) (xy 225.217192 -65.210918) (xy 225.161819 -65.233854)
			(xy 225.103926 -65.249367) (xy 225.044504 -65.25719) (xy 224.984568 -65.25719) (xy 224.925146 -65.249367)
			(xy 224.867253 -65.233854) (xy 224.81188 -65.210918) (xy 224.759974 -65.180951) (xy 224.712424 -65.144464)
			(xy 224.670044 -65.102084) (xy 224.633557 -65.054534) (xy 224.60359 -65.002628) (xy 224.580654 -64.947255)
			(xy 224.565141 -64.889362) (xy 224.557318 -64.82994) (xy 224.556828 -64.799972) (xy 215.757709 -64.799972)
			(xy 215.805181 -64.820145) (xy 215.852787 -64.849199) (xy 215.895655 -64.884874) (xy 215.932872 -64.926411)
			(xy 215.963645 -64.972924) (xy 215.987317 -65.023421) (xy 216.003385 -65.076828) (xy 216.011505 -65.132004)
			(xy 216.012014 -65.15989) (xy 216.011505 -65.187776) (xy 216.003385 -65.242952) (xy 215.987317 -65.296359)
			(xy 215.963645 -65.346856) (xy 215.932872 -65.393369) (xy 215.895655 -65.434906) (xy 215.852787 -65.470581)
			(xy 215.805181 -65.499635) (xy 215.753852 -65.521447) (xy 215.699895 -65.535553) (xy 215.644458 -65.541653)
			(xy 215.588724 -65.539616) (xy 215.533881 -65.529486) (xy 215.481097 -65.511479) (xy 215.431497 -65.485978)
			(xy 215.386139 -65.453527) (xy 215.34599 -65.414818) (xy 215.311904 -65.370675) (xy 215.284608 -65.32204)
			(xy 215.264685 -65.269949) (xy 215.252559 -65.215512) (xy 215.248488 -65.15989) (xy 214.990937 -65.15989)
			(xy 214.987385 -65.184024) (xy 214.971317 -65.237431) (xy 214.947645 -65.287928) (xy 214.916872 -65.334441)
			(xy 214.879655 -65.375978) (xy 214.836787 -65.411653) (xy 214.789181 -65.440707) (xy 214.737852 -65.462519)
			(xy 214.683895 -65.476625) (xy 214.628458 -65.482725) (xy 214.572724 -65.480688) (xy 214.517881 -65.470558)
			(xy 214.465097 -65.452551) (xy 214.415497 -65.42705) (xy 214.370139 -65.394599) (xy 214.32999 -65.35589)
			(xy 214.295904 -65.311747) (xy 214.268608 -65.263112) (xy 214.248685 -65.211021) (xy 214.236559 -65.156584)
			(xy 214.232488 -65.100962) (xy 213.974937 -65.100962) (xy 213.979505 -65.132004) (xy 213.980014 -65.15989)
			(xy 213.979505 -65.187776) (xy 213.971385 -65.242952) (xy 213.955317 -65.296359) (xy 213.931645 -65.346856)
			(xy 213.900872 -65.393369) (xy 213.863655 -65.434906) (xy 213.820787 -65.470581) (xy 213.773181 -65.499635)
			(xy 213.721852 -65.521447) (xy 213.667895 -65.535553) (xy 213.612458 -65.541653) (xy 213.556724 -65.539616)
			(xy 213.501881 -65.529486) (xy 213.449097 -65.511479) (xy 213.399497 -65.485978) (xy 213.354139 -65.453527)
			(xy 213.31399 -65.414818) (xy 213.279904 -65.370675) (xy 213.252608 -65.32204) (xy 213.232685 -65.269949)
			(xy 213.220559 -65.215512) (xy 213.216488 -65.15989) (xy 201.045836 -65.15989) (xy 201.038783 -65.213466)
			(xy 201.02327 -65.271359) (xy 201.000334 -65.326732) (xy 200.970367 -65.378638) (xy 200.93388 -65.426188)
			(xy 200.8915 -65.468568) (xy 200.84395 -65.505055) (xy 200.792044 -65.535022) (xy 200.736671 -65.557958)
			(xy 200.678778 -65.573471) (xy 200.619356 -65.581294) (xy 200.55942 -65.581294) (xy 200.499998 -65.573471)
			(xy 200.442105 -65.557958) (xy 200.386732 -65.535022) (xy 200.334826 -65.505055) (xy 200.287276 -65.468568)
			(xy 200.244896 -65.426188) (xy 200.208409 -65.378638) (xy 200.178442 -65.326732) (xy 200.155506 -65.271359)
			(xy 200.139993 -65.213466) (xy 200.13217 -65.154044) (xy 190.011959 -65.154044) (xy 190.012066 -65.15989)
			(xy 190.011557 -65.187776) (xy 190.003437 -65.242952) (xy 189.987369 -65.296359) (xy 189.963697 -65.346856)
			(xy 189.932924 -65.393369) (xy 189.895707 -65.434906) (xy 189.852839 -65.470581) (xy 189.805233 -65.499635)
			(xy 189.753904 -65.521447) (xy 189.699947 -65.535553) (xy 189.64451 -65.541653) (xy 189.588776 -65.539616)
			(xy 189.533933 -65.529486) (xy 189.481149 -65.511479) (xy 189.431549 -65.485978) (xy 189.386191 -65.453527)
			(xy 189.346042 -65.414818) (xy 189.311956 -65.370675) (xy 189.28466 -65.32204) (xy 189.264737 -65.269949)
			(xy 189.252611 -65.215512) (xy 189.24854 -65.15989) (xy 188.990989 -65.15989) (xy 188.987437 -65.184024)
			(xy 188.971369 -65.237431) (xy 188.947697 -65.287928) (xy 188.916924 -65.334441) (xy 188.879707 -65.375978)
			(xy 188.836839 -65.411653) (xy 188.789233 -65.440707) (xy 188.737904 -65.462519) (xy 188.683947 -65.476625)
			(xy 188.62851 -65.482725) (xy 188.572776 -65.480688) (xy 188.517933 -65.470558) (xy 188.465149 -65.452551)
			(xy 188.415549 -65.42705) (xy 188.370191 -65.394599) (xy 188.330042 -65.35589) (xy 188.295956 -65.311747)
			(xy 188.26866 -65.263112) (xy 188.248737 -65.211021) (xy 188.236611 -65.156584) (xy 188.23254 -65.100962)
			(xy 187.974989 -65.100962) (xy 187.979557 -65.132004) (xy 187.980066 -65.15989) (xy 187.979557 -65.187776)
			(xy 187.971437 -65.242952) (xy 187.955369 -65.296359) (xy 187.931697 -65.346856) (xy 187.900924 -65.393369)
			(xy 187.863707 -65.434906) (xy 187.820839 -65.470581) (xy 187.773233 -65.499635) (xy 187.721904 -65.521447)
			(xy 187.667947 -65.535553) (xy 187.61251 -65.541653) (xy 187.556776 -65.539616) (xy 187.501933 -65.529486)
			(xy 187.449149 -65.511479) (xy 187.399549 -65.485978) (xy 187.354191 -65.453527) (xy 187.314042 -65.414818)
			(xy 187.279956 -65.370675) (xy 187.25266 -65.32204) (xy 187.232737 -65.269949) (xy 187.220611 -65.215512)
			(xy 187.21654 -65.15989) (xy 164.012118 -65.15989) (xy 164.011609 -65.187776) (xy 164.003489 -65.242952)
			(xy 163.987421 -65.296359) (xy 163.963749 -65.346856) (xy 163.932976 -65.393369) (xy 163.895759 -65.434906)
			(xy 163.852891 -65.470581) (xy 163.805285 -65.499635) (xy 163.753956 -65.521447) (xy 163.699999 -65.535553)
			(xy 163.644562 -65.541653) (xy 163.588828 -65.539616) (xy 163.533985 -65.529486) (xy 163.481201 -65.511479)
			(xy 163.431601 -65.485978) (xy 163.386243 -65.453527) (xy 163.346094 -65.414818) (xy 163.312008 -65.370675)
			(xy 163.284712 -65.32204) (xy 163.264789 -65.269949) (xy 163.252663 -65.215512) (xy 163.248592 -65.15989)
			(xy 162.991041 -65.15989) (xy 162.987489 -65.184024) (xy 162.971421 -65.237431) (xy 162.947749 -65.287928)
			(xy 162.916976 -65.334441) (xy 162.879759 -65.375978) (xy 162.836891 -65.411653) (xy 162.789285 -65.440707)
			(xy 162.737956 -65.462519) (xy 162.683999 -65.476625) (xy 162.628562 -65.482725) (xy 162.572828 -65.480688)
			(xy 162.517985 -65.470558) (xy 162.465201 -65.452551) (xy 162.415601 -65.42705) (xy 162.370243 -65.394599)
			(xy 162.330094 -65.35589) (xy 162.296008 -65.311747) (xy 162.268712 -65.263112) (xy 162.248789 -65.211021)
			(xy 162.236663 -65.156584) (xy 162.232592 -65.100962) (xy 161.975041 -65.100962) (xy 161.979609 -65.132004)
			(xy 161.980118 -65.15989) (xy 161.979609 -65.187776) (xy 161.971489 -65.242952) (xy 161.955421 -65.296359)
			(xy 161.931749 -65.346856) (xy 161.900976 -65.393369) (xy 161.863759 -65.434906) (xy 161.820891 -65.470581)
			(xy 161.773285 -65.499635) (xy 161.721956 -65.521447) (xy 161.667999 -65.535553) (xy 161.612562 -65.541653)
			(xy 161.556828 -65.539616) (xy 161.501985 -65.529486) (xy 161.449201 -65.511479) (xy 161.399601 -65.485978)
			(xy 161.354243 -65.453527) (xy 161.314094 -65.414818) (xy 161.280008 -65.370675) (xy 161.252712 -65.32204)
			(xy 161.232789 -65.269949) (xy 161.220663 -65.215512) (xy 161.216592 -65.15989) (xy 149.04594 -65.15989)
			(xy 149.038887 -65.213466) (xy 149.023374 -65.271359) (xy 149.000438 -65.326732) (xy 148.970471 -65.378638)
			(xy 148.933984 -65.426188) (xy 148.891604 -65.468568) (xy 148.844054 -65.505055) (xy 148.792148 -65.535022)
			(xy 148.736775 -65.557958) (xy 148.678882 -65.573471) (xy 148.61946 -65.581294) (xy 148.559524 -65.581294)
			(xy 148.500102 -65.573471) (xy 148.442209 -65.557958) (xy 148.386836 -65.535022) (xy 148.33493 -65.505055)
			(xy 148.28738 -65.468568) (xy 148.245 -65.426188) (xy 148.208513 -65.378638) (xy 148.178546 -65.326732)
			(xy 148.15561 -65.271359) (xy 148.140097 -65.213466) (xy 148.132274 -65.154044) (xy 138.012063 -65.154044)
			(xy 138.01217 -65.15989) (xy 138.011661 -65.187776) (xy 138.003541 -65.242952) (xy 137.987473 -65.296359)
			(xy 137.963801 -65.346856) (xy 137.933028 -65.393369) (xy 137.895811 -65.434906) (xy 137.852943 -65.470581)
			(xy 137.805337 -65.499635) (xy 137.754008 -65.521447) (xy 137.700051 -65.535553) (xy 137.644614 -65.541653)
			(xy 137.58888 -65.539616) (xy 137.534037 -65.529486) (xy 137.481253 -65.511479) (xy 137.431653 -65.485978)
			(xy 137.386295 -65.453527) (xy 137.346146 -65.414818) (xy 137.31206 -65.370675) (xy 137.284764 -65.32204)
			(xy 137.264841 -65.269949) (xy 137.252715 -65.215512) (xy 137.248644 -65.15989) (xy 136.991093 -65.15989)
			(xy 136.987541 -65.184024) (xy 136.971473 -65.237431) (xy 136.947801 -65.287928) (xy 136.917028 -65.334441)
			(xy 136.879811 -65.375978) (xy 136.836943 -65.411653) (xy 136.789337 -65.440707) (xy 136.738008 -65.462519)
			(xy 136.684051 -65.476625) (xy 136.628614 -65.482725) (xy 136.57288 -65.480688) (xy 136.518037 -65.470558)
			(xy 136.465253 -65.452551) (xy 136.415653 -65.42705) (xy 136.370295 -65.394599) (xy 136.330146 -65.35589)
			(xy 136.29606 -65.311747) (xy 136.268764 -65.263112) (xy 136.248841 -65.211021) (xy 136.236715 -65.156584)
			(xy 136.232644 -65.100962) (xy 135.975093 -65.100962) (xy 135.979661 -65.132004) (xy 135.98017 -65.15989)
			(xy 135.979661 -65.187776) (xy 135.971541 -65.242952) (xy 135.955473 -65.296359) (xy 135.931801 -65.346856)
			(xy 135.901028 -65.393369) (xy 135.863811 -65.434906) (xy 135.820943 -65.470581) (xy 135.773337 -65.499635)
			(xy 135.722008 -65.521447) (xy 135.668051 -65.535553) (xy 135.612614 -65.541653) (xy 135.55688 -65.539616)
			(xy 135.502037 -65.529486) (xy 135.449253 -65.511479) (xy 135.399653 -65.485978) (xy 135.354295 -65.453527)
			(xy 135.314146 -65.414818) (xy 135.28006 -65.370675) (xy 135.252764 -65.32204) (xy 135.232841 -65.269949)
			(xy 135.220715 -65.215512) (xy 135.216644 -65.15989) (xy 123.045992 -65.15989) (xy 123.038939 -65.213466)
			(xy 123.023426 -65.271359) (xy 123.00049 -65.326732) (xy 122.970523 -65.378638) (xy 122.934036 -65.426188)
			(xy 122.891656 -65.468568) (xy 122.844106 -65.505055) (xy 122.7922 -65.535022) (xy 122.736827 -65.557958)
			(xy 122.678934 -65.573471) (xy 122.619512 -65.581294) (xy 122.559576 -65.581294) (xy 122.500154 -65.573471)
			(xy 122.442261 -65.557958) (xy 122.386888 -65.535022) (xy 122.334982 -65.505055) (xy 122.287432 -65.468568)
			(xy 122.245052 -65.426188) (xy 122.208565 -65.378638) (xy 122.178598 -65.326732) (xy 122.155662 -65.271359)
			(xy 122.140149 -65.213466) (xy 122.132326 -65.154044) (xy 99.911809 -65.154044) (xy 99.911916 -65.15989)
			(xy 99.911407 -65.187776) (xy 99.903287 -65.242952) (xy 99.887219 -65.296359) (xy 99.863547 -65.346856)
			(xy 99.832774 -65.393369) (xy 99.795557 -65.434906) (xy 99.752689 -65.470581) (xy 99.705083 -65.499635)
			(xy 99.653754 -65.521447) (xy 99.599797 -65.535553) (xy 99.54436 -65.541653) (xy 99.488626 -65.539616)
			(xy 99.433783 -65.529486) (xy 99.380999 -65.511479) (xy 99.331399 -65.485978) (xy 99.286041 -65.453527)
			(xy 99.245892 -65.414818) (xy 99.211806 -65.370675) (xy 99.18451 -65.32204) (xy 99.164587 -65.269949)
			(xy 99.152461 -65.215512) (xy 99.14839 -65.15989) (xy 98.890839 -65.15989) (xy 98.887287 -65.184024)
			(xy 98.871219 -65.237431) (xy 98.847547 -65.287928) (xy 98.816774 -65.334441) (xy 98.779557 -65.375978)
			(xy 98.736689 -65.411653) (xy 98.689083 -65.440707) (xy 98.637754 -65.462519) (xy 98.583797 -65.476625)
			(xy 98.52836 -65.482725) (xy 98.472626 -65.480688) (xy 98.417783 -65.470558) (xy 98.364999 -65.452551)
			(xy 98.315399 -65.42705) (xy 98.270041 -65.394599) (xy 98.229892 -65.35589) (xy 98.195806 -65.311747)
			(xy 98.16851 -65.263112) (xy 98.148587 -65.211021) (xy 98.136461 -65.156584) (xy 98.13239 -65.100962)
			(xy 97.874839 -65.100962) (xy 97.879407 -65.132004) (xy 97.879916 -65.15989) (xy 97.879407 -65.187776)
			(xy 97.871287 -65.242952) (xy 97.855219 -65.296359) (xy 97.831547 -65.346856) (xy 97.800774 -65.393369)
			(xy 97.763557 -65.434906) (xy 97.720689 -65.470581) (xy 97.673083 -65.499635) (xy 97.621754 -65.521447)
			(xy 97.567797 -65.535553) (xy 97.51236 -65.541653) (xy 97.456626 -65.539616) (xy 97.401783 -65.529486)
			(xy 97.348999 -65.511479) (xy 97.299399 -65.485978) (xy 97.254041 -65.453527) (xy 97.213892 -65.414818)
			(xy 97.179806 -65.370675) (xy 97.15251 -65.32204) (xy 97.132587 -65.269949) (xy 97.120461 -65.215512)
			(xy 97.11639 -65.15989) (xy 84.945738 -65.15989) (xy 84.938685 -65.213466) (xy 84.923172 -65.271359)
			(xy 84.900236 -65.326732) (xy 84.870269 -65.378638) (xy 84.833782 -65.426188) (xy 84.791402 -65.468568)
			(xy 84.743852 -65.505055) (xy 84.691946 -65.535022) (xy 84.636573 -65.557958) (xy 84.57868 -65.573471)
			(xy 84.519258 -65.581294) (xy 84.459322 -65.581294) (xy 84.3999 -65.573471) (xy 84.342007 -65.557958)
			(xy 84.286634 -65.535022) (xy 84.234728 -65.505055) (xy 84.187178 -65.468568) (xy 84.144798 -65.426188)
			(xy 84.108311 -65.378638) (xy 84.078344 -65.326732) (xy 84.055408 -65.271359) (xy 84.039895 -65.213466)
			(xy 84.032072 -65.154044) (xy 73.911861 -65.154044) (xy 73.911968 -65.15989) (xy 73.911459 -65.187776)
			(xy 73.903339 -65.242952) (xy 73.887271 -65.296359) (xy 73.863599 -65.346856) (xy 73.832826 -65.393369)
			(xy 73.795609 -65.434906) (xy 73.752741 -65.470581) (xy 73.705135 -65.499635) (xy 73.653806 -65.521447)
			(xy 73.599849 -65.535553) (xy 73.544412 -65.541653) (xy 73.488678 -65.539616) (xy 73.433835 -65.529486)
			(xy 73.381051 -65.511479) (xy 73.331451 -65.485978) (xy 73.286093 -65.453527) (xy 73.245944 -65.414818)
			(xy 73.211858 -65.370675) (xy 73.184562 -65.32204) (xy 73.164639 -65.269949) (xy 73.152513 -65.215512)
			(xy 73.148442 -65.15989) (xy 72.890891 -65.15989) (xy 72.887339 -65.184024) (xy 72.871271 -65.237431)
			(xy 72.847599 -65.287928) (xy 72.816826 -65.334441) (xy 72.779609 -65.375978) (xy 72.736741 -65.411653)
			(xy 72.689135 -65.440707) (xy 72.637806 -65.462519) (xy 72.583849 -65.476625) (xy 72.528412 -65.482725)
			(xy 72.472678 -65.480688) (xy 72.417835 -65.470558) (xy 72.365051 -65.452551) (xy 72.315451 -65.42705)
			(xy 72.270093 -65.394599) (xy 72.229944 -65.35589) (xy 72.195858 -65.311747) (xy 72.168562 -65.263112)
			(xy 72.148639 -65.211021) (xy 72.136513 -65.156584) (xy 72.132442 -65.100962) (xy 71.874891 -65.100962)
			(xy 71.879459 -65.132004) (xy 71.879968 -65.15989) (xy 71.879459 -65.187776) (xy 71.871339 -65.242952)
			(xy 71.855271 -65.296359) (xy 71.831599 -65.346856) (xy 71.800826 -65.393369) (xy 71.763609 -65.434906)
			(xy 71.720741 -65.470581) (xy 71.673135 -65.499635) (xy 71.621806 -65.521447) (xy 71.567849 -65.535553)
			(xy 71.512412 -65.541653) (xy 71.456678 -65.539616) (xy 71.401835 -65.529486) (xy 71.349051 -65.511479)
			(xy 71.299451 -65.485978) (xy 71.254093 -65.453527) (xy 71.213944 -65.414818) (xy 71.179858 -65.370675)
			(xy 71.152562 -65.32204) (xy 71.132639 -65.269949) (xy 71.120513 -65.215512) (xy 71.116442 -65.15989)
			(xy 47.91202 -65.15989) (xy 47.911511 -65.187776) (xy 47.903391 -65.242952) (xy 47.887323 -65.296359)
			(xy 47.863651 -65.346856) (xy 47.832878 -65.393369) (xy 47.795661 -65.434906) (xy 47.752793 -65.470581)
			(xy 47.705187 -65.499635) (xy 47.653858 -65.521447) (xy 47.599901 -65.535553) (xy 47.544464 -65.541653)
			(xy 47.48873 -65.539616) (xy 47.433887 -65.529486) (xy 47.381103 -65.511479) (xy 47.331503 -65.485978)
			(xy 47.286145 -65.453527) (xy 47.245996 -65.414818) (xy 47.21191 -65.370675) (xy 47.184614 -65.32204)
			(xy 47.164691 -65.269949) (xy 47.152565 -65.215512) (xy 47.148494 -65.15989) (xy 46.890943 -65.15989)
			(xy 46.887391 -65.184024) (xy 46.871323 -65.237431) (xy 46.847651 -65.287928) (xy 46.816878 -65.334441)
			(xy 46.779661 -65.375978) (xy 46.736793 -65.411653) (xy 46.689187 -65.440707) (xy 46.637858 -65.462519)
			(xy 46.583901 -65.476625) (xy 46.528464 -65.482725) (xy 46.47273 -65.480688) (xy 46.417887 -65.470558)
			(xy 46.365103 -65.452551) (xy 46.315503 -65.42705) (xy 46.270145 -65.394599) (xy 46.229996 -65.35589)
			(xy 46.19591 -65.311747) (xy 46.168614 -65.263112) (xy 46.148691 -65.211021) (xy 46.136565 -65.156584)
			(xy 46.132494 -65.100962) (xy 45.874943 -65.100962) (xy 45.879511 -65.132004) (xy 45.88002 -65.15989)
			(xy 45.879511 -65.187776) (xy 45.871391 -65.242952) (xy 45.855323 -65.296359) (xy 45.831651 -65.346856)
			(xy 45.800878 -65.393369) (xy 45.763661 -65.434906) (xy 45.720793 -65.470581) (xy 45.673187 -65.499635)
			(xy 45.621858 -65.521447) (xy 45.567901 -65.535553) (xy 45.512464 -65.541653) (xy 45.45673 -65.539616)
			(xy 45.401887 -65.529486) (xy 45.349103 -65.511479) (xy 45.299503 -65.485978) (xy 45.254145 -65.453527)
			(xy 45.213996 -65.414818) (xy 45.17991 -65.370675) (xy 45.152614 -65.32204) (xy 45.132691 -65.269949)
			(xy 45.120565 -65.215512) (xy 45.116494 -65.15989) (xy 32.945842 -65.15989) (xy 32.938789 -65.213466)
			(xy 32.923276 -65.271359) (xy 32.90034 -65.326732) (xy 32.870373 -65.378638) (xy 32.833886 -65.426188)
			(xy 32.791506 -65.468568) (xy 32.743956 -65.505055) (xy 32.69205 -65.535022) (xy 32.636677 -65.557958)
			(xy 32.578784 -65.573471) (xy 32.519362 -65.581294) (xy 32.459426 -65.581294) (xy 32.400004 -65.573471)
			(xy 32.342111 -65.557958) (xy 32.286738 -65.535022) (xy 32.234832 -65.505055) (xy 32.187282 -65.468568)
			(xy 32.144902 -65.426188) (xy 32.108415 -65.378638) (xy 32.078448 -65.326732) (xy 32.055512 -65.271359)
			(xy 32.039999 -65.213466) (xy 32.032176 -65.154044) (xy 21.911965 -65.154044) (xy 21.912072 -65.15989)
			(xy 21.911563 -65.187776) (xy 21.903443 -65.242952) (xy 21.887375 -65.296359) (xy 21.863703 -65.346856)
			(xy 21.83293 -65.393369) (xy 21.795713 -65.434906) (xy 21.752845 -65.470581) (xy 21.705239 -65.499635)
			(xy 21.65391 -65.521447) (xy 21.599953 -65.535553) (xy 21.544516 -65.541653) (xy 21.488782 -65.539616)
			(xy 21.433939 -65.529486) (xy 21.381155 -65.511479) (xy 21.331555 -65.485978) (xy 21.286197 -65.453527)
			(xy 21.246048 -65.414818) (xy 21.211962 -65.370675) (xy 21.184666 -65.32204) (xy 21.164743 -65.269949)
			(xy 21.152617 -65.215512) (xy 21.148546 -65.15989) (xy 20.890995 -65.15989) (xy 20.887443 -65.184024)
			(xy 20.871375 -65.237431) (xy 20.847703 -65.287928) (xy 20.81693 -65.334441) (xy 20.779713 -65.375978)
			(xy 20.736845 -65.411653) (xy 20.689239 -65.440707) (xy 20.63791 -65.462519) (xy 20.583953 -65.476625)
			(xy 20.528516 -65.482725) (xy 20.472782 -65.480688) (xy 20.417939 -65.470558) (xy 20.365155 -65.452551)
			(xy 20.315555 -65.42705) (xy 20.270197 -65.394599) (xy 20.230048 -65.35589) (xy 20.195962 -65.311747)
			(xy 20.168666 -65.263112) (xy 20.148743 -65.211021) (xy 20.136617 -65.156584) (xy 20.132546 -65.100962)
			(xy 19.874995 -65.100962) (xy 19.879563 -65.132004) (xy 19.880072 -65.15989) (xy 19.879563 -65.187776)
			(xy 19.871443 -65.242952) (xy 19.855375 -65.296359) (xy 19.831703 -65.346856) (xy 19.80093 -65.393369)
			(xy 19.763713 -65.434906) (xy 19.720845 -65.470581) (xy 19.673239 -65.499635) (xy 19.62191 -65.521447)
			(xy 19.567953 -65.535553) (xy 19.512516 -65.541653) (xy 19.456782 -65.539616) (xy 19.401939 -65.529486)
			(xy 19.349155 -65.511479) (xy 19.299555 -65.485978) (xy 19.254197 -65.453527) (xy 19.214048 -65.414818)
			(xy 19.179962 -65.370675) (xy 19.152666 -65.32204) (xy 19.132743 -65.269949) (xy 19.120617 -65.215512)
			(xy 19.116546 -65.15989) (xy 6.945931 -65.15989) (xy 6.938961 -65.213094) (xy 6.9237 -65.27044) (xy 6.912864 -65.298066)
			(xy 6.91007 -65.30721) (xy 6.907022 -65.321942) (xy 6.907216 -65.329046) (xy 6.91108 -65.342717)
			(xy 6.914642 -65.348866) (xy 6.926834 -65.367916) (xy 6.926834 -65.368424) (xy 6.93801 -65.386204)
			(xy 6.960108 -65.39865) (xy 6.965188 -65.398904) (xy 6.994652 -65.400174) (xy 6.99643 -65.400428)
			(xy 7.918958 -65.400428) (xy 7.952235 -65.400975) (xy 8.018219 -65.409666) (xy 8.082506 -65.426892)
			(xy 8.143995 -65.452358) (xy 8.201636 -65.485628) (xy 8.254444 -65.526135) (xy 8.278368 -65.549272)
			(xy 8.344916 -65.615566) (xy 8.526526 -65.797176) (xy 8.533882 -65.803823) (xy 8.552184 -65.811398)
			(xy 8.562086 -65.811908)
		)
		(stroke
			(width 0)
			(type solid)
		)
		(fill yes)
		(layer "B.Cu")
		(net "P5V_AUX")
	)
	(gr_line
		(start 23.943818 -267.391896)
		(end 23.943818 -267.39215)
		(stroke
			(width 0.05715)
			(type default)
		)
		(layer "B.Cu")
	)
	(gr_line
		(start 23.943818 -267.391896)
		(end 23.971758 -267.45946)
		(stroke
			(width 0.05715)
			(type default)
		)
		(layer "B.Cu")
	)
	(gr_line
		(start 23.971758 -267.45946)
		(end 23.971758 -267.532866)
		(stroke
			(width 0.05715)
			(type default)
		)
		(layer "B.Cu")
	)
	(gr_line
		(start 24.849074 -294.790114)
		(end 24.849074 -295.465754)
		(stroke
			(width 0.05715)
			(type default)
		)
		(layer "B.Cu")
	)
	(gr_line
		(start 24.849074 -293.713154)
		(end 24.849074 -294.388794)
		(stroke
			(width 0.05715)
			(type default)
		)
		(layer "B.Cu")
	)
	(gr_line
		(start 24.849074 -292.636194)
		(end 24.849074 -293.311834)
		(stroke
			(width 0.05715)
			(type default)
		)
		(layer "B.Cu")
	)
	(gr_line
		(start 24.849074 -291.559234)
		(end 24.849074 -292.234874)
		(stroke
			(width 0.05715)
			(type default)
		)
		(layer "B.Cu")
	)
	(gr_line
		(start 24.849074 -290.477194)
		(end 24.849074 -291.155374)
		(stroke
			(width 0.05715)
			(type default)
		)
		(layer "B.Cu")
	)
	(gr_line
		(start 24.849074 -289.395154)
		(end 24.849074 -290.073334)
		(stroke
			(width 0.05715)
			(type default)
		)
		(layer "B.Cu")
	)
	(gr_line
		(start 25.219914 -294.792654)
		(end 25.354534 -294.927274)
		(stroke
			(width 0.05715)
			(type default)
		)
		(layer "B.Cu")
	)
	(gr_line
		(start 25.219914 -293.715694)
		(end 25.354534 -293.850314)
		(stroke
			(width 0.05715)
			(type default)
		)
		(layer "B.Cu")
	)
	(gr_line
		(start 25.219914 -292.638734)
		(end 25.354534 -292.773354)
		(stroke
			(width 0.05715)
			(type default)
		)
		(layer "B.Cu")
	)
	(gr_line
		(start 25.219914 -291.561774)
		(end 25.354534 -291.696394)
		(stroke
			(width 0.05715)
			(type default)
		)
		(layer "B.Cu")
	)
	(gr_line
		(start 25.219914 -290.479734)
		(end 25.354534 -290.614354)
		(stroke
			(width 0.05715)
			(type default)
		)
		(layer "B.Cu")
	)
	(gr_line
		(start 25.219914 -289.397694)
		(end 25.354534 -289.532314)
		(stroke
			(width 0.05715)
			(type default)
		)
		(layer "B.Cu")
	)
	(gr_line
		(start 25.354534 -295.328594)
		(end 25.219914 -295.463214)
		(stroke
			(width 0.05715)
			(type default)
		)
		(layer "B.Cu")
	)
	(gr_line
		(start 25.354534 -294.927274)
		(end 25.354534 -295.328594)
		(stroke
			(width 0.05715)
			(type default)
		)
		(layer "B.Cu")
	)
	(gr_line
		(start 25.354534 -294.251634)
		(end 25.219914 -294.386254)
		(stroke
			(width 0.05715)
			(type default)
		)
		(layer "B.Cu")
	)
	(gr_line
		(start 25.354534 -293.850314)
		(end 25.354534 -294.251634)
		(stroke
			(width 0.05715)
			(type default)
		)
		(layer "B.Cu")
	)
	(gr_line
		(start 25.354534 -293.174674)
		(end 25.219914 -293.309294)
		(stroke
			(width 0.05715)
			(type default)
		)
		(layer "B.Cu")
	)
	(gr_line
		(start 25.354534 -292.773354)
		(end 25.354534 -293.174674)
		(stroke
			(width 0.05715)
			(type default)
		)
		(layer "B.Cu")
	)
	(gr_line
		(start 25.354534 -292.097714)
		(end 25.219914 -292.232334)
		(stroke
			(width 0.05715)
			(type default)
		)
		(layer "B.Cu")
	)
	(gr_line
		(start 25.354534 -291.696394)
		(end 25.354534 -292.097714)
		(stroke
			(width 0.05715)
			(type default)
		)
		(layer "B.Cu")
	)
	(gr_line
		(start 25.354534 -291.018214)
		(end 25.219914 -291.152834)
		(stroke
			(width 0.05715)
			(type default)
		)
		(layer "B.Cu")
	)
	(gr_line
		(start 25.354534 -290.614354)
		(end 25.354534 -291.018214)
		(stroke
			(width 0.05715)
			(type default)
		)
		(layer "B.Cu")
	)
	(gr_line
		(start 25.354534 -289.936174)
		(end 25.219914 -290.070794)
		(stroke
			(width 0.05715)
			(type default)
		)
		(layer "B.Cu")
	)
	(gr_line
		(start 25.354534 -289.532314)
		(end 25.354534 -289.936174)
		(stroke
			(width 0.05715)
			(type default)
		)
		(layer "B.Cu")
	)
	(gr_line
		(start 28.263342 -297.023536)
		(end 28.938982 -297.023536)
		(stroke
			(width 0.05715)
			(type default)
		)
		(layer "B.Cu")
	)
	(gr_line
		(start 28.265882 -296.652696)
		(end 28.400502 -296.518076)
		(stroke
			(width 0.05715)
			(type default)
		)
		(layer "B.Cu")
	)
	(gr_line
		(start 28.400502 -296.518076)
		(end 28.801822 -296.518076)
		(stroke
			(width 0.05715)
			(type default)
		)
		(layer "B.Cu")
	)
	(gr_line
		(start 28.801822 -296.518076)
		(end 28.936442 -296.652696)
		(stroke
			(width 0.05715)
			(type default)
		)
		(layer "B.Cu")
	)
	(gr_line
		(start 29.340302 -297.023536)
		(end 30.015942 -297.023536)
		(stroke
			(width 0.05715)
			(type default)
		)
		(layer "B.Cu")
	)
	(gr_line
		(start 29.342842 -296.652696)
		(end 29.477462 -296.518076)
		(stroke
			(width 0.05715)
			(type default)
		)
		(layer "B.Cu")
	)
	(gr_line
		(start 29.477462 -296.518076)
		(end 29.878782 -296.518076)
		(stroke
			(width 0.05715)
			(type default)
		)
		(layer "B.Cu")
	)
	(gr_line
		(start 29.878782 -296.518076)
		(end 30.013402 -296.652696)
		(stroke
			(width 0.05715)
			(type default)
		)
		(layer "B.Cu")
	)
	(gr_line
		(start 29.922216 -292.00983)
		(end 30.056836 -292.14445)
		(stroke
			(width 0.05715)
			(type default)
		)
		(layer "B.Cu")
	)
	(gr_line
		(start 29.922216 -290.92779)
		(end 30.056836 -291.06241)
		(stroke
			(width 0.05715)
			(type default)
		)
		(layer "B.Cu")
	)
	(gr_line
		(start 29.922216 -289.84575)
		(end 30.056836 -289.98037)
		(stroke
			(width 0.05715)
			(type default)
		)
		(layer "B.Cu")
	)
	(gr_line
		(start 29.922216 -288.76371)
		(end 30.056836 -288.89833)
		(stroke
			(width 0.05715)
			(type default)
		)
		(layer "B.Cu")
	)
	(gr_line
		(start 29.922216 -287.68167)
		(end 30.056836 -287.81629)
		(stroke
			(width 0.05715)
			(type default)
		)
		(layer "B.Cu")
	)
	(gr_line
		(start 29.922216 -286.59963)
		(end 30.056836 -286.73425)
		(stroke
			(width 0.05715)
			(type default)
		)
		(layer "B.Cu")
	)
	(gr_line
		(start 29.922216 -285.51759)
		(end 30.056836 -285.65221)
		(stroke
			(width 0.05715)
			(type default)
		)
		(layer "B.Cu")
	)
	(gr_line
		(start 30.056836 -292.54831)
		(end 29.922216 -292.68293)
		(stroke
			(width 0.05715)
			(type default)
		)
		(layer "B.Cu")
	)
	(gr_line
		(start 30.056836 -292.14445)
		(end 30.056836 -292.54831)
		(stroke
			(width 0.05715)
			(type default)
		)
		(layer "B.Cu")
	)
	(gr_line
		(start 30.056836 -291.46627)
		(end 29.922216 -291.60089)
		(stroke
			(width 0.05715)
			(type default)
		)
		(layer "B.Cu")
	)
	(gr_line
		(start 30.056836 -291.06241)
		(end 30.056836 -291.46627)
		(stroke
			(width 0.05715)
			(type default)
		)
		(layer "B.Cu")
	)
	(gr_line
		(start 30.056836 -290.38423)
		(end 29.922216 -290.51885)
		(stroke
			(width 0.05715)
			(type default)
		)
		(layer "B.Cu")
	)
	(gr_line
		(start 30.056836 -289.98037)
		(end 30.056836 -290.38423)
		(stroke
			(width 0.05715)
			(type default)
		)
		(layer "B.Cu")
	)
	(gr_line
		(start 30.056836 -289.30219)
		(end 29.922216 -289.43681)
		(stroke
			(width 0.05715)
			(type default)
		)
		(layer "B.Cu")
	)
	(gr_line
		(start 30.056836 -288.89833)
		(end 30.056836 -289.30219)
		(stroke
			(width 0.05715)
			(type default)
		)
		(layer "B.Cu")
	)
	(gr_line
		(start 30.056836 -288.22015)
		(end 29.922216 -288.35477)
		(stroke
			(width 0.05715)
			(type default)
		)
		(layer "B.Cu")
	)
	(gr_line
		(start 30.056836 -287.81629)
		(end 30.056836 -288.22015)
		(stroke
			(width 0.05715)
			(type default)
		)
		(layer "B.Cu")
	)
	(gr_line
		(start 30.056836 -287.13811)
		(end 29.922216 -287.27273)
		(stroke
			(width 0.05715)
			(type default)
		)
		(layer "B.Cu")
	)
	(gr_line
		(start 30.056836 -286.73425)
		(end 30.056836 -287.13811)
		(stroke
			(width 0.05715)
			(type default)
		)
		(layer "B.Cu")
	)
	(gr_line
		(start 30.056836 -286.05607)
		(end 29.922216 -286.19069)
		(stroke
			(width 0.05715)
			(type default)
		)
		(layer "B.Cu")
	)
	(gr_line
		(start 30.056836 -285.65221)
		(end 30.056836 -286.05607)
		(stroke
			(width 0.05715)
			(type default)
		)
		(layer "B.Cu")
	)
	(gr_line
		(start 35.258502 -296.56405)
		(end 35.2806 -296.56405)
		(stroke
			(width 0.04445)
			(type default)
		)
		(layer "B.Cu")
	)
	(gr_line
		(start 35.2806 -296.56405)
		(end 35.36315 -296.6466)
		(stroke
			(width 0.04445)
			(type default)
		)
		(layer "B.Cu")
	)
	(gr_line
		(start 35.334702 -299.98035)
		(end 35.3568 -299.98035)
		(stroke
			(width 0.04445)
			(type default)
		)
		(layer "B.Cu")
	)
	(gr_line
		(start 35.334702 -299.61205)
		(end 35.3568 -299.61205)
		(stroke
			(width 0.04445)
			(type default)
		)
		(layer "B.Cu")
	)
	(gr_line
		(start 35.3568 -299.98035)
		(end 35.43935 -299.8978)
		(stroke
			(width 0.04445)
			(type default)
		)
		(layer "B.Cu")
	)
	(gr_line
		(start 35.3568 -299.61205)
		(end 35.43935 -299.6946)
		(stroke
			(width 0.04445)
			(type default)
		)
		(layer "B.Cu")
	)
	(gr_line
		(start 36.665408 -299.224954)
		(end 36.374578 -299.224954)
		(stroke
			(width 0.04445)
			(type default)
		)
		(layer "B.Cu")
	)
	(gr_line
		(start 36.741608 -299.313854)
		(end 36.741608 -299.301154)
		(stroke
			(width 0.04445)
			(type default)
		)
		(layer "B.Cu")
	)
	(gr_line
		(start 36.741608 -299.301154)
		(end 36.665408 -299.224954)
		(stroke
			(width 0.04445)
			(type default)
		)
		(layer "B.Cu")
	)
	(gr_line
		(start 36.947348 -299.311314)
		(end 37.033708 -299.224954)
		(stroke
			(width 0.04445)
			(type default)
		)
		(layer "B.Cu")
	)
	(gr_line
		(start 36.947348 -297.23842)
		(end 37.033708 -297.32478)
		(stroke
			(width 0.04445)
			(type default)
		)
		(layer "B.Cu")
	)
	(gr_line
		(start 37.033708 -299.224954)
		(end 37.324538 -299.224954)
		(stroke
			(width 0.04445)
			(type default)
		)
		(layer "B.Cu")
	)
	(gr_line
		(start 37.033708 -297.32478)
		(end 37.324538 -297.32478)
		(stroke
			(width 0.04445)
			(type default)
		)
		(layer "B.Cu")
	)
	(gr_line
		(start 55.237126 -366.108488)
		(end 54.89575 -365.767112)
		(stroke
			(width 0.06731)
			(type default)
		)
		(layer "B.Cu")
	)
	(gr_line
		(start 55.251096 -366.122458)
		(end 55.238396 -366.109758)
		(stroke
			(width 0.06731)
			(type default)
		)
		(layer "B.Cu")
	)
	(gr_line
		(start 55.512716 -366.109758)
		(end 55.512716 -366.014)
		(stroke
			(width 0.06731)
			(type default)
		)
		(layer "B.Cu")
	)
	(gr_line
		(start 55.512716 -366.014)
		(end 55.75935 -365.767112)
		(stroke
			(width 0.06731)
			(type default)
		)
		(layer "B.Cu")
	)
	(gr_line
		(start 55.525416 -366.122458)
		(end 55.512716 -366.109758)
		(stroke
			(width 0.06731)
			(type default)
		)
		(layer "B.Cu")
	)
	(gr_line
		(start 97.316798 -334.530192)
		(end 97.479358 -334.692752)
		(stroke
			(width 0.05715)
			(type default)
		)
		(layer "B.Cu")
	)
	(gr_line
		(start 97.479358 -335.073752)
		(end 97.316798 -335.236312)
		(stroke
			(width 0.05715)
			(type default)
		)
		(layer "B.Cu")
	)
	(gr_line
		(start 97.479358 -334.692752)
		(end 97.479358 -335.073752)
		(stroke
			(width 0.05715)
			(type default)
		)
		(layer "B.Cu")
	)
	(gr_line
		(start 98.638614 -333.7687)
		(end 98.620326 -333.7687)
		(stroke
			(width 0.05715)
			(type default)
		)
		(layer "B.Cu")
	)
	(gr_line
		(start 98.95332 -334.083406)
		(end 98.638614 -333.7687)
		(stroke
			(width 0.05715)
			(type default)
		)
		(layer "B.Cu")
	)
	(gr_line
		(start 99.375722 -338.309966)
		(end 99.566222 -338.309966)
		(stroke
			(width 0.05715)
			(type default)
		)
		(layer "B.Cu")
	)
	(gr_line
		(start 99.566222 -338.309966)
		(end 99.851972 -338.59597)
		(stroke
			(width 0.05715)
			(type default)
		)
		(layer "B.Cu")
	)
	(gr_line
		(start 99.851972 -338.59597)
		(end 99.851972 -338.786216)
		(stroke
			(width 0.05715)
			(type default)
		)
		(layer "B.Cu")
	)
	(gr_line
		(start 100.078286 -333.75854)
		(end 99.75342 -334.083406)
		(stroke
			(width 0.05715)
			(type default)
		)
		(layer "B.Cu")
	)
	(gr_line
		(start 100.141024 -339.075268)
		(end 100.331524 -339.075268)
		(stroke
			(width 0.05715)
			(type default)
		)
		(layer "B.Cu")
	)
	(gr_line
		(start 100.331524 -339.075268)
		(end 100.617274 -339.361272)
		(stroke
			(width 0.05715)
			(type default)
		)
		(layer "B.Cu")
	)
	(gr_line
		(start 100.617274 -339.361272)
		(end 100.617274 -339.551518)
		(stroke
			(width 0.05715)
			(type default)
		)
		(layer "B.Cu")
	)
	(gr_line
		(start 100.906326 -339.84057)
		(end 101.096826 -339.84057)
		(stroke
			(width 0.05715)
			(type default)
		)
		(layer "B.Cu")
	)
	(gr_line
		(start 101.096826 -339.84057)
		(end 101.382576 -340.126574)
		(stroke
			(width 0.05715)
			(type default)
		)
		(layer "B.Cu")
	)
	(gr_line
		(start 101.382576 -340.126574)
		(end 101.382576 -340.31682)
		(stroke
			(width 0.05715)
			(type default)
		)
		(layer "B.Cu")
	)
	(gr_line
		(start 102.106222 -340.603332)
		(end 102.281482 -340.428072)
		(stroke
			(width 0.05715)
			(type default)
		)
		(layer "B.Cu")
	)
	(gr_line
		(start 102.281482 -340.428072)
		(end 102.662482 -340.428072)
		(stroke
			(width 0.05715)
			(type default)
		)
		(layer "B.Cu")
	)
	(gr_line
		(start 102.662482 -340.428072)
		(end 102.837742 -340.603332)
		(stroke
			(width 0.05715)
			(type default)
		)
		(layer "B.Cu")
	)
	(gr_line
		(start 103.223822 -340.603332)
		(end 103.399082 -340.428072)
		(stroke
			(width 0.05715)
			(type default)
		)
		(layer "B.Cu")
	)
	(gr_line
		(start 103.399082 -340.428072)
		(end 103.780082 -340.428072)
		(stroke
			(width 0.05715)
			(type default)
		)
		(layer "B.Cu")
	)
	(gr_line
		(start 103.718106 -332.800452)
		(end 103.66121 -332.743556)
		(stroke
			(width 0.05715)
			(type default)
		)
		(layer "B.Cu")
	)
	(gr_line
		(start 103.780082 -340.428072)
		(end 103.955342 -340.603332)
		(stroke
			(width 0.05715)
			(type default)
		)
		(layer "B.Cu")
	)
	(gr_line
		(start 103.939594 -332.800452)
		(end 103.718106 -332.800452)
		(stroke
			(width 0.05715)
			(type default)
		)
		(layer "B.Cu")
	)
	(gr_line
		(start 104.341422 -340.603332)
		(end 104.516682 -340.428072)
		(stroke
			(width 0.05715)
			(type default)
		)
		(layer "B.Cu")
	)
	(gr_line
		(start 104.516682 -340.428072)
		(end 104.897682 -340.428072)
		(stroke
			(width 0.05715)
			(type default)
		)
		(layer "B.Cu")
	)
	(gr_line
		(start 104.897682 -340.428072)
		(end 105.072942 -340.603332)
		(stroke
			(width 0.05715)
			(type default)
		)
		(layer "B.Cu")
	)
	(gr_line
		(start 105.093262 -385.289044)
		(end 105.381552 -385.000754)
		(stroke
			(width 0.06731)
			(type default)
		)
		(layer "B.Cu")
	)
	(gr_line
		(start 105.381552 -385.000754)
		(end 105.381552 -384.988054)
		(stroke
			(width 0.06731)
			(type default)
		)
		(layer "B.Cu")
	)
	(gr_line
		(start 105.459022 -340.603332)
		(end 105.634282 -340.428072)
		(stroke
			(width 0.05715)
			(type default)
		)
		(layer "B.Cu")
	)
	(gr_line
		(start 105.634282 -340.428072)
		(end 106.015282 -340.428072)
		(stroke
			(width 0.05715)
			(type default)
		)
		(layer "B.Cu")
	)
	(gr_line
		(start 105.956862 -385.289044)
		(end 105.657142 -384.989324)
		(stroke
			(width 0.06731)
			(type default)
		)
		(layer "B.Cu")
	)
	(gr_line
		(start 106.015282 -340.428072)
		(end 106.190542 -340.603332)
		(stroke
			(width 0.05715)
			(type default)
		)
		(layer "B.Cu")
	)
	(gr_line
		(start 108.908342 -332.30058)
		(end 108.689394 -332.30058)
		(stroke
			(width 0.06731)
			(type default)
		)
		(layer "B.Cu")
	)
	(gr_line
		(start 109.013752 -332.19517)
		(end 108.908342 -332.30058)
		(stroke
			(width 0.06731)
			(type default)
		)
		(layer "B.Cu")
	)
	(gr_line
		(start 109.027722 -332.1812)
		(end 109.015022 -332.1939)
		(stroke
			(width 0.06731)
			(type default)
		)
		(layer "B.Cu")
	)
	(gr_line
		(start 112.747044 -331.2414)
		(end 112.739424 -331.2414)
		(stroke
			(width 0.06731)
			(type default)
		)
		(layer "B.Cu")
	)
	(gr_line
		(start 113.114074 -331.60843)
		(end 112.747044 -331.2414)
		(stroke
			(width 0.06731)
			(type default)
		)
		(layer "B.Cu")
	)
	(gr_line
		(start 114.281204 -331.2414)
		(end 113.914174 -331.60843)
		(stroke
			(width 0.06731)
			(type default)
		)
		(layer "B.Cu")
	)
	(gr_line
		(start 114.288824 -331.2414)
		(end 114.281204 -331.2414)
		(stroke
			(width 0.06731)
			(type default)
		)
		(layer "B.Cu")
	)
	(gr_line
		(start 114.669824 -340.31682)
		(end 114.669824 -340.126574)
		(stroke
			(width 0.05715)
			(type default)
		)
		(layer "B.Cu")
	)
	(gr_line
		(start 114.669824 -340.126574)
		(end 114.955574 -339.84057)
		(stroke
			(width 0.05715)
			(type default)
		)
		(layer "B.Cu")
	)
	(gr_line
		(start 114.955574 -339.84057)
		(end 115.146074 -339.84057)
		(stroke
			(width 0.05715)
			(type default)
		)
		(layer "B.Cu")
	)
	(gr_line
		(start 115.12296 -331.2414)
		(end 115.11534 -331.2414)
		(stroke
			(width 0.06731)
			(type default)
		)
		(layer "B.Cu")
	)
	(gr_line
		(start 115.41379 -331.53223)
		(end 115.12296 -331.2414)
		(stroke
			(width 0.06731)
			(type default)
		)
		(layer "B.Cu")
	)
	(gr_line
		(start 127.437642 -197.095618)
		(end 127.437134 -197.095872)
		(stroke
			(width 0.05715)
			(type default)
		)
		(layer "B.Cu")
	)
	(gr_line
		(start 127.458724 -197.095618)
		(end 127.437642 -197.095618)
		(stroke
			(width 0.05715)
			(type default)
		)
		(layer "B.Cu")
	)
	(gr_line
		(start 127.47371 -197.080632)
		(end 127.458724 -197.095618)
		(stroke
			(width 0.05715)
			(type default)
		)
		(layer "B.Cu")
	)
	(gr_line
		(start 127.504952 -197.067678)
		(end 127.47371 -197.080632)
		(stroke
			(width 0.05715)
			(type default)
		)
		(layer "B.Cu")
	)
	(gr_line
		(start 127.556768 -197.015862)
		(end 127.504952 -197.067678)
		(stroke
			(width 0.05715)
			(type default)
		)
		(layer "B.Cu")
	)
	(gr_line
		(start 127.998474 -195.940934)
		(end 127.998474 -195.946522)
		(stroke
			(width 0.05715)
			(type default)
		)
		(layer "B.Cu")
	)
	(gr_line
		(start 128.24333 -195.696078)
		(end 127.998474 -195.940934)
		(stroke
			(width 0.05715)
			(type default)
		)
		(layer "B.Cu")
	)
	(gr_line
		(start 143.807688 -278.224488)
		(end 144.285716 -278.702516)
		(stroke
			(width 0.05715)
			(type default)
		)
		(layer "B.Cu")
	)
	(gr_line
		(start 144.071848 -277.964138)
		(end 144.262348 -277.964138)
		(stroke
			(width 0.05715)
			(type default)
		)
		(layer "B.Cu")
	)
	(gr_line
		(start 144.262348 -277.964138)
		(end 144.54632 -278.248364)
		(stroke
			(width 0.05715)
			(type default)
		)
		(layer "B.Cu")
	)
	(gr_line
		(start 144.54632 -278.248364)
		(end 144.54632 -278.43861)
		(stroke
			(width 0.05715)
			(type default)
		)
		(layer "B.Cu")
	)
	(gr_line
		(start 144.569688 -278.986488)
		(end 145.047716 -279.464516)
		(stroke
			(width 0.05715)
			(type default)
		)
		(layer "B.Cu")
	)
	(gr_line
		(start 144.833594 -278.725884)
		(end 145.024094 -278.725884)
		(stroke
			(width 0.05715)
			(type default)
		)
		(layer "B.Cu")
	)
	(gr_line
		(start 145.024094 -278.725884)
		(end 145.308066 -279.01011)
		(stroke
			(width 0.05715)
			(type default)
		)
		(layer "B.Cu")
	)
	(gr_line
		(start 145.223484 -294.824912)
		(end 145.223484 -295.500552)
		(stroke
			(width 0.05715)
			(type default)
		)
		(layer "B.Cu")
	)
	(gr_line
		(start 145.308066 -279.01011)
		(end 145.308066 -279.200356)
		(stroke
			(width 0.05715)
			(type default)
		)
		(layer "B.Cu")
	)
	(gr_line
		(start 145.594324 -294.827452)
		(end 145.728944 -294.962072)
		(stroke
			(width 0.05715)
			(type default)
		)
		(layer "B.Cu")
	)
	(gr_line
		(start 145.728944 -295.363392)
		(end 145.594324 -295.498012)
		(stroke
			(width 0.05715)
			(type default)
		)
		(layer "B.Cu")
	)
	(gr_line
		(start 145.728944 -294.962072)
		(end 145.728944 -295.363392)
		(stroke
			(width 0.05715)
			(type default)
		)
		(layer "B.Cu")
	)
	(gr_line
		(start 145.860516 -296.691558)
		(end 146.338798 -297.16984)
		(stroke
			(width 0.05715)
			(type default)
		)
		(layer "B.Cu")
	)
	(gr_line
		(start 146.124676 -296.431208)
		(end 146.315176 -296.431208)
		(stroke
			(width 0.05715)
			(type default)
		)
		(layer "B.Cu")
	)
	(gr_line
		(start 146.315176 -296.431208)
		(end 146.599148 -296.715434)
		(stroke
			(width 0.05715)
			(type default)
		)
		(layer "B.Cu")
	)
	(gr_line
		(start 146.574256 -290.52647)
		(end 146.574256 -291.20465)
		(stroke
			(width 0.05715)
			(type default)
		)
		(layer "B.Cu")
	)
	(gr_line
		(start 146.599148 -296.715434)
		(end 146.599148 -296.90568)
		(stroke
			(width 0.05715)
			(type default)
		)
		(layer "B.Cu")
	)
	(gr_line
		(start 146.622516 -297.453304)
		(end 147.100544 -297.931332)
		(stroke
			(width 0.05715)
			(type default)
		)
		(layer "B.Cu")
	)
	(gr_line
		(start 146.886422 -297.192954)
		(end 147.076922 -297.192954)
		(stroke
			(width 0.05715)
			(type default)
		)
		(layer "B.Cu")
	)
	(gr_line
		(start 146.945096 -290.52901)
		(end 147.079716 -290.66363)
		(stroke
			(width 0.05715)
			(type default)
		)
		(layer "B.Cu")
	)
	(gr_line
		(start 147.076922 -297.192954)
		(end 147.360894 -297.47718)
		(stroke
			(width 0.05715)
			(type default)
		)
		(layer "B.Cu")
	)
	(gr_line
		(start 147.079716 -291.06749)
		(end 146.945096 -291.20211)
		(stroke
			(width 0.05715)
			(type default)
		)
		(layer "B.Cu")
	)
	(gr_line
		(start 147.079716 -290.66363)
		(end 147.079716 -291.06749)
		(stroke
			(width 0.05715)
			(type default)
		)
		(layer "B.Cu")
	)
	(gr_line
		(start 147.360894 -297.47718)
		(end 147.360894 -297.667426)
		(stroke
			(width 0.05715)
			(type default)
		)
		(layer "B.Cu")
	)
	(gr_line
		(start 148.282914 -298.323)
		(end 148.958554 -298.323)
		(stroke
			(width 0.05715)
			(type default)
		)
		(layer "B.Cu")
	)
	(gr_line
		(start 148.285454 -297.95216)
		(end 148.420074 -297.81754)
		(stroke
			(width 0.05715)
			(type default)
		)
		(layer "B.Cu")
	)
	(gr_line
		(start 148.420074 -297.81754)
		(end 148.821394 -297.81754)
		(stroke
			(width 0.05715)
			(type default)
		)
		(layer "B.Cu")
	)
	(gr_line
		(start 148.821394 -297.81754)
		(end 148.956014 -297.95216)
		(stroke
			(width 0.05715)
			(type default)
		)
		(layer "B.Cu")
	)
	(gr_line
		(start 149.91334 -299.02912)
		(end 150.391368 -299.507148)
		(stroke
			(width 0.05715)
			(type default)
		)
		(layer "B.Cu")
	)
	(gr_line
		(start 150.1775 -298.76877)
		(end 150.368 -298.76877)
		(stroke
			(width 0.05715)
			(type default)
		)
		(layer "B.Cu")
	)
	(gr_line
		(start 150.368 -298.76877)
		(end 150.651972 -299.052996)
		(stroke
			(width 0.05715)
			(type default)
		)
		(layer "B.Cu")
	)
	(gr_line
		(start 150.651972 -299.052996)
		(end 150.651972 -299.243242)
		(stroke
			(width 0.05715)
			(type default)
		)
		(layer "B.Cu")
	)
	(gr_line
		(start 151.23922 -299.898816)
		(end 151.261318 -299.898816)
		(stroke
			(width 0.04445)
			(type default)
		)
		(layer "B.Cu")
	)
	(gr_line
		(start 151.23922 -299.530516)
		(end 151.261318 -299.530516)
		(stroke
			(width 0.04445)
			(type default)
		)
		(layer "B.Cu")
	)
	(gr_line
		(start 151.261318 -299.898816)
		(end 151.343868 -299.816266)
		(stroke
			(width 0.04445)
			(type default)
		)
		(layer "B.Cu")
	)
	(gr_line
		(start 151.261318 -299.530516)
		(end 151.343868 -299.613066)
		(stroke
			(width 0.04445)
			(type default)
		)
		(layer "B.Cu")
	)
	(gr_line
		(start 151.895302 -296.70375)
		(end 151.9174 -296.70375)
		(stroke
			(width 0.04445)
			(type default)
		)
		(layer "B.Cu")
	)
	(gr_line
		(start 151.895302 -296.33545)
		(end 151.9174 -296.33545)
		(stroke
			(width 0.04445)
			(type default)
		)
		(layer "B.Cu")
	)
	(gr_line
		(start 151.9174 -296.70375)
		(end 151.99995 -296.6212)
		(stroke
			(width 0.04445)
			(type default)
		)
		(layer "B.Cu")
	)
	(gr_line
		(start 151.9174 -296.33545)
		(end 151.99995 -296.418)
		(stroke
			(width 0.04445)
			(type default)
		)
		(layer "B.Cu")
	)
	(gr_line
		(start 152.759156 -299.224954)
		(end 152.474676 -299.224954)
		(stroke
			(width 0.04445)
			(type default)
		)
		(layer "B.Cu")
	)
	(gr_line
		(start 152.765506 -297.32478)
		(end 152.474676 -297.32478)
		(stroke
			(width 0.04445)
			(type default)
		)
		(layer "B.Cu")
	)
	(gr_line
		(start 152.848056 -299.313854)
		(end 152.759156 -299.224954)
		(stroke
			(width 0.04445)
			(type default)
		)
		(layer "B.Cu")
	)
	(gr_line
		(start 152.851866 -297.23842)
		(end 152.765506 -297.32478)
		(stroke
			(width 0.04445)
			(type default)
		)
		(layer "B.Cu")
	)
	(gr_line
		(start 153.051256 -299.313854)
		(end 153.140156 -299.224954)
		(stroke
			(width 0.04445)
			(type default)
		)
		(layer "B.Cu")
	)
	(gr_line
		(start 153.057606 -297.24858)
		(end 153.133806 -297.32478)
		(stroke
			(width 0.04445)
			(type default)
		)
		(layer "B.Cu")
	)
	(gr_line
		(start 153.057606 -297.23588)
		(end 153.057606 -297.24858)
		(stroke
			(width 0.04445)
			(type default)
		)
		(layer "B.Cu")
	)
	(gr_line
		(start 153.133806 -297.32478)
		(end 153.424636 -297.32478)
		(stroke
			(width 0.04445)
			(type default)
		)
		(layer "B.Cu")
	)
	(gr_line
		(start 153.140156 -299.224954)
		(end 153.424636 -299.224954)
		(stroke
			(width 0.04445)
			(type default)
		)
		(layer "B.Cu")
	)
	(gr_line
		(start 153.856182 -239.048798)
		(end 154.107642 -239.300258)
		(stroke
			(width 0.05715)
			(type default)
		)
		(layer "B.Cu")
	)
	(gr_line
		(start 154.478482 -239.290098)
		(end 154.478482 -239.302798)
		(stroke
			(width 0.05715)
			(type default)
		)
		(layer "B.Cu")
	)
	(gr_line
		(start 154.719782 -239.048798)
		(end 154.478482 -239.290098)
		(stroke
			(width 0.05715)
			(type default)
		)
		(layer "B.Cu")
	)
	(gr_line
		(start 226.894136 -60.131706)
		(end 227.183442 -59.8424)
		(stroke
			(width 0.06731)
			(type default)
		)
		(layer "B.Cu")
	)
	(gr_line
		(start 226.894136 -59.268106)
		(end 227.19284 -59.56681)
		(stroke
			(width 0.06731)
			(type default)
		)
		(layer "B.Cu")
	)
	(gr_line
		(start 227.183442 -59.8424)
		(end 227.19411 -59.8424)
		(stroke
			(width 0.06731)
			(type default)
		)
		(layer "B.Cu")
	)
	(gr_line
		(start 228.771704 -157.870144)
		(end 229.018846 -158.117286)
		(stroke
			(width 0.05715)
			(type default)
		)
		(layer "B.Cu")
	)
	(gr_line
		(start 228.945948 -72.49033)
		(end 229.081838 -72.62622)
		(stroke
			(width 0.06731)
			(type default)
		)
		(layer "B.Cu")
	)
	(gr_line
		(start 228.945948 -72.08647)
		(end 228.945948 -72.49033)
		(stroke
			(width 0.06731)
			(type default)
		)
		(layer "B.Cu")
	)
	(gr_line
		(start 228.945948 -71.40829)
		(end 229.081838 -71.54418)
		(stroke
			(width 0.06731)
			(type default)
		)
		(layer "B.Cu")
	)
	(gr_line
		(start 228.945948 -71.00443)
		(end 228.945948 -71.40829)
		(stroke
			(width 0.06731)
			(type default)
		)
		(layer "B.Cu")
	)
	(gr_line
		(start 228.945948 -70.32625)
		(end 229.081838 -70.46214)
		(stroke
			(width 0.06731)
			(type default)
		)
		(layer "B.Cu")
	)
	(gr_line
		(start 228.945948 -69.92239)
		(end 228.945948 -70.32625)
		(stroke
			(width 0.06731)
			(type default)
		)
		(layer "B.Cu")
	)
	(gr_line
		(start 229.081838 -71.95058)
		(end 228.945948 -72.08647)
		(stroke
			(width 0.06731)
			(type default)
		)
		(layer "B.Cu")
	)
	(gr_line
		(start 229.081838 -70.86854)
		(end 228.945948 -71.00443)
		(stroke
			(width 0.06731)
			(type default)
		)
		(layer "B.Cu")
	)
	(gr_line
		(start 229.081838 -69.7865)
		(end 228.945948 -69.92239)
		(stroke
			(width 0.06731)
			(type default)
		)
		(layer "B.Cu")
	)
	(gr_line
		(start 229.357428 -71.94931)
		(end 229.357428 -72.62749)
		(stroke
			(width 0.06731)
			(type default)
		)
		(layer "B.Cu")
	)
	(gr_line
		(start 229.357428 -70.86727)
		(end 229.357428 -71.54545)
		(stroke
			(width 0.06731)
			(type default)
		)
		(layer "B.Cu")
	)
	(gr_line
		(start 229.357428 -69.78523)
		(end 229.357428 -70.46341)
		(stroke
			(width 0.06731)
			(type default)
		)
		(layer "B.Cu")
	)
	(gr_line
		(start 229.388162 -158.117286)
		(end 229.388162 -158.118302)
		(stroke
			(width 0.05715)
			(type default)
		)
		(layer "B.Cu")
	)
	(gr_line
		(start 229.635304 -157.870144)
		(end 229.388162 -158.117286)
		(stroke
			(width 0.05715)
			(type default)
		)
		(layer "B.Cu")
	)
	(gr_line
		(start 230.393494 -76.500228)
		(end 230.098092 -76.796138)
		(stroke
			(width 0.06731)
			(type default)
		)
		(layer "B.Cu")
	)
	(gr_line
		(start 230.669084 -76.50353)
		(end 230.961692 -76.796138)
		(stroke
			(width 0.06731)
			(type default)
		)
		(layer "B.Cu")
	)
	(gr_line
		(start 230.669084 -76.498958)
		(end 230.669084 -76.50353)
		(stroke
			(width 0.06731)
			(type default)
		)
		(layer "B.Cu")
	)
	(gr_line
		(start 231.015032 -157.890464)
		(end 231.256332 -158.131764)
		(stroke
			(width 0.05715)
			(type default)
		)
		(layer "B.Cu")
	)
	(gr_line
		(start 231.056942 -159.712914)
		(end 230.866442 -159.712914)
		(stroke
			(width 0.05715)
			(type default)
		)
		(layer "B.Cu")
	)
	(gr_line
		(start 231.080564 -158.974536)
		(end 230.602282 -159.452564)
		(stroke
			(width 0.05715)
			(type default)
		)
		(layer "B.Cu")
	)
	(gr_line
		(start 231.256332 -158.131764)
		(end 231.256332 -158.144464)
		(stroke
			(width 0.05715)
			(type default)
		)
		(layer "B.Cu")
	)
	(gr_line
		(start 231.340914 -159.428688)
		(end 231.056942 -159.712914)
		(stroke
			(width 0.05715)
			(type default)
		)
		(layer "B.Cu")
	)
	(gr_line
		(start 231.340914 -159.238442)
		(end 231.340914 -159.428688)
		(stroke
			(width 0.05715)
			(type default)
		)
		(layer "B.Cu")
	)
	(gr_line
		(start 231.878632 -157.890464)
		(end 231.627172 -158.141924)
		(stroke
			(width 0.05715)
			(type default)
		)
		(layer "B.Cu")
	)
	(gr_line
		(start 232.722166 -85.428582)
		(end 233.010456 -85.716872)
		(stroke
			(width 0.06731)
			(type default)
		)
		(layer "B.Cu")
	)
	(gr_line
		(start 233.010456 -85.716872)
		(end 233.010456 -85.729572)
		(stroke
			(width 0.06731)
			(type default)
		)
		(layer "B.Cu")
	)
	(gr_line
		(start 233.585766 -85.428582)
		(end 233.286046 -85.728302)
		(stroke
			(width 0.06731)
			(type default)
		)
		(layer "B.Cu")
	)
	(gr_line
		(start 234.60964 -336.653886)
		(end 234.8611 -336.402426)
		(stroke
			(width 0.05715)
			(type default)
		)
		(layer "B.Cu")
	)
	(gr_line
		(start 237.16615 -149.691344)
		(end 237.40745 -149.450044)
		(stroke
			(width 0.05715)
			(type default)
		)
		(layer "B.Cu")
	)
	(gr_line
		(start 237.16615 -148.827744)
		(end 237.41761 -149.079204)
		(stroke
			(width 0.05715)
			(type default)
		)
		(layer "B.Cu")
	)
	(gr_line
		(start 237.40745 -149.450044)
		(end 237.42015 -149.450044)
		(stroke
			(width 0.05715)
			(type default)
		)
		(layer "B.Cu")
	)
	(gr_line
		(start 238.28629 -79.608426)
		(end 237.998 -79.320136)
		(stroke
			(width 0.06731)
			(type default)
		)
		(layer "B.Cu")
	)
	(gr_line
		(start 238.29772 -79.884016)
		(end 237.998 -80.183736)
		(stroke
			(width 0.06731)
			(type default)
		)
		(layer "B.Cu")
	)
	(gr_line
		(start 238.29899 -79.608426)
		(end 238.28629 -79.608426)
		(stroke
			(width 0.06731)
			(type default)
		)
		(layer "B.Cu")
	)
	(gr_line
		(start 257.977386 -173.495716)
		(end 258.228846 -173.244256)
		(stroke
			(width 0.05715)
			(type default)
		)
		(layer "B.Cu")
	)
	(gr_line
		(start 261.727442 -176.202086)
		(end 261.943088 -176.417732)
		(stroke
			(width 0.05715)
			(type default)
		)
		(layer "B.Cu")
	)
	(gr_line
		(start 261.727442 -175.953928)
		(end 261.727442 -176.202086)
		(stroke
			(width 0.05715)
			(type default)
		)
		(layer "B.Cu")
	)
	(gr_line
		(start 261.943088 -176.417732)
		(end 262.191246 -176.417732)
		(stroke
			(width 0.05715)
			(type default)
		)
		(layer "B.Cu")
	)
	(gr_line
		(start 377.4186 -294.818562)
		(end 377.4186 -295.494202)
		(stroke
			(width 0.05715)
			(type default)
		)
		(layer "B.Cu")
	)
	(gr_line
		(start 377.78944 -294.821102)
		(end 377.92406 -294.955722)
		(stroke
			(width 0.05715)
			(type default)
		)
		(layer "B.Cu")
	)
	(gr_line
		(start 377.92406 -295.357042)
		(end 377.78944 -295.491662)
		(stroke
			(width 0.05715)
			(type default)
		)
		(layer "B.Cu")
	)
	(gr_line
		(start 377.92406 -294.955722)
		(end 377.92406 -295.357042)
		(stroke
			(width 0.05715)
			(type default)
		)
		(layer "B.Cu")
	)
	(gr_line
		(start 378.049536 -296.679112)
		(end 378.527564 -297.15714)
		(stroke
			(width 0.05715)
			(type default)
		)
		(layer "B.Cu")
	)
	(gr_line
		(start 378.313442 -296.418508)
		(end 378.503942 -296.418508)
		(stroke
			(width 0.05715)
			(type default)
		)
		(layer "B.Cu")
	)
	(gr_line
		(start 378.503942 -296.418508)
		(end 378.787914 -296.702734)
		(stroke
			(width 0.05715)
			(type default)
		)
		(layer "B.Cu")
	)
	(gr_line
		(start 378.787914 -296.702734)
		(end 378.787914 -296.89298)
		(stroke
			(width 0.05715)
			(type default)
		)
		(layer "B.Cu")
	)
	(gr_line
		(start 378.811028 -297.440858)
		(end 379.289056 -297.918886)
		(stroke
			(width 0.05715)
			(type default)
		)
		(layer "B.Cu")
	)
	(gr_line
		(start 379.075188 -297.180254)
		(end 379.265688 -297.180254)
		(stroke
			(width 0.05715)
			(type default)
		)
		(layer "B.Cu")
	)
	(gr_line
		(start 379.265688 -297.180254)
		(end 379.54966 -297.46448)
		(stroke
			(width 0.05715)
			(type default)
		)
		(layer "B.Cu")
	)
	(gr_line
		(start 379.54966 -297.46448)
		(end 379.54966 -297.654726)
		(stroke
			(width 0.05715)
			(type default)
		)
		(layer "B.Cu")
	)
	(gr_line
		(start 383.670302 -299.89526)
		(end 383.6924 -299.89526)
		(stroke
			(width 0.04445)
			(type default)
		)
		(layer "B.Cu")
	)
	(gr_line
		(start 383.670302 -299.52696)
		(end 383.6924 -299.52696)
		(stroke
			(width 0.04445)
			(type default)
		)
		(layer "B.Cu")
	)
	(gr_line
		(start 383.6924 -299.89526)
		(end 383.77495 -299.81271)
		(stroke
			(width 0.04445)
			(type default)
		)
		(layer "B.Cu")
	)
	(gr_line
		(start 383.6924 -299.52696)
		(end 383.77495 -299.60951)
		(stroke
			(width 0.04445)
			(type default)
		)
		(layer "B.Cu")
	)
	(gr_line
		(start 383.695702 -297.03395)
		(end 383.7178 -297.03395)
		(stroke
			(width 0.04445)
			(type default)
		)
		(layer "B.Cu")
	)
	(gr_line
		(start 383.7178 -297.03395)
		(end 383.80035 -296.9514)
		(stroke
			(width 0.04445)
			(type default)
		)
		(layer "B.Cu")
	)
	(gr_line
		(start 383.973578 -230.573834)
		(end 383.673858 -230.873554)
		(stroke
			(width 0.06731)
			(type default)
		)
		(layer "B.Cu")
	)
	(gr_line
		(start 384.249168 -230.585264)
		(end 384.537458 -230.873554)
		(stroke
			(width 0.06731)
			(type default)
		)
		(layer "B.Cu")
	)
	(gr_line
		(start 384.249168 -230.572564)
		(end 384.249168 -230.585264)
		(stroke
			(width 0.06731)
			(type default)
		)
		(layer "B.Cu")
	)
	(gr_line
		(start 384.965448 -299.224954)
		(end 384.674618 -299.224954)
		(stroke
			(width 0.04445)
			(type default)
		)
		(layer "B.Cu")
	)
	(gr_line
		(start 384.965448 -297.32478)
		(end 384.674618 -297.32478)
		(stroke
			(width 0.04445)
			(type default)
		)
		(layer "B.Cu")
	)
	(gr_line
		(start 385.051808 -299.311314)
		(end 384.965448 -299.224954)
		(stroke
			(width 0.04445)
			(type default)
		)
		(layer "B.Cu")
	)
	(gr_line
		(start 385.051808 -297.23842)
		(end 384.965448 -297.32478)
		(stroke
			(width 0.04445)
			(type default)
		)
		(layer "B.Cu")
	)
	(gr_line
		(start 385.257548 -299.313854)
		(end 385.257548 -299.301154)
		(stroke
			(width 0.04445)
			(type default)
		)
		(layer "B.Cu")
	)
	(gr_line
		(start 385.257548 -299.301154)
		(end 385.333748 -299.224954)
		(stroke
			(width 0.04445)
			(type default)
		)
		(layer "B.Cu")
	)
	(gr_line
		(start 385.333748 -299.224954)
		(end 385.624578 -299.224954)
		(stroke
			(width 0.04445)
			(type default)
		)
		(layer "B.Cu")
	)
	(gr_line
		(start 446.6082 -232.79989)
		(end 446.6082 -232.12171)
		(stroke
			(width 0.06731)
			(type default)
		)
		(layer "B.Cu")
	)
	(gr_line
		(start 446.6082 -231.71785)
		(end 446.6082 -231.03967)
		(stroke
			(width 0.06731)
			(type default)
		)
		(layer "B.Cu")
	)
	(gr_line
		(start 446.6082 -230.63581)
		(end 446.6082 -229.95763)
		(stroke
			(width 0.06731)
			(type default)
		)
		(layer "B.Cu")
	)
	(gr_line
		(start 446.88379 -232.79862)
		(end 447.01968 -232.66273)
		(stroke
			(width 0.06731)
			(type default)
		)
		(layer "B.Cu")
	)
	(gr_line
		(start 446.88379 -231.71658)
		(end 447.01968 -231.58069)
		(stroke
			(width 0.06731)
			(type default)
		)
		(layer "B.Cu")
	)
	(gr_line
		(start 446.88379 -230.63454)
		(end 447.01968 -230.49865)
		(stroke
			(width 0.06731)
			(type default)
		)
		(layer "B.Cu")
	)
	(gr_line
		(start 447.01968 -232.66273)
		(end 447.01968 -232.25887)
		(stroke
			(width 0.06731)
			(type default)
		)
		(layer "B.Cu")
	)
	(gr_line
		(start 447.01968 -232.25887)
		(end 446.88379 -232.12298)
		(stroke
			(width 0.06731)
			(type default)
		)
		(layer "B.Cu")
	)
	(gr_line
		(start 447.01968 -231.58069)
		(end 447.01968 -231.17683)
		(stroke
			(width 0.06731)
			(type default)
		)
		(layer "B.Cu")
	)
	(gr_line
		(start 447.01968 -231.17683)
		(end 446.88379 -231.04094)
		(stroke
			(width 0.06731)
			(type default)
		)
		(layer "B.Cu")
	)
	(gr_line
		(start 447.01968 -230.49865)
		(end 447.01968 -230.09479)
		(stroke
			(width 0.06731)
			(type default)
		)
		(layer "B.Cu")
	)
	(gr_line
		(start 447.01968 -230.09479)
		(end 446.88379 -229.9589)
		(stroke
			(width 0.06731)
			(type default)
		)
		(layer "B.Cu")
	)
	(gr_line
		(start 448.478656 -234.625896)
		(end 448.77228 -234.91952)
		(stroke
			(width 0.06731)
			(type default)
		)
		(layer "B.Cu")
	)
	(gr_line
		(start 448.77228 -234.91952)
		(end 448.77228 -234.921552)
		(stroke
			(width 0.06731)
			(type default)
		)
		(layer "B.Cu")
	)
	(gr_line
		(start 449.342256 -234.625896)
		(end 449.04787 -234.920282)
		(stroke
			(width 0.06731)
			(type default)
		)
		(layer "B.Cu")
	)
	(gr_poly
		(pts
			(arc
				(start 265.615928 -377.679966)
				(mid 265.635451 -377.676065)
				(end 265.651996 -377.66498)
			)
			(arc
				(start 265.851386 -377.46559)
				(mid 265.862497 -377.449056)
				(end 265.866372 -377.429522)
			)
			(arc
				(start 265.866372 -368.884962)
				(mid 265.862471 -368.865439)
				(end 265.851386 -368.848894)
			)
			(arc
				(start 265.514582 -368.51209)
				(mid 265.498048 -368.500979)
				(end 265.478514 -368.497104)
			)
			(arc
				(start 242.901216 -368.497104)
				(mid 242.881693 -368.501005)
				(end 242.865148 -368.51209)
			)
			(arc
				(start 242.760754 -368.616484)
				(mid 242.749643 -368.633018)
				(end 242.745768 -368.652552)
			)
			(arc
				(start 242.745768 -377.268994)
				(mid 242.749669 -377.288517)
				(end 242.760754 -377.305062)
			)
			(arc
				(start 243.120672 -377.66498)
				(mid 243.137206 -377.676091)
				(end 243.15674 -377.679966)
			)
		)
		(stroke
			(width 0)
			(type solid)
		)
		(fill yes)
		(layer "In1.Cu")
		(net "P12V_STBY_R2")
	)
	(gr_poly
		(pts
			(arc
				(start 37.053012 -316.799722)
				(mid 36.646612 -316.799722)
				(end 37.053012 -316.799722)
			)
		)
		(stroke
			(width 0)
			(type solid)
		)
		(fill yes)
		(layer "In1.Cu")
		(net "P5E_PEX0_STN7_RX_DN<122>")
	)
	(gr_poly
		(pts
			(arc
				(start 37.053012 -314.899802)
				(mid 36.646612 -314.899802)
				(end 37.053012 -314.899802)
			)
		)
		(stroke
			(width 0)
			(type solid)
		)
		(fill yes)
		(layer "In1.Cu")
		(net "P5E_PEX0_STN7_TX_DN<122>")
	)
	(gr_poly
		(pts
			(arc
				(start 37.053012 -312.049922)
				(mid 36.646612 -312.049922)
				(end 37.053012 -312.049922)
			)
		)
		(stroke
			(width 0)
			(type solid)
		)
		(fill yes)
		(layer "In1.Cu")
		(net "P5E_PEX0_STN7_TX_DN<121>")
	)
	(gr_poly
		(pts
			(arc
				(start 37.053012 -310.149748)
				(mid 36.646612 -310.149748)
				(end 37.053012 -310.149748)
			)
		)
		(stroke
			(width 0)
			(type solid)
		)
		(fill yes)
		(layer "In1.Cu")
		(net "P5E_PEX0_STN7_RX_DN<121>")
	)
	(gr_poly
		(pts
			(arc
				(start 37.053012 -308.249828)
				(mid 36.646612 -308.249828)
				(end 37.053012 -308.249828)
			)
		)
		(stroke
			(width 0)
			(type solid)
		)
		(fill yes)
		(layer "In1.Cu")
		(net "P5E_PEX0_STN7_RX_DN<119>")
	)
	(gr_poly
		(pts
			(arc
				(start 37.053012 -306.349908)
				(mid 36.646612 -306.349908)
				(end 37.053012 -306.349908)
			)
		)
		(stroke
			(width 0)
			(type solid)
		)
		(fill yes)
		(layer "In1.Cu")
		(net "P5E_PEX0_STN7_RX_DN<117>")
	)
	(gr_poly
		(pts
			(arc
				(start 37.053012 -304.449734)
				(mid 36.646612 -304.449734)
				(end 37.053012 -304.449734)
			)
		)
		(stroke
			(width 0)
			(type solid)
		)
		(fill yes)
		(layer "In1.Cu")
		(net "P5E_PEX0_STN7_RX_DN<115>")
	)
	(gr_poly
		(pts
			(arc
				(start 37.053012 -302.549814)
				(mid 36.646612 -302.549814)
				(end 37.053012 -302.549814)
			)
		)
		(stroke
			(width 0)
			(type solid)
		)
		(fill yes)
		(layer "In1.Cu")
		(net "P5E_PEX0_STN7_RX_DN<113>")
	)
	(gr_poly
		(pts
			(arc
				(start 38.002972 -316.799722)
				(mid 37.596572 -316.799722)
				(end 38.002972 -316.799722)
			)
		)
		(stroke
			(width 0)
			(type solid)
		)
		(fill yes)
		(layer "In1.Cu")
		(net "P5E_PEX0_STN7_RX_DP<122>")
	)
	(gr_poly
		(pts
			(arc
				(start 38.002972 -314.899802)
				(mid 37.596572 -314.899802)
				(end 38.002972 -314.899802)
			)
		)
		(stroke
			(width 0)
			(type solid)
		)
		(fill yes)
		(layer "In1.Cu")
		(net "P5E_PEX0_STN7_TX_DP<122>")
	)
	(gr_poly
		(pts
			(arc
				(start 38.002972 -312.049922)
				(mid 37.596572 -312.049922)
				(end 38.002972 -312.049922)
			)
		)
		(stroke
			(width 0)
			(type solid)
		)
		(fill yes)
		(layer "In1.Cu")
		(net "P5E_PEX0_STN7_TX_DP<121>")
	)
	(gr_poly
		(pts
			(arc
				(start 38.002972 -310.149748)
				(mid 37.596572 -310.149748)
				(end 38.002972 -310.149748)
			)
		)
		(stroke
			(width 0)
			(type solid)
		)
		(fill yes)
		(layer "In1.Cu")
		(net "P5E_PEX0_STN7_RX_DP<121>")
	)
	(gr_poly
		(pts
			(arc
				(start 38.002972 -308.249828)
				(mid 37.596572 -308.249828)
				(end 38.002972 -308.249828)
			)
		)
		(stroke
			(width 0)
			(type solid)
		)
		(fill yes)
		(layer "In1.Cu")
		(net "P5E_PEX0_STN7_RX_DP<119>")
	)
	(gr_poly
		(pts
			(arc
				(start 38.002972 -306.349908)
				(mid 37.596572 -306.349908)
				(end 38.002972 -306.349908)
			)
		)
		(stroke
			(width 0)
			(type solid)
		)
		(fill yes)
		(layer "In1.Cu")
		(net "P5E_PEX0_STN7_RX_DP<117>")
	)
	(gr_poly
		(pts
			(arc
				(start 38.002972 -304.449734)
				(mid 37.596572 -304.449734)
				(end 38.002972 -304.449734)
			)
		)
		(stroke
			(width 0)
			(type solid)
		)
		(fill yes)
		(layer "In1.Cu")
		(net "P5E_PEX0_STN7_RX_DP<115>")
	)
	(gr_poly
		(pts
			(arc
				(start 38.002972 -302.549814)
				(mid 37.596572 -302.549814)
				(end 38.002972 -302.549814)
			)
		)
		(stroke
			(width 0)
			(type solid)
		)
		(fill yes)
		(layer "In1.Cu")
		(net "P5E_PEX0_STN7_RX_DP<113>")
	)
	(gr_poly
		(pts
			(arc
				(start 38.953186 -318.699896)
				(mid 38.546786 -318.699896)
				(end 38.953186 -318.699896)
			)
		)
		(stroke
			(width 0)
			(type solid)
		)
		(fill yes)
		(layer "In1.Cu")
		(net "P5E_PEX0_STN7_RX_DN<123>")
	)
	(gr_poly
		(pts
			(arc
				(start 38.953186 -317.749936)
				(mid 38.546786 -317.749936)
				(end 38.953186 -317.749936)
			)
		)
		(stroke
			(width 0)
			(type solid)
		)
		(fill yes)
		(layer "In1.Cu")
		(net "P5E_PEX0_STN7_RX_DP<123>")
	)
	(gr_poly
		(pts
			(arc
				(start 38.953186 -313.949842)
				(mid 38.546786 -313.949842)
				(end 38.953186 -313.949842)
			)
		)
		(stroke
			(width 0)
			(type solid)
		)
		(fill yes)
		(layer "In1.Cu")
		(net "P5E_PEX0_STN7_TX_DN<123>")
	)
	(gr_poly
		(pts
			(arc
				(start 38.953186 -312.999882)
				(mid 38.546786 -312.999882)
				(end 38.953186 -312.999882)
			)
		)
		(stroke
			(width 0)
			(type solid)
		)
		(fill yes)
		(layer "In1.Cu")
		(net "P5E_PEX0_STN7_TX_DP<123>")
	)
	(gr_poly
		(pts
			(arc
				(start 38.953186 -309.199788)
				(mid 38.546786 -309.199788)
				(end 38.953186 -309.199788)
			)
		)
		(stroke
			(width 0)
			(type solid)
		)
		(fill yes)
		(layer "In1.Cu")
		(net "P5E_PEX0_STN7_RX_DN<120>")
	)
	(gr_poly
		(pts
			(arc
				(start 38.953186 -307.299868)
				(mid 38.546786 -307.299868)
				(end 38.953186 -307.299868)
			)
		)
		(stroke
			(width 0)
			(type solid)
		)
		(fill yes)
		(layer "In1.Cu")
		(net "P5E_PEX0_STN7_RX_DN<118>")
	)
	(gr_poly
		(pts
			(arc
				(start 38.953186 -305.399948)
				(mid 38.546786 -305.399948)
				(end 38.953186 -305.399948)
			)
		)
		(stroke
			(width 0)
			(type solid)
		)
		(fill yes)
		(layer "In1.Cu")
		(net "P5E_PEX0_STN7_RX_DN<116>")
	)
	(gr_poly
		(pts
			(arc
				(start 38.953186 -303.499774)
				(mid 38.546786 -303.499774)
				(end 38.953186 -303.499774)
			)
		)
		(stroke
			(width 0)
			(type solid)
		)
		(fill yes)
		(layer "In1.Cu")
		(net "P5E_PEX0_STN7_RX_DN<114>")
	)
	(gr_poly
		(pts
			(arc
				(start 38.953186 -301.599854)
				(mid 38.546786 -301.599854)
				(end 38.953186 -301.599854)
			)
		)
		(stroke
			(width 0)
			(type solid)
		)
		(fill yes)
		(layer "In1.Cu")
		(net "P5E_PEX0_STN7_RX_DN<112>")
	)
	(gr_poly
		(pts
			(arc
				(start 39.903146 -316.799722)
				(mid 39.496746 -316.799722)
				(end 39.903146 -316.799722)
			)
		)
		(stroke
			(width 0)
			(type solid)
		)
		(fill yes)
		(layer "In1.Cu")
		(net "P5E_PEX0_STN7_RX_DN<124>")
	)
	(gr_poly
		(pts
			(arc
				(start 39.903146 -315.849762)
				(mid 39.496746 -315.849762)
				(end 39.903146 -315.849762)
			)
		)
		(stroke
			(width 0)
			(type solid)
		)
		(fill yes)
		(layer "In1.Cu")
		(net "P5E_PEX0_STN7_RX_DP<124>")
	)
	(gr_poly
		(pts
			(arc
				(start 39.903146 -312.049922)
				(mid 39.496746 -312.049922)
				(end 39.903146 -312.049922)
			)
		)
		(stroke
			(width 0)
			(type solid)
		)
		(fill yes)
		(layer "In1.Cu")
		(net "P5E_PEX0_STN7_TX_DN<124>")
	)
	(gr_poly
		(pts
			(arc
				(start 39.903146 -311.099962)
				(mid 39.496746 -311.099962)
				(end 39.903146 -311.099962)
			)
		)
		(stroke
			(width 0)
			(type solid)
		)
		(fill yes)
		(layer "In1.Cu")
		(net "P5E_PEX0_STN7_TX_DP<124>")
	)
	(gr_poly
		(pts
			(arc
				(start 39.903146 -309.199788)
				(mid 39.496746 -309.199788)
				(end 39.903146 -309.199788)
			)
		)
		(stroke
			(width 0)
			(type solid)
		)
		(fill yes)
		(layer "In1.Cu")
		(net "P5E_PEX0_STN7_RX_DP<120>")
	)
	(gr_poly
		(pts
			(arc
				(start 39.903146 -307.299868)
				(mid 39.496746 -307.299868)
				(end 39.903146 -307.299868)
			)
		)
		(stroke
			(width 0)
			(type solid)
		)
		(fill yes)
		(layer "In1.Cu")
		(net "P5E_PEX0_STN7_RX_DP<118>")
	)
	(gr_poly
		(pts
			(arc
				(start 39.903146 -305.399948)
				(mid 39.496746 -305.399948)
				(end 39.903146 -305.399948)
			)
		)
		(stroke
			(width 0)
			(type solid)
		)
		(fill yes)
		(layer "In1.Cu")
		(net "P5E_PEX0_STN7_RX_DP<116>")
	)
	(gr_poly
		(pts
			(arc
				(start 39.903146 -303.499774)
				(mid 39.496746 -303.499774)
				(end 39.903146 -303.499774)
			)
		)
		(stroke
			(width 0)
			(type solid)
		)
		(fill yes)
		(layer "In1.Cu")
		(net "P5E_PEX0_STN7_RX_DP<114>")
	)
	(gr_poly
		(pts
			(arc
				(start 39.903146 -301.599854)
				(mid 39.496746 -301.599854)
				(end 39.903146 -301.599854)
			)
		)
		(stroke
			(width 0)
			(type solid)
		)
		(fill yes)
		(layer "In1.Cu")
		(net "P5E_PEX0_STN7_RX_DP<112>")
	)
	(gr_poly
		(pts
			(arc
				(start 40.853106 -318.699896)
				(mid 40.446706 -318.699896)
				(end 40.853106 -318.699896)
			)
		)
		(stroke
			(width 0)
			(type solid)
		)
		(fill yes)
		(layer "In1.Cu")
		(net "P5E_PEX0_STN7_RX_DN<125>")
	)
	(gr_poly
		(pts
			(arc
				(start 40.853106 -317.749936)
				(mid 40.446706 -317.749936)
				(end 40.853106 -317.749936)
			)
		)
		(stroke
			(width 0)
			(type solid)
		)
		(fill yes)
		(layer "In1.Cu")
		(net "P5E_PEX0_STN7_RX_DP<125>")
	)
	(gr_poly
		(pts
			(arc
				(start 40.853106 -313.949842)
				(mid 40.446706 -313.949842)
				(end 40.853106 -313.949842)
			)
		)
		(stroke
			(width 0)
			(type solid)
		)
		(fill yes)
		(layer "In1.Cu")
		(net "P5E_PEX0_STN7_TX_DN<125>")
	)
	(gr_poly
		(pts
			(arc
				(start 40.853106 -312.999882)
				(mid 40.446706 -312.999882)
				(end 40.853106 -312.999882)
			)
		)
		(stroke
			(width 0)
			(type solid)
		)
		(fill yes)
		(layer "In1.Cu")
		(net "P5E_PEX0_STN7_TX_DP<125>")
	)
	(gr_poly
		(pts
			(arc
				(start 41.803066 -316.799722)
				(mid 41.396666 -316.799722)
				(end 41.803066 -316.799722)
			)
		)
		(stroke
			(width 0)
			(type solid)
		)
		(fill yes)
		(layer "In1.Cu")
		(net "P5E_PEX0_STN7_RX_DN<126>")
	)
	(gr_poly
		(pts
			(arc
				(start 41.803066 -315.849762)
				(mid 41.396666 -315.849762)
				(end 41.803066 -315.849762)
			)
		)
		(stroke
			(width 0)
			(type solid)
		)
		(fill yes)
		(layer "In1.Cu")
		(net "P5E_PEX0_STN7_RX_DP<126>")
	)
	(gr_poly
		(pts
			(arc
				(start 41.803066 -312.049922)
				(mid 41.396666 -312.049922)
				(end 41.803066 -312.049922)
			)
		)
		(stroke
			(width 0)
			(type solid)
		)
		(fill yes)
		(layer "In1.Cu")
		(net "P5E_PEX0_STN7_TX_DN<126>")
	)
	(gr_poly
		(pts
			(arc
				(start 41.803066 -311.099962)
				(mid 41.396666 -311.099962)
				(end 41.803066 -311.099962)
			)
		)
		(stroke
			(width 0)
			(type solid)
		)
		(fill yes)
		(layer "In1.Cu")
		(net "P5E_PEX0_STN7_TX_DP<126>")
	)
	(gr_poly
		(pts
			(arc
				(start 41.803066 -309.199788)
				(mid 41.396666 -309.199788)
				(end 41.803066 -309.199788)
			)
		)
		(stroke
			(width 0)
			(type solid)
		)
		(fill yes)
		(layer "In1.Cu")
		(net "P5E_PEX0_STN7_TX_DN<120>")
	)
	(gr_poly
		(pts
			(arc
				(start 41.803066 -307.299868)
				(mid 41.396666 -307.299868)
				(end 41.803066 -307.299868)
			)
		)
		(stroke
			(width 0)
			(type solid)
		)
		(fill yes)
		(layer "In1.Cu")
		(net "P5E_PEX0_STN7_TX_DN<118>")
	)
	(gr_poly
		(pts
			(arc
				(start 41.803066 -305.399948)
				(mid 41.396666 -305.399948)
				(end 41.803066 -305.399948)
			)
		)
		(stroke
			(width 0)
			(type solid)
		)
		(fill yes)
		(layer "In1.Cu")
		(net "P5E_PEX0_STN7_TX_DN<116>")
	)
	(gr_poly
		(pts
			(arc
				(start 41.803066 -303.499774)
				(mid 41.396666 -303.499774)
				(end 41.803066 -303.499774)
			)
		)
		(stroke
			(width 0)
			(type solid)
		)
		(fill yes)
		(layer "In1.Cu")
		(net "P5E_PEX0_STN7_TX_DN<114>")
	)
	(gr_poly
		(pts
			(arc
				(start 41.803066 -301.599854)
				(mid 41.396666 -301.599854)
				(end 41.803066 -301.599854)
			)
		)
		(stroke
			(width 0)
			(type solid)
		)
		(fill yes)
		(layer "In1.Cu")
		(net "P5E_PEX0_STN7_TX_DN<112>")
	)
	(gr_poly
		(pts
			(arc
				(start 42.753026 -318.699896)
				(mid 42.346626 -318.699896)
				(end 42.753026 -318.699896)
			)
		)
		(stroke
			(width 0)
			(type solid)
		)
		(fill yes)
		(layer "In1.Cu")
		(net "P5E_PEX0_STN7_RX_DN<127>")
	)
	(gr_poly
		(pts
			(arc
				(start 42.753026 -317.749936)
				(mid 42.346626 -317.749936)
				(end 42.753026 -317.749936)
			)
		)
		(stroke
			(width 0)
			(type solid)
		)
		(fill yes)
		(layer "In1.Cu")
		(net "P5E_PEX0_STN7_RX_DP<127>")
	)
	(gr_poly
		(pts
			(arc
				(start 42.753026 -313.949842)
				(mid 42.346626 -313.949842)
				(end 42.753026 -313.949842)
			)
		)
		(stroke
			(width 0)
			(type solid)
		)
		(fill yes)
		(layer "In1.Cu")
		(net "P5E_PEX0_STN7_TX_DN<127>")
	)
	(gr_poly
		(pts
			(arc
				(start 42.753026 -312.999882)
				(mid 42.346626 -312.999882)
				(end 42.753026 -312.999882)
			)
		)
		(stroke
			(width 0)
			(type solid)
		)
		(fill yes)
		(layer "In1.Cu")
		(net "P5E_PEX0_STN7_TX_DP<127>")
	)
	(gr_poly
		(pts
			(arc
				(start 42.753026 -309.199788)
				(mid 42.346626 -309.199788)
				(end 42.753026 -309.199788)
			)
		)
		(stroke
			(width 0)
			(type solid)
		)
		(fill yes)
		(layer "In1.Cu")
		(net "P5E_PEX0_STN7_TX_DP<120>")
	)
	(gr_poly
		(pts
			(arc
				(start 42.753026 -307.299868)
				(mid 42.346626 -307.299868)
				(end 42.753026 -307.299868)
			)
		)
		(stroke
			(width 0)
			(type solid)
		)
		(fill yes)
		(layer "In1.Cu")
		(net "P5E_PEX0_STN7_TX_DP<118>")
	)
	(gr_poly
		(pts
			(arc
				(start 42.753026 -305.399948)
				(mid 42.346626 -305.399948)
				(end 42.753026 -305.399948)
			)
		)
		(stroke
			(width 0)
			(type solid)
		)
		(fill yes)
		(layer "In1.Cu")
		(net "P5E_PEX0_STN7_TX_DP<116>")
	)
	(gr_poly
		(pts
			(arc
				(start 42.753026 -303.499774)
				(mid 42.346626 -303.499774)
				(end 42.753026 -303.499774)
			)
		)
		(stroke
			(width 0)
			(type solid)
		)
		(fill yes)
		(layer "In1.Cu")
		(net "P5E_PEX0_STN7_TX_DP<114>")
	)
	(gr_poly
		(pts
			(arc
				(start 42.753026 -301.599854)
				(mid 42.346626 -301.599854)
				(end 42.753026 -301.599854)
			)
		)
		(stroke
			(width 0)
			(type solid)
		)
		(fill yes)
		(layer "In1.Cu")
		(net "P5E_PEX0_STN7_TX_DP<112>")
	)
	(gr_poly
		(pts
			(arc
				(start 43.702986 -316.799722)
				(mid 43.296586 -316.799722)
				(end 43.702986 -316.799722)
			)
		)
		(stroke
			(width 0)
			(type solid)
		)
		(fill yes)
		(layer "In1.Cu")
		(net "P5E_PEX0_STN6_RX_DN<111>")
	)
	(gr_poly
		(pts
			(arc
				(start 43.702986 -315.849762)
				(mid 43.296586 -315.849762)
				(end 43.702986 -315.849762)
			)
		)
		(stroke
			(width 0)
			(type solid)
		)
		(fill yes)
		(layer "In1.Cu")
		(net "P5E_PEX0_STN6_RX_DP<111>")
	)
	(gr_poly
		(pts
			(arc
				(start 43.702986 -312.049922)
				(mid 43.296586 -312.049922)
				(end 43.702986 -312.049922)
			)
		)
		(stroke
			(width 0)
			(type solid)
		)
		(fill yes)
		(layer "In1.Cu")
		(net "P5E_PEX0_STN6_TX_DN<111>")
	)
	(gr_poly
		(pts
			(arc
				(start 43.702986 -311.099962)
				(mid 43.296586 -311.099962)
				(end 43.702986 -311.099962)
			)
		)
		(stroke
			(width 0)
			(type solid)
		)
		(fill yes)
		(layer "In1.Cu")
		(net "P5E_PEX0_STN6_TX_DP<111>")
	)
	(gr_poly
		(pts
			(arc
				(start 43.702986 -308.249828)
				(mid 43.296586 -308.249828)
				(end 43.702986 -308.249828)
			)
		)
		(stroke
			(width 0)
			(type solid)
		)
		(fill yes)
		(layer "In1.Cu")
		(net "P5E_PEX0_STN7_TX_DN<119>")
	)
	(gr_poly
		(pts
			(arc
				(start 43.702986 -306.349908)
				(mid 43.296586 -306.349908)
				(end 43.702986 -306.349908)
			)
		)
		(stroke
			(width 0)
			(type solid)
		)
		(fill yes)
		(layer "In1.Cu")
		(net "P5E_PEX0_STN7_TX_DN<117>")
	)
	(gr_poly
		(pts
			(arc
				(start 43.702986 -304.449734)
				(mid 43.296586 -304.449734)
				(end 43.702986 -304.449734)
			)
		)
		(stroke
			(width 0)
			(type solid)
		)
		(fill yes)
		(layer "In1.Cu")
		(net "P5E_PEX0_STN7_TX_DN<115>")
	)
	(gr_poly
		(pts
			(arc
				(start 43.702986 -302.549814)
				(mid 43.296586 -302.549814)
				(end 43.702986 -302.549814)
			)
		)
		(stroke
			(width 0)
			(type solid)
		)
		(fill yes)
		(layer "In1.Cu")
		(net "P5E_PEX0_STN7_TX_DN<113>")
	)
	(gr_poly
		(pts
			(arc
				(start 44.652946 -318.699896)
				(mid 44.246546 -318.699896)
				(end 44.652946 -318.699896)
			)
		)
		(stroke
			(width 0)
			(type solid)
		)
		(fill yes)
		(layer "In1.Cu")
		(net "P5E_PEX0_STN6_RX_DN<110>")
	)
	(gr_poly
		(pts
			(arc
				(start 44.652946 -317.749936)
				(mid 44.246546 -317.749936)
				(end 44.652946 -317.749936)
			)
		)
		(stroke
			(width 0)
			(type solid)
		)
		(fill yes)
		(layer "In1.Cu")
		(net "P5E_PEX0_STN6_RX_DP<110>")
	)
	(gr_poly
		(pts
			(arc
				(start 44.652946 -313.949842)
				(mid 44.246546 -313.949842)
				(end 44.652946 -313.949842)
			)
		)
		(stroke
			(width 0)
			(type solid)
		)
		(fill yes)
		(layer "In1.Cu")
		(net "P5E_PEX0_STN6_TX_DN<110>")
	)
	(gr_poly
		(pts
			(arc
				(start 44.652946 -312.999882)
				(mid 44.246546 -312.999882)
				(end 44.652946 -312.999882)
			)
		)
		(stroke
			(width 0)
			(type solid)
		)
		(fill yes)
		(layer "In1.Cu")
		(net "P5E_PEX0_STN6_TX_DP<110>")
	)
	(gr_poly
		(pts
			(arc
				(start 44.652946 -308.249828)
				(mid 44.246546 -308.249828)
				(end 44.652946 -308.249828)
			)
		)
		(stroke
			(width 0)
			(type solid)
		)
		(fill yes)
		(layer "In1.Cu")
		(net "P5E_PEX0_STN7_TX_DP<119>")
	)
	(gr_poly
		(pts
			(arc
				(start 44.652946 -306.349908)
				(mid 44.246546 -306.349908)
				(end 44.652946 -306.349908)
			)
		)
		(stroke
			(width 0)
			(type solid)
		)
		(fill yes)
		(layer "In1.Cu")
		(net "P5E_PEX0_STN7_TX_DP<117>")
	)
	(gr_poly
		(pts
			(arc
				(start 44.652946 -304.449734)
				(mid 44.246546 -304.449734)
				(end 44.652946 -304.449734)
			)
		)
		(stroke
			(width 0)
			(type solid)
		)
		(fill yes)
		(layer "In1.Cu")
		(net "P5E_PEX0_STN7_TX_DP<115>")
	)
	(gr_poly
		(pts
			(arc
				(start 44.652946 -302.549814)
				(mid 44.246546 -302.549814)
				(end 44.652946 -302.549814)
			)
		)
		(stroke
			(width 0)
			(type solid)
		)
		(fill yes)
		(layer "In1.Cu")
		(net "P5E_PEX0_STN7_TX_DP<113>")
	)
	(gr_poly
		(pts
			(arc
				(start 44.652946 -278.799798)
				(mid 44.246546 -278.799798)
				(end 44.652946 -278.799798)
			)
		)
		(stroke
			(width 0)
			(type solid)
		)
		(fill yes)
		(layer "In1.Cu")
		(net "P5E_PEX0_STN2_TX_DP<47>")
	)
	(gr_poly
		(pts
			(arc
				(start 44.652946 -277.849838)
				(mid 44.246546 -277.849838)
				(end 44.652946 -277.849838)
			)
		)
		(stroke
			(width 0)
			(type solid)
		)
		(fill yes)
		(layer "In1.Cu")
		(net "P5E_PEX0_STN2_TX_DN<47>")
	)
	(gr_poly
		(pts
			(arc
				(start 44.652946 -274.049744)
				(mid 44.246546 -274.049744)
				(end 44.652946 -274.049744)
			)
		)
		(stroke
			(width 0)
			(type solid)
		)
		(fill yes)
		(layer "In1.Cu")
		(net "P5E_PEX0_STN2_RX_DP<47>")
	)
	(gr_poly
		(pts
			(arc
				(start 44.652946 -273.099784)
				(mid 44.246546 -273.099784)
				(end 44.652946 -273.099784)
			)
		)
		(stroke
			(width 0)
			(type solid)
		)
		(fill yes)
		(layer "In1.Cu")
		(net "P5E_PEX0_STN2_RX_DN<47>")
	)
	(gr_poly
		(pts
			(arc
				(start 45.60316 -316.799722)
				(mid 45.19676 -316.799722)
				(end 45.60316 -316.799722)
			)
		)
		(stroke
			(width 0)
			(type solid)
		)
		(fill yes)
		(layer "In1.Cu")
		(net "P5E_PEX0_STN6_RX_DN<109>")
	)
	(gr_poly
		(pts
			(arc
				(start 45.60316 -315.849762)
				(mid 45.19676 -315.849762)
				(end 45.60316 -315.849762)
			)
		)
		(stroke
			(width 0)
			(type solid)
		)
		(fill yes)
		(layer "In1.Cu")
		(net "P5E_PEX0_STN6_RX_DP<109>")
	)
	(gr_poly
		(pts
			(arc
				(start 45.60316 -312.049922)
				(mid 45.19676 -312.049922)
				(end 45.60316 -312.049922)
			)
		)
		(stroke
			(width 0)
			(type solid)
		)
		(fill yes)
		(layer "In1.Cu")
		(net "P5E_PEX0_STN6_TX_DN<109>")
	)
	(gr_poly
		(pts
			(arc
				(start 45.60316 -311.099962)
				(mid 45.19676 -311.099962)
				(end 45.60316 -311.099962)
			)
		)
		(stroke
			(width 0)
			(type solid)
		)
		(fill yes)
		(layer "In1.Cu")
		(net "P5E_PEX0_STN6_TX_DP<109>")
	)
	(gr_poly
		(pts
			(arc
				(start 45.60316 -280.699718)
				(mid 45.19676 -280.699718)
				(end 45.60316 -280.699718)
			)
		)
		(stroke
			(width 0)
			(type solid)
		)
		(fill yes)
		(layer "In1.Cu")
		(net "P5E_PEX0_STN2_TX_DP<46>")
	)
	(gr_poly
		(pts
			(arc
				(start 45.60316 -279.749504)
				(mid 45.19676 -279.749504)
				(end 45.60316 -279.749504)
			)
		)
		(stroke
			(width 0)
			(type solid)
		)
		(fill yes)
		(layer "In1.Cu")
		(net "P5E_PEX0_STN2_TX_DN<46>")
	)
	(gr_poly
		(pts
			(arc
				(start 45.60316 -275.949918)
				(mid 45.19676 -275.949918)
				(end 45.60316 -275.949918)
			)
		)
		(stroke
			(width 0)
			(type solid)
		)
		(fill yes)
		(layer "In1.Cu")
		(net "P5E_PEX0_STN2_RX_DP<46>")
	)
	(gr_poly
		(pts
			(arc
				(start 45.60316 -274.999958)
				(mid 45.19676 -274.999958)
				(end 45.60316 -274.999958)
			)
		)
		(stroke
			(width 0)
			(type solid)
		)
		(fill yes)
		(layer "In1.Cu")
		(net "P5E_PEX0_STN2_RX_DN<46>")
	)
	(gr_poly
		(pts
			(arc
				(start 46.55312 -318.699896)
				(mid 46.14672 -318.699896)
				(end 46.55312 -318.699896)
			)
		)
		(stroke
			(width 0)
			(type solid)
		)
		(fill yes)
		(layer "In1.Cu")
		(net "P5E_PEX0_STN6_RX_DN<108>")
	)
	(gr_poly
		(pts
			(arc
				(start 46.55312 -317.749936)
				(mid 46.14672 -317.749936)
				(end 46.55312 -317.749936)
			)
		)
		(stroke
			(width 0)
			(type solid)
		)
		(fill yes)
		(layer "In1.Cu")
		(net "P5E_PEX0_STN6_RX_DP<108>")
	)
	(gr_poly
		(pts
			(arc
				(start 46.55312 -313.949842)
				(mid 46.14672 -313.949842)
				(end 46.55312 -313.949842)
			)
		)
		(stroke
			(width 0)
			(type solid)
		)
		(fill yes)
		(layer "In1.Cu")
		(net "P5E_PEX0_STN6_TX_DN<108>")
	)
	(gr_poly
		(pts
			(arc
				(start 46.55312 -312.999882)
				(mid 46.14672 -312.999882)
				(end 46.55312 -312.999882)
			)
		)
		(stroke
			(width 0)
			(type solid)
		)
		(fill yes)
		(layer "In1.Cu")
		(net "P5E_PEX0_STN6_TX_DP<108>")
	)
	(gr_poly
		(pts
			(arc
				(start 46.55312 -278.799798)
				(mid 46.14672 -278.799798)
				(end 46.55312 -278.799798)
			)
		)
		(stroke
			(width 0)
			(type solid)
		)
		(fill yes)
		(layer "In1.Cu")
		(net "P5E_PEX0_STN2_TX_DP<45>")
	)
	(gr_poly
		(pts
			(arc
				(start 46.55312 -277.849838)
				(mid 46.14672 -277.849838)
				(end 46.55312 -277.849838)
			)
		)
		(stroke
			(width 0)
			(type solid)
		)
		(fill yes)
		(layer "In1.Cu")
		(net "P5E_PEX0_STN2_TX_DN<45>")
	)
	(gr_poly
		(pts
			(arc
				(start 46.55312 -274.049744)
				(mid 46.14672 -274.049744)
				(end 46.55312 -274.049744)
			)
		)
		(stroke
			(width 0)
			(type solid)
		)
		(fill yes)
		(layer "In1.Cu")
		(net "P5E_PEX0_STN2_RX_DP<45>")
	)
	(gr_poly
		(pts
			(arc
				(start 46.55312 -273.099784)
				(mid 46.14672 -273.099784)
				(end 46.55312 -273.099784)
			)
		)
		(stroke
			(width 0)
			(type solid)
		)
		(fill yes)
		(layer "In1.Cu")
		(net "P5E_PEX0_STN2_RX_DN<45>")
	)
	(gr_poly
		(pts
			(arc
				(start 47.50308 -316.799722)
				(mid 47.09668 -316.799722)
				(end 47.50308 -316.799722)
			)
		)
		(stroke
			(width 0)
			(type solid)
		)
		(fill yes)
		(layer "In1.Cu")
		(net "P5E_PEX0_STN6_RX_DN<107>")
	)
	(gr_poly
		(pts
			(arc
				(start 47.50308 -315.849762)
				(mid 47.09668 -315.849762)
				(end 47.50308 -315.849762)
			)
		)
		(stroke
			(width 0)
			(type solid)
		)
		(fill yes)
		(layer "In1.Cu")
		(net "P5E_PEX0_STN6_RX_DP<107>")
	)
	(gr_poly
		(pts
			(arc
				(start 47.50308 -312.049922)
				(mid 47.09668 -312.049922)
				(end 47.50308 -312.049922)
			)
		)
		(stroke
			(width 0)
			(type solid)
		)
		(fill yes)
		(layer "In1.Cu")
		(net "P5E_PEX0_STN6_TX_DN<107>")
	)
	(gr_poly
		(pts
			(arc
				(start 47.50308 -311.099962)
				(mid 47.09668 -311.099962)
				(end 47.50308 -311.099962)
			)
		)
		(stroke
			(width 0)
			(type solid)
		)
		(fill yes)
		(layer "In1.Cu")
		(net "P5E_PEX0_STN6_TX_DP<107>")
	)
	(gr_poly
		(pts
			(arc
				(start 47.50308 -280.699718)
				(mid 47.09668 -280.699718)
				(end 47.50308 -280.699718)
			)
		)
		(stroke
			(width 0)
			(type solid)
		)
		(fill yes)
		(layer "In1.Cu")
		(net "P5E_PEX0_STN2_TX_DP<44>")
	)
	(gr_poly
		(pts
			(arc
				(start 47.50308 -279.749504)
				(mid 47.09668 -279.749504)
				(end 47.50308 -279.749504)
			)
		)
		(stroke
			(width 0)
			(type solid)
		)
		(fill yes)
		(layer "In1.Cu")
		(net "P5E_PEX0_STN2_TX_DN<44>")
	)
	(gr_poly
		(pts
			(arc
				(start 47.50308 -275.949918)
				(mid 47.09668 -275.949918)
				(end 47.50308 -275.949918)
			)
		)
		(stroke
			(width 0)
			(type solid)
		)
		(fill yes)
		(layer "In1.Cu")
		(net "P5E_PEX0_STN2_RX_DP<44>")
	)
	(gr_poly
		(pts
			(arc
				(start 47.50308 -274.999958)
				(mid 47.09668 -274.999958)
				(end 47.50308 -274.999958)
			)
		)
		(stroke
			(width 0)
			(type solid)
		)
		(fill yes)
		(layer "In1.Cu")
		(net "P5E_PEX0_STN2_RX_DN<44>")
	)
	(gr_poly
		(pts
			(arc
				(start 48.45304 -318.699896)
				(mid 48.04664 -318.699896)
				(end 48.45304 -318.699896)
			)
		)
		(stroke
			(width 0)
			(type solid)
		)
		(fill yes)
		(layer "In1.Cu")
		(net "P5E_PEX0_STN6_RX_DN<106>")
	)
	(gr_poly
		(pts
			(arc
				(start 48.45304 -317.749936)
				(mid 48.04664 -317.749936)
				(end 48.45304 -317.749936)
			)
		)
		(stroke
			(width 0)
			(type solid)
		)
		(fill yes)
		(layer "In1.Cu")
		(net "P5E_PEX0_STN6_RX_DP<106>")
	)
	(gr_poly
		(pts
			(arc
				(start 48.45304 -313.949842)
				(mid 48.04664 -313.949842)
				(end 48.45304 -313.949842)
			)
		)
		(stroke
			(width 0)
			(type solid)
		)
		(fill yes)
		(layer "In1.Cu")
		(net "P5E_PEX0_STN6_TX_DN<106>")
	)
	(gr_poly
		(pts
			(arc
				(start 48.45304 -312.999882)
				(mid 48.04664 -312.999882)
				(end 48.45304 -312.999882)
			)
		)
		(stroke
			(width 0)
			(type solid)
		)
		(fill yes)
		(layer "In1.Cu")
		(net "P5E_PEX0_STN6_TX_DP<106>")
	)
	(gr_poly
		(pts
			(arc
				(start 48.45304 -278.799798)
				(mid 48.04664 -278.799798)
				(end 48.45304 -278.799798)
			)
		)
		(stroke
			(width 0)
			(type solid)
		)
		(fill yes)
		(layer "In1.Cu")
		(net "P5E_PEX0_STN2_TX_DP<43>")
	)
	(gr_poly
		(pts
			(arc
				(start 48.45304 -277.849838)
				(mid 48.04664 -277.849838)
				(end 48.45304 -277.849838)
			)
		)
		(stroke
			(width 0)
			(type solid)
		)
		(fill yes)
		(layer "In1.Cu")
		(net "P5E_PEX0_STN2_TX_DN<43>")
	)
	(gr_poly
		(pts
			(arc
				(start 48.45304 -274.049744)
				(mid 48.04664 -274.049744)
				(end 48.45304 -274.049744)
			)
		)
		(stroke
			(width 0)
			(type solid)
		)
		(fill yes)
		(layer "In1.Cu")
		(net "P5E_PEX0_STN2_RX_DP<43>")
	)
	(gr_poly
		(pts
			(arc
				(start 48.45304 -273.099784)
				(mid 48.04664 -273.099784)
				(end 48.45304 -273.099784)
			)
		)
		(stroke
			(width 0)
			(type solid)
		)
		(fill yes)
		(layer "In1.Cu")
		(net "P5E_PEX0_STN2_RX_DN<43>")
	)
	(gr_poly
		(pts
			(arc
				(start 49.403 -316.799722)
				(mid 48.9966 -316.799722)
				(end 49.403 -316.799722)
			)
		)
		(stroke
			(width 0)
			(type solid)
		)
		(fill yes)
		(layer "In1.Cu")
		(net "P5E_PEX0_STN6_RX_DN<105>")
	)
	(gr_poly
		(pts
			(arc
				(start 49.403 -315.849762)
				(mid 48.9966 -315.849762)
				(end 49.403 -315.849762)
			)
		)
		(stroke
			(width 0)
			(type solid)
		)
		(fill yes)
		(layer "In1.Cu")
		(net "P5E_PEX0_STN6_RX_DP<105>")
	)
	(gr_poly
		(pts
			(arc
				(start 49.403 -312.049922)
				(mid 48.9966 -312.049922)
				(end 49.403 -312.049922)
			)
		)
		(stroke
			(width 0)
			(type solid)
		)
		(fill yes)
		(layer "In1.Cu")
		(net "P5E_PEX0_STN6_TX_DN<105>")
	)
	(gr_poly
		(pts
			(arc
				(start 49.403 -311.099962)
				(mid 48.9966 -311.099962)
				(end 49.403 -311.099962)
			)
		)
		(stroke
			(width 0)
			(type solid)
		)
		(fill yes)
		(layer "In1.Cu")
		(net "P5E_PEX0_STN6_TX_DP<105>")
	)
	(gr_poly
		(pts
			(arc
				(start 49.403 -280.699718)
				(mid 48.9966 -280.699718)
				(end 49.403 -280.699718)
			)
		)
		(stroke
			(width 0)
			(type solid)
		)
		(fill yes)
		(layer "In1.Cu")
		(net "P5E_PEX0_STN2_TX_DP<42>")
	)
	(gr_poly
		(pts
			(arc
				(start 49.403 -279.749504)
				(mid 48.9966 -279.749504)
				(end 49.403 -279.749504)
			)
		)
		(stroke
			(width 0)
			(type solid)
		)
		(fill yes)
		(layer "In1.Cu")
		(net "P5E_PEX0_STN2_TX_DN<42>")
	)
	(gr_poly
		(pts
			(arc
				(start 49.403 -275.949918)
				(mid 48.9966 -275.949918)
				(end 49.403 -275.949918)
			)
		)
		(stroke
			(width 0)
			(type solid)
		)
		(fill yes)
		(layer "In1.Cu")
		(net "P5E_PEX0_STN2_RX_DP<42>")
	)
	(gr_poly
		(pts
			(arc
				(start 49.403 -274.999958)
				(mid 48.9966 -274.999958)
				(end 49.403 -274.999958)
			)
		)
		(stroke
			(width 0)
			(type solid)
		)
		(fill yes)
		(layer "In1.Cu")
		(net "P5E_PEX0_STN2_RX_DN<42>")
	)
	(gr_poly
		(pts
			(arc
				(start 50.35296 -318.699896)
				(mid 49.94656 -318.699896)
				(end 50.35296 -318.699896)
			)
		)
		(stroke
			(width 0)
			(type solid)
		)
		(fill yes)
		(layer "In1.Cu")
		(net "P5E_PEX0_STN6_RX_DN<104>")
	)
	(gr_poly
		(pts
			(arc
				(start 50.35296 -317.749936)
				(mid 49.94656 -317.749936)
				(end 50.35296 -317.749936)
			)
		)
		(stroke
			(width 0)
			(type solid)
		)
		(fill yes)
		(layer "In1.Cu")
		(net "P5E_PEX0_STN6_RX_DP<104>")
	)
	(gr_poly
		(pts
			(arc
				(start 50.35296 -313.949842)
				(mid 49.94656 -313.949842)
				(end 50.35296 -313.949842)
			)
		)
		(stroke
			(width 0)
			(type solid)
		)
		(fill yes)
		(layer "In1.Cu")
		(net "P5E_PEX0_STN6_TX_DN<104>")
	)
	(gr_poly
		(pts
			(arc
				(start 50.35296 -312.999882)
				(mid 49.94656 -312.999882)
				(end 50.35296 -312.999882)
			)
		)
		(stroke
			(width 0)
			(type solid)
		)
		(fill yes)
		(layer "In1.Cu")
		(net "P5E_PEX0_STN6_TX_DP<104>")
	)
	(gr_poly
		(pts
			(arc
				(start 50.35296 -278.799798)
				(mid 49.94656 -278.799798)
				(end 50.35296 -278.799798)
			)
		)
		(stroke
			(width 0)
			(type solid)
		)
		(fill yes)
		(layer "In1.Cu")
		(net "P5E_PEX0_STN2_TX_DP<41>")
	)
	(gr_poly
		(pts
			(arc
				(start 50.35296 -277.849838)
				(mid 49.94656 -277.849838)
				(end 50.35296 -277.849838)
			)
		)
		(stroke
			(width 0)
			(type solid)
		)
		(fill yes)
		(layer "In1.Cu")
		(net "P5E_PEX0_STN2_TX_DN<41>")
	)
	(gr_poly
		(pts
			(arc
				(start 50.35296 -274.049744)
				(mid 49.94656 -274.049744)
				(end 50.35296 -274.049744)
			)
		)
		(stroke
			(width 0)
			(type solid)
		)
		(fill yes)
		(layer "In1.Cu")
		(net "P5E_PEX0_STN2_RX_DP<41>")
	)
	(gr_poly
		(pts
			(arc
				(start 50.35296 -273.099784)
				(mid 49.94656 -273.099784)
				(end 50.35296 -273.099784)
			)
		)
		(stroke
			(width 0)
			(type solid)
		)
		(fill yes)
		(layer "In1.Cu")
		(net "P5E_PEX0_STN2_RX_DN<41>")
	)
	(gr_poly
		(pts
			(arc
				(start 51.303174 -316.799722)
				(mid 50.896774 -316.799722)
				(end 51.303174 -316.799722)
			)
		)
		(stroke
			(width 0)
			(type solid)
		)
		(fill yes)
		(layer "In1.Cu")
		(net "P5E_PEX0_STN6_RX_DN<103>")
	)
	(gr_poly
		(pts
			(arc
				(start 51.303174 -315.849762)
				(mid 50.896774 -315.849762)
				(end 51.303174 -315.849762)
			)
		)
		(stroke
			(width 0)
			(type solid)
		)
		(fill yes)
		(layer "In1.Cu")
		(net "P5E_PEX0_STN6_RX_DP<103>")
	)
	(gr_poly
		(pts
			(arc
				(start 51.303174 -312.049922)
				(mid 50.896774 -312.049922)
				(end 51.303174 -312.049922)
			)
		)
		(stroke
			(width 0)
			(type solid)
		)
		(fill yes)
		(layer "In1.Cu")
		(net "P5E_PEX0_STN6_TX_DN<103>")
	)
	(gr_poly
		(pts
			(arc
				(start 51.303174 -311.099962)
				(mid 50.896774 -311.099962)
				(end 51.303174 -311.099962)
			)
		)
		(stroke
			(width 0)
			(type solid)
		)
		(fill yes)
		(layer "In1.Cu")
		(net "P5E_PEX0_STN6_TX_DP<103>")
	)
	(gr_poly
		(pts
			(arc
				(start 51.303174 -280.699718)
				(mid 50.896774 -280.699718)
				(end 51.303174 -280.699718)
			)
		)
		(stroke
			(width 0)
			(type solid)
		)
		(fill yes)
		(layer "In1.Cu")
		(net "P5E_PEX0_STN2_TX_DP<40>")
	)
	(gr_poly
		(pts
			(arc
				(start 51.303174 -279.749504)
				(mid 50.896774 -279.749504)
				(end 51.303174 -279.749504)
			)
		)
		(stroke
			(width 0)
			(type solid)
		)
		(fill yes)
		(layer "In1.Cu")
		(net "P5E_PEX0_STN2_TX_DN<40>")
	)
	(gr_poly
		(pts
			(arc
				(start 51.303174 -275.949918)
				(mid 50.896774 -275.949918)
				(end 51.303174 -275.949918)
			)
		)
		(stroke
			(width 0)
			(type solid)
		)
		(fill yes)
		(layer "In1.Cu")
		(net "P5E_PEX0_STN2_RX_DP<40>")
	)
	(gr_poly
		(pts
			(arc
				(start 51.303174 -274.999958)
				(mid 50.896774 -274.999958)
				(end 51.303174 -274.999958)
			)
		)
		(stroke
			(width 0)
			(type solid)
		)
		(fill yes)
		(layer "In1.Cu")
		(net "P5E_PEX0_STN2_RX_DN<40>")
	)
	(gr_poly
		(pts
			(arc
				(start 52.253134 -318.699896)
				(mid 51.846734 -318.699896)
				(end 52.253134 -318.699896)
			)
		)
		(stroke
			(width 0)
			(type solid)
		)
		(fill yes)
		(layer "In1.Cu")
		(net "P5E_PEX0_STN6_RX_DN<102>")
	)
	(gr_poly
		(pts
			(arc
				(start 52.253134 -317.749936)
				(mid 51.846734 -317.749936)
				(end 52.253134 -317.749936)
			)
		)
		(stroke
			(width 0)
			(type solid)
		)
		(fill yes)
		(layer "In1.Cu")
		(net "P5E_PEX0_STN6_RX_DP<102>")
	)
	(gr_poly
		(pts
			(arc
				(start 52.253134 -313.949842)
				(mid 51.846734 -313.949842)
				(end 52.253134 -313.949842)
			)
		)
		(stroke
			(width 0)
			(type solid)
		)
		(fill yes)
		(layer "In1.Cu")
		(net "P5E_PEX0_STN6_TX_DN<102>")
	)
	(gr_poly
		(pts
			(arc
				(start 52.253134 -312.999882)
				(mid 51.846734 -312.999882)
				(end 52.253134 -312.999882)
			)
		)
		(stroke
			(width 0)
			(type solid)
		)
		(fill yes)
		(layer "In1.Cu")
		(net "P5E_PEX0_STN6_TX_DP<102>")
	)
	(gr_poly
		(pts
			(arc
				(start 52.253134 -278.799798)
				(mid 51.846734 -278.799798)
				(end 52.253134 -278.799798)
			)
		)
		(stroke
			(width 0)
			(type solid)
		)
		(fill yes)
		(layer "In1.Cu")
		(net "P5E_PEX0_STN2_TX_DP<39>")
	)
	(gr_poly
		(pts
			(arc
				(start 52.253134 -277.849838)
				(mid 51.846734 -277.849838)
				(end 52.253134 -277.849838)
			)
		)
		(stroke
			(width 0)
			(type solid)
		)
		(fill yes)
		(layer "In1.Cu")
		(net "P5E_PEX0_STN2_TX_DN<39>")
	)
	(gr_poly
		(pts
			(arc
				(start 52.253134 -274.049744)
				(mid 51.846734 -274.049744)
				(end 52.253134 -274.049744)
			)
		)
		(stroke
			(width 0)
			(type solid)
		)
		(fill yes)
		(layer "In1.Cu")
		(net "P5E_PEX0_STN2_RX_DP<39>")
	)
	(gr_poly
		(pts
			(arc
				(start 52.253134 -273.099784)
				(mid 51.846734 -273.099784)
				(end 52.253134 -273.099784)
			)
		)
		(stroke
			(width 0)
			(type solid)
		)
		(fill yes)
		(layer "In1.Cu")
		(net "P5E_PEX0_STN2_RX_DN<39>")
	)
	(gr_poly
		(pts
			(arc
				(start 53.203094 -316.799722)
				(mid 52.796694 -316.799722)
				(end 53.203094 -316.799722)
			)
		)
		(stroke
			(width 0)
			(type solid)
		)
		(fill yes)
		(layer "In1.Cu")
		(net "P5E_PEX0_STN6_RX_DN<101>")
	)
	(gr_poly
		(pts
			(arc
				(start 53.203094 -315.849762)
				(mid 52.796694 -315.849762)
				(end 53.203094 -315.849762)
			)
		)
		(stroke
			(width 0)
			(type solid)
		)
		(fill yes)
		(layer "In1.Cu")
		(net "P5E_PEX0_STN6_RX_DP<101>")
	)
	(gr_poly
		(pts
			(arc
				(start 53.203094 -312.049922)
				(mid 52.796694 -312.049922)
				(end 53.203094 -312.049922)
			)
		)
		(stroke
			(width 0)
			(type solid)
		)
		(fill yes)
		(layer "In1.Cu")
		(net "P5E_PEX0_STN6_TX_DN<101>")
	)
	(gr_poly
		(pts
			(arc
				(start 53.203094 -311.099962)
				(mid 52.796694 -311.099962)
				(end 53.203094 -311.099962)
			)
		)
		(stroke
			(width 0)
			(type solid)
		)
		(fill yes)
		(layer "In1.Cu")
		(net "P5E_PEX0_STN6_TX_DP<101>")
	)
	(gr_poly
		(pts
			(arc
				(start 53.203094 -280.699718)
				(mid 52.796694 -280.699718)
				(end 53.203094 -280.699718)
			)
		)
		(stroke
			(width 0)
			(type solid)
		)
		(fill yes)
		(layer "In1.Cu")
		(net "P5E_PEX0_STN2_TX_DP<38>")
	)
	(gr_poly
		(pts
			(arc
				(start 53.203094 -279.749504)
				(mid 52.796694 -279.749504)
				(end 53.203094 -279.749504)
			)
		)
		(stroke
			(width 0)
			(type solid)
		)
		(fill yes)
		(layer "In1.Cu")
		(net "P5E_PEX0_STN2_TX_DN<38>")
	)
	(gr_poly
		(pts
			(arc
				(start 53.203094 -275.949918)
				(mid 52.796694 -275.949918)
				(end 53.203094 -275.949918)
			)
		)
		(stroke
			(width 0)
			(type solid)
		)
		(fill yes)
		(layer "In1.Cu")
		(net "P5E_PEX0_STN2_RX_DP<38>")
	)
	(gr_poly
		(pts
			(arc
				(start 53.203094 -274.999958)
				(mid 52.796694 -274.999958)
				(end 53.203094 -274.999958)
			)
		)
		(stroke
			(width 0)
			(type solid)
		)
		(fill yes)
		(layer "In1.Cu")
		(net "P5E_PEX0_STN2_RX_DN<38>")
	)
	(gr_poly
		(pts
			(arc
				(start 54.153054 -318.699896)
				(mid 53.746654 -318.699896)
				(end 54.153054 -318.699896)
			)
		)
		(stroke
			(width 0)
			(type solid)
		)
		(fill yes)
		(layer "In1.Cu")
		(net "P5E_PEX0_STN6_RX_DN<100>")
	)
	(gr_poly
		(pts
			(arc
				(start 54.153054 -317.749936)
				(mid 53.746654 -317.749936)
				(end 54.153054 -317.749936)
			)
		)
		(stroke
			(width 0)
			(type solid)
		)
		(fill yes)
		(layer "In1.Cu")
		(net "P5E_PEX0_STN6_RX_DP<100>")
	)
	(gr_poly
		(pts
			(arc
				(start 54.153054 -313.949842)
				(mid 53.746654 -313.949842)
				(end 54.153054 -313.949842)
			)
		)
		(stroke
			(width 0)
			(type solid)
		)
		(fill yes)
		(layer "In1.Cu")
		(net "P5E_PEX0_STN6_TX_DN<100>")
	)
	(gr_poly
		(pts
			(arc
				(start 54.153054 -312.999882)
				(mid 53.746654 -312.999882)
				(end 54.153054 -312.999882)
			)
		)
		(stroke
			(width 0)
			(type solid)
		)
		(fill yes)
		(layer "In1.Cu")
		(net "P5E_PEX0_STN6_TX_DP<100>")
	)
	(gr_poly
		(pts
			(arc
				(start 54.153054 -278.799798)
				(mid 53.746654 -278.799798)
				(end 54.153054 -278.799798)
			)
		)
		(stroke
			(width 0)
			(type solid)
		)
		(fill yes)
		(layer "In1.Cu")
		(net "P5E_PEX0_STN2_TX_DP<37>")
	)
	(gr_poly
		(pts
			(arc
				(start 54.153054 -277.849838)
				(mid 53.746654 -277.849838)
				(end 54.153054 -277.849838)
			)
		)
		(stroke
			(width 0)
			(type solid)
		)
		(fill yes)
		(layer "In1.Cu")
		(net "P5E_PEX0_STN2_TX_DN<37>")
	)
	(gr_poly
		(pts
			(arc
				(start 54.153054 -274.049744)
				(mid 53.746654 -274.049744)
				(end 54.153054 -274.049744)
			)
		)
		(stroke
			(width 0)
			(type solid)
		)
		(fill yes)
		(layer "In1.Cu")
		(net "P5E_PEX0_STN2_RX_DP<37>")
	)
	(gr_poly
		(pts
			(arc
				(start 54.153054 -273.099784)
				(mid 53.746654 -273.099784)
				(end 54.153054 -273.099784)
			)
		)
		(stroke
			(width 0)
			(type solid)
		)
		(fill yes)
		(layer "In1.Cu")
		(net "P5E_PEX0_STN2_RX_DN<37>")
	)
	(gr_poly
		(pts
			(arc
				(start 55.103014 -316.799722)
				(mid 54.696614 -316.799722)
				(end 55.103014 -316.799722)
			)
		)
		(stroke
			(width 0)
			(type solid)
		)
		(fill yes)
		(layer "In1.Cu")
		(net "P5E_PEX0_STN6_RX_DN<99>")
	)
	(gr_poly
		(pts
			(arc
				(start 55.103014 -315.849762)
				(mid 54.696614 -315.849762)
				(end 55.103014 -315.849762)
			)
		)
		(stroke
			(width 0)
			(type solid)
		)
		(fill yes)
		(layer "In1.Cu")
		(net "P5E_PEX0_STN6_RX_DP<99>")
	)
	(gr_poly
		(pts
			(arc
				(start 55.103014 -312.049922)
				(mid 54.696614 -312.049922)
				(end 55.103014 -312.049922)
			)
		)
		(stroke
			(width 0)
			(type solid)
		)
		(fill yes)
		(layer "In1.Cu")
		(net "P5E_PEX0_STN6_TX_DN<99>")
	)
	(gr_poly
		(pts
			(arc
				(start 55.103014 -311.099962)
				(mid 54.696614 -311.099962)
				(end 55.103014 -311.099962)
			)
		)
		(stroke
			(width 0)
			(type solid)
		)
		(fill yes)
		(layer "In1.Cu")
		(net "P5E_PEX0_STN6_TX_DP<99>")
	)
	(gr_poly
		(pts
			(arc
				(start 55.103014 -280.699718)
				(mid 54.696614 -280.699718)
				(end 55.103014 -280.699718)
			)
		)
		(stroke
			(width 0)
			(type solid)
		)
		(fill yes)
		(layer "In1.Cu")
		(net "P5E_PEX0_STN2_TX_DP<36>")
	)
	(gr_poly
		(pts
			(arc
				(start 55.103014 -279.749504)
				(mid 54.696614 -279.749504)
				(end 55.103014 -279.749504)
			)
		)
		(stroke
			(width 0)
			(type solid)
		)
		(fill yes)
		(layer "In1.Cu")
		(net "P5E_PEX0_STN2_TX_DN<36>")
	)
	(gr_poly
		(pts
			(arc
				(start 55.103014 -275.949918)
				(mid 54.696614 -275.949918)
				(end 55.103014 -275.949918)
			)
		)
		(stroke
			(width 0)
			(type solid)
		)
		(fill yes)
		(layer "In1.Cu")
		(net "P5E_PEX0_STN2_RX_DP<36>")
	)
	(gr_poly
		(pts
			(arc
				(start 55.103014 -274.999958)
				(mid 54.696614 -274.999958)
				(end 55.103014 -274.999958)
			)
		)
		(stroke
			(width 0)
			(type solid)
		)
		(fill yes)
		(layer "In1.Cu")
		(net "P5E_PEX0_STN2_RX_DN<36>")
	)
	(gr_poly
		(pts
			(arc
				(start 56.052974 -318.699896)
				(mid 55.646574 -318.699896)
				(end 56.052974 -318.699896)
			)
		)
		(stroke
			(width 0)
			(type solid)
		)
		(fill yes)
		(layer "In1.Cu")
		(net "P5E_PEX0_STN6_RX_DN<98>")
	)
	(gr_poly
		(pts
			(arc
				(start 56.052974 -317.749936)
				(mid 55.646574 -317.749936)
				(end 56.052974 -317.749936)
			)
		)
		(stroke
			(width 0)
			(type solid)
		)
		(fill yes)
		(layer "In1.Cu")
		(net "P5E_PEX0_STN6_RX_DP<98>")
	)
	(gr_poly
		(pts
			(arc
				(start 56.052974 -313.949842)
				(mid 55.646574 -313.949842)
				(end 56.052974 -313.949842)
			)
		)
		(stroke
			(width 0)
			(type solid)
		)
		(fill yes)
		(layer "In1.Cu")
		(net "P5E_PEX0_STN6_TX_DN<98>")
	)
	(gr_poly
		(pts
			(arc
				(start 56.052974 -312.999882)
				(mid 55.646574 -312.999882)
				(end 56.052974 -312.999882)
			)
		)
		(stroke
			(width 0)
			(type solid)
		)
		(fill yes)
		(layer "In1.Cu")
		(net "P5E_PEX0_STN6_TX_DP<98>")
	)
	(gr_poly
		(pts
			(arc
				(start 56.052974 -278.799798)
				(mid 55.646574 -278.799798)
				(end 56.052974 -278.799798)
			)
		)
		(stroke
			(width 0)
			(type solid)
		)
		(fill yes)
		(layer "In1.Cu")
		(net "P5E_PEX0_STN2_TX_DP<35>")
	)
	(gr_poly
		(pts
			(arc
				(start 56.052974 -277.849838)
				(mid 55.646574 -277.849838)
				(end 56.052974 -277.849838)
			)
		)
		(stroke
			(width 0)
			(type solid)
		)
		(fill yes)
		(layer "In1.Cu")
		(net "P5E_PEX0_STN2_TX_DN<35>")
	)
	(gr_poly
		(pts
			(arc
				(start 56.052974 -274.049744)
				(mid 55.646574 -274.049744)
				(end 56.052974 -274.049744)
			)
		)
		(stroke
			(width 0)
			(type solid)
		)
		(fill yes)
		(layer "In1.Cu")
		(net "P5E_PEX0_STN2_RX_DP<35>")
	)
	(gr_poly
		(pts
			(arc
				(start 56.052974 -273.099784)
				(mid 55.646574 -273.099784)
				(end 56.052974 -273.099784)
			)
		)
		(stroke
			(width 0)
			(type solid)
		)
		(fill yes)
		(layer "In1.Cu")
		(net "P5E_PEX0_STN2_RX_DN<35>")
	)
	(gr_poly
		(pts
			(arc
				(start 57.002934 -280.699718)
				(mid 56.596534 -280.699718)
				(end 57.002934 -280.699718)
			)
		)
		(stroke
			(width 0)
			(type solid)
		)
		(fill yes)
		(layer "In1.Cu")
		(net "P5E_PEX0_STN2_TX_DP<34>")
	)
	(gr_poly
		(pts
			(arc
				(start 57.002934 -279.749504)
				(mid 56.596534 -279.749504)
				(end 57.002934 -279.749504)
			)
		)
		(stroke
			(width 0)
			(type solid)
		)
		(fill yes)
		(layer "In1.Cu")
		(net "P5E_PEX0_STN2_TX_DN<34>")
	)
	(gr_poly
		(pts
			(arc
				(start 57.003188 -316.799722)
				(mid 56.596788 -316.799722)
				(end 57.003188 -316.799722)
			)
		)
		(stroke
			(width 0)
			(type solid)
		)
		(fill yes)
		(layer "In1.Cu")
		(net "P5E_PEX0_STN6_RX_DN<97>")
	)
	(gr_poly
		(pts
			(arc
				(start 57.003188 -315.849762)
				(mid 56.596788 -315.849762)
				(end 57.003188 -315.849762)
			)
		)
		(stroke
			(width 0)
			(type solid)
		)
		(fill yes)
		(layer "In1.Cu")
		(net "P5E_PEX0_STN6_RX_DP<97>")
	)
	(gr_poly
		(pts
			(arc
				(start 57.003188 -312.049922)
				(mid 56.596788 -312.049922)
				(end 57.003188 -312.049922)
			)
		)
		(stroke
			(width 0)
			(type solid)
		)
		(fill yes)
		(layer "In1.Cu")
		(net "P5E_PEX0_STN6_TX_DN<97>")
	)
	(gr_poly
		(pts
			(arc
				(start 57.003188 -311.099962)
				(mid 56.596788 -311.099962)
				(end 57.003188 -311.099962)
			)
		)
		(stroke
			(width 0)
			(type solid)
		)
		(fill yes)
		(layer "In1.Cu")
		(net "P5E_PEX0_STN6_TX_DP<97>")
	)
	(gr_poly
		(pts
			(arc
				(start 57.003188 -275.949918)
				(mid 56.596788 -275.949918)
				(end 57.003188 -275.949918)
			)
		)
		(stroke
			(width 0)
			(type solid)
		)
		(fill yes)
		(layer "In1.Cu")
		(net "P5E_PEX0_STN2_RX_DP<34>")
	)
	(gr_poly
		(pts
			(arc
				(start 57.003188 -274.999958)
				(mid 56.596788 -274.999958)
				(end 57.003188 -274.999958)
			)
		)
		(stroke
			(width 0)
			(type solid)
		)
		(fill yes)
		(layer "In1.Cu")
		(net "P5E_PEX0_STN2_RX_DN<34>")
	)
	(gr_poly
		(pts
			(arc
				(start 57.953148 -318.699896)
				(mid 57.546748 -318.699896)
				(end 57.953148 -318.699896)
			)
		)
		(stroke
			(width 0)
			(type solid)
		)
		(fill yes)
		(layer "In1.Cu")
		(net "P5E_PEX0_STN6_RX_DN<96>")
	)
	(gr_poly
		(pts
			(arc
				(start 57.953148 -317.749936)
				(mid 57.546748 -317.749936)
				(end 57.953148 -317.749936)
			)
		)
		(stroke
			(width 0)
			(type solid)
		)
		(fill yes)
		(layer "In1.Cu")
		(net "P5E_PEX0_STN6_RX_DP<96>")
	)
	(gr_poly
		(pts
			(arc
				(start 57.953148 -313.949842)
				(mid 57.546748 -313.949842)
				(end 57.953148 -313.949842)
			)
		)
		(stroke
			(width 0)
			(type solid)
		)
		(fill yes)
		(layer "In1.Cu")
		(net "P5E_PEX0_STN6_TX_DN<96>")
	)
	(gr_poly
		(pts
			(arc
				(start 57.953148 -312.999882)
				(mid 57.546748 -312.999882)
				(end 57.953148 -312.999882)
			)
		)
		(stroke
			(width 0)
			(type solid)
		)
		(fill yes)
		(layer "In1.Cu")
		(net "P5E_PEX0_STN6_TX_DP<96>")
	)
	(gr_poly
		(pts
			(arc
				(start 57.953148 -278.799798)
				(mid 57.546748 -278.799798)
				(end 57.953148 -278.799798)
			)
		)
		(stroke
			(width 0)
			(type solid)
		)
		(fill yes)
		(layer "In1.Cu")
		(net "P5E_PEX0_STN2_TX_DP<33>")
	)
	(gr_poly
		(pts
			(arc
				(start 57.953148 -277.849838)
				(mid 57.546748 -277.849838)
				(end 57.953148 -277.849838)
			)
		)
		(stroke
			(width 0)
			(type solid)
		)
		(fill yes)
		(layer "In1.Cu")
		(net "P5E_PEX0_STN2_TX_DN<33>")
	)
	(gr_poly
		(pts
			(arc
				(start 57.953148 -274.049744)
				(mid 57.546748 -274.049744)
				(end 57.953148 -274.049744)
			)
		)
		(stroke
			(width 0)
			(type solid)
		)
		(fill yes)
		(layer "In1.Cu")
		(net "P5E_PEX0_STN2_RX_DP<33>")
	)
	(gr_poly
		(pts
			(arc
				(start 57.953148 -273.099784)
				(mid 57.546748 -273.099784)
				(end 57.953148 -273.099784)
			)
		)
		(stroke
			(width 0)
			(type solid)
		)
		(fill yes)
		(layer "In1.Cu")
		(net "P5E_PEX0_STN2_RX_DN<33>")
	)
	(gr_poly
		(pts
			(arc
				(start 58.903108 -316.799722)
				(mid 58.496708 -316.799722)
				(end 58.903108 -316.799722)
			)
		)
		(stroke
			(width 0)
			(type solid)
		)
		(fill yes)
		(layer "In1.Cu")
		(net "P5E_PEX0_STN5_RX_DN<80>")
	)
	(gr_poly
		(pts
			(arc
				(start 58.903108 -315.849762)
				(mid 58.496708 -315.849762)
				(end 58.903108 -315.849762)
			)
		)
		(stroke
			(width 0)
			(type solid)
		)
		(fill yes)
		(layer "In1.Cu")
		(net "P5E_PEX0_STN5_RX_DP<80>")
	)
	(gr_poly
		(pts
			(arc
				(start 58.903108 -312.049922)
				(mid 58.496708 -312.049922)
				(end 58.903108 -312.049922)
			)
		)
		(stroke
			(width 0)
			(type solid)
		)
		(fill yes)
		(layer "In1.Cu")
		(net "P5E_PEX0_STN5_TX_DN<80>")
	)
	(gr_poly
		(pts
			(arc
				(start 58.903108 -311.099962)
				(mid 58.496708 -311.099962)
				(end 58.903108 -311.099962)
			)
		)
		(stroke
			(width 0)
			(type solid)
		)
		(fill yes)
		(layer "In1.Cu")
		(net "P5E_PEX0_STN5_TX_DP<80>")
	)
	(gr_poly
		(pts
			(arc
				(start 58.903108 -280.699718)
				(mid 58.496708 -280.699718)
				(end 58.903108 -280.699718)
			)
		)
		(stroke
			(width 0)
			(type solid)
		)
		(fill yes)
		(layer "In1.Cu")
		(net "P5E_PEX0_STN2_TX_DP<32>")
	)
	(gr_poly
		(pts
			(arc
				(start 58.903108 -279.749504)
				(mid 58.496708 -279.749504)
				(end 58.903108 -279.749504)
			)
		)
		(stroke
			(width 0)
			(type solid)
		)
		(fill yes)
		(layer "In1.Cu")
		(net "P5E_PEX0_STN2_TX_DN<32>")
	)
	(gr_poly
		(pts
			(arc
				(start 58.903108 -275.949918)
				(mid 58.496708 -275.949918)
				(end 58.903108 -275.949918)
			)
		)
		(stroke
			(width 0)
			(type solid)
		)
		(fill yes)
		(layer "In1.Cu")
		(net "P5E_PEX0_STN2_RX_DP<32>")
	)
	(gr_poly
		(pts
			(arc
				(start 58.903108 -274.999958)
				(mid 58.496708 -274.999958)
				(end 58.903108 -274.999958)
			)
		)
		(stroke
			(width 0)
			(type solid)
		)
		(fill yes)
		(layer "In1.Cu")
		(net "P5E_PEX0_STN2_RX_DN<32>")
	)
	(gr_poly
		(pts
			(arc
				(start 59.852814 -278.799798)
				(mid 59.446414 -278.799798)
				(end 59.852814 -278.799798)
			)
		)
		(stroke
			(width 0)
			(type solid)
		)
		(fill yes)
		(layer "In1.Cu")
		(net "P5E_PEX0_STN1_TX_DP<16>")
	)
	(gr_poly
		(pts
			(arc
				(start 59.852814 -277.849838)
				(mid 59.446414 -277.849838)
				(end 59.852814 -277.849838)
			)
		)
		(stroke
			(width 0)
			(type solid)
		)
		(fill yes)
		(layer "In1.Cu")
		(net "P5E_PEX0_STN1_TX_DN<16>")
	)
	(gr_poly
		(pts
			(arc
				(start 59.852814 -274.04949)
				(mid 59.446414 -274.04949)
				(end 59.852814 -274.04949)
			)
		)
		(stroke
			(width 0)
			(type solid)
		)
		(fill yes)
		(layer "In1.Cu")
		(net "P5E_PEX0_STN1_RX_DP<16>")
	)
	(gr_poly
		(pts
			(arc
				(start 59.852814 -273.09953)
				(mid 59.446414 -273.09953)
				(end 59.852814 -273.09953)
			)
		)
		(stroke
			(width 0)
			(type solid)
		)
		(fill yes)
		(layer "In1.Cu")
		(net "P5E_PEX0_STN1_RX_DN<16>")
	)
	(gr_poly
		(pts
			(arc
				(start 59.853068 -318.699896)
				(mid 59.446668 -318.699896)
				(end 59.853068 -318.699896)
			)
		)
		(stroke
			(width 0)
			(type solid)
		)
		(fill yes)
		(layer "In1.Cu")
		(net "P5E_PEX0_STN5_RX_DN<81>")
	)
	(gr_poly
		(pts
			(arc
				(start 59.853068 -317.749936)
				(mid 59.446668 -317.749936)
				(end 59.853068 -317.749936)
			)
		)
		(stroke
			(width 0)
			(type solid)
		)
		(fill yes)
		(layer "In1.Cu")
		(net "P5E_PEX0_STN5_RX_DP<81>")
	)
	(gr_poly
		(pts
			(arc
				(start 59.853068 -313.949842)
				(mid 59.446668 -313.949842)
				(end 59.853068 -313.949842)
			)
		)
		(stroke
			(width 0)
			(type solid)
		)
		(fill yes)
		(layer "In1.Cu")
		(net "P5E_PEX0_STN5_TX_DN<81>")
	)
	(gr_poly
		(pts
			(arc
				(start 59.853068 -312.999882)
				(mid 59.446668 -312.999882)
				(end 59.853068 -312.999882)
			)
		)
		(stroke
			(width 0)
			(type solid)
		)
		(fill yes)
		(layer "In1.Cu")
		(net "P5E_PEX0_STN5_TX_DP<81>")
	)
	(gr_poly
		(pts
			(arc
				(start 60.802774 -275.949664)
				(mid 60.396374 -275.949664)
				(end 60.802774 -275.949664)
			)
		)
		(stroke
			(width 0)
			(type solid)
		)
		(fill yes)
		(layer "In1.Cu")
		(net "P5E_PEX0_STN1_RX_DP<17>")
	)
	(gr_poly
		(pts
			(arc
				(start 60.802774 -274.999704)
				(mid 60.396374 -274.999704)
				(end 60.802774 -274.999704)
			)
		)
		(stroke
			(width 0)
			(type solid)
		)
		(fill yes)
		(layer "In1.Cu")
		(net "P5E_PEX0_STN1_RX_DN<17>")
	)
	(gr_poly
		(pts
			(arc
				(start 60.803028 -316.799722)
				(mid 60.396628 -316.799722)
				(end 60.803028 -316.799722)
			)
		)
		(stroke
			(width 0)
			(type solid)
		)
		(fill yes)
		(layer "In1.Cu")
		(net "P5E_PEX0_STN5_RX_DN<82>")
	)
	(gr_poly
		(pts
			(arc
				(start 60.803028 -315.849762)
				(mid 60.396628 -315.849762)
				(end 60.803028 -315.849762)
			)
		)
		(stroke
			(width 0)
			(type solid)
		)
		(fill yes)
		(layer "In1.Cu")
		(net "P5E_PEX0_STN5_RX_DP<82>")
	)
	(gr_poly
		(pts
			(arc
				(start 60.803028 -312.049922)
				(mid 60.396628 -312.049922)
				(end 60.803028 -312.049922)
			)
		)
		(stroke
			(width 0)
			(type solid)
		)
		(fill yes)
		(layer "In1.Cu")
		(net "P5E_PEX0_STN5_TX_DN<82>")
	)
	(gr_poly
		(pts
			(arc
				(start 60.803028 -311.099962)
				(mid 60.396628 -311.099962)
				(end 60.803028 -311.099962)
			)
		)
		(stroke
			(width 0)
			(type solid)
		)
		(fill yes)
		(layer "In1.Cu")
		(net "P5E_PEX0_STN5_TX_DP<82>")
	)
	(gr_poly
		(pts
			(arc
				(start 60.803028 -280.699718)
				(mid 60.396628 -280.699718)
				(end 60.803028 -280.699718)
			)
		)
		(stroke
			(width 0)
			(type solid)
		)
		(fill yes)
		(layer "In1.Cu")
		(net "P5E_PEX0_STN1_TX_DN<17>")
	)
	(gr_poly
		(pts
			(arc
				(start 60.803028 -279.749504)
				(mid 60.396628 -279.749504)
				(end 60.803028 -279.749504)
			)
		)
		(stroke
			(width 0)
			(type solid)
		)
		(fill yes)
		(layer "In1.Cu")
		(net "P5E_PEX0_STN1_TX_DP<17>")
	)
	(gr_poly
		(pts
			(arc
				(start 61.752734 -278.799798)
				(mid 61.346334 -278.799798)
				(end 61.752734 -278.799798)
			)
		)
		(stroke
			(width 0)
			(type solid)
		)
		(fill yes)
		(layer "In1.Cu")
		(net "P5E_PEX0_STN1_TX_DP<18>")
	)
	(gr_poly
		(pts
			(arc
				(start 61.752734 -277.849838)
				(mid 61.346334 -277.849838)
				(end 61.752734 -277.849838)
			)
		)
		(stroke
			(width 0)
			(type solid)
		)
		(fill yes)
		(layer "In1.Cu")
		(net "P5E_PEX0_STN1_TX_DN<18>")
	)
	(gr_poly
		(pts
			(arc
				(start 61.752734 -274.049744)
				(mid 61.346334 -274.049744)
				(end 61.752734 -274.049744)
			)
		)
		(stroke
			(width 0)
			(type solid)
		)
		(fill yes)
		(layer "In1.Cu")
		(net "P5E_PEX0_STN1_RX_DP<18>")
	)
	(gr_poly
		(pts
			(arc
				(start 61.752734 -273.099784)
				(mid 61.346334 -273.099784)
				(end 61.752734 -273.099784)
			)
		)
		(stroke
			(width 0)
			(type solid)
		)
		(fill yes)
		(layer "In1.Cu")
		(net "P5E_PEX0_STN1_RX_DN<18>")
	)
	(gr_poly
		(pts
			(arc
				(start 61.752988 -318.699896)
				(mid 61.346588 -318.699896)
				(end 61.752988 -318.699896)
			)
		)
		(stroke
			(width 0)
			(type solid)
		)
		(fill yes)
		(layer "In1.Cu")
		(net "P5E_PEX0_STN5_RX_DN<83>")
	)
	(gr_poly
		(pts
			(arc
				(start 61.752988 -317.749936)
				(mid 61.346588 -317.749936)
				(end 61.752988 -317.749936)
			)
		)
		(stroke
			(width 0)
			(type solid)
		)
		(fill yes)
		(layer "In1.Cu")
		(net "P5E_PEX0_STN5_RX_DP<83>")
	)
	(gr_poly
		(pts
			(arc
				(start 61.752988 -313.949842)
				(mid 61.346588 -313.949842)
				(end 61.752988 -313.949842)
			)
		)
		(stroke
			(width 0)
			(type solid)
		)
		(fill yes)
		(layer "In1.Cu")
		(net "P5E_PEX0_STN5_TX_DN<83>")
	)
	(gr_poly
		(pts
			(arc
				(start 61.752988 -312.999882)
				(mid 61.346588 -312.999882)
				(end 61.752988 -312.999882)
			)
		)
		(stroke
			(width 0)
			(type solid)
		)
		(fill yes)
		(layer "In1.Cu")
		(net "P5E_PEX0_STN5_TX_DP<83>")
	)
	(gr_poly
		(pts
			(arc
				(start 62.702694 -275.949918)
				(mid 62.296294 -275.949918)
				(end 62.702694 -275.949918)
			)
		)
		(stroke
			(width 0)
			(type solid)
		)
		(fill yes)
		(layer "In1.Cu")
		(net "P5E_PEX0_STN1_RX_DP<19>")
	)
	(gr_poly
		(pts
			(arc
				(start 62.702694 -274.999958)
				(mid 62.296294 -274.999958)
				(end 62.702694 -274.999958)
			)
		)
		(stroke
			(width 0)
			(type solid)
		)
		(fill yes)
		(layer "In1.Cu")
		(net "P5E_PEX0_STN1_RX_DN<19>")
	)
	(gr_poly
		(pts
			(arc
				(start 62.702948 -316.799722)
				(mid 62.296548 -316.799722)
				(end 62.702948 -316.799722)
			)
		)
		(stroke
			(width 0)
			(type solid)
		)
		(fill yes)
		(layer "In1.Cu")
		(net "P5E_PEX0_STN5_RX_DN<84>")
	)
	(gr_poly
		(pts
			(arc
				(start 62.702948 -315.849762)
				(mid 62.296548 -315.849762)
				(end 62.702948 -315.849762)
			)
		)
		(stroke
			(width 0)
			(type solid)
		)
		(fill yes)
		(layer "In1.Cu")
		(net "P5E_PEX0_STN5_RX_DP<84>")
	)
	(gr_poly
		(pts
			(arc
				(start 62.702948 -312.049922)
				(mid 62.296548 -312.049922)
				(end 62.702948 -312.049922)
			)
		)
		(stroke
			(width 0)
			(type solid)
		)
		(fill yes)
		(layer "In1.Cu")
		(net "P5E_PEX0_STN5_TX_DN<84>")
	)
	(gr_poly
		(pts
			(arc
				(start 62.702948 -311.099962)
				(mid 62.296548 -311.099962)
				(end 62.702948 -311.099962)
			)
		)
		(stroke
			(width 0)
			(type solid)
		)
		(fill yes)
		(layer "In1.Cu")
		(net "P5E_PEX0_STN5_TX_DP<84>")
	)
	(gr_poly
		(pts
			(arc
				(start 62.702948 -280.699718)
				(mid 62.296548 -280.699718)
				(end 62.702948 -280.699718)
			)
		)
		(stroke
			(width 0)
			(type solid)
		)
		(fill yes)
		(layer "In1.Cu")
		(net "P5E_PEX0_STN1_TX_DN<19>")
	)
	(gr_poly
		(pts
			(arc
				(start 62.702948 -279.749504)
				(mid 62.296548 -279.749504)
				(end 62.702948 -279.749504)
			)
		)
		(stroke
			(width 0)
			(type solid)
		)
		(fill yes)
		(layer "In1.Cu")
		(net "P5E_PEX0_STN1_TX_DP<19>")
	)
	(gr_poly
		(pts
			(arc
				(start 63.652908 -278.799798)
				(mid 63.246508 -278.799798)
				(end 63.652908 -278.799798)
			)
		)
		(stroke
			(width 0)
			(type solid)
		)
		(fill yes)
		(layer "In1.Cu")
		(net "P5E_PEX0_STN1_TX_DP<20>")
	)
	(gr_poly
		(pts
			(arc
				(start 63.652908 -277.849838)
				(mid 63.246508 -277.849838)
				(end 63.652908 -277.849838)
			)
		)
		(stroke
			(width 0)
			(type solid)
		)
		(fill yes)
		(layer "In1.Cu")
		(net "P5E_PEX0_STN1_TX_DN<20>")
	)
	(gr_poly
		(pts
			(arc
				(start 63.652908 -274.049744)
				(mid 63.246508 -274.049744)
				(end 63.652908 -274.049744)
			)
		)
		(stroke
			(width 0)
			(type solid)
		)
		(fill yes)
		(layer "In1.Cu")
		(net "P5E_PEX0_STN1_RX_DP<20>")
	)
	(gr_poly
		(pts
			(arc
				(start 63.652908 -273.099784)
				(mid 63.246508 -273.099784)
				(end 63.652908 -273.099784)
			)
		)
		(stroke
			(width 0)
			(type solid)
		)
		(fill yes)
		(layer "In1.Cu")
		(net "P5E_PEX0_STN1_RX_DN<20>")
	)
	(gr_poly
		(pts
			(arc
				(start 63.653162 -318.699896)
				(mid 63.246762 -318.699896)
				(end 63.653162 -318.699896)
			)
		)
		(stroke
			(width 0)
			(type solid)
		)
		(fill yes)
		(layer "In1.Cu")
		(net "P5E_PEX0_STN5_RX_DN<85>")
	)
	(gr_poly
		(pts
			(arc
				(start 63.653162 -317.749936)
				(mid 63.246762 -317.749936)
				(end 63.653162 -317.749936)
			)
		)
		(stroke
			(width 0)
			(type solid)
		)
		(fill yes)
		(layer "In1.Cu")
		(net "P5E_PEX0_STN5_RX_DP<85>")
	)
	(gr_poly
		(pts
			(arc
				(start 63.653162 -313.949842)
				(mid 63.246762 -313.949842)
				(end 63.653162 -313.949842)
			)
		)
		(stroke
			(width 0)
			(type solid)
		)
		(fill yes)
		(layer "In1.Cu")
		(net "P5E_PEX0_STN5_TX_DN<85>")
	)
	(gr_poly
		(pts
			(arc
				(start 63.653162 -312.999882)
				(mid 63.246762 -312.999882)
				(end 63.653162 -312.999882)
			)
		)
		(stroke
			(width 0)
			(type solid)
		)
		(fill yes)
		(layer "In1.Cu")
		(net "P5E_PEX0_STN5_TX_DP<85>")
	)
	(gr_poly
		(pts
			(arc
				(start 64.602868 -275.949664)
				(mid 64.196468 -275.949664)
				(end 64.602868 -275.949664)
			)
		)
		(stroke
			(width 0)
			(type solid)
		)
		(fill yes)
		(layer "In1.Cu")
		(net "P5E_PEX0_STN1_RX_DP<21>")
	)
	(gr_poly
		(pts
			(arc
				(start 64.602868 -274.999704)
				(mid 64.196468 -274.999704)
				(end 64.602868 -274.999704)
			)
		)
		(stroke
			(width 0)
			(type solid)
		)
		(fill yes)
		(layer "In1.Cu")
		(net "P5E_PEX0_STN1_RX_DN<21>")
	)
	(gr_poly
		(pts
			(arc
				(start 64.603122 -316.799722)
				(mid 64.196722 -316.799722)
				(end 64.603122 -316.799722)
			)
		)
		(stroke
			(width 0)
			(type solid)
		)
		(fill yes)
		(layer "In1.Cu")
		(net "P5E_PEX0_STN5_RX_DN<86>")
	)
	(gr_poly
		(pts
			(arc
				(start 64.603122 -315.849762)
				(mid 64.196722 -315.849762)
				(end 64.603122 -315.849762)
			)
		)
		(stroke
			(width 0)
			(type solid)
		)
		(fill yes)
		(layer "In1.Cu")
		(net "P5E_PEX0_STN5_RX_DP<86>")
	)
	(gr_poly
		(pts
			(arc
				(start 64.603122 -312.049922)
				(mid 64.196722 -312.049922)
				(end 64.603122 -312.049922)
			)
		)
		(stroke
			(width 0)
			(type solid)
		)
		(fill yes)
		(layer "In1.Cu")
		(net "P5E_PEX0_STN5_TX_DN<86>")
	)
	(gr_poly
		(pts
			(arc
				(start 64.603122 -311.099962)
				(mid 64.196722 -311.099962)
				(end 64.603122 -311.099962)
			)
		)
		(stroke
			(width 0)
			(type solid)
		)
		(fill yes)
		(layer "In1.Cu")
		(net "P5E_PEX0_STN5_TX_DP<86>")
	)
	(gr_poly
		(pts
			(arc
				(start 64.603122 -280.699718)
				(mid 64.196722 -280.699718)
				(end 64.603122 -280.699718)
			)
		)
		(stroke
			(width 0)
			(type solid)
		)
		(fill yes)
		(layer "In1.Cu")
		(net "P5E_PEX0_STN1_TX_DN<21>")
	)
	(gr_poly
		(pts
			(arc
				(start 64.603122 -279.749504)
				(mid 64.196722 -279.749504)
				(end 64.603122 -279.749504)
			)
		)
		(stroke
			(width 0)
			(type solid)
		)
		(fill yes)
		(layer "In1.Cu")
		(net "P5E_PEX0_STN1_TX_DP<21>")
	)
	(gr_poly
		(pts
			(arc
				(start 65.552828 -278.799798)
				(mid 65.146428 -278.799798)
				(end 65.552828 -278.799798)
			)
		)
		(stroke
			(width 0)
			(type solid)
		)
		(fill yes)
		(layer "In1.Cu")
		(net "P5E_PEX0_STN1_TX_DP<22>")
	)
	(gr_poly
		(pts
			(arc
				(start 65.552828 -277.849838)
				(mid 65.146428 -277.849838)
				(end 65.552828 -277.849838)
			)
		)
		(stroke
			(width 0)
			(type solid)
		)
		(fill yes)
		(layer "In1.Cu")
		(net "P5E_PEX0_STN1_TX_DN<22>")
	)
	(gr_poly
		(pts
			(arc
				(start 65.552828 -274.049744)
				(mid 65.146428 -274.049744)
				(end 65.552828 -274.049744)
			)
		)
		(stroke
			(width 0)
			(type solid)
		)
		(fill yes)
		(layer "In1.Cu")
		(net "P5E_PEX0_STN1_RX_DP<22>")
	)
	(gr_poly
		(pts
			(arc
				(start 65.552828 -273.099784)
				(mid 65.146428 -273.099784)
				(end 65.552828 -273.099784)
			)
		)
		(stroke
			(width 0)
			(type solid)
		)
		(fill yes)
		(layer "In1.Cu")
		(net "P5E_PEX0_STN1_RX_DN<22>")
	)
	(gr_poly
		(pts
			(arc
				(start 65.553082 -318.699896)
				(mid 65.146682 -318.699896)
				(end 65.553082 -318.699896)
			)
		)
		(stroke
			(width 0)
			(type solid)
		)
		(fill yes)
		(layer "In1.Cu")
		(net "P5E_PEX0_STN5_RX_DN<87>")
	)
	(gr_poly
		(pts
			(arc
				(start 65.553082 -317.749936)
				(mid 65.146682 -317.749936)
				(end 65.553082 -317.749936)
			)
		)
		(stroke
			(width 0)
			(type solid)
		)
		(fill yes)
		(layer "In1.Cu")
		(net "P5E_PEX0_STN5_RX_DP<87>")
	)
	(gr_poly
		(pts
			(arc
				(start 65.553082 -313.949842)
				(mid 65.146682 -313.949842)
				(end 65.553082 -313.949842)
			)
		)
		(stroke
			(width 0)
			(type solid)
		)
		(fill yes)
		(layer "In1.Cu")
		(net "P5E_PEX0_STN5_TX_DN<87>")
	)
	(gr_poly
		(pts
			(arc
				(start 65.553082 -312.999882)
				(mid 65.146682 -312.999882)
				(end 65.553082 -312.999882)
			)
		)
		(stroke
			(width 0)
			(type solid)
		)
		(fill yes)
		(layer "In1.Cu")
		(net "P5E_PEX0_STN5_TX_DP<87>")
	)
	(gr_poly
		(pts
			(arc
				(start 66.502788 -275.949918)
				(mid 66.096388 -275.949918)
				(end 66.502788 -275.949918)
			)
		)
		(stroke
			(width 0)
			(type solid)
		)
		(fill yes)
		(layer "In1.Cu")
		(net "P5E_PEX0_STN1_RX_DP<23>")
	)
	(gr_poly
		(pts
			(arc
				(start 66.502788 -274.999958)
				(mid 66.096388 -274.999958)
				(end 66.502788 -274.999958)
			)
		)
		(stroke
			(width 0)
			(type solid)
		)
		(fill yes)
		(layer "In1.Cu")
		(net "P5E_PEX0_STN1_RX_DN<23>")
	)
	(gr_poly
		(pts
			(arc
				(start 66.503042 -316.799722)
				(mid 66.096642 -316.799722)
				(end 66.503042 -316.799722)
			)
		)
		(stroke
			(width 0)
			(type solid)
		)
		(fill yes)
		(layer "In1.Cu")
		(net "P5E_PEX0_STN5_RX_DN<88>")
	)
	(gr_poly
		(pts
			(arc
				(start 66.503042 -315.849762)
				(mid 66.096642 -315.849762)
				(end 66.503042 -315.849762)
			)
		)
		(stroke
			(width 0)
			(type solid)
		)
		(fill yes)
		(layer "In1.Cu")
		(net "P5E_PEX0_STN5_RX_DP<88>")
	)
	(gr_poly
		(pts
			(arc
				(start 66.503042 -312.049922)
				(mid 66.096642 -312.049922)
				(end 66.503042 -312.049922)
			)
		)
		(stroke
			(width 0)
			(type solid)
		)
		(fill yes)
		(layer "In1.Cu")
		(net "P5E_PEX0_STN5_TX_DN<88>")
	)
	(gr_poly
		(pts
			(arc
				(start 66.503042 -311.099962)
				(mid 66.096642 -311.099962)
				(end 66.503042 -311.099962)
			)
		)
		(stroke
			(width 0)
			(type solid)
		)
		(fill yes)
		(layer "In1.Cu")
		(net "P5E_PEX0_STN5_TX_DP<88>")
	)
	(gr_poly
		(pts
			(arc
				(start 66.503042 -280.699718)
				(mid 66.096642 -280.699718)
				(end 66.503042 -280.699718)
			)
		)
		(stroke
			(width 0)
			(type solid)
		)
		(fill yes)
		(layer "In1.Cu")
		(net "P5E_PEX0_STN1_TX_DN<23>")
	)
	(gr_poly
		(pts
			(arc
				(start 66.503042 -279.749504)
				(mid 66.096642 -279.749504)
				(end 66.503042 -279.749504)
			)
		)
		(stroke
			(width 0)
			(type solid)
		)
		(fill yes)
		(layer "In1.Cu")
		(net "P5E_PEX0_STN1_TX_DP<23>")
	)
	(gr_poly
		(pts
			(arc
				(start 67.452748 -278.799798)
				(mid 67.046348 -278.799798)
				(end 67.452748 -278.799798)
			)
		)
		(stroke
			(width 0)
			(type solid)
		)
		(fill yes)
		(layer "In1.Cu")
		(net "P5E_PEX0_STN1_TX_DP<24>")
	)
	(gr_poly
		(pts
			(arc
				(start 67.452748 -277.849838)
				(mid 67.046348 -277.849838)
				(end 67.452748 -277.849838)
			)
		)
		(stroke
			(width 0)
			(type solid)
		)
		(fill yes)
		(layer "In1.Cu")
		(net "P5E_PEX0_STN1_TX_DN<24>")
	)
	(gr_poly
		(pts
			(arc
				(start 67.452748 -274.049744)
				(mid 67.046348 -274.049744)
				(end 67.452748 -274.049744)
			)
		)
		(stroke
			(width 0)
			(type solid)
		)
		(fill yes)
		(layer "In1.Cu")
		(net "P5E_PEX0_STN1_RX_DP<24>")
	)
	(gr_poly
		(pts
			(arc
				(start 67.452748 -273.099784)
				(mid 67.046348 -273.099784)
				(end 67.452748 -273.099784)
			)
		)
		(stroke
			(width 0)
			(type solid)
		)
		(fill yes)
		(layer "In1.Cu")
		(net "P5E_PEX0_STN1_RX_DN<24>")
	)
	(gr_poly
		(pts
			(arc
				(start 67.453002 -318.699896)
				(mid 67.046602 -318.699896)
				(end 67.453002 -318.699896)
			)
		)
		(stroke
			(width 0)
			(type solid)
		)
		(fill yes)
		(layer "In1.Cu")
		(net "P5E_PEX0_STN5_RX_DN<89>")
	)
	(gr_poly
		(pts
			(arc
				(start 67.453002 -317.749936)
				(mid 67.046602 -317.749936)
				(end 67.453002 -317.749936)
			)
		)
		(stroke
			(width 0)
			(type solid)
		)
		(fill yes)
		(layer "In1.Cu")
		(net "P5E_PEX0_STN5_RX_DP<89>")
	)
	(gr_poly
		(pts
			(arc
				(start 67.453002 -313.949842)
				(mid 67.046602 -313.949842)
				(end 67.453002 -313.949842)
			)
		)
		(stroke
			(width 0)
			(type solid)
		)
		(fill yes)
		(layer "In1.Cu")
		(net "P5E_PEX0_STN5_TX_DN<89>")
	)
	(gr_poly
		(pts
			(arc
				(start 67.453002 -312.999882)
				(mid 67.046602 -312.999882)
				(end 67.453002 -312.999882)
			)
		)
		(stroke
			(width 0)
			(type solid)
		)
		(fill yes)
		(layer "In1.Cu")
		(net "P5E_PEX0_STN5_TX_DP<89>")
	)
	(gr_poly
		(pts
			(arc
				(start 68.402708 -275.949664)
				(mid 67.996308 -275.949664)
				(end 68.402708 -275.949664)
			)
		)
		(stroke
			(width 0)
			(type solid)
		)
		(fill yes)
		(layer "In1.Cu")
		(net "P5E_PEX0_STN1_RX_DP<25>")
	)
	(gr_poly
		(pts
			(arc
				(start 68.402708 -274.999704)
				(mid 67.996308 -274.999704)
				(end 68.402708 -274.999704)
			)
		)
		(stroke
			(width 0)
			(type solid)
		)
		(fill yes)
		(layer "In1.Cu")
		(net "P5E_PEX0_STN1_RX_DN<25>")
	)
	(gr_poly
		(pts
			(arc
				(start 68.402962 -316.799722)
				(mid 67.996562 -316.799722)
				(end 68.402962 -316.799722)
			)
		)
		(stroke
			(width 0)
			(type solid)
		)
		(fill yes)
		(layer "In1.Cu")
		(net "P5E_PEX0_STN5_RX_DN<90>")
	)
	(gr_poly
		(pts
			(arc
				(start 68.402962 -315.849762)
				(mid 67.996562 -315.849762)
				(end 68.402962 -315.849762)
			)
		)
		(stroke
			(width 0)
			(type solid)
		)
		(fill yes)
		(layer "In1.Cu")
		(net "P5E_PEX0_STN5_RX_DP<90>")
	)
	(gr_poly
		(pts
			(arc
				(start 68.402962 -312.049922)
				(mid 67.996562 -312.049922)
				(end 68.402962 -312.049922)
			)
		)
		(stroke
			(width 0)
			(type solid)
		)
		(fill yes)
		(layer "In1.Cu")
		(net "P5E_PEX0_STN5_TX_DN<90>")
	)
	(gr_poly
		(pts
			(arc
				(start 68.402962 -311.099962)
				(mid 67.996562 -311.099962)
				(end 68.402962 -311.099962)
			)
		)
		(stroke
			(width 0)
			(type solid)
		)
		(fill yes)
		(layer "In1.Cu")
		(net "P5E_PEX0_STN5_TX_DP<90>")
	)
	(gr_poly
		(pts
			(arc
				(start 68.402962 -280.699718)
				(mid 67.996562 -280.699718)
				(end 68.402962 -280.699718)
			)
		)
		(stroke
			(width 0)
			(type solid)
		)
		(fill yes)
		(layer "In1.Cu")
		(net "P5E_PEX0_STN1_TX_DN<25>")
	)
	(gr_poly
		(pts
			(arc
				(start 68.402962 -279.749504)
				(mid 67.996562 -279.749504)
				(end 68.402962 -279.749504)
			)
		)
		(stroke
			(width 0)
			(type solid)
		)
		(fill yes)
		(layer "In1.Cu")
		(net "P5E_PEX0_STN1_TX_DP<25>")
	)
	(gr_poly
		(pts
			(arc
				(start 69.352922 -278.799798)
				(mid 68.946522 -278.799798)
				(end 69.352922 -278.799798)
			)
		)
		(stroke
			(width 0)
			(type solid)
		)
		(fill yes)
		(layer "In1.Cu")
		(net "P5E_PEX0_STN1_TX_DP<26>")
	)
	(gr_poly
		(pts
			(arc
				(start 69.352922 -277.849838)
				(mid 68.946522 -277.849838)
				(end 69.352922 -277.849838)
			)
		)
		(stroke
			(width 0)
			(type solid)
		)
		(fill yes)
		(layer "In1.Cu")
		(net "P5E_PEX0_STN1_TX_DN<26>")
	)
	(gr_poly
		(pts
			(arc
				(start 69.352922 -274.049744)
				(mid 68.946522 -274.049744)
				(end 69.352922 -274.049744)
			)
		)
		(stroke
			(width 0)
			(type solid)
		)
		(fill yes)
		(layer "In1.Cu")
		(net "P5E_PEX0_STN1_RX_DP<26>")
	)
	(gr_poly
		(pts
			(arc
				(start 69.352922 -273.099784)
				(mid 68.946522 -273.099784)
				(end 69.352922 -273.099784)
			)
		)
		(stroke
			(width 0)
			(type solid)
		)
		(fill yes)
		(layer "In1.Cu")
		(net "P5E_PEX0_STN1_RX_DN<26>")
	)
	(gr_poly
		(pts
			(arc
				(start 69.353176 -318.699896)
				(mid 68.946776 -318.699896)
				(end 69.353176 -318.699896)
			)
		)
		(stroke
			(width 0)
			(type solid)
		)
		(fill yes)
		(layer "In1.Cu")
		(net "P5E_PEX0_STN5_RX_DN<91>")
	)
	(gr_poly
		(pts
			(arc
				(start 69.353176 -317.749936)
				(mid 68.946776 -317.749936)
				(end 69.353176 -317.749936)
			)
		)
		(stroke
			(width 0)
			(type solid)
		)
		(fill yes)
		(layer "In1.Cu")
		(net "P5E_PEX0_STN5_RX_DP<91>")
	)
	(gr_poly
		(pts
			(arc
				(start 69.353176 -313.949842)
				(mid 68.946776 -313.949842)
				(end 69.353176 -313.949842)
			)
		)
		(stroke
			(width 0)
			(type solid)
		)
		(fill yes)
		(layer "In1.Cu")
		(net "P5E_PEX0_STN5_TX_DN<91>")
	)
	(gr_poly
		(pts
			(arc
				(start 69.353176 -312.999882)
				(mid 68.946776 -312.999882)
				(end 69.353176 -312.999882)
			)
		)
		(stroke
			(width 0)
			(type solid)
		)
		(fill yes)
		(layer "In1.Cu")
		(net "P5E_PEX0_STN5_TX_DP<91>")
	)
	(gr_poly
		(pts
			(arc
				(start 70.302628 -275.949918)
				(mid 69.896228 -275.949918)
				(end 70.302628 -275.949918)
			)
		)
		(stroke
			(width 0)
			(type solid)
		)
		(fill yes)
		(layer "In1.Cu")
		(net "P5E_PEX0_STN1_RX_DP<27>")
	)
	(gr_poly
		(pts
			(arc
				(start 70.302628 -274.999958)
				(mid 69.896228 -274.999958)
				(end 70.302628 -274.999958)
			)
		)
		(stroke
			(width 0)
			(type solid)
		)
		(fill yes)
		(layer "In1.Cu")
		(net "P5E_PEX0_STN1_RX_DN<27>")
	)
	(gr_poly
		(pts
			(arc
				(start 70.303136 -316.799722)
				(mid 69.896736 -316.799722)
				(end 70.303136 -316.799722)
			)
		)
		(stroke
			(width 0)
			(type solid)
		)
		(fill yes)
		(layer "In1.Cu")
		(net "P5E_PEX0_STN5_RX_DN<92>")
	)
	(gr_poly
		(pts
			(arc
				(start 70.303136 -315.849762)
				(mid 69.896736 -315.849762)
				(end 70.303136 -315.849762)
			)
		)
		(stroke
			(width 0)
			(type solid)
		)
		(fill yes)
		(layer "In1.Cu")
		(net "P5E_PEX0_STN5_RX_DP<92>")
	)
	(gr_poly
		(pts
			(arc
				(start 70.303136 -312.049922)
				(mid 69.896736 -312.049922)
				(end 70.303136 -312.049922)
			)
		)
		(stroke
			(width 0)
			(type solid)
		)
		(fill yes)
		(layer "In1.Cu")
		(net "P5E_PEX0_STN5_TX_DN<92>")
	)
	(gr_poly
		(pts
			(arc
				(start 70.303136 -311.099962)
				(mid 69.896736 -311.099962)
				(end 70.303136 -311.099962)
			)
		)
		(stroke
			(width 0)
			(type solid)
		)
		(fill yes)
		(layer "In1.Cu")
		(net "P5E_PEX0_STN5_TX_DP<92>")
	)
	(gr_poly
		(pts
			(arc
				(start 70.303136 -280.699718)
				(mid 69.896736 -280.699718)
				(end 70.303136 -280.699718)
			)
		)
		(stroke
			(width 0)
			(type solid)
		)
		(fill yes)
		(layer "In1.Cu")
		(net "P5E_PEX0_STN1_TX_DN<27>")
	)
	(gr_poly
		(pts
			(arc
				(start 70.303136 -279.749504)
				(mid 69.896736 -279.749504)
				(end 70.303136 -279.749504)
			)
		)
		(stroke
			(width 0)
			(type solid)
		)
		(fill yes)
		(layer "In1.Cu")
		(net "P5E_PEX0_STN1_TX_DP<27>")
	)
	(gr_poly
		(pts
			(arc
				(start 71.252842 -278.799798)
				(mid 70.846442 -278.799798)
				(end 71.252842 -278.799798)
			)
		)
		(stroke
			(width 0)
			(type solid)
		)
		(fill yes)
		(layer "In1.Cu")
		(net "P5E_PEX0_STN1_TX_DP<28>")
	)
	(gr_poly
		(pts
			(arc
				(start 71.252842 -277.849838)
				(mid 70.846442 -277.849838)
				(end 71.252842 -277.849838)
			)
		)
		(stroke
			(width 0)
			(type solid)
		)
		(fill yes)
		(layer "In1.Cu")
		(net "P5E_PEX0_STN1_TX_DN<28>")
	)
	(gr_poly
		(pts
			(arc
				(start 71.252842 -274.049744)
				(mid 70.846442 -274.049744)
				(end 71.252842 -274.049744)
			)
		)
		(stroke
			(width 0)
			(type solid)
		)
		(fill yes)
		(layer "In1.Cu")
		(net "P5E_PEX0_STN1_RX_DP<28>")
	)
	(gr_poly
		(pts
			(arc
				(start 71.252842 -273.099784)
				(mid 70.846442 -273.099784)
				(end 71.252842 -273.099784)
			)
		)
		(stroke
			(width 0)
			(type solid)
		)
		(fill yes)
		(layer "In1.Cu")
		(net "P5E_PEX0_STN1_RX_DN<28>")
	)
	(gr_poly
		(pts
			(arc
				(start 71.253096 -318.699896)
				(mid 70.846696 -318.699896)
				(end 71.253096 -318.699896)
			)
		)
		(stroke
			(width 0)
			(type solid)
		)
		(fill yes)
		(layer "In1.Cu")
		(net "P5E_PEX0_STN5_RX_DN<93>")
	)
	(gr_poly
		(pts
			(arc
				(start 71.253096 -317.749936)
				(mid 70.846696 -317.749936)
				(end 71.253096 -317.749936)
			)
		)
		(stroke
			(width 0)
			(type solid)
		)
		(fill yes)
		(layer "In1.Cu")
		(net "P5E_PEX0_STN5_RX_DP<93>")
	)
	(gr_poly
		(pts
			(arc
				(start 71.253096 -313.949842)
				(mid 70.846696 -313.949842)
				(end 71.253096 -313.949842)
			)
		)
		(stroke
			(width 0)
			(type solid)
		)
		(fill yes)
		(layer "In1.Cu")
		(net "P5E_PEX0_STN5_TX_DN<93>")
	)
	(gr_poly
		(pts
			(arc
				(start 71.253096 -312.999882)
				(mid 70.846696 -312.999882)
				(end 71.253096 -312.999882)
			)
		)
		(stroke
			(width 0)
			(type solid)
		)
		(fill yes)
		(layer "In1.Cu")
		(net "P5E_PEX0_STN5_TX_DP<93>")
	)
	(gr_poly
		(pts
			(arc
				(start 72.202802 -275.949664)
				(mid 71.796402 -275.949664)
				(end 72.202802 -275.949664)
			)
		)
		(stroke
			(width 0)
			(type solid)
		)
		(fill yes)
		(layer "In1.Cu")
		(net "P5E_PEX0_STN1_RX_DP<29>")
	)
	(gr_poly
		(pts
			(arc
				(start 72.202802 -274.999704)
				(mid 71.796402 -274.999704)
				(end 72.202802 -274.999704)
			)
		)
		(stroke
			(width 0)
			(type solid)
		)
		(fill yes)
		(layer "In1.Cu")
		(net "P5E_PEX0_STN1_RX_DN<29>")
	)
	(gr_poly
		(pts
			(arc
				(start 72.203056 -316.799722)
				(mid 71.796656 -316.799722)
				(end 72.203056 -316.799722)
			)
		)
		(stroke
			(width 0)
			(type solid)
		)
		(fill yes)
		(layer "In1.Cu")
		(net "P5E_PEX0_STN5_RX_DN<94>")
	)
	(gr_poly
		(pts
			(arc
				(start 72.203056 -315.849762)
				(mid 71.796656 -315.849762)
				(end 72.203056 -315.849762)
			)
		)
		(stroke
			(width 0)
			(type solid)
		)
		(fill yes)
		(layer "In1.Cu")
		(net "P5E_PEX0_STN5_RX_DP<94>")
	)
	(gr_poly
		(pts
			(arc
				(start 72.203056 -312.049922)
				(mid 71.796656 -312.049922)
				(end 72.203056 -312.049922)
			)
		)
		(stroke
			(width 0)
			(type solid)
		)
		(fill yes)
		(layer "In1.Cu")
		(net "P5E_PEX0_STN5_TX_DN<94>")
	)
	(gr_poly
		(pts
			(arc
				(start 72.203056 -311.099962)
				(mid 71.796656 -311.099962)
				(end 72.203056 -311.099962)
			)
		)
		(stroke
			(width 0)
			(type solid)
		)
		(fill yes)
		(layer "In1.Cu")
		(net "P5E_PEX0_STN5_TX_DP<94>")
	)
	(gr_poly
		(pts
			(arc
				(start 72.203056 -280.699718)
				(mid 71.796656 -280.699718)
				(end 72.203056 -280.699718)
			)
		)
		(stroke
			(width 0)
			(type solid)
		)
		(fill yes)
		(layer "In1.Cu")
		(net "P5E_PEX0_STN1_TX_DN<29>")
	)
	(gr_poly
		(pts
			(arc
				(start 72.203056 -279.749504)
				(mid 71.796656 -279.749504)
				(end 72.203056 -279.749504)
			)
		)
		(stroke
			(width 0)
			(type solid)
		)
		(fill yes)
		(layer "In1.Cu")
		(net "P5E_PEX0_STN1_TX_DP<29>")
	)
	(gr_poly
		(pts
			(arc
				(start 73.152762 -278.799798)
				(mid 72.746362 -278.799798)
				(end 73.152762 -278.799798)
			)
		)
		(stroke
			(width 0)
			(type solid)
		)
		(fill yes)
		(layer "In1.Cu")
		(net "P5E_PEX0_STN1_TX_DP<30>")
	)
	(gr_poly
		(pts
			(arc
				(start 73.152762 -277.849838)
				(mid 72.746362 -277.849838)
				(end 73.152762 -277.849838)
			)
		)
		(stroke
			(width 0)
			(type solid)
		)
		(fill yes)
		(layer "In1.Cu")
		(net "P5E_PEX0_STN1_TX_DN<30>")
	)
	(gr_poly
		(pts
			(arc
				(start 73.152762 -274.049744)
				(mid 72.746362 -274.049744)
				(end 73.152762 -274.049744)
			)
		)
		(stroke
			(width 0)
			(type solid)
		)
		(fill yes)
		(layer "In1.Cu")
		(net "P5E_PEX0_STN1_RX_DP<30>")
	)
	(gr_poly
		(pts
			(arc
				(start 73.152762 -273.099784)
				(mid 72.746362 -273.099784)
				(end 73.152762 -273.099784)
			)
		)
		(stroke
			(width 0)
			(type solid)
		)
		(fill yes)
		(layer "In1.Cu")
		(net "P5E_PEX0_STN1_RX_DN<30>")
	)
	(gr_poly
		(pts
			(arc
				(start 73.153016 -318.699896)
				(mid 72.746616 -318.699896)
				(end 73.153016 -318.699896)
			)
		)
		(stroke
			(width 0)
			(type solid)
		)
		(fill yes)
		(layer "In1.Cu")
		(net "P5E_PEX0_STN5_RX_DN<95>")
	)
	(gr_poly
		(pts
			(arc
				(start 73.153016 -317.749936)
				(mid 72.746616 -317.749936)
				(end 73.153016 -317.749936)
			)
		)
		(stroke
			(width 0)
			(type solid)
		)
		(fill yes)
		(layer "In1.Cu")
		(net "P5E_PEX0_STN5_RX_DP<95>")
	)
	(gr_poly
		(pts
			(arc
				(start 73.153016 -313.949842)
				(mid 72.746616 -313.949842)
				(end 73.153016 -313.949842)
			)
		)
		(stroke
			(width 0)
			(type solid)
		)
		(fill yes)
		(layer "In1.Cu")
		(net "P5E_PEX0_STN5_TX_DN<95>")
	)
	(gr_poly
		(pts
			(arc
				(start 73.153016 -312.999882)
				(mid 72.746616 -312.999882)
				(end 73.153016 -312.999882)
			)
		)
		(stroke
			(width 0)
			(type solid)
		)
		(fill yes)
		(layer "In1.Cu")
		(net "P5E_PEX0_STN5_TX_DP<95>")
	)
	(gr_poly
		(pts
			(arc
				(start 74.102722 -275.949918)
				(mid 73.696322 -275.949918)
				(end 74.102722 -275.949918)
			)
		)
		(stroke
			(width 0)
			(type solid)
		)
		(fill yes)
		(layer "In1.Cu")
		(net "P5E_PEX0_STN1_RX_DP<31>")
	)
	(gr_poly
		(pts
			(arc
				(start 74.102722 -274.999958)
				(mid 73.696322 -274.999958)
				(end 74.102722 -274.999958)
			)
		)
		(stroke
			(width 0)
			(type solid)
		)
		(fill yes)
		(layer "In1.Cu")
		(net "P5E_PEX0_STN1_RX_DN<31>")
	)
	(gr_poly
		(pts
			(arc
				(start 74.102976 -316.799722)
				(mid 73.696576 -316.799722)
				(end 74.102976 -316.799722)
			)
		)
		(stroke
			(width 0)
			(type solid)
		)
		(fill yes)
		(layer "In1.Cu")
		(net "P5E_PEX0_STN4_RX_DN<79>")
	)
	(gr_poly
		(pts
			(arc
				(start 74.102976 -315.849762)
				(mid 73.696576 -315.849762)
				(end 74.102976 -315.849762)
			)
		)
		(stroke
			(width 0)
			(type solid)
		)
		(fill yes)
		(layer "In1.Cu")
		(net "P5E_PEX0_STN4_RX_DP<79>")
	)
	(gr_poly
		(pts
			(arc
				(start 74.102976 -312.049922)
				(mid 73.696576 -312.049922)
				(end 74.102976 -312.049922)
			)
		)
		(stroke
			(width 0)
			(type solid)
		)
		(fill yes)
		(layer "In1.Cu")
		(net "P5E_PEX0_STN4_TX_DN<79>")
	)
	(gr_poly
		(pts
			(arc
				(start 74.102976 -311.099962)
				(mid 73.696576 -311.099962)
				(end 74.102976 -311.099962)
			)
		)
		(stroke
			(width 0)
			(type solid)
		)
		(fill yes)
		(layer "In1.Cu")
		(net "P5E_PEX0_STN4_TX_DP<79>")
	)
	(gr_poly
		(pts
			(arc
				(start 74.102976 -280.699718)
				(mid 73.696576 -280.699718)
				(end 74.102976 -280.699718)
			)
		)
		(stroke
			(width 0)
			(type solid)
		)
		(fill yes)
		(layer "In1.Cu")
		(net "P5E_PEX0_STN1_TX_DN<31>")
	)
	(gr_poly
		(pts
			(arc
				(start 74.102976 -279.749504)
				(mid 73.696576 -279.749504)
				(end 74.102976 -279.749504)
			)
		)
		(stroke
			(width 0)
			(type solid)
		)
		(fill yes)
		(layer "In1.Cu")
		(net "P5E_PEX0_STN1_TX_DP<31>")
	)
	(gr_poly
		(pts
			(arc
				(start 75.052936 -287.349946)
				(mid 74.646536 -287.349946)
				(end 75.052936 -287.349946)
			)
		)
		(stroke
			(width 0)
			(type solid)
		)
		(fill yes)
		(layer "In1.Cu")
		(net "P5E_PEX0_STN0_TX_DP<1>")
	)
	(gr_poly
		(pts
			(arc
				(start 75.052936 -285.449772)
				(mid 74.646536 -285.449772)
				(end 75.052936 -285.449772)
			)
		)
		(stroke
			(width 0)
			(type solid)
		)
		(fill yes)
		(layer "In1.Cu")
		(net "P5E_PEX0_STN0_TX_DP<3>")
	)
	(gr_poly
		(pts
			(arc
				(start 75.052936 -283.549852)
				(mid 74.646536 -283.549852)
				(end 75.052936 -283.549852)
			)
		)
		(stroke
			(width 0)
			(type solid)
		)
		(fill yes)
		(layer "In1.Cu")
		(net "P5E_PEX0_STN0_TX_DP<5>")
	)
	(gr_poly
		(pts
			(arc
				(start 75.052936 -278.799798)
				(mid 74.646536 -278.799798)
				(end 75.052936 -278.799798)
			)
		)
		(stroke
			(width 0)
			(type solid)
		)
		(fill yes)
		(layer "In1.Cu")
		(net "P5E_PEX0_STN0_TX_DP<15>")
	)
	(gr_poly
		(pts
			(arc
				(start 75.052936 -277.849838)
				(mid 74.646536 -277.849838)
				(end 75.052936 -277.849838)
			)
		)
		(stroke
			(width 0)
			(type solid)
		)
		(fill yes)
		(layer "In1.Cu")
		(net "P5E_PEX0_STN0_TX_DN<15>")
	)
	(gr_poly
		(pts
			(arc
				(start 75.052936 -274.049744)
				(mid 74.646536 -274.049744)
				(end 75.052936 -274.049744)
			)
		)
		(stroke
			(width 0)
			(type solid)
		)
		(fill yes)
		(layer "In1.Cu")
		(net "P5E_PEX0_STN0_RX_DP<15>")
	)
	(gr_poly
		(pts
			(arc
				(start 75.052936 -273.099784)
				(mid 74.646536 -273.099784)
				(end 75.052936 -273.099784)
			)
		)
		(stroke
			(width 0)
			(type solid)
		)
		(fill yes)
		(layer "In1.Cu")
		(net "P5E_PEX0_STN0_RX_DN<15>")
	)
	(gr_poly
		(pts
			(arc
				(start 75.05319 -318.699896)
				(mid 74.64679 -318.699896)
				(end 75.05319 -318.699896)
			)
		)
		(stroke
			(width 0)
			(type solid)
		)
		(fill yes)
		(layer "In1.Cu")
		(net "P5E_PEX0_STN4_RX_DN<78>")
	)
	(gr_poly
		(pts
			(arc
				(start 75.05319 -317.749936)
				(mid 74.64679 -317.749936)
				(end 75.05319 -317.749936)
			)
		)
		(stroke
			(width 0)
			(type solid)
		)
		(fill yes)
		(layer "In1.Cu")
		(net "P5E_PEX0_STN4_RX_DP<78>")
	)
	(gr_poly
		(pts
			(arc
				(start 75.05319 -313.949842)
				(mid 74.64679 -313.949842)
				(end 75.05319 -313.949842)
			)
		)
		(stroke
			(width 0)
			(type solid)
		)
		(fill yes)
		(layer "In1.Cu")
		(net "P5E_PEX0_STN4_TX_DN<78>")
	)
	(gr_poly
		(pts
			(arc
				(start 75.05319 -312.999882)
				(mid 74.64679 -312.999882)
				(end 75.05319 -312.999882)
			)
		)
		(stroke
			(width 0)
			(type solid)
		)
		(fill yes)
		(layer "In1.Cu")
		(net "P5E_PEX0_STN4_TX_DP<78>")
	)
	(gr_poly
		(pts
			(arc
				(start 75.05319 -308.249828)
				(mid 74.64679 -308.249828)
				(end 75.05319 -308.249828)
			)
		)
		(stroke
			(width 0)
			(type solid)
		)
		(fill yes)
		(layer "In1.Cu")
		(net "P5E_PEX0_STN4_TX_DP<68>")
	)
	(gr_poly
		(pts
			(arc
				(start 75.05319 -306.349908)
				(mid 74.64679 -306.349908)
				(end 75.05319 -306.349908)
			)
		)
		(stroke
			(width 0)
			(type solid)
		)
		(fill yes)
		(layer "In1.Cu")
		(net "P5E_PEX0_STN4_TX_DP<66>")
	)
	(gr_poly
		(pts
			(arc
				(start 75.05319 -304.449734)
				(mid 74.64679 -304.449734)
				(end 75.05319 -304.449734)
			)
		)
		(stroke
			(width 0)
			(type solid)
		)
		(fill yes)
		(layer "In1.Cu")
		(net "P5E_PEX0_STN4_TX_DP<64>")
	)
	(gr_poly
		(pts
			(arc
				(start 76.002896 -275.949664)
				(mid 75.596496 -275.949664)
				(end 76.002896 -275.949664)
			)
		)
		(stroke
			(width 0)
			(type solid)
		)
		(fill yes)
		(layer "In1.Cu")
		(net "P5E_PEX0_STN0_RX_DP<14>")
	)
	(gr_poly
		(pts
			(arc
				(start 76.002896 -274.999704)
				(mid 75.596496 -274.999704)
				(end 76.002896 -274.999704)
			)
		)
		(stroke
			(width 0)
			(type solid)
		)
		(fill yes)
		(layer "In1.Cu")
		(net "P5E_PEX0_STN0_RX_DN<14>")
	)
	(gr_poly
		(pts
			(arc
				(start 76.00315 -316.799722)
				(mid 75.59675 -316.799722)
				(end 76.00315 -316.799722)
			)
		)
		(stroke
			(width 0)
			(type solid)
		)
		(fill yes)
		(layer "In1.Cu")
		(net "P5E_PEX0_STN4_RX_DN<77>")
	)
	(gr_poly
		(pts
			(arc
				(start 76.00315 -315.849762)
				(mid 75.59675 -315.849762)
				(end 76.00315 -315.849762)
			)
		)
		(stroke
			(width 0)
			(type solid)
		)
		(fill yes)
		(layer "In1.Cu")
		(net "P5E_PEX0_STN4_RX_DP<77>")
	)
	(gr_poly
		(pts
			(arc
				(start 76.00315 -312.049922)
				(mid 75.59675 -312.049922)
				(end 76.00315 -312.049922)
			)
		)
		(stroke
			(width 0)
			(type solid)
		)
		(fill yes)
		(layer "In1.Cu")
		(net "P5E_PEX0_STN4_TX_DN<77>")
	)
	(gr_poly
		(pts
			(arc
				(start 76.00315 -311.099962)
				(mid 75.59675 -311.099962)
				(end 76.00315 -311.099962)
			)
		)
		(stroke
			(width 0)
			(type solid)
		)
		(fill yes)
		(layer "In1.Cu")
		(net "P5E_PEX0_STN4_TX_DP<77>")
	)
	(gr_poly
		(pts
			(arc
				(start 76.00315 -308.249828)
				(mid 75.59675 -308.249828)
				(end 76.00315 -308.249828)
			)
		)
		(stroke
			(width 0)
			(type solid)
		)
		(fill yes)
		(layer "In1.Cu")
		(net "P5E_PEX0_STN4_TX_DN<68>")
	)
	(gr_poly
		(pts
			(arc
				(start 76.00315 -306.349908)
				(mid 75.59675 -306.349908)
				(end 76.00315 -306.349908)
			)
		)
		(stroke
			(width 0)
			(type solid)
		)
		(fill yes)
		(layer "In1.Cu")
		(net "P5E_PEX0_STN4_TX_DN<66>")
	)
	(gr_poly
		(pts
			(arc
				(start 76.00315 -304.449734)
				(mid 75.59675 -304.449734)
				(end 76.00315 -304.449734)
			)
		)
		(stroke
			(width 0)
			(type solid)
		)
		(fill yes)
		(layer "In1.Cu")
		(net "P5E_PEX0_STN4_TX_DN<64>")
	)
	(gr_poly
		(pts
			(arc
				(start 76.00315 -287.349946)
				(mid 75.59675 -287.349946)
				(end 76.00315 -287.349946)
			)
		)
		(stroke
			(width 0)
			(type solid)
		)
		(fill yes)
		(layer "In1.Cu")
		(net "P5E_PEX0_STN0_TX_DN<1>")
	)
	(gr_poly
		(pts
			(arc
				(start 76.00315 -285.449772)
				(mid 75.59675 -285.449772)
				(end 76.00315 -285.449772)
			)
		)
		(stroke
			(width 0)
			(type solid)
		)
		(fill yes)
		(layer "In1.Cu")
		(net "P5E_PEX0_STN0_TX_DN<3>")
	)
	(gr_poly
		(pts
			(arc
				(start 76.00315 -283.549852)
				(mid 75.59675 -283.549852)
				(end 76.00315 -283.549852)
			)
		)
		(stroke
			(width 0)
			(type solid)
		)
		(fill yes)
		(layer "In1.Cu")
		(net "P5E_PEX0_STN0_TX_DN<5>")
	)
	(gr_poly
		(pts
			(arc
				(start 76.00315 -280.699718)
				(mid 75.59675 -280.699718)
				(end 76.00315 -280.699718)
			)
		)
		(stroke
			(width 0)
			(type solid)
		)
		(fill yes)
		(layer "In1.Cu")
		(net "P5E_PEX0_STN0_TX_DN<14>")
	)
	(gr_poly
		(pts
			(arc
				(start 76.00315 -279.749504)
				(mid 75.59675 -279.749504)
				(end 76.00315 -279.749504)
			)
		)
		(stroke
			(width 0)
			(type solid)
		)
		(fill yes)
		(layer "In1.Cu")
		(net "P5E_PEX0_STN0_TX_DP<14>")
	)
	(gr_poly
		(pts
			(arc
				(start 76.952856 -278.799798)
				(mid 76.546456 -278.799798)
				(end 76.952856 -278.799798)
			)
		)
		(stroke
			(width 0)
			(type solid)
		)
		(fill yes)
		(layer "In1.Cu")
		(net "P5E_PEX0_STN0_TX_DP<13>")
	)
	(gr_poly
		(pts
			(arc
				(start 76.952856 -277.849838)
				(mid 76.546456 -277.849838)
				(end 76.952856 -277.849838)
			)
		)
		(stroke
			(width 0)
			(type solid)
		)
		(fill yes)
		(layer "In1.Cu")
		(net "P5E_PEX0_STN0_TX_DN<13>")
	)
	(gr_poly
		(pts
			(arc
				(start 76.952856 -274.049744)
				(mid 76.546456 -274.049744)
				(end 76.952856 -274.049744)
			)
		)
		(stroke
			(width 0)
			(type solid)
		)
		(fill yes)
		(layer "In1.Cu")
		(net "P5E_PEX0_STN0_RX_DP<13>")
	)
	(gr_poly
		(pts
			(arc
				(start 76.952856 -273.099784)
				(mid 76.546456 -273.099784)
				(end 76.952856 -273.099784)
			)
		)
		(stroke
			(width 0)
			(type solid)
		)
		(fill yes)
		(layer "In1.Cu")
		(net "P5E_PEX0_STN0_RX_DN<13>")
	)
	(gr_poly
		(pts
			(arc
				(start 76.95311 -318.699896)
				(mid 76.54671 -318.699896)
				(end 76.95311 -318.699896)
			)
		)
		(stroke
			(width 0)
			(type solid)
		)
		(fill yes)
		(layer "In1.Cu")
		(net "P5E_PEX0_STN4_RX_DN<76>")
	)
	(gr_poly
		(pts
			(arc
				(start 76.95311 -317.749936)
				(mid 76.54671 -317.749936)
				(end 76.95311 -317.749936)
			)
		)
		(stroke
			(width 0)
			(type solid)
		)
		(fill yes)
		(layer "In1.Cu")
		(net "P5E_PEX0_STN4_RX_DP<76>")
	)
	(gr_poly
		(pts
			(arc
				(start 76.95311 -313.949842)
				(mid 76.54671 -313.949842)
				(end 76.95311 -313.949842)
			)
		)
		(stroke
			(width 0)
			(type solid)
		)
		(fill yes)
		(layer "In1.Cu")
		(net "P5E_PEX0_STN4_TX_DN<76>")
	)
	(gr_poly
		(pts
			(arc
				(start 76.95311 -312.999882)
				(mid 76.54671 -312.999882)
				(end 76.95311 -312.999882)
			)
		)
		(stroke
			(width 0)
			(type solid)
		)
		(fill yes)
		(layer "In1.Cu")
		(net "P5E_PEX0_STN4_TX_DP<76>")
	)
	(gr_poly
		(pts
			(arc
				(start 76.95311 -309.199788)
				(mid 76.54671 -309.199788)
				(end 76.95311 -309.199788)
			)
		)
		(stroke
			(width 0)
			(type solid)
		)
		(fill yes)
		(layer "In1.Cu")
		(net "P5E_PEX0_STN4_TX_DP<69>")
	)
	(gr_poly
		(pts
			(arc
				(start 76.95311 -307.299868)
				(mid 76.54671 -307.299868)
				(end 76.95311 -307.299868)
			)
		)
		(stroke
			(width 0)
			(type solid)
		)
		(fill yes)
		(layer "In1.Cu")
		(net "P5E_PEX0_STN4_TX_DP<67>")
	)
	(gr_poly
		(pts
			(arc
				(start 76.95311 -305.399948)
				(mid 76.54671 -305.399948)
				(end 76.95311 -305.399948)
			)
		)
		(stroke
			(width 0)
			(type solid)
		)
		(fill yes)
		(layer "In1.Cu")
		(net "P5E_PEX0_STN4_TX_DP<65>")
	)
	(gr_poly
		(pts
			(arc
				(start 76.95311 -288.299906)
				(mid 76.54671 -288.299906)
				(end 76.95311 -288.299906)
			)
		)
		(stroke
			(width 0)
			(type solid)
		)
		(fill yes)
		(layer "In1.Cu")
		(net "P5E_PEX0_STN0_TX_DP<0>")
	)
	(gr_poly
		(pts
			(arc
				(start 76.95311 -286.399986)
				(mid 76.54671 -286.399986)
				(end 76.95311 -286.399986)
			)
		)
		(stroke
			(width 0)
			(type solid)
		)
		(fill yes)
		(layer "In1.Cu")
		(net "P5E_PEX0_STN0_TX_DP<2>")
	)
	(gr_poly
		(pts
			(arc
				(start 76.95311 -284.499812)
				(mid 76.54671 -284.499812)
				(end 76.95311 -284.499812)
			)
		)
		(stroke
			(width 0)
			(type solid)
		)
		(fill yes)
		(layer "In1.Cu")
		(net "P5E_PEX0_STN0_TX_DP<4>")
	)
	(gr_poly
		(pts
			(arc
				(start 76.95311 -282.599892)
				(mid 76.54671 -282.599892)
				(end 76.95311 -282.599892)
			)
		)
		(stroke
			(width 0)
			(type solid)
		)
		(fill yes)
		(layer "In1.Cu")
		(net "P5E_PEX0_STN0_TX_DP<6>")
	)
	(gr_poly
		(pts
			(arc
				(start 77.902816 -275.949918)
				(mid 77.496416 -275.949918)
				(end 77.902816 -275.949918)
			)
		)
		(stroke
			(width 0)
			(type solid)
		)
		(fill yes)
		(layer "In1.Cu")
		(net "P5E_PEX0_STN0_RX_DP<12>")
	)
	(gr_poly
		(pts
			(arc
				(start 77.902816 -274.999958)
				(mid 77.496416 -274.999958)
				(end 77.902816 -274.999958)
			)
		)
		(stroke
			(width 0)
			(type solid)
		)
		(fill yes)
		(layer "In1.Cu")
		(net "P5E_PEX0_STN0_RX_DN<12>")
	)
	(gr_poly
		(pts
			(arc
				(start 77.90307 -316.799722)
				(mid 77.49667 -316.799722)
				(end 77.90307 -316.799722)
			)
		)
		(stroke
			(width 0)
			(type solid)
		)
		(fill yes)
		(layer "In1.Cu")
		(net "P5E_PEX0_STN4_RX_DN<75>")
	)
	(gr_poly
		(pts
			(arc
				(start 77.90307 -315.849762)
				(mid 77.49667 -315.849762)
				(end 77.90307 -315.849762)
			)
		)
		(stroke
			(width 0)
			(type solid)
		)
		(fill yes)
		(layer "In1.Cu")
		(net "P5E_PEX0_STN4_RX_DP<75>")
	)
	(gr_poly
		(pts
			(arc
				(start 77.90307 -312.049922)
				(mid 77.49667 -312.049922)
				(end 77.90307 -312.049922)
			)
		)
		(stroke
			(width 0)
			(type solid)
		)
		(fill yes)
		(layer "In1.Cu")
		(net "P5E_PEX0_STN4_TX_DN<75>")
	)
	(gr_poly
		(pts
			(arc
				(start 77.90307 -311.099962)
				(mid 77.49667 -311.099962)
				(end 77.90307 -311.099962)
			)
		)
		(stroke
			(width 0)
			(type solid)
		)
		(fill yes)
		(layer "In1.Cu")
		(net "P5E_PEX0_STN4_TX_DP<75>")
	)
	(gr_poly
		(pts
			(arc
				(start 77.90307 -309.199788)
				(mid 77.49667 -309.199788)
				(end 77.90307 -309.199788)
			)
		)
		(stroke
			(width 0)
			(type solid)
		)
		(fill yes)
		(layer "In1.Cu")
		(net "P5E_PEX0_STN4_TX_DN<69>")
	)
	(gr_poly
		(pts
			(arc
				(start 77.90307 -307.299868)
				(mid 77.49667 -307.299868)
				(end 77.90307 -307.299868)
			)
		)
		(stroke
			(width 0)
			(type solid)
		)
		(fill yes)
		(layer "In1.Cu")
		(net "P5E_PEX0_STN4_TX_DN<67>")
	)
	(gr_poly
		(pts
			(arc
				(start 77.90307 -305.399948)
				(mid 77.49667 -305.399948)
				(end 77.90307 -305.399948)
			)
		)
		(stroke
			(width 0)
			(type solid)
		)
		(fill yes)
		(layer "In1.Cu")
		(net "P5E_PEX0_STN4_TX_DN<65>")
	)
	(gr_poly
		(pts
			(arc
				(start 77.90307 -288.299906)
				(mid 77.49667 -288.299906)
				(end 77.90307 -288.299906)
			)
		)
		(stroke
			(width 0)
			(type solid)
		)
		(fill yes)
		(layer "In1.Cu")
		(net "P5E_PEX0_STN0_TX_DN<0>")
	)
	(gr_poly
		(pts
			(arc
				(start 77.90307 -286.399986)
				(mid 77.49667 -286.399986)
				(end 77.90307 -286.399986)
			)
		)
		(stroke
			(width 0)
			(type solid)
		)
		(fill yes)
		(layer "In1.Cu")
		(net "P5E_PEX0_STN0_TX_DN<2>")
	)
	(gr_poly
		(pts
			(arc
				(start 77.90307 -284.499812)
				(mid 77.49667 -284.499812)
				(end 77.90307 -284.499812)
			)
		)
		(stroke
			(width 0)
			(type solid)
		)
		(fill yes)
		(layer "In1.Cu")
		(net "P5E_PEX0_STN0_TX_DN<4>")
	)
	(gr_poly
		(pts
			(arc
				(start 77.90307 -282.599892)
				(mid 77.49667 -282.599892)
				(end 77.90307 -282.599892)
			)
		)
		(stroke
			(width 0)
			(type solid)
		)
		(fill yes)
		(layer "In1.Cu")
		(net "P5E_PEX0_STN0_TX_DN<6>")
	)
	(gr_poly
		(pts
			(arc
				(start 77.90307 -280.699718)
				(mid 77.49667 -280.699718)
				(end 77.90307 -280.699718)
			)
		)
		(stroke
			(width 0)
			(type solid)
		)
		(fill yes)
		(layer "In1.Cu")
		(net "P5E_PEX0_STN0_TX_DN<12>")
	)
	(gr_poly
		(pts
			(arc
				(start 77.90307 -279.749504)
				(mid 77.49667 -279.749504)
				(end 77.90307 -279.749504)
			)
		)
		(stroke
			(width 0)
			(type solid)
		)
		(fill yes)
		(layer "In1.Cu")
		(net "P5E_PEX0_STN0_TX_DP<12>")
	)
	(gr_poly
		(pts
			(arc
				(start 78.852776 -278.799798)
				(mid 78.446376 -278.799798)
				(end 78.852776 -278.799798)
			)
		)
		(stroke
			(width 0)
			(type solid)
		)
		(fill yes)
		(layer "In1.Cu")
		(net "P5E_PEX0_STN0_TX_DP<11>")
	)
	(gr_poly
		(pts
			(arc
				(start 78.852776 -277.849838)
				(mid 78.446376 -277.849838)
				(end 78.852776 -277.849838)
			)
		)
		(stroke
			(width 0)
			(type solid)
		)
		(fill yes)
		(layer "In1.Cu")
		(net "P5E_PEX0_STN0_TX_DN<11>")
	)
	(gr_poly
		(pts
			(arc
				(start 78.852776 -274.049744)
				(mid 78.446376 -274.049744)
				(end 78.852776 -274.049744)
			)
		)
		(stroke
			(width 0)
			(type solid)
		)
		(fill yes)
		(layer "In1.Cu")
		(net "P5E_PEX0_STN0_RX_DP<11>")
	)
	(gr_poly
		(pts
			(arc
				(start 78.852776 -273.099784)
				(mid 78.446376 -273.099784)
				(end 78.852776 -273.099784)
			)
		)
		(stroke
			(width 0)
			(type solid)
		)
		(fill yes)
		(layer "In1.Cu")
		(net "P5E_PEX0_STN0_RX_DN<11>")
	)
	(gr_poly
		(pts
			(arc
				(start 78.85303 -318.699896)
				(mid 78.44663 -318.699896)
				(end 78.85303 -318.699896)
			)
		)
		(stroke
			(width 0)
			(type solid)
		)
		(fill yes)
		(layer "In1.Cu")
		(net "P5E_PEX0_STN4_RX_DN<74>")
	)
	(gr_poly
		(pts
			(arc
				(start 78.85303 -317.749936)
				(mid 78.44663 -317.749936)
				(end 78.85303 -317.749936)
			)
		)
		(stroke
			(width 0)
			(type solid)
		)
		(fill yes)
		(layer "In1.Cu")
		(net "P5E_PEX0_STN4_RX_DP<74>")
	)
	(gr_poly
		(pts
			(arc
				(start 78.85303 -313.949842)
				(mid 78.44663 -313.949842)
				(end 78.85303 -313.949842)
			)
		)
		(stroke
			(width 0)
			(type solid)
		)
		(fill yes)
		(layer "In1.Cu")
		(net "P5E_PEX0_STN4_TX_DN<74>")
	)
	(gr_poly
		(pts
			(arc
				(start 78.85303 -312.999882)
				(mid 78.44663 -312.999882)
				(end 78.85303 -312.999882)
			)
		)
		(stroke
			(width 0)
			(type solid)
		)
		(fill yes)
		(layer "In1.Cu")
		(net "P5E_PEX0_STN4_TX_DP<74>")
	)
	(gr_poly
		(pts
			(arc
				(start 79.802736 -275.949918)
				(mid 79.396336 -275.949918)
				(end 79.802736 -275.949918)
			)
		)
		(stroke
			(width 0)
			(type solid)
		)
		(fill yes)
		(layer "In1.Cu")
		(net "P5E_PEX0_STN0_RX_DP<10>")
	)
	(gr_poly
		(pts
			(arc
				(start 79.802736 -274.999958)
				(mid 79.396336 -274.999958)
				(end 79.802736 -274.999958)
			)
		)
		(stroke
			(width 0)
			(type solid)
		)
		(fill yes)
		(layer "In1.Cu")
		(net "P5E_PEX0_STN0_RX_DN<10>")
	)
	(gr_poly
		(pts
			(arc
				(start 79.80299 -316.799722)
				(mid 79.39659 -316.799722)
				(end 79.80299 -316.799722)
			)
		)
		(stroke
			(width 0)
			(type solid)
		)
		(fill yes)
		(layer "In1.Cu")
		(net "P5E_PEX0_STN4_RX_DN<73>")
	)
	(gr_poly
		(pts
			(arc
				(start 79.80299 -315.849762)
				(mid 79.39659 -315.849762)
				(end 79.80299 -315.849762)
			)
		)
		(stroke
			(width 0)
			(type solid)
		)
		(fill yes)
		(layer "In1.Cu")
		(net "P5E_PEX0_STN4_RX_DP<73>")
	)
	(gr_poly
		(pts
			(arc
				(start 79.80299 -312.049922)
				(mid 79.39659 -312.049922)
				(end 79.80299 -312.049922)
			)
		)
		(stroke
			(width 0)
			(type solid)
		)
		(fill yes)
		(layer "In1.Cu")
		(net "P5E_PEX0_STN4_TX_DN<73>")
	)
	(gr_poly
		(pts
			(arc
				(start 79.80299 -311.099962)
				(mid 79.39659 -311.099962)
				(end 79.80299 -311.099962)
			)
		)
		(stroke
			(width 0)
			(type solid)
		)
		(fill yes)
		(layer "In1.Cu")
		(net "P5E_PEX0_STN4_TX_DP<73>")
	)
	(gr_poly
		(pts
			(arc
				(start 79.80299 -309.199788)
				(mid 79.39659 -309.199788)
				(end 79.80299 -309.199788)
			)
		)
		(stroke
			(width 0)
			(type solid)
		)
		(fill yes)
		(layer "In1.Cu")
		(net "P5E_PEX0_STN4_RX_DP<69>")
	)
	(gr_poly
		(pts
			(arc
				(start 79.80299 -307.299868)
				(mid 79.39659 -307.299868)
				(end 79.80299 -307.299868)
			)
		)
		(stroke
			(width 0)
			(type solid)
		)
		(fill yes)
		(layer "In1.Cu")
		(net "P5E_PEX0_STN4_RX_DP<67>")
	)
	(gr_poly
		(pts
			(arc
				(start 79.80299 -305.399948)
				(mid 79.39659 -305.399948)
				(end 79.80299 -305.399948)
			)
		)
		(stroke
			(width 0)
			(type solid)
		)
		(fill yes)
		(layer "In1.Cu")
		(net "P5E_PEX0_STN4_RX_DP<65>")
	)
	(gr_poly
		(pts
			(arc
				(start 79.80299 -288.299906)
				(mid 79.39659 -288.299906)
				(end 79.80299 -288.299906)
			)
		)
		(stroke
			(width 0)
			(type solid)
		)
		(fill yes)
		(layer "In1.Cu")
		(net "P5E_PEX0_STN0_RX_DP<0>")
	)
	(gr_poly
		(pts
			(arc
				(start 79.80299 -286.399732)
				(mid 79.39659 -286.399732)
				(end 79.80299 -286.399732)
			)
		)
		(stroke
			(width 0)
			(type solid)
		)
		(fill yes)
		(layer "In1.Cu")
		(net "P5E_PEX0_STN0_RX_DP<2>")
	)
	(gr_poly
		(pts
			(arc
				(start 79.80299 -284.499812)
				(mid 79.39659 -284.499812)
				(end 79.80299 -284.499812)
			)
		)
		(stroke
			(width 0)
			(type solid)
		)
		(fill yes)
		(layer "In1.Cu")
		(net "P5E_PEX0_STN0_RX_DP<4>")
	)
	(gr_poly
		(pts
			(arc
				(start 79.80299 -282.599892)
				(mid 79.39659 -282.599892)
				(end 79.80299 -282.599892)
			)
		)
		(stroke
			(width 0)
			(type solid)
		)
		(fill yes)
		(layer "In1.Cu")
		(net "P5E_PEX0_STN0_RX_DP<6>")
	)
	(gr_poly
		(pts
			(arc
				(start 79.80299 -280.699718)
				(mid 79.39659 -280.699718)
				(end 79.80299 -280.699718)
			)
		)
		(stroke
			(width 0)
			(type solid)
		)
		(fill yes)
		(layer "In1.Cu")
		(net "P5E_PEX0_STN0_TX_DP<10>")
	)
	(gr_poly
		(pts
			(arc
				(start 79.80299 -279.749758)
				(mid 79.39659 -279.749758)
				(end 79.80299 -279.749758)
			)
		)
		(stroke
			(width 0)
			(type solid)
		)
		(fill yes)
		(layer "In1.Cu")
		(net "P5E_PEX0_STN0_TX_DN<10>")
	)
	(gr_poly
		(pts
			(arc
				(start 80.752696 -274.049744)
				(mid 80.346296 -274.049744)
				(end 80.752696 -274.049744)
			)
		)
		(stroke
			(width 0)
			(type solid)
		)
		(fill yes)
		(layer "In1.Cu")
		(net "P5E_PEX0_STN0_RX_DP<9>")
	)
	(gr_poly
		(pts
			(arc
				(start 80.752696 -273.099784)
				(mid 80.346296 -273.099784)
				(end 80.752696 -273.099784)
			)
		)
		(stroke
			(width 0)
			(type solid)
		)
		(fill yes)
		(layer "In1.Cu")
		(net "P5E_PEX0_STN0_RX_DN<9>")
	)
	(gr_poly
		(pts
			(arc
				(start 80.75295 -318.699896)
				(mid 80.34655 -318.699896)
				(end 80.75295 -318.699896)
			)
		)
		(stroke
			(width 0)
			(type solid)
		)
		(fill yes)
		(layer "In1.Cu")
		(net "P5E_PEX0_STN4_RX_DN<72>")
	)
	(gr_poly
		(pts
			(arc
				(start 80.75295 -317.749936)
				(mid 80.34655 -317.749936)
				(end 80.75295 -317.749936)
			)
		)
		(stroke
			(width 0)
			(type solid)
		)
		(fill yes)
		(layer "In1.Cu")
		(net "P5E_PEX0_STN4_RX_DP<72>")
	)
	(gr_poly
		(pts
			(arc
				(start 80.75295 -313.949842)
				(mid 80.34655 -313.949842)
				(end 80.75295 -313.949842)
			)
		)
		(stroke
			(width 0)
			(type solid)
		)
		(fill yes)
		(layer "In1.Cu")
		(net "P5E_PEX0_STN4_TX_DN<72>")
	)
	(gr_poly
		(pts
			(arc
				(start 80.75295 -312.999882)
				(mid 80.34655 -312.999882)
				(end 80.75295 -312.999882)
			)
		)
		(stroke
			(width 0)
			(type solid)
		)
		(fill yes)
		(layer "In1.Cu")
		(net "P5E_PEX0_STN4_TX_DP<72>")
	)
	(gr_poly
		(pts
			(arc
				(start 80.75295 -309.199788)
				(mid 80.34655 -309.199788)
				(end 80.75295 -309.199788)
			)
		)
		(stroke
			(width 0)
			(type solid)
		)
		(fill yes)
		(layer "In1.Cu")
		(net "P5E_PEX0_STN4_RX_DN<69>")
	)
	(gr_poly
		(pts
			(arc
				(start 80.75295 -307.299868)
				(mid 80.34655 -307.299868)
				(end 80.75295 -307.299868)
			)
		)
		(stroke
			(width 0)
			(type solid)
		)
		(fill yes)
		(layer "In1.Cu")
		(net "P5E_PEX0_STN4_RX_DN<67>")
	)
	(gr_poly
		(pts
			(arc
				(start 80.75295 -305.399948)
				(mid 80.34655 -305.399948)
				(end 80.75295 -305.399948)
			)
		)
		(stroke
			(width 0)
			(type solid)
		)
		(fill yes)
		(layer "In1.Cu")
		(net "P5E_PEX0_STN4_RX_DN<65>")
	)
	(gr_poly
		(pts
			(arc
				(start 80.75295 -288.299906)
				(mid 80.34655 -288.299906)
				(end 80.75295 -288.299906)
			)
		)
		(stroke
			(width 0)
			(type solid)
		)
		(fill yes)
		(layer "In1.Cu")
		(net "P5E_PEX0_STN0_RX_DN<0>")
	)
	(gr_poly
		(pts
			(arc
				(start 80.75295 -286.399732)
				(mid 80.34655 -286.399732)
				(end 80.75295 -286.399732)
			)
		)
		(stroke
			(width 0)
			(type solid)
		)
		(fill yes)
		(layer "In1.Cu")
		(net "P5E_PEX0_STN0_RX_DN<2>")
	)
	(gr_poly
		(pts
			(arc
				(start 80.75295 -284.499812)
				(mid 80.34655 -284.499812)
				(end 80.75295 -284.499812)
			)
		)
		(stroke
			(width 0)
			(type solid)
		)
		(fill yes)
		(layer "In1.Cu")
		(net "P5E_PEX0_STN0_RX_DN<4>")
	)
	(gr_poly
		(pts
			(arc
				(start 80.75295 -282.599892)
				(mid 80.34655 -282.599892)
				(end 80.75295 -282.599892)
			)
		)
		(stroke
			(width 0)
			(type solid)
		)
		(fill yes)
		(layer "In1.Cu")
		(net "P5E_PEX0_STN0_RX_DN<6>")
	)
	(gr_poly
		(pts
			(arc
				(start 80.75295 -278.799798)
				(mid 80.34655 -278.799798)
				(end 80.75295 -278.799798)
			)
		)
		(stroke
			(width 0)
			(type solid)
		)
		(fill yes)
		(layer "In1.Cu")
		(net "P5E_PEX0_STN0_TX_DP<9>")
	)
	(gr_poly
		(pts
			(arc
				(start 80.75295 -277.849838)
				(mid 80.34655 -277.849838)
				(end 80.75295 -277.849838)
			)
		)
		(stroke
			(width 0)
			(type solid)
		)
		(fill yes)
		(layer "In1.Cu")
		(net "P5E_PEX0_STN0_TX_DN<9>")
	)
	(gr_poly
		(pts
			(arc
				(start 81.703164 -316.799722)
				(mid 81.296764 -316.799722)
				(end 81.703164 -316.799722)
			)
		)
		(stroke
			(width 0)
			(type solid)
		)
		(fill yes)
		(layer "In1.Cu")
		(net "P5E_PEX0_STN4_RX_DP<71>")
	)
	(gr_poly
		(pts
			(arc
				(start 81.703164 -314.899802)
				(mid 81.296764 -314.899802)
				(end 81.703164 -314.899802)
			)
		)
		(stroke
			(width 0)
			(type solid)
		)
		(fill yes)
		(layer "In1.Cu")
		(net "P5E_PEX0_STN4_TX_DP<71>")
	)
	(gr_poly
		(pts
			(arc
				(start 81.703164 -312.049922)
				(mid 81.296764 -312.049922)
				(end 81.703164 -312.049922)
			)
		)
		(stroke
			(width 0)
			(type solid)
		)
		(fill yes)
		(layer "In1.Cu")
		(net "P5E_PEX0_STN4_TX_DP<70>")
	)
	(gr_poly
		(pts
			(arc
				(start 81.703164 -310.149748)
				(mid 81.296764 -310.149748)
				(end 81.703164 -310.149748)
			)
		)
		(stroke
			(width 0)
			(type solid)
		)
		(fill yes)
		(layer "In1.Cu")
		(net "P5E_PEX0_STN4_RX_DP<70>")
	)
	(gr_poly
		(pts
			(arc
				(start 81.703164 -308.249828)
				(mid 81.296764 -308.249828)
				(end 81.703164 -308.249828)
			)
		)
		(stroke
			(width 0)
			(type solid)
		)
		(fill yes)
		(layer "In1.Cu")
		(net "P5E_PEX0_STN4_RX_DP<68>")
	)
	(gr_poly
		(pts
			(arc
				(start 81.703164 -306.349908)
				(mid 81.296764 -306.349908)
				(end 81.703164 -306.349908)
			)
		)
		(stroke
			(width 0)
			(type solid)
		)
		(fill yes)
		(layer "In1.Cu")
		(net "P5E_PEX0_STN4_RX_DP<66>")
	)
	(gr_poly
		(pts
			(arc
				(start 81.703164 -304.449734)
				(mid 81.296764 -304.449734)
				(end 81.703164 -304.449734)
			)
		)
		(stroke
			(width 0)
			(type solid)
		)
		(fill yes)
		(layer "In1.Cu")
		(net "P5E_PEX0_STN4_RX_DP<64>")
	)
	(gr_poly
		(pts
			(arc
				(start 81.703164 -287.349946)
				(mid 81.296764 -287.349946)
				(end 81.703164 -287.349946)
			)
		)
		(stroke
			(width 0)
			(type solid)
		)
		(fill yes)
		(layer "In1.Cu")
		(net "P5E_PEX0_STN0_RX_DP<1>")
	)
	(gr_poly
		(pts
			(arc
				(start 81.703164 -285.449772)
				(mid 81.296764 -285.449772)
				(end 81.703164 -285.449772)
			)
		)
		(stroke
			(width 0)
			(type solid)
		)
		(fill yes)
		(layer "In1.Cu")
		(net "P5E_PEX0_STN0_RX_DP<3>")
	)
	(gr_poly
		(pts
			(arc
				(start 81.703164 -283.549852)
				(mid 81.296764 -283.549852)
				(end 81.703164 -283.549852)
			)
		)
		(stroke
			(width 0)
			(type solid)
		)
		(fill yes)
		(layer "In1.Cu")
		(net "P5E_PEX0_STN0_RX_DP<5>")
	)
	(gr_poly
		(pts
			(arc
				(start 81.703164 -281.649932)
				(mid 81.296764 -281.649932)
				(end 81.703164 -281.649932)
			)
		)
		(stroke
			(width 0)
			(type solid)
		)
		(fill yes)
		(layer "In1.Cu")
		(net "P5E_PEX0_STN0_RX_DP<7>")
	)
	(gr_poly
		(pts
			(arc
				(start 81.703164 -279.749758)
				(mid 81.296764 -279.749758)
				(end 81.703164 -279.749758)
			)
		)
		(stroke
			(width 0)
			(type solid)
		)
		(fill yes)
		(layer "In1.Cu")
		(net "P5E_PEX0_STN0_TX_DP<7>")
	)
	(gr_poly
		(pts
			(arc
				(start 81.703164 -276.899878)
				(mid 81.296764 -276.899878)
				(end 81.703164 -276.899878)
			)
		)
		(stroke
			(width 0)
			(type solid)
		)
		(fill yes)
		(layer "In1.Cu")
		(net "P5E_PEX0_STN0_TX_DP<8>")
	)
	(gr_poly
		(pts
			(arc
				(start 81.703164 -274.999704)
				(mid 81.296764 -274.999704)
				(end 81.703164 -274.999704)
			)
		)
		(stroke
			(width 0)
			(type solid)
		)
		(fill yes)
		(layer "In1.Cu")
		(net "P5E_PEX0_STN0_RX_DP<8>")
	)
	(gr_poly
		(pts
			(arc
				(start 82.653124 -316.799722)
				(mid 82.246724 -316.799722)
				(end 82.653124 -316.799722)
			)
		)
		(stroke
			(width 0)
			(type solid)
		)
		(fill yes)
		(layer "In1.Cu")
		(net "P5E_PEX0_STN4_RX_DN<71>")
	)
	(gr_poly
		(pts
			(arc
				(start 82.653124 -314.899802)
				(mid 82.246724 -314.899802)
				(end 82.653124 -314.899802)
			)
		)
		(stroke
			(width 0)
			(type solid)
		)
		(fill yes)
		(layer "In1.Cu")
		(net "P5E_PEX0_STN4_TX_DN<71>")
	)
	(gr_poly
		(pts
			(arc
				(start 82.653124 -312.049922)
				(mid 82.246724 -312.049922)
				(end 82.653124 -312.049922)
			)
		)
		(stroke
			(width 0)
			(type solid)
		)
		(fill yes)
		(layer "In1.Cu")
		(net "P5E_PEX0_STN4_TX_DN<70>")
	)
	(gr_poly
		(pts
			(arc
				(start 82.653124 -310.149748)
				(mid 82.246724 -310.149748)
				(end 82.653124 -310.149748)
			)
		)
		(stroke
			(width 0)
			(type solid)
		)
		(fill yes)
		(layer "In1.Cu")
		(net "P5E_PEX0_STN4_RX_DN<70>")
	)
	(gr_poly
		(pts
			(arc
				(start 82.653124 -308.249828)
				(mid 82.246724 -308.249828)
				(end 82.653124 -308.249828)
			)
		)
		(stroke
			(width 0)
			(type solid)
		)
		(fill yes)
		(layer "In1.Cu")
		(net "P5E_PEX0_STN4_RX_DN<68>")
	)
	(gr_poly
		(pts
			(arc
				(start 82.653124 -306.349908)
				(mid 82.246724 -306.349908)
				(end 82.653124 -306.349908)
			)
		)
		(stroke
			(width 0)
			(type solid)
		)
		(fill yes)
		(layer "In1.Cu")
		(net "P5E_PEX0_STN4_RX_DN<66>")
	)
	(gr_poly
		(pts
			(arc
				(start 82.653124 -304.449734)
				(mid 82.246724 -304.449734)
				(end 82.653124 -304.449734)
			)
		)
		(stroke
			(width 0)
			(type solid)
		)
		(fill yes)
		(layer "In1.Cu")
		(net "P5E_PEX0_STN4_RX_DN<64>")
	)
	(gr_poly
		(pts
			(arc
				(start 82.653124 -287.349946)
				(mid 82.246724 -287.349946)
				(end 82.653124 -287.349946)
			)
		)
		(stroke
			(width 0)
			(type solid)
		)
		(fill yes)
		(layer "In1.Cu")
		(net "P5E_PEX0_STN0_RX_DN<1>")
	)
	(gr_poly
		(pts
			(arc
				(start 82.653124 -285.449772)
				(mid 82.246724 -285.449772)
				(end 82.653124 -285.449772)
			)
		)
		(stroke
			(width 0)
			(type solid)
		)
		(fill yes)
		(layer "In1.Cu")
		(net "P5E_PEX0_STN0_RX_DN<3>")
	)
	(gr_poly
		(pts
			(arc
				(start 82.653124 -283.549852)
				(mid 82.246724 -283.549852)
				(end 82.653124 -283.549852)
			)
		)
		(stroke
			(width 0)
			(type solid)
		)
		(fill yes)
		(layer "In1.Cu")
		(net "P5E_PEX0_STN0_RX_DN<5>")
	)
	(gr_poly
		(pts
			(arc
				(start 82.653124 -281.649932)
				(mid 82.246724 -281.649932)
				(end 82.653124 -281.649932)
			)
		)
		(stroke
			(width 0)
			(type solid)
		)
		(fill yes)
		(layer "In1.Cu")
		(net "P5E_PEX0_STN0_RX_DN<7>")
	)
	(gr_poly
		(pts
			(arc
				(start 82.653124 -279.749758)
				(mid 82.246724 -279.749758)
				(end 82.653124 -279.749758)
			)
		)
		(stroke
			(width 0)
			(type solid)
		)
		(fill yes)
		(layer "In1.Cu")
		(net "P5E_PEX0_STN0_TX_DN<7>")
	)
	(gr_poly
		(pts
			(arc
				(start 82.653124 -276.899878)
				(mid 82.246724 -276.899878)
				(end 82.653124 -276.899878)
			)
		)
		(stroke
			(width 0)
			(type solid)
		)
		(fill yes)
		(layer "In1.Cu")
		(net "P5E_PEX0_STN0_TX_DN<8>")
	)
	(gr_poly
		(pts
			(arc
				(start 82.653124 -274.999704)
				(mid 82.246724 -274.999704)
				(end 82.653124 -274.999704)
			)
		)
		(stroke
			(width 0)
			(type solid)
		)
		(fill yes)
		(layer "In1.Cu")
		(net "P5E_PEX0_STN0_RX_DN<8>")
	)
	(gr_poly
		(pts
			(arc
				(start 153.15311 -316.799722)
				(mid 152.74671 -316.799722)
				(end 153.15311 -316.799722)
			)
		)
		(stroke
			(width 0)
			(type solid)
		)
		(fill yes)
		(layer "In1.Cu")
		(net "P5E_PEX1_STN7_RX_DN<122>")
	)
	(gr_poly
		(pts
			(arc
				(start 153.15311 -314.899802)
				(mid 152.74671 -314.899802)
				(end 153.15311 -314.899802)
			)
		)
		(stroke
			(width 0)
			(type solid)
		)
		(fill yes)
		(layer "In1.Cu")
		(net "P5E_PEX1_STN7_TX_DN<122>")
	)
	(gr_poly
		(pts
			(arc
				(start 153.15311 -312.049922)
				(mid 152.74671 -312.049922)
				(end 153.15311 -312.049922)
			)
		)
		(stroke
			(width 0)
			(type solid)
		)
		(fill yes)
		(layer "In1.Cu")
		(net "P5E_PEX1_STN7_TX_DN<121>")
	)
	(gr_poly
		(pts
			(arc
				(start 153.15311 -310.149748)
				(mid 152.74671 -310.149748)
				(end 153.15311 -310.149748)
			)
		)
		(stroke
			(width 0)
			(type solid)
		)
		(fill yes)
		(layer "In1.Cu")
		(net "P5E_PEX1_STN7_RX_DN<121>")
	)
	(gr_poly
		(pts
			(arc
				(start 153.15311 -308.249828)
				(mid 152.74671 -308.249828)
				(end 153.15311 -308.249828)
			)
		)
		(stroke
			(width 0)
			(type solid)
		)
		(fill yes)
		(layer "In1.Cu")
		(net "P5E_PEX1_STN7_RX_DN<119>")
	)
	(gr_poly
		(pts
			(arc
				(start 153.15311 -306.349908)
				(mid 152.74671 -306.349908)
				(end 153.15311 -306.349908)
			)
		)
		(stroke
			(width 0)
			(type solid)
		)
		(fill yes)
		(layer "In1.Cu")
		(net "P5E_PEX1_STN7_RX_DN<117>")
	)
	(gr_poly
		(pts
			(arc
				(start 153.15311 -304.449734)
				(mid 152.74671 -304.449734)
				(end 153.15311 -304.449734)
			)
		)
		(stroke
			(width 0)
			(type solid)
		)
		(fill yes)
		(layer "In1.Cu")
		(net "P5E_PEX1_STN7_RX_DN<115>")
	)
	(gr_poly
		(pts
			(arc
				(start 153.15311 -302.549814)
				(mid 152.74671 -302.549814)
				(end 153.15311 -302.549814)
			)
		)
		(stroke
			(width 0)
			(type solid)
		)
		(fill yes)
		(layer "In1.Cu")
		(net "P5E_PEX1_STN7_RX_DN<113>")
	)
	(gr_poly
		(pts
			(arc
				(start 154.10307 -316.799722)
				(mid 153.69667 -316.799722)
				(end 154.10307 -316.799722)
			)
		)
		(stroke
			(width 0)
			(type solid)
		)
		(fill yes)
		(layer "In1.Cu")
		(net "P5E_PEX1_STN7_RX_DP<122>")
	)
	(gr_poly
		(pts
			(arc
				(start 154.10307 -314.899802)
				(mid 153.69667 -314.899802)
				(end 154.10307 -314.899802)
			)
		)
		(stroke
			(width 0)
			(type solid)
		)
		(fill yes)
		(layer "In1.Cu")
		(net "P5E_PEX1_STN7_TX_DP<122>")
	)
	(gr_poly
		(pts
			(arc
				(start 154.10307 -312.049922)
				(mid 153.69667 -312.049922)
				(end 154.10307 -312.049922)
			)
		)
		(stroke
			(width 0)
			(type solid)
		)
		(fill yes)
		(layer "In1.Cu")
		(net "P5E_PEX1_STN7_TX_DP<121>")
	)
	(gr_poly
		(pts
			(arc
				(start 154.10307 -310.149748)
				(mid 153.69667 -310.149748)
				(end 154.10307 -310.149748)
			)
		)
		(stroke
			(width 0)
			(type solid)
		)
		(fill yes)
		(layer "In1.Cu")
		(net "P5E_PEX1_STN7_RX_DP<121>")
	)
	(gr_poly
		(pts
			(arc
				(start 154.10307 -308.249828)
				(mid 153.69667 -308.249828)
				(end 154.10307 -308.249828)
			)
		)
		(stroke
			(width 0)
			(type solid)
		)
		(fill yes)
		(layer "In1.Cu")
		(net "P5E_PEX1_STN7_RX_DP<119>")
	)
	(gr_poly
		(pts
			(arc
				(start 154.10307 -306.349908)
				(mid 153.69667 -306.349908)
				(end 154.10307 -306.349908)
			)
		)
		(stroke
			(width 0)
			(type solid)
		)
		(fill yes)
		(layer "In1.Cu")
		(net "P5E_PEX1_STN7_RX_DP<117>")
	)
	(gr_poly
		(pts
			(arc
				(start 154.10307 -304.449734)
				(mid 153.69667 -304.449734)
				(end 154.10307 -304.449734)
			)
		)
		(stroke
			(width 0)
			(type solid)
		)
		(fill yes)
		(layer "In1.Cu")
		(net "P5E_PEX1_STN7_RX_DP<115>")
	)
	(gr_poly
		(pts
			(arc
				(start 154.10307 -302.549814)
				(mid 153.69667 -302.549814)
				(end 154.10307 -302.549814)
			)
		)
		(stroke
			(width 0)
			(type solid)
		)
		(fill yes)
		(layer "In1.Cu")
		(net "P5E_PEX1_STN7_RX_DP<113>")
	)
	(gr_poly
		(pts
			(arc
				(start 155.053284 -318.699896)
				(mid 154.646884 -318.699896)
				(end 155.053284 -318.699896)
			)
		)
		(stroke
			(width 0)
			(type solid)
		)
		(fill yes)
		(layer "In1.Cu")
		(net "P5E_PEX1_STN7_RX_DN<123>")
	)
	(gr_poly
		(pts
			(arc
				(start 155.053284 -317.749936)
				(mid 154.646884 -317.749936)
				(end 155.053284 -317.749936)
			)
		)
		(stroke
			(width 0)
			(type solid)
		)
		(fill yes)
		(layer "In1.Cu")
		(net "P5E_PEX1_STN7_RX_DP<123>")
	)
	(gr_poly
		(pts
			(arc
				(start 155.053284 -313.949842)
				(mid 154.646884 -313.949842)
				(end 155.053284 -313.949842)
			)
		)
		(stroke
			(width 0)
			(type solid)
		)
		(fill yes)
		(layer "In1.Cu")
		(net "P5E_PEX1_STN7_TX_DN<123>")
	)
	(gr_poly
		(pts
			(arc
				(start 155.053284 -312.999882)
				(mid 154.646884 -312.999882)
				(end 155.053284 -312.999882)
			)
		)
		(stroke
			(width 0)
			(type solid)
		)
		(fill yes)
		(layer "In1.Cu")
		(net "P5E_PEX1_STN7_TX_DP<123>")
	)
	(gr_poly
		(pts
			(arc
				(start 155.053284 -309.199788)
				(mid 154.646884 -309.199788)
				(end 155.053284 -309.199788)
			)
		)
		(stroke
			(width 0)
			(type solid)
		)
		(fill yes)
		(layer "In1.Cu")
		(net "P5E_PEX1_STN7_RX_DN<120>")
	)
	(gr_poly
		(pts
			(arc
				(start 155.053284 -307.299868)
				(mid 154.646884 -307.299868)
				(end 155.053284 -307.299868)
			)
		)
		(stroke
			(width 0)
			(type solid)
		)
		(fill yes)
		(layer "In1.Cu")
		(net "P5E_PEX1_STN7_RX_DN<118>")
	)
	(gr_poly
		(pts
			(arc
				(start 155.053284 -305.399948)
				(mid 154.646884 -305.399948)
				(end 155.053284 -305.399948)
			)
		)
		(stroke
			(width 0)
			(type solid)
		)
		(fill yes)
		(layer "In1.Cu")
		(net "P5E_PEX1_STN7_RX_DN<116>")
	)
	(gr_poly
		(pts
			(arc
				(start 155.053284 -303.499774)
				(mid 154.646884 -303.499774)
				(end 155.053284 -303.499774)
			)
		)
		(stroke
			(width 0)
			(type solid)
		)
		(fill yes)
		(layer "In1.Cu")
		(net "P5E_PEX1_STN7_RX_DN<114>")
	)
	(gr_poly
		(pts
			(arc
				(start 155.053284 -301.599854)
				(mid 154.646884 -301.599854)
				(end 155.053284 -301.599854)
			)
		)
		(stroke
			(width 0)
			(type solid)
		)
		(fill yes)
		(layer "In1.Cu")
		(net "P5E_PEX1_STN7_RX_DN<112>")
	)
	(gr_poly
		(pts
			(arc
				(start 156.003244 -316.799722)
				(mid 155.596844 -316.799722)
				(end 156.003244 -316.799722)
			)
		)
		(stroke
			(width 0)
			(type solid)
		)
		(fill yes)
		(layer "In1.Cu")
		(net "P5E_PEX1_STN7_RX_DN<124>")
	)
	(gr_poly
		(pts
			(arc
				(start 156.003244 -315.849762)
				(mid 155.596844 -315.849762)
				(end 156.003244 -315.849762)
			)
		)
		(stroke
			(width 0)
			(type solid)
		)
		(fill yes)
		(layer "In1.Cu")
		(net "P5E_PEX1_STN7_RX_DP<124>")
	)
	(gr_poly
		(pts
			(arc
				(start 156.003244 -312.049922)
				(mid 155.596844 -312.049922)
				(end 156.003244 -312.049922)
			)
		)
		(stroke
			(width 0)
			(type solid)
		)
		(fill yes)
		(layer "In1.Cu")
		(net "P5E_PEX1_STN7_TX_DN<124>")
	)
	(gr_poly
		(pts
			(arc
				(start 156.003244 -311.099962)
				(mid 155.596844 -311.099962)
				(end 156.003244 -311.099962)
			)
		)
		(stroke
			(width 0)
			(type solid)
		)
		(fill yes)
		(layer "In1.Cu")
		(net "P5E_PEX1_STN7_TX_DP<124>")
	)
	(gr_poly
		(pts
			(arc
				(start 156.003244 -309.199788)
				(mid 155.596844 -309.199788)
				(end 156.003244 -309.199788)
			)
		)
		(stroke
			(width 0)
			(type solid)
		)
		(fill yes)
		(layer "In1.Cu")
		(net "P5E_PEX1_STN7_RX_DP<120>")
	)
	(gr_poly
		(pts
			(arc
				(start 156.003244 -307.299868)
				(mid 155.596844 -307.299868)
				(end 156.003244 -307.299868)
			)
		)
		(stroke
			(width 0)
			(type solid)
		)
		(fill yes)
		(layer "In1.Cu")
		(net "P5E_PEX1_STN7_RX_DP<118>")
	)
	(gr_poly
		(pts
			(arc
				(start 156.003244 -305.399948)
				(mid 155.596844 -305.399948)
				(end 156.003244 -305.399948)
			)
		)
		(stroke
			(width 0)
			(type solid)
		)
		(fill yes)
		(layer "In1.Cu")
		(net "P5E_PEX1_STN7_RX_DP<116>")
	)
	(gr_poly
		(pts
			(arc
				(start 156.003244 -303.499774)
				(mid 155.596844 -303.499774)
				(end 156.003244 -303.499774)
			)
		)
		(stroke
			(width 0)
			(type solid)
		)
		(fill yes)
		(layer "In1.Cu")
		(net "P5E_PEX1_STN7_RX_DP<114>")
	)
	(gr_poly
		(pts
			(arc
				(start 156.003244 -301.599854)
				(mid 155.596844 -301.599854)
				(end 156.003244 -301.599854)
			)
		)
		(stroke
			(width 0)
			(type solid)
		)
		(fill yes)
		(layer "In1.Cu")
		(net "P5E_PEX1_STN7_RX_DP<112>")
	)
	(gr_poly
		(pts
			(arc
				(start 156.953204 -318.699896)
				(mid 156.546804 -318.699896)
				(end 156.953204 -318.699896)
			)
		)
		(stroke
			(width 0)
			(type solid)
		)
		(fill yes)
		(layer "In1.Cu")
		(net "P5E_PEX1_STN7_RX_DN<125>")
	)
	(gr_poly
		(pts
			(arc
				(start 156.953204 -317.749936)
				(mid 156.546804 -317.749936)
				(end 156.953204 -317.749936)
			)
		)
		(stroke
			(width 0)
			(type solid)
		)
		(fill yes)
		(layer "In1.Cu")
		(net "P5E_PEX1_STN7_RX_DP<125>")
	)
	(gr_poly
		(pts
			(arc
				(start 156.953204 -313.949842)
				(mid 156.546804 -313.949842)
				(end 156.953204 -313.949842)
			)
		)
		(stroke
			(width 0)
			(type solid)
		)
		(fill yes)
		(layer "In1.Cu")
		(net "P5E_PEX1_STN7_TX_DN<125>")
	)
	(gr_poly
		(pts
			(arc
				(start 156.953204 -312.999882)
				(mid 156.546804 -312.999882)
				(end 156.953204 -312.999882)
			)
		)
		(stroke
			(width 0)
			(type solid)
		)
		(fill yes)
		(layer "In1.Cu")
		(net "P5E_PEX1_STN7_TX_DP<125>")
	)
	(gr_poly
		(pts
			(arc
				(start 157.903164 -316.799722)
				(mid 157.496764 -316.799722)
				(end 157.903164 -316.799722)
			)
		)
		(stroke
			(width 0)
			(type solid)
		)
		(fill yes)
		(layer "In1.Cu")
		(net "P5E_PEX1_STN7_RX_DN<126>")
	)
	(gr_poly
		(pts
			(arc
				(start 157.903164 -315.849762)
				(mid 157.496764 -315.849762)
				(end 157.903164 -315.849762)
			)
		)
		(stroke
			(width 0)
			(type solid)
		)
		(fill yes)
		(layer "In1.Cu")
		(net "P5E_PEX1_STN7_RX_DP<126>")
	)
	(gr_poly
		(pts
			(arc
				(start 157.903164 -312.049922)
				(mid 157.496764 -312.049922)
				(end 157.903164 -312.049922)
			)
		)
		(stroke
			(width 0)
			(type solid)
		)
		(fill yes)
		(layer "In1.Cu")
		(net "P5E_PEX1_STN7_TX_DN<126>")
	)
	(gr_poly
		(pts
			(arc
				(start 157.903164 -311.099962)
				(mid 157.496764 -311.099962)
				(end 157.903164 -311.099962)
			)
		)
		(stroke
			(width 0)
			(type solid)
		)
		(fill yes)
		(layer "In1.Cu")
		(net "P5E_PEX1_STN7_TX_DP<126>")
	)
	(gr_poly
		(pts
			(arc
				(start 157.903164 -309.199788)
				(mid 157.496764 -309.199788)
				(end 157.903164 -309.199788)
			)
		)
		(stroke
			(width 0)
			(type solid)
		)
		(fill yes)
		(layer "In1.Cu")
		(net "P5E_PEX1_STN7_TX_DN<120>")
	)
	(gr_poly
		(pts
			(arc
				(start 157.903164 -307.299868)
				(mid 157.496764 -307.299868)
				(end 157.903164 -307.299868)
			)
		)
		(stroke
			(width 0)
			(type solid)
		)
		(fill yes)
		(layer "In1.Cu")
		(net "P5E_PEX1_STN7_TX_DN<118>")
	)
	(gr_poly
		(pts
			(arc
				(start 157.903164 -305.399948)
				(mid 157.496764 -305.399948)
				(end 157.903164 -305.399948)
			)
		)
		(stroke
			(width 0)
			(type solid)
		)
		(fill yes)
		(layer "In1.Cu")
		(net "P5E_PEX1_STN7_TX_DN<116>")
	)
	(gr_poly
		(pts
			(arc
				(start 157.903164 -303.499774)
				(mid 157.496764 -303.499774)
				(end 157.903164 -303.499774)
			)
		)
		(stroke
			(width 0)
			(type solid)
		)
		(fill yes)
		(layer "In1.Cu")
		(net "P5E_PEX1_STN7_TX_DN<114>")
	)
	(gr_poly
		(pts
			(arc
				(start 157.903164 -301.599854)
				(mid 157.496764 -301.599854)
				(end 157.903164 -301.599854)
			)
		)
		(stroke
			(width 0)
			(type solid)
		)
		(fill yes)
		(layer "In1.Cu")
		(net "P5E_PEX1_STN7_TX_DN<112>")
	)
	(gr_poly
		(pts
			(arc
				(start 158.853124 -318.699896)
				(mid 158.446724 -318.699896)
				(end 158.853124 -318.699896)
			)
		)
		(stroke
			(width 0)
			(type solid)
		)
		(fill yes)
		(layer "In1.Cu")
		(net "P5E_PEX1_STN7_RX_DN<127>")
	)
	(gr_poly
		(pts
			(arc
				(start 158.853124 -317.749936)
				(mid 158.446724 -317.749936)
				(end 158.853124 -317.749936)
			)
		)
		(stroke
			(width 0)
			(type solid)
		)
		(fill yes)
		(layer "In1.Cu")
		(net "P5E_PEX1_STN7_RX_DP<127>")
	)
	(gr_poly
		(pts
			(arc
				(start 158.853124 -313.949842)
				(mid 158.446724 -313.949842)
				(end 158.853124 -313.949842)
			)
		)
		(stroke
			(width 0)
			(type solid)
		)
		(fill yes)
		(layer "In1.Cu")
		(net "P5E_PEX1_STN7_TX_DN<127>")
	)
	(gr_poly
		(pts
			(arc
				(start 158.853124 -312.999882)
				(mid 158.446724 -312.999882)
				(end 158.853124 -312.999882)
			)
		)
		(stroke
			(width 0)
			(type solid)
		)
		(fill yes)
		(layer "In1.Cu")
		(net "P5E_PEX1_STN7_TX_DP<127>")
	)
	(gr_poly
		(pts
			(arc
				(start 158.853124 -309.199788)
				(mid 158.446724 -309.199788)
				(end 158.853124 -309.199788)
			)
		)
		(stroke
			(width 0)
			(type solid)
		)
		(fill yes)
		(layer "In1.Cu")
		(net "P5E_PEX1_STN7_TX_DP<120>")
	)
	(gr_poly
		(pts
			(arc
				(start 158.853124 -307.299868)
				(mid 158.446724 -307.299868)
				(end 158.853124 -307.299868)
			)
		)
		(stroke
			(width 0)
			(type solid)
		)
		(fill yes)
		(layer "In1.Cu")
		(net "P5E_PEX1_STN7_TX_DP<118>")
	)
	(gr_poly
		(pts
			(arc
				(start 158.853124 -305.399948)
				(mid 158.446724 -305.399948)
				(end 158.853124 -305.399948)
			)
		)
		(stroke
			(width 0)
			(type solid)
		)
		(fill yes)
		(layer "In1.Cu")
		(net "P5E_PEX1_STN7_TX_DP<116>")
	)
	(gr_poly
		(pts
			(arc
				(start 158.853124 -303.499774)
				(mid 158.446724 -303.499774)
				(end 158.853124 -303.499774)
			)
		)
		(stroke
			(width 0)
			(type solid)
		)
		(fill yes)
		(layer "In1.Cu")
		(net "P5E_PEX1_STN7_TX_DP<114>")
	)
	(gr_poly
		(pts
			(arc
				(start 158.853124 -301.599854)
				(mid 158.446724 -301.599854)
				(end 158.853124 -301.599854)
			)
		)
		(stroke
			(width 0)
			(type solid)
		)
		(fill yes)
		(layer "In1.Cu")
		(net "P5E_PEX1_STN7_TX_DP<112>")
	)
	(gr_poly
		(pts
			(arc
				(start 159.803084 -316.799722)
				(mid 159.396684 -316.799722)
				(end 159.803084 -316.799722)
			)
		)
		(stroke
			(width 0)
			(type solid)
		)
		(fill yes)
		(layer "In1.Cu")
		(net "P5E_PEX1_STN6_RX_DN<111>")
	)
	(gr_poly
		(pts
			(arc
				(start 159.803084 -315.849762)
				(mid 159.396684 -315.849762)
				(end 159.803084 -315.849762)
			)
		)
		(stroke
			(width 0)
			(type solid)
		)
		(fill yes)
		(layer "In1.Cu")
		(net "P5E_PEX1_STN6_RX_DP<111>")
	)
	(gr_poly
		(pts
			(arc
				(start 159.803084 -312.049922)
				(mid 159.396684 -312.049922)
				(end 159.803084 -312.049922)
			)
		)
		(stroke
			(width 0)
			(type solid)
		)
		(fill yes)
		(layer "In1.Cu")
		(net "P5E_PEX1_STN6_TX_DN<111>")
	)
	(gr_poly
		(pts
			(arc
				(start 159.803084 -311.099962)
				(mid 159.396684 -311.099962)
				(end 159.803084 -311.099962)
			)
		)
		(stroke
			(width 0)
			(type solid)
		)
		(fill yes)
		(layer "In1.Cu")
		(net "P5E_PEX1_STN6_TX_DP<111>")
	)
	(gr_poly
		(pts
			(arc
				(start 159.803084 -308.249828)
				(mid 159.396684 -308.249828)
				(end 159.803084 -308.249828)
			)
		)
		(stroke
			(width 0)
			(type solid)
		)
		(fill yes)
		(layer "In1.Cu")
		(net "P5E_PEX1_STN7_TX_DN<119>")
	)
	(gr_poly
		(pts
			(arc
				(start 159.803084 -306.349908)
				(mid 159.396684 -306.349908)
				(end 159.803084 -306.349908)
			)
		)
		(stroke
			(width 0)
			(type solid)
		)
		(fill yes)
		(layer "In1.Cu")
		(net "P5E_PEX1_STN7_TX_DN<117>")
	)
	(gr_poly
		(pts
			(arc
				(start 159.803084 -304.449734)
				(mid 159.396684 -304.449734)
				(end 159.803084 -304.449734)
			)
		)
		(stroke
			(width 0)
			(type solid)
		)
		(fill yes)
		(layer "In1.Cu")
		(net "P5E_PEX1_STN7_TX_DN<115>")
	)
	(gr_poly
		(pts
			(arc
				(start 159.803084 -302.549814)
				(mid 159.396684 -302.549814)
				(end 159.803084 -302.549814)
			)
		)
		(stroke
			(width 0)
			(type solid)
		)
		(fill yes)
		(layer "In1.Cu")
		(net "P5E_PEX1_STN7_TX_DN<113>")
	)
	(gr_poly
		(pts
			(arc
				(start 160.753044 -318.699896)
				(mid 160.346644 -318.699896)
				(end 160.753044 -318.699896)
			)
		)
		(stroke
			(width 0)
			(type solid)
		)
		(fill yes)
		(layer "In1.Cu")
		(net "P5E_PEX1_STN6_RX_DN<110>")
	)
	(gr_poly
		(pts
			(arc
				(start 160.753044 -317.749936)
				(mid 160.346644 -317.749936)
				(end 160.753044 -317.749936)
			)
		)
		(stroke
			(width 0)
			(type solid)
		)
		(fill yes)
		(layer "In1.Cu")
		(net "P5E_PEX1_STN6_RX_DP<110>")
	)
	(gr_poly
		(pts
			(arc
				(start 160.753044 -313.949842)
				(mid 160.346644 -313.949842)
				(end 160.753044 -313.949842)
			)
		)
		(stroke
			(width 0)
			(type solid)
		)
		(fill yes)
		(layer "In1.Cu")
		(net "P5E_PEX1_STN6_TX_DN<110>")
	)
	(gr_poly
		(pts
			(arc
				(start 160.753044 -312.999882)
				(mid 160.346644 -312.999882)
				(end 160.753044 -312.999882)
			)
		)
		(stroke
			(width 0)
			(type solid)
		)
		(fill yes)
		(layer "In1.Cu")
		(net "P5E_PEX1_STN6_TX_DP<110>")
	)
	(gr_poly
		(pts
			(arc
				(start 160.753044 -308.249828)
				(mid 160.346644 -308.249828)
				(end 160.753044 -308.249828)
			)
		)
		(stroke
			(width 0)
			(type solid)
		)
		(fill yes)
		(layer "In1.Cu")
		(net "P5E_PEX1_STN7_TX_DP<119>")
	)
	(gr_poly
		(pts
			(arc
				(start 160.753044 -306.349908)
				(mid 160.346644 -306.349908)
				(end 160.753044 -306.349908)
			)
		)
		(stroke
			(width 0)
			(type solid)
		)
		(fill yes)
		(layer "In1.Cu")
		(net "P5E_PEX1_STN7_TX_DP<117>")
	)
	(gr_poly
		(pts
			(arc
				(start 160.753044 -304.449734)
				(mid 160.346644 -304.449734)
				(end 160.753044 -304.449734)
			)
		)
		(stroke
			(width 0)
			(type solid)
		)
		(fill yes)
		(layer "In1.Cu")
		(net "P5E_PEX1_STN7_TX_DP<115>")
	)
	(gr_poly
		(pts
			(arc
				(start 160.753044 -302.549814)
				(mid 160.346644 -302.549814)
				(end 160.753044 -302.549814)
			)
		)
		(stroke
			(width 0)
			(type solid)
		)
		(fill yes)
		(layer "In1.Cu")
		(net "P5E_PEX1_STN7_TX_DP<113>")
	)
	(gr_poly
		(pts
			(arc
				(start 160.753044 -278.799798)
				(mid 160.346644 -278.799798)
				(end 160.753044 -278.799798)
			)
		)
		(stroke
			(width 0)
			(type solid)
		)
		(fill yes)
		(layer "In1.Cu")
		(net "P5E_PEX1_STN2_TX_DP<47>")
	)
	(gr_poly
		(pts
			(arc
				(start 160.753044 -277.849838)
				(mid 160.346644 -277.849838)
				(end 160.753044 -277.849838)
			)
		)
		(stroke
			(width 0)
			(type solid)
		)
		(fill yes)
		(layer "In1.Cu")
		(net "P5E_PEX1_STN2_TX_DN<47>")
	)
	(gr_poly
		(pts
			(arc
				(start 160.753044 -274.049744)
				(mid 160.346644 -274.049744)
				(end 160.753044 -274.049744)
			)
		)
		(stroke
			(width 0)
			(type solid)
		)
		(fill yes)
		(layer "In1.Cu")
		(net "P5E_PEX1_STN2_RX_DP<47>")
	)
	(gr_poly
		(pts
			(arc
				(start 160.753044 -273.099784)
				(mid 160.346644 -273.099784)
				(end 160.753044 -273.099784)
			)
		)
		(stroke
			(width 0)
			(type solid)
		)
		(fill yes)
		(layer "In1.Cu")
		(net "P5E_PEX1_STN2_RX_DN<47>")
	)
	(gr_poly
		(pts
			(arc
				(start 161.703258 -316.799722)
				(mid 161.296858 -316.799722)
				(end 161.703258 -316.799722)
			)
		)
		(stroke
			(width 0)
			(type solid)
		)
		(fill yes)
		(layer "In1.Cu")
		(net "P5E_PEX1_STN6_RX_DN<109>")
	)
	(gr_poly
		(pts
			(arc
				(start 161.703258 -315.849762)
				(mid 161.296858 -315.849762)
				(end 161.703258 -315.849762)
			)
		)
		(stroke
			(width 0)
			(type solid)
		)
		(fill yes)
		(layer "In1.Cu")
		(net "P5E_PEX1_STN6_RX_DP<109>")
	)
	(gr_poly
		(pts
			(arc
				(start 161.703258 -312.049922)
				(mid 161.296858 -312.049922)
				(end 161.703258 -312.049922)
			)
		)
		(stroke
			(width 0)
			(type solid)
		)
		(fill yes)
		(layer "In1.Cu")
		(net "P5E_PEX1_STN6_TX_DN<109>")
	)
	(gr_poly
		(pts
			(arc
				(start 161.703258 -311.099962)
				(mid 161.296858 -311.099962)
				(end 161.703258 -311.099962)
			)
		)
		(stroke
			(width 0)
			(type solid)
		)
		(fill yes)
		(layer "In1.Cu")
		(net "P5E_PEX1_STN6_TX_DP<109>")
	)
	(gr_poly
		(pts
			(arc
				(start 161.703258 -280.699718)
				(mid 161.296858 -280.699718)
				(end 161.703258 -280.699718)
			)
		)
		(stroke
			(width 0)
			(type solid)
		)
		(fill yes)
		(layer "In1.Cu")
		(net "P5E_PEX1_STN2_TX_DP<46>")
	)
	(gr_poly
		(pts
			(arc
				(start 161.703258 -279.749504)
				(mid 161.296858 -279.749504)
				(end 161.703258 -279.749504)
			)
		)
		(stroke
			(width 0)
			(type solid)
		)
		(fill yes)
		(layer "In1.Cu")
		(net "P5E_PEX1_STN2_TX_DN<46>")
	)
	(gr_poly
		(pts
			(arc
				(start 161.703258 -275.949918)
				(mid 161.296858 -275.949918)
				(end 161.703258 -275.949918)
			)
		)
		(stroke
			(width 0)
			(type solid)
		)
		(fill yes)
		(layer "In1.Cu")
		(net "P5E_PEX1_STN2_RX_DP<46>")
	)
	(gr_poly
		(pts
			(arc
				(start 161.703258 -274.999958)
				(mid 161.296858 -274.999958)
				(end 161.703258 -274.999958)
			)
		)
		(stroke
			(width 0)
			(type solid)
		)
		(fill yes)
		(layer "In1.Cu")
		(net "P5E_PEX1_STN2_RX_DN<46>")
	)
	(gr_poly
		(pts
			(arc
				(start 162.653218 -318.699896)
				(mid 162.246818 -318.699896)
				(end 162.653218 -318.699896)
			)
		)
		(stroke
			(width 0)
			(type solid)
		)
		(fill yes)
		(layer "In1.Cu")
		(net "P5E_PEX1_STN6_RX_DN<108>")
	)
	(gr_poly
		(pts
			(arc
				(start 162.653218 -317.749936)
				(mid 162.246818 -317.749936)
				(end 162.653218 -317.749936)
			)
		)
		(stroke
			(width 0)
			(type solid)
		)
		(fill yes)
		(layer "In1.Cu")
		(net "P5E_PEX1_STN6_RX_DP<108>")
	)
	(gr_poly
		(pts
			(arc
				(start 162.653218 -313.949842)
				(mid 162.246818 -313.949842)
				(end 162.653218 -313.949842)
			)
		)
		(stroke
			(width 0)
			(type solid)
		)
		(fill yes)
		(layer "In1.Cu")
		(net "P5E_PEX1_STN6_TX_DN<108>")
	)
	(gr_poly
		(pts
			(arc
				(start 162.653218 -312.999882)
				(mid 162.246818 -312.999882)
				(end 162.653218 -312.999882)
			)
		)
		(stroke
			(width 0)
			(type solid)
		)
		(fill yes)
		(layer "In1.Cu")
		(net "P5E_PEX1_STN6_TX_DP<108>")
	)
	(gr_poly
		(pts
			(arc
				(start 162.653218 -278.799798)
				(mid 162.246818 -278.799798)
				(end 162.653218 -278.799798)
			)
		)
		(stroke
			(width 0)
			(type solid)
		)
		(fill yes)
		(layer "In1.Cu")
		(net "P5E_PEX1_STN2_TX_DP<45>")
	)
	(gr_poly
		(pts
			(arc
				(start 162.653218 -277.849838)
				(mid 162.246818 -277.849838)
				(end 162.653218 -277.849838)
			)
		)
		(stroke
			(width 0)
			(type solid)
		)
		(fill yes)
		(layer "In1.Cu")
		(net "P5E_PEX1_STN2_TX_DN<45>")
	)
	(gr_poly
		(pts
			(arc
				(start 162.653218 -274.049744)
				(mid 162.246818 -274.049744)
				(end 162.653218 -274.049744)
			)
		)
		(stroke
			(width 0)
			(type solid)
		)
		(fill yes)
		(layer "In1.Cu")
		(net "P5E_PEX1_STN2_RX_DP<45>")
	)
	(gr_poly
		(pts
			(arc
				(start 162.653218 -273.099784)
				(mid 162.246818 -273.099784)
				(end 162.653218 -273.099784)
			)
		)
		(stroke
			(width 0)
			(type solid)
		)
		(fill yes)
		(layer "In1.Cu")
		(net "P5E_PEX1_STN2_RX_DN<45>")
	)
	(gr_poly
		(pts
			(arc
				(start 163.603178 -316.799722)
				(mid 163.196778 -316.799722)
				(end 163.603178 -316.799722)
			)
		)
		(stroke
			(width 0)
			(type solid)
		)
		(fill yes)
		(layer "In1.Cu")
		(net "P5E_PEX1_STN6_RX_DN<107>")
	)
	(gr_poly
		(pts
			(arc
				(start 163.603178 -315.849762)
				(mid 163.196778 -315.849762)
				(end 163.603178 -315.849762)
			)
		)
		(stroke
			(width 0)
			(type solid)
		)
		(fill yes)
		(layer "In1.Cu")
		(net "P5E_PEX1_STN6_RX_DP<107>")
	)
	(gr_poly
		(pts
			(arc
				(start 163.603178 -312.049922)
				(mid 163.196778 -312.049922)
				(end 163.603178 -312.049922)
			)
		)
		(stroke
			(width 0)
			(type solid)
		)
		(fill yes)
		(layer "In1.Cu")
		(net "P5E_PEX1_STN6_TX_DN<107>")
	)
	(gr_poly
		(pts
			(arc
				(start 163.603178 -311.099962)
				(mid 163.196778 -311.099962)
				(end 163.603178 -311.099962)
			)
		)
		(stroke
			(width 0)
			(type solid)
		)
		(fill yes)
		(layer "In1.Cu")
		(net "P5E_PEX1_STN6_TX_DP<107>")
	)
	(gr_poly
		(pts
			(arc
				(start 163.603178 -280.699718)
				(mid 163.196778 -280.699718)
				(end 163.603178 -280.699718)
			)
		)
		(stroke
			(width 0)
			(type solid)
		)
		(fill yes)
		(layer "In1.Cu")
		(net "P5E_PEX1_STN2_TX_DP<44>")
	)
	(gr_poly
		(pts
			(arc
				(start 163.603178 -279.749504)
				(mid 163.196778 -279.749504)
				(end 163.603178 -279.749504)
			)
		)
		(stroke
			(width 0)
			(type solid)
		)
		(fill yes)
		(layer "In1.Cu")
		(net "P5E_PEX1_STN2_TX_DN<44>")
	)
	(gr_poly
		(pts
			(arc
				(start 163.603178 -275.949918)
				(mid 163.196778 -275.949918)
				(end 163.603178 -275.949918)
			)
		)
		(stroke
			(width 0)
			(type solid)
		)
		(fill yes)
		(layer "In1.Cu")
		(net "P5E_PEX1_STN2_RX_DP<44>")
	)
	(gr_poly
		(pts
			(arc
				(start 163.603178 -274.999958)
				(mid 163.196778 -274.999958)
				(end 163.603178 -274.999958)
			)
		)
		(stroke
			(width 0)
			(type solid)
		)
		(fill yes)
		(layer "In1.Cu")
		(net "P5E_PEX1_STN2_RX_DN<44>")
	)
	(gr_poly
		(pts
			(arc
				(start 164.553138 -318.699896)
				(mid 164.146738 -318.699896)
				(end 164.553138 -318.699896)
			)
		)
		(stroke
			(width 0)
			(type solid)
		)
		(fill yes)
		(layer "In1.Cu")
		(net "P5E_PEX1_STN6_RX_DN<106>")
	)
	(gr_poly
		(pts
			(arc
				(start 164.553138 -317.749936)
				(mid 164.146738 -317.749936)
				(end 164.553138 -317.749936)
			)
		)
		(stroke
			(width 0)
			(type solid)
		)
		(fill yes)
		(layer "In1.Cu")
		(net "P5E_PEX1_STN6_RX_DP<106>")
	)
	(gr_poly
		(pts
			(arc
				(start 164.553138 -313.949842)
				(mid 164.146738 -313.949842)
				(end 164.553138 -313.949842)
			)
		)
		(stroke
			(width 0)
			(type solid)
		)
		(fill yes)
		(layer "In1.Cu")
		(net "P5E_PEX1_STN6_TX_DN<106>")
	)
	(gr_poly
		(pts
			(arc
				(start 164.553138 -312.999882)
				(mid 164.146738 -312.999882)
				(end 164.553138 -312.999882)
			)
		)
		(stroke
			(width 0)
			(type solid)
		)
		(fill yes)
		(layer "In1.Cu")
		(net "P5E_PEX1_STN6_TX_DP<106>")
	)
	(gr_poly
		(pts
			(arc
				(start 164.553138 -278.799798)
				(mid 164.146738 -278.799798)
				(end 164.553138 -278.799798)
			)
		)
		(stroke
			(width 0)
			(type solid)
		)
		(fill yes)
		(layer "In1.Cu")
		(net "P5E_PEX1_STN2_TX_DP<43>")
	)
	(gr_poly
		(pts
			(arc
				(start 164.553138 -277.849838)
				(mid 164.146738 -277.849838)
				(end 164.553138 -277.849838)
			)
		)
		(stroke
			(width 0)
			(type solid)
		)
		(fill yes)
		(layer "In1.Cu")
		(net "P5E_PEX1_STN2_TX_DN<43>")
	)
	(gr_poly
		(pts
			(arc
				(start 164.553138 -274.049744)
				(mid 164.146738 -274.049744)
				(end 164.553138 -274.049744)
			)
		)
		(stroke
			(width 0)
			(type solid)
		)
		(fill yes)
		(layer "In1.Cu")
		(net "P5E_PEX1_STN2_RX_DP<43>")
	)
	(gr_poly
		(pts
			(arc
				(start 164.553138 -273.099784)
				(mid 164.146738 -273.099784)
				(end 164.553138 -273.099784)
			)
		)
		(stroke
			(width 0)
			(type solid)
		)
		(fill yes)
		(layer "In1.Cu")
		(net "P5E_PEX1_STN2_RX_DN<43>")
	)
	(gr_poly
		(pts
			(arc
				(start 165.503098 -316.799722)
				(mid 165.096698 -316.799722)
				(end 165.503098 -316.799722)
			)
		)
		(stroke
			(width 0)
			(type solid)
		)
		(fill yes)
		(layer "In1.Cu")
		(net "P5E_PEX1_STN6_RX_DN<105>")
	)
	(gr_poly
		(pts
			(arc
				(start 165.503098 -315.849762)
				(mid 165.096698 -315.849762)
				(end 165.503098 -315.849762)
			)
		)
		(stroke
			(width 0)
			(type solid)
		)
		(fill yes)
		(layer "In1.Cu")
		(net "P5E_PEX1_STN6_RX_DP<105>")
	)
	(gr_poly
		(pts
			(arc
				(start 165.503098 -312.049922)
				(mid 165.096698 -312.049922)
				(end 165.503098 -312.049922)
			)
		)
		(stroke
			(width 0)
			(type solid)
		)
		(fill yes)
		(layer "In1.Cu")
		(net "P5E_PEX1_STN6_TX_DN<105>")
	)
	(gr_poly
		(pts
			(arc
				(start 165.503098 -311.099962)
				(mid 165.096698 -311.099962)
				(end 165.503098 -311.099962)
			)
		)
		(stroke
			(width 0)
			(type solid)
		)
		(fill yes)
		(layer "In1.Cu")
		(net "P5E_PEX1_STN6_TX_DP<105>")
	)
	(gr_poly
		(pts
			(arc
				(start 165.503098 -280.699718)
				(mid 165.096698 -280.699718)
				(end 165.503098 -280.699718)
			)
		)
		(stroke
			(width 0)
			(type solid)
		)
		(fill yes)
		(layer "In1.Cu")
		(net "P5E_PEX1_STN2_TX_DP<42>")
	)
	(gr_poly
		(pts
			(arc
				(start 165.503098 -279.749504)
				(mid 165.096698 -279.749504)
				(end 165.503098 -279.749504)
			)
		)
		(stroke
			(width 0)
			(type solid)
		)
		(fill yes)
		(layer "In1.Cu")
		(net "P5E_PEX1_STN2_TX_DN<42>")
	)
	(gr_poly
		(pts
			(arc
				(start 165.503098 -275.949918)
				(mid 165.096698 -275.949918)
				(end 165.503098 -275.949918)
			)
		)
		(stroke
			(width 0)
			(type solid)
		)
		(fill yes)
		(layer "In1.Cu")
		(net "P5E_PEX1_STN2_RX_DP<42>")
	)
	(gr_poly
		(pts
			(arc
				(start 165.503098 -274.999958)
				(mid 165.096698 -274.999958)
				(end 165.503098 -274.999958)
			)
		)
		(stroke
			(width 0)
			(type solid)
		)
		(fill yes)
		(layer "In1.Cu")
		(net "P5E_PEX1_STN2_RX_DN<42>")
	)
	(gr_poly
		(pts
			(arc
				(start 166.453058 -318.699896)
				(mid 166.046658 -318.699896)
				(end 166.453058 -318.699896)
			)
		)
		(stroke
			(width 0)
			(type solid)
		)
		(fill yes)
		(layer "In1.Cu")
		(net "P5E_PEX1_STN6_RX_DN<104>")
	)
	(gr_poly
		(pts
			(arc
				(start 166.453058 -317.749936)
				(mid 166.046658 -317.749936)
				(end 166.453058 -317.749936)
			)
		)
		(stroke
			(width 0)
			(type solid)
		)
		(fill yes)
		(layer "In1.Cu")
		(net "P5E_PEX1_STN6_RX_DP<104>")
	)
	(gr_poly
		(pts
			(arc
				(start 166.453058 -313.949842)
				(mid 166.046658 -313.949842)
				(end 166.453058 -313.949842)
			)
		)
		(stroke
			(width 0)
			(type solid)
		)
		(fill yes)
		(layer "In1.Cu")
		(net "P5E_PEX1_STN6_TX_DN<104>")
	)
	(gr_poly
		(pts
			(arc
				(start 166.453058 -312.999882)
				(mid 166.046658 -312.999882)
				(end 166.453058 -312.999882)
			)
		)
		(stroke
			(width 0)
			(type solid)
		)
		(fill yes)
		(layer "In1.Cu")
		(net "P5E_PEX1_STN6_TX_DP<104>")
	)
	(gr_poly
		(pts
			(arc
				(start 166.453058 -278.799798)
				(mid 166.046658 -278.799798)
				(end 166.453058 -278.799798)
			)
		)
		(stroke
			(width 0)
			(type solid)
		)
		(fill yes)
		(layer "In1.Cu")
		(net "P5E_PEX1_STN2_TX_DP<41>")
	)
	(gr_poly
		(pts
			(arc
				(start 166.453058 -277.849838)
				(mid 166.046658 -277.849838)
				(end 166.453058 -277.849838)
			)
		)
		(stroke
			(width 0)
			(type solid)
		)
		(fill yes)
		(layer "In1.Cu")
		(net "P5E_PEX1_STN2_TX_DN<41>")
	)
	(gr_poly
		(pts
			(arc
				(start 166.453058 -274.049744)
				(mid 166.046658 -274.049744)
				(end 166.453058 -274.049744)
			)
		)
		(stroke
			(width 0)
			(type solid)
		)
		(fill yes)
		(layer "In1.Cu")
		(net "P5E_PEX1_STN2_RX_DP<41>")
	)
	(gr_poly
		(pts
			(arc
				(start 166.453058 -273.099784)
				(mid 166.046658 -273.099784)
				(end 166.453058 -273.099784)
			)
		)
		(stroke
			(width 0)
			(type solid)
		)
		(fill yes)
		(layer "In1.Cu")
		(net "P5E_PEX1_STN2_RX_DN<41>")
	)
	(gr_poly
		(pts
			(arc
				(start 167.403272 -316.799722)
				(mid 166.996872 -316.799722)
				(end 167.403272 -316.799722)
			)
		)
		(stroke
			(width 0)
			(type solid)
		)
		(fill yes)
		(layer "In1.Cu")
		(net "P5E_PEX1_STN6_RX_DN<103>")
	)
	(gr_poly
		(pts
			(arc
				(start 167.403272 -315.849762)
				(mid 166.996872 -315.849762)
				(end 167.403272 -315.849762)
			)
		)
		(stroke
			(width 0)
			(type solid)
		)
		(fill yes)
		(layer "In1.Cu")
		(net "P5E_PEX1_STN6_RX_DP<103>")
	)
	(gr_poly
		(pts
			(arc
				(start 167.403272 -312.049922)
				(mid 166.996872 -312.049922)
				(end 167.403272 -312.049922)
			)
		)
		(stroke
			(width 0)
			(type solid)
		)
		(fill yes)
		(layer "In1.Cu")
		(net "P5E_PEX1_STN6_TX_DN<103>")
	)
	(gr_poly
		(pts
			(arc
				(start 167.403272 -311.099962)
				(mid 166.996872 -311.099962)
				(end 167.403272 -311.099962)
			)
		)
		(stroke
			(width 0)
			(type solid)
		)
		(fill yes)
		(layer "In1.Cu")
		(net "P5E_PEX1_STN6_TX_DP<103>")
	)
	(gr_poly
		(pts
			(arc
				(start 167.403272 -280.699718)
				(mid 166.996872 -280.699718)
				(end 167.403272 -280.699718)
			)
		)
		(stroke
			(width 0)
			(type solid)
		)
		(fill yes)
		(layer "In1.Cu")
		(net "P5E_PEX1_STN2_TX_DP<40>")
	)
	(gr_poly
		(pts
			(arc
				(start 167.403272 -279.749504)
				(mid 166.996872 -279.749504)
				(end 167.403272 -279.749504)
			)
		)
		(stroke
			(width 0)
			(type solid)
		)
		(fill yes)
		(layer "In1.Cu")
		(net "P5E_PEX1_STN2_TX_DN<40>")
	)
	(gr_poly
		(pts
			(arc
				(start 167.403272 -275.949918)
				(mid 166.996872 -275.949918)
				(end 167.403272 -275.949918)
			)
		)
		(stroke
			(width 0)
			(type solid)
		)
		(fill yes)
		(layer "In1.Cu")
		(net "P5E_PEX1_STN2_RX_DP<40>")
	)
	(gr_poly
		(pts
			(arc
				(start 167.403272 -274.999958)
				(mid 166.996872 -274.999958)
				(end 167.403272 -274.999958)
			)
		)
		(stroke
			(width 0)
			(type solid)
		)
		(fill yes)
		(layer "In1.Cu")
		(net "P5E_PEX1_STN2_RX_DN<40>")
	)
	(gr_poly
		(pts
			(arc
				(start 168.353232 -318.699896)
				(mid 167.946832 -318.699896)
				(end 168.353232 -318.699896)
			)
		)
		(stroke
			(width 0)
			(type solid)
		)
		(fill yes)
		(layer "In1.Cu")
		(net "P5E_PEX1_STN6_RX_DN<102>")
	)
	(gr_poly
		(pts
			(arc
				(start 168.353232 -317.749936)
				(mid 167.946832 -317.749936)
				(end 168.353232 -317.749936)
			)
		)
		(stroke
			(width 0)
			(type solid)
		)
		(fill yes)
		(layer "In1.Cu")
		(net "P5E_PEX1_STN6_RX_DP<102>")
	)
	(gr_poly
		(pts
			(arc
				(start 168.353232 -313.949842)
				(mid 167.946832 -313.949842)
				(end 168.353232 -313.949842)
			)
		)
		(stroke
			(width 0)
			(type solid)
		)
		(fill yes)
		(layer "In1.Cu")
		(net "P5E_PEX1_STN6_TX_DN<102>")
	)
	(gr_poly
		(pts
			(arc
				(start 168.353232 -312.999882)
				(mid 167.946832 -312.999882)
				(end 168.353232 -312.999882)
			)
		)
		(stroke
			(width 0)
			(type solid)
		)
		(fill yes)
		(layer "In1.Cu")
		(net "P5E_PEX1_STN6_TX_DP<102>")
	)
	(gr_poly
		(pts
			(arc
				(start 168.353232 -278.799798)
				(mid 167.946832 -278.799798)
				(end 168.353232 -278.799798)
			)
		)
		(stroke
			(width 0)
			(type solid)
		)
		(fill yes)
		(layer "In1.Cu")
		(net "P5E_PEX1_STN2_TX_DP<39>")
	)
	(gr_poly
		(pts
			(arc
				(start 168.353232 -277.849838)
				(mid 167.946832 -277.849838)
				(end 168.353232 -277.849838)
			)
		)
		(stroke
			(width 0)
			(type solid)
		)
		(fill yes)
		(layer "In1.Cu")
		(net "P5E_PEX1_STN2_TX_DN<39>")
	)
	(gr_poly
		(pts
			(arc
				(start 168.353232 -274.049744)
				(mid 167.946832 -274.049744)
				(end 168.353232 -274.049744)
			)
		)
		(stroke
			(width 0)
			(type solid)
		)
		(fill yes)
		(layer "In1.Cu")
		(net "P5E_PEX1_STN2_RX_DP<39>")
	)
	(gr_poly
		(pts
			(arc
				(start 168.353232 -273.099784)
				(mid 167.946832 -273.099784)
				(end 168.353232 -273.099784)
			)
		)
		(stroke
			(width 0)
			(type solid)
		)
		(fill yes)
		(layer "In1.Cu")
		(net "P5E_PEX1_STN2_RX_DN<39>")
	)
	(gr_poly
		(pts
			(arc
				(start 169.303192 -316.799722)
				(mid 168.896792 -316.799722)
				(end 169.303192 -316.799722)
			)
		)
		(stroke
			(width 0)
			(type solid)
		)
		(fill yes)
		(layer "In1.Cu")
		(net "P5E_PEX1_STN6_RX_DN<101>")
	)
	(gr_poly
		(pts
			(arc
				(start 169.303192 -315.849762)
				(mid 168.896792 -315.849762)
				(end 169.303192 -315.849762)
			)
		)
		(stroke
			(width 0)
			(type solid)
		)
		(fill yes)
		(layer "In1.Cu")
		(net "P5E_PEX1_STN6_RX_DP<101>")
	)
	(gr_poly
		(pts
			(arc
				(start 169.303192 -312.049922)
				(mid 168.896792 -312.049922)
				(end 169.303192 -312.049922)
			)
		)
		(stroke
			(width 0)
			(type solid)
		)
		(fill yes)
		(layer "In1.Cu")
		(net "P5E_PEX1_STN6_TX_DN<101>")
	)
	(gr_poly
		(pts
			(arc
				(start 169.303192 -311.099962)
				(mid 168.896792 -311.099962)
				(end 169.303192 -311.099962)
			)
		)
		(stroke
			(width 0)
			(type solid)
		)
		(fill yes)
		(layer "In1.Cu")
		(net "P5E_PEX1_STN6_TX_DP<101>")
	)
	(gr_poly
		(pts
			(arc
				(start 169.303192 -280.699718)
				(mid 168.896792 -280.699718)
				(end 169.303192 -280.699718)
			)
		)
		(stroke
			(width 0)
			(type solid)
		)
		(fill yes)
		(layer "In1.Cu")
		(net "P5E_PEX1_STN2_TX_DP<38>")
	)
	(gr_poly
		(pts
			(arc
				(start 169.303192 -279.749504)
				(mid 168.896792 -279.749504)
				(end 169.303192 -279.749504)
			)
		)
		(stroke
			(width 0)
			(type solid)
		)
		(fill yes)
		(layer "In1.Cu")
		(net "P5E_PEX1_STN2_TX_DN<38>")
	)
	(gr_poly
		(pts
			(arc
				(start 169.303192 -275.949918)
				(mid 168.896792 -275.949918)
				(end 169.303192 -275.949918)
			)
		)
		(stroke
			(width 0)
			(type solid)
		)
		(fill yes)
		(layer "In1.Cu")
		(net "P5E_PEX1_STN2_RX_DP<38>")
	)
	(gr_poly
		(pts
			(arc
				(start 169.303192 -274.999958)
				(mid 168.896792 -274.999958)
				(end 169.303192 -274.999958)
			)
		)
		(stroke
			(width 0)
			(type solid)
		)
		(fill yes)
		(layer "In1.Cu")
		(net "P5E_PEX1_STN2_RX_DN<38>")
	)
	(gr_poly
		(pts
			(arc
				(start 170.253152 -318.699896)
				(mid 169.846752 -318.699896)
				(end 170.253152 -318.699896)
			)
		)
		(stroke
			(width 0)
			(type solid)
		)
		(fill yes)
		(layer "In1.Cu")
		(net "P5E_PEX1_STN6_RX_DN<100>")
	)
	(gr_poly
		(pts
			(arc
				(start 170.253152 -317.749936)
				(mid 169.846752 -317.749936)
				(end 170.253152 -317.749936)
			)
		)
		(stroke
			(width 0)
			(type solid)
		)
		(fill yes)
		(layer "In1.Cu")
		(net "P5E_PEX1_STN6_RX_DP<100>")
	)
	(gr_poly
		(pts
			(arc
				(start 170.253152 -313.949842)
				(mid 169.846752 -313.949842)
				(end 170.253152 -313.949842)
			)
		)
		(stroke
			(width 0)
			(type solid)
		)
		(fill yes)
		(layer "In1.Cu")
		(net "P5E_PEX1_STN6_TX_DN<100>")
	)
	(gr_poly
		(pts
			(arc
				(start 170.253152 -312.999882)
				(mid 169.846752 -312.999882)
				(end 170.253152 -312.999882)
			)
		)
		(stroke
			(width 0)
			(type solid)
		)
		(fill yes)
		(layer "In1.Cu")
		(net "P5E_PEX1_STN6_TX_DP<100>")
	)
	(gr_poly
		(pts
			(arc
				(start 170.253152 -278.799798)
				(mid 169.846752 -278.799798)
				(end 170.253152 -278.799798)
			)
		)
		(stroke
			(width 0)
			(type solid)
		)
		(fill yes)
		(layer "In1.Cu")
		(net "P5E_PEX1_STN2_TX_DP<37>")
	)
	(gr_poly
		(pts
			(arc
				(start 170.253152 -277.849838)
				(mid 169.846752 -277.849838)
				(end 170.253152 -277.849838)
			)
		)
		(stroke
			(width 0)
			(type solid)
		)
		(fill yes)
		(layer "In1.Cu")
		(net "P5E_PEX1_STN2_TX_DN<37>")
	)
	(gr_poly
		(pts
			(arc
				(start 170.253152 -274.049744)
				(mid 169.846752 -274.049744)
				(end 170.253152 -274.049744)
			)
		)
		(stroke
			(width 0)
			(type solid)
		)
		(fill yes)
		(layer "In1.Cu")
		(net "P5E_PEX1_STN2_RX_DP<37>")
	)
	(gr_poly
		(pts
			(arc
				(start 170.253152 -273.099784)
				(mid 169.846752 -273.099784)
				(end 170.253152 -273.099784)
			)
		)
		(stroke
			(width 0)
			(type solid)
		)
		(fill yes)
		(layer "In1.Cu")
		(net "P5E_PEX1_STN2_RX_DN<37>")
	)
	(gr_poly
		(pts
			(arc
				(start 171.203112 -316.799722)
				(mid 170.796712 -316.799722)
				(end 171.203112 -316.799722)
			)
		)
		(stroke
			(width 0)
			(type solid)
		)
		(fill yes)
		(layer "In1.Cu")
		(net "P5E_PEX1_STN6_RX_DN<99>")
	)
	(gr_poly
		(pts
			(arc
				(start 171.203112 -315.849762)
				(mid 170.796712 -315.849762)
				(end 171.203112 -315.849762)
			)
		)
		(stroke
			(width 0)
			(type solid)
		)
		(fill yes)
		(layer "In1.Cu")
		(net "P5E_PEX1_STN6_RX_DP<99>")
	)
	(gr_poly
		(pts
			(arc
				(start 171.203112 -312.049922)
				(mid 170.796712 -312.049922)
				(end 171.203112 -312.049922)
			)
		)
		(stroke
			(width 0)
			(type solid)
		)
		(fill yes)
		(layer "In1.Cu")
		(net "P5E_PEX1_STN6_TX_DN<99>")
	)
	(gr_poly
		(pts
			(arc
				(start 171.203112 -311.099962)
				(mid 170.796712 -311.099962)
				(end 171.203112 -311.099962)
			)
		)
		(stroke
			(width 0)
			(type solid)
		)
		(fill yes)
		(layer "In1.Cu")
		(net "P5E_PEX1_STN6_TX_DP<99>")
	)
	(gr_poly
		(pts
			(arc
				(start 171.203112 -280.699718)
				(mid 170.796712 -280.699718)
				(end 171.203112 -280.699718)
			)
		)
		(stroke
			(width 0)
			(type solid)
		)
		(fill yes)
		(layer "In1.Cu")
		(net "P5E_PEX1_STN2_TX_DP<36>")
	)
	(gr_poly
		(pts
			(arc
				(start 171.203112 -279.749504)
				(mid 170.796712 -279.749504)
				(end 171.203112 -279.749504)
			)
		)
		(stroke
			(width 0)
			(type solid)
		)
		(fill yes)
		(layer "In1.Cu")
		(net "P5E_PEX1_STN2_TX_DN<36>")
	)
	(gr_poly
		(pts
			(arc
				(start 171.203112 -275.949918)
				(mid 170.796712 -275.949918)
				(end 171.203112 -275.949918)
			)
		)
		(stroke
			(width 0)
			(type solid)
		)
		(fill yes)
		(layer "In1.Cu")
		(net "P5E_PEX1_STN2_RX_DP<36>")
	)
	(gr_poly
		(pts
			(arc
				(start 171.203112 -274.999958)
				(mid 170.796712 -274.999958)
				(end 171.203112 -274.999958)
			)
		)
		(stroke
			(width 0)
			(type solid)
		)
		(fill yes)
		(layer "In1.Cu")
		(net "P5E_PEX1_STN2_RX_DN<36>")
	)
	(gr_poly
		(pts
			(arc
				(start 172.153072 -318.699896)
				(mid 171.746672 -318.699896)
				(end 172.153072 -318.699896)
			)
		)
		(stroke
			(width 0)
			(type solid)
		)
		(fill yes)
		(layer "In1.Cu")
		(net "P5E_PEX1_STN6_RX_DN<98>")
	)
	(gr_poly
		(pts
			(arc
				(start 172.153072 -317.749936)
				(mid 171.746672 -317.749936)
				(end 172.153072 -317.749936)
			)
		)
		(stroke
			(width 0)
			(type solid)
		)
		(fill yes)
		(layer "In1.Cu")
		(net "P5E_PEX1_STN6_RX_DP<98>")
	)
	(gr_poly
		(pts
			(arc
				(start 172.153072 -313.949842)
				(mid 171.746672 -313.949842)
				(end 172.153072 -313.949842)
			)
		)
		(stroke
			(width 0)
			(type solid)
		)
		(fill yes)
		(layer "In1.Cu")
		(net "P5E_PEX1_STN6_TX_DN<98>")
	)
	(gr_poly
		(pts
			(arc
				(start 172.153072 -312.999882)
				(mid 171.746672 -312.999882)
				(end 172.153072 -312.999882)
			)
		)
		(stroke
			(width 0)
			(type solid)
		)
		(fill yes)
		(layer "In1.Cu")
		(net "P5E_PEX1_STN6_TX_DP<98>")
	)
	(gr_poly
		(pts
			(arc
				(start 172.153072 -278.799798)
				(mid 171.746672 -278.799798)
				(end 172.153072 -278.799798)
			)
		)
		(stroke
			(width 0)
			(type solid)
		)
		(fill yes)
		(layer "In1.Cu")
		(net "P5E_PEX1_STN2_TX_DP<35>")
	)
	(gr_poly
		(pts
			(arc
				(start 172.153072 -277.849838)
				(mid 171.746672 -277.849838)
				(end 172.153072 -277.849838)
			)
		)
		(stroke
			(width 0)
			(type solid)
		)
		(fill yes)
		(layer "In1.Cu")
		(net "P5E_PEX1_STN2_TX_DN<35>")
	)
	(gr_poly
		(pts
			(arc
				(start 172.153072 -274.049744)
				(mid 171.746672 -274.049744)
				(end 172.153072 -274.049744)
			)
		)
		(stroke
			(width 0)
			(type solid)
		)
		(fill yes)
		(layer "In1.Cu")
		(net "P5E_PEX1_STN2_RX_DP<35>")
	)
	(gr_poly
		(pts
			(arc
				(start 172.153072 -273.099784)
				(mid 171.746672 -273.099784)
				(end 172.153072 -273.099784)
			)
		)
		(stroke
			(width 0)
			(type solid)
		)
		(fill yes)
		(layer "In1.Cu")
		(net "P5E_PEX1_STN2_RX_DN<35>")
	)
	(gr_poly
		(pts
			(arc
				(start 173.103032 -280.699718)
				(mid 172.696632 -280.699718)
				(end 173.103032 -280.699718)
			)
		)
		(stroke
			(width 0)
			(type solid)
		)
		(fill yes)
		(layer "In1.Cu")
		(net "P5E_PEX1_STN2_TX_DP<34>")
	)
	(gr_poly
		(pts
			(arc
				(start 173.103032 -279.749504)
				(mid 172.696632 -279.749504)
				(end 173.103032 -279.749504)
			)
		)
		(stroke
			(width 0)
			(type solid)
		)
		(fill yes)
		(layer "In1.Cu")
		(net "P5E_PEX1_STN2_TX_DN<34>")
	)
	(gr_poly
		(pts
			(arc
				(start 173.103286 -316.799722)
				(mid 172.696886 -316.799722)
				(end 173.103286 -316.799722)
			)
		)
		(stroke
			(width 0)
			(type solid)
		)
		(fill yes)
		(layer "In1.Cu")
		(net "P5E_PEX1_STN6_RX_DN<97>")
	)
	(gr_poly
		(pts
			(arc
				(start 173.103286 -315.849762)
				(mid 172.696886 -315.849762)
				(end 173.103286 -315.849762)
			)
		)
		(stroke
			(width 0)
			(type solid)
		)
		(fill yes)
		(layer "In1.Cu")
		(net "P5E_PEX1_STN6_RX_DP<97>")
	)
	(gr_poly
		(pts
			(arc
				(start 173.103286 -312.049922)
				(mid 172.696886 -312.049922)
				(end 173.103286 -312.049922)
			)
		)
		(stroke
			(width 0)
			(type solid)
		)
		(fill yes)
		(layer "In1.Cu")
		(net "P5E_PEX1_STN6_TX_DN<97>")
	)
	(gr_poly
		(pts
			(arc
				(start 173.103286 -311.099962)
				(mid 172.696886 -311.099962)
				(end 173.103286 -311.099962)
			)
		)
		(stroke
			(width 0)
			(type solid)
		)
		(fill yes)
		(layer "In1.Cu")
		(net "P5E_PEX1_STN6_TX_DP<97>")
	)
	(gr_poly
		(pts
			(arc
				(start 173.103286 -275.949918)
				(mid 172.696886 -275.949918)
				(end 173.103286 -275.949918)
			)
		)
		(stroke
			(width 0)
			(type solid)
		)
		(fill yes)
		(layer "In1.Cu")
		(net "P5E_PEX1_STN2_RX_DP<34>")
	)
	(gr_poly
		(pts
			(arc
				(start 173.103286 -274.999958)
				(mid 172.696886 -274.999958)
				(end 173.103286 -274.999958)
			)
		)
		(stroke
			(width 0)
			(type solid)
		)
		(fill yes)
		(layer "In1.Cu")
		(net "P5E_PEX1_STN2_RX_DN<34>")
	)
	(gr_poly
		(pts
			(arc
				(start 174.053246 -318.699896)
				(mid 173.646846 -318.699896)
				(end 174.053246 -318.699896)
			)
		)
		(stroke
			(width 0)
			(type solid)
		)
		(fill yes)
		(layer "In1.Cu")
		(net "P5E_PEX1_STN6_RX_DN<96>")
	)
	(gr_poly
		(pts
			(arc
				(start 174.053246 -317.749936)
				(mid 173.646846 -317.749936)
				(end 174.053246 -317.749936)
			)
		)
		(stroke
			(width 0)
			(type solid)
		)
		(fill yes)
		(layer "In1.Cu")
		(net "P5E_PEX1_STN6_RX_DP<96>")
	)
	(gr_poly
		(pts
			(arc
				(start 174.053246 -313.949842)
				(mid 173.646846 -313.949842)
				(end 174.053246 -313.949842)
			)
		)
		(stroke
			(width 0)
			(type solid)
		)
		(fill yes)
		(layer "In1.Cu")
		(net "P5E_PEX1_STN6_TX_DN<96>")
	)
	(gr_poly
		(pts
			(arc
				(start 174.053246 -312.999882)
				(mid 173.646846 -312.999882)
				(end 174.053246 -312.999882)
			)
		)
		(stroke
			(width 0)
			(type solid)
		)
		(fill yes)
		(layer "In1.Cu")
		(net "P5E_PEX1_STN6_TX_DP<96>")
	)
	(gr_poly
		(pts
			(arc
				(start 174.053246 -278.799798)
				(mid 173.646846 -278.799798)
				(end 174.053246 -278.799798)
			)
		)
		(stroke
			(width 0)
			(type solid)
		)
		(fill yes)
		(layer "In1.Cu")
		(net "P5E_PEX1_STN2_TX_DP<33>")
	)
	(gr_poly
		(pts
			(arc
				(start 174.053246 -277.849838)
				(mid 173.646846 -277.849838)
				(end 174.053246 -277.849838)
			)
		)
		(stroke
			(width 0)
			(type solid)
		)
		(fill yes)
		(layer "In1.Cu")
		(net "P5E_PEX1_STN2_TX_DN<33>")
	)
	(gr_poly
		(pts
			(arc
				(start 174.053246 -274.049744)
				(mid 173.646846 -274.049744)
				(end 174.053246 -274.049744)
			)
		)
		(stroke
			(width 0)
			(type solid)
		)
		(fill yes)
		(layer "In1.Cu")
		(net "P5E_PEX1_STN2_RX_DP<33>")
	)
	(gr_poly
		(pts
			(arc
				(start 174.053246 -273.099784)
				(mid 173.646846 -273.099784)
				(end 174.053246 -273.099784)
			)
		)
		(stroke
			(width 0)
			(type solid)
		)
		(fill yes)
		(layer "In1.Cu")
		(net "P5E_PEX1_STN2_RX_DN<33>")
	)
	(gr_poly
		(pts
			(arc
				(start 175.003206 -316.799722)
				(mid 174.596806 -316.799722)
				(end 175.003206 -316.799722)
			)
		)
		(stroke
			(width 0)
			(type solid)
		)
		(fill yes)
		(layer "In1.Cu")
		(net "P5E_PEX1_STN5_RX_DN<80>")
	)
	(gr_poly
		(pts
			(arc
				(start 175.003206 -315.849762)
				(mid 174.596806 -315.849762)
				(end 175.003206 -315.849762)
			)
		)
		(stroke
			(width 0)
			(type solid)
		)
		(fill yes)
		(layer "In1.Cu")
		(net "P5E_PEX1_STN5_RX_DP<80>")
	)
	(gr_poly
		(pts
			(arc
				(start 175.003206 -312.049922)
				(mid 174.596806 -312.049922)
				(end 175.003206 -312.049922)
			)
		)
		(stroke
			(width 0)
			(type solid)
		)
		(fill yes)
		(layer "In1.Cu")
		(net "P5E_PEX1_STN5_TX_DN<80>")
	)
	(gr_poly
		(pts
			(arc
				(start 175.003206 -311.099962)
				(mid 174.596806 -311.099962)
				(end 175.003206 -311.099962)
			)
		)
		(stroke
			(width 0)
			(type solid)
		)
		(fill yes)
		(layer "In1.Cu")
		(net "P5E_PEX1_STN5_TX_DP<80>")
	)
	(gr_poly
		(pts
			(arc
				(start 175.003206 -280.699718)
				(mid 174.596806 -280.699718)
				(end 175.003206 -280.699718)
			)
		)
		(stroke
			(width 0)
			(type solid)
		)
		(fill yes)
		(layer "In1.Cu")
		(net "P5E_PEX1_STN2_TX_DP<32>")
	)
	(gr_poly
		(pts
			(arc
				(start 175.003206 -279.749504)
				(mid 174.596806 -279.749504)
				(end 175.003206 -279.749504)
			)
		)
		(stroke
			(width 0)
			(type solid)
		)
		(fill yes)
		(layer "In1.Cu")
		(net "P5E_PEX1_STN2_TX_DN<32>")
	)
	(gr_poly
		(pts
			(arc
				(start 175.003206 -275.949918)
				(mid 174.596806 -275.949918)
				(end 175.003206 -275.949918)
			)
		)
		(stroke
			(width 0)
			(type solid)
		)
		(fill yes)
		(layer "In1.Cu")
		(net "P5E_PEX1_STN2_RX_DP<32>")
	)
	(gr_poly
		(pts
			(arc
				(start 175.003206 -274.999958)
				(mid 174.596806 -274.999958)
				(end 175.003206 -274.999958)
			)
		)
		(stroke
			(width 0)
			(type solid)
		)
		(fill yes)
		(layer "In1.Cu")
		(net "P5E_PEX1_STN2_RX_DN<32>")
	)
	(gr_poly
		(pts
			(arc
				(start 175.952912 -278.799798)
				(mid 175.546512 -278.799798)
				(end 175.952912 -278.799798)
			)
		)
		(stroke
			(width 0)
			(type solid)
		)
		(fill yes)
		(layer "In1.Cu")
		(net "P5E_PEX1_STN1_TX_DP<16>")
	)
	(gr_poly
		(pts
			(arc
				(start 175.952912 -277.849838)
				(mid 175.546512 -277.849838)
				(end 175.952912 -277.849838)
			)
		)
		(stroke
			(width 0)
			(type solid)
		)
		(fill yes)
		(layer "In1.Cu")
		(net "P5E_PEX1_STN1_TX_DN<16>")
	)
	(gr_poly
		(pts
			(arc
				(start 175.952912 -274.04949)
				(mid 175.546512 -274.04949)
				(end 175.952912 -274.04949)
			)
		)
		(stroke
			(width 0)
			(type solid)
		)
		(fill yes)
		(layer "In1.Cu")
		(net "P5E_PEX1_STN1_RX_DP<16>")
	)
	(gr_poly
		(pts
			(arc
				(start 175.952912 -273.09953)
				(mid 175.546512 -273.09953)
				(end 175.952912 -273.09953)
			)
		)
		(stroke
			(width 0)
			(type solid)
		)
		(fill yes)
		(layer "In1.Cu")
		(net "P5E_PEX1_STN1_RX_DN<16>")
	)
	(gr_poly
		(pts
			(arc
				(start 175.953166 -318.699896)
				(mid 175.546766 -318.699896)
				(end 175.953166 -318.699896)
			)
		)
		(stroke
			(width 0)
			(type solid)
		)
		(fill yes)
		(layer "In1.Cu")
		(net "P5E_PEX1_STN5_RX_DN<81>")
	)
	(gr_poly
		(pts
			(arc
				(start 175.953166 -317.749936)
				(mid 175.546766 -317.749936)
				(end 175.953166 -317.749936)
			)
		)
		(stroke
			(width 0)
			(type solid)
		)
		(fill yes)
		(layer "In1.Cu")
		(net "P5E_PEX1_STN5_RX_DP<81>")
	)
	(gr_poly
		(pts
			(arc
				(start 175.953166 -313.949842)
				(mid 175.546766 -313.949842)
				(end 175.953166 -313.949842)
			)
		)
		(stroke
			(width 0)
			(type solid)
		)
		(fill yes)
		(layer "In1.Cu")
		(net "P5E_PEX1_STN5_TX_DN<81>")
	)
	(gr_poly
		(pts
			(arc
				(start 175.953166 -312.999882)
				(mid 175.546766 -312.999882)
				(end 175.953166 -312.999882)
			)
		)
		(stroke
			(width 0)
			(type solid)
		)
		(fill yes)
		(layer "In1.Cu")
		(net "P5E_PEX1_STN5_TX_DP<81>")
	)
	(gr_poly
		(pts
			(arc
				(start 176.902872 -275.949664)
				(mid 176.496472 -275.949664)
				(end 176.902872 -275.949664)
			)
		)
		(stroke
			(width 0)
			(type solid)
		)
		(fill yes)
		(layer "In1.Cu")
		(net "P5E_PEX1_STN1_RX_DP<17>")
	)
	(gr_poly
		(pts
			(arc
				(start 176.902872 -274.999704)
				(mid 176.496472 -274.999704)
				(end 176.902872 -274.999704)
			)
		)
		(stroke
			(width 0)
			(type solid)
		)
		(fill yes)
		(layer "In1.Cu")
		(net "P5E_PEX1_STN1_RX_DN<17>")
	)
	(gr_poly
		(pts
			(arc
				(start 176.903126 -316.799722)
				(mid 176.496726 -316.799722)
				(end 176.903126 -316.799722)
			)
		)
		(stroke
			(width 0)
			(type solid)
		)
		(fill yes)
		(layer "In1.Cu")
		(net "P5E_PEX1_STN5_RX_DN<82>")
	)
	(gr_poly
		(pts
			(arc
				(start 176.903126 -315.849762)
				(mid 176.496726 -315.849762)
				(end 176.903126 -315.849762)
			)
		)
		(stroke
			(width 0)
			(type solid)
		)
		(fill yes)
		(layer "In1.Cu")
		(net "P5E_PEX1_STN5_RX_DP<82>")
	)
	(gr_poly
		(pts
			(arc
				(start 176.903126 -312.049922)
				(mid 176.496726 -312.049922)
				(end 176.903126 -312.049922)
			)
		)
		(stroke
			(width 0)
			(type solid)
		)
		(fill yes)
		(layer "In1.Cu")
		(net "P5E_PEX1_STN5_TX_DN<82>")
	)
	(gr_poly
		(pts
			(arc
				(start 176.903126 -311.099962)
				(mid 176.496726 -311.099962)
				(end 176.903126 -311.099962)
			)
		)
		(stroke
			(width 0)
			(type solid)
		)
		(fill yes)
		(layer "In1.Cu")
		(net "P5E_PEX1_STN5_TX_DP<82>")
	)
	(gr_poly
		(pts
			(arc
				(start 176.903126 -280.699718)
				(mid 176.496726 -280.699718)
				(end 176.903126 -280.699718)
			)
		)
		(stroke
			(width 0)
			(type solid)
		)
		(fill yes)
		(layer "In1.Cu")
		(net "P5E_PEX1_STN1_TX_DN<17>")
	)
	(gr_poly
		(pts
			(arc
				(start 176.903126 -279.749504)
				(mid 176.496726 -279.749504)
				(end 176.903126 -279.749504)
			)
		)
		(stroke
			(width 0)
			(type solid)
		)
		(fill yes)
		(layer "In1.Cu")
		(net "P5E_PEX1_STN1_TX_DP<17>")
	)
	(gr_poly
		(pts
			(arc
				(start 177.852832 -278.799798)
				(mid 177.446432 -278.799798)
				(end 177.852832 -278.799798)
			)
		)
		(stroke
			(width 0)
			(type solid)
		)
		(fill yes)
		(layer "In1.Cu")
		(net "P5E_PEX1_STN1_TX_DP<18>")
	)
	(gr_poly
		(pts
			(arc
				(start 177.852832 -277.849838)
				(mid 177.446432 -277.849838)
				(end 177.852832 -277.849838)
			)
		)
		(stroke
			(width 0)
			(type solid)
		)
		(fill yes)
		(layer "In1.Cu")
		(net "P5E_PEX1_STN1_TX_DN<18>")
	)
	(gr_poly
		(pts
			(arc
				(start 177.852832 -274.049744)
				(mid 177.446432 -274.049744)
				(end 177.852832 -274.049744)
			)
		)
		(stroke
			(width 0)
			(type solid)
		)
		(fill yes)
		(layer "In1.Cu")
		(net "P5E_PEX1_STN1_RX_DP<18>")
	)
	(gr_poly
		(pts
			(arc
				(start 177.852832 -273.099784)
				(mid 177.446432 -273.099784)
				(end 177.852832 -273.099784)
			)
		)
		(stroke
			(width 0)
			(type solid)
		)
		(fill yes)
		(layer "In1.Cu")
		(net "P5E_PEX1_STN1_RX_DN<18>")
	)
	(gr_poly
		(pts
			(arc
				(start 177.853086 -318.699896)
				(mid 177.446686 -318.699896)
				(end 177.853086 -318.699896)
			)
		)
		(stroke
			(width 0)
			(type solid)
		)
		(fill yes)
		(layer "In1.Cu")
		(net "P5E_PEX1_STN5_RX_DN<83>")
	)
	(gr_poly
		(pts
			(arc
				(start 177.853086 -317.749936)
				(mid 177.446686 -317.749936)
				(end 177.853086 -317.749936)
			)
		)
		(stroke
			(width 0)
			(type solid)
		)
		(fill yes)
		(layer "In1.Cu")
		(net "P5E_PEX1_STN5_RX_DP<83>")
	)
	(gr_poly
		(pts
			(arc
				(start 177.853086 -313.949842)
				(mid 177.446686 -313.949842)
				(end 177.853086 -313.949842)
			)
		)
		(stroke
			(width 0)
			(type solid)
		)
		(fill yes)
		(layer "In1.Cu")
		(net "P5E_PEX1_STN5_TX_DN<83>")
	)
	(gr_poly
		(pts
			(arc
				(start 177.853086 -312.999882)
				(mid 177.446686 -312.999882)
				(end 177.853086 -312.999882)
			)
		)
		(stroke
			(width 0)
			(type solid)
		)
		(fill yes)
		(layer "In1.Cu")
		(net "P5E_PEX1_STN5_TX_DP<83>")
	)
	(gr_poly
		(pts
			(arc
				(start 178.802792 -275.949918)
				(mid 178.396392 -275.949918)
				(end 178.802792 -275.949918)
			)
		)
		(stroke
			(width 0)
			(type solid)
		)
		(fill yes)
		(layer "In1.Cu")
		(net "P5E_PEX1_STN1_RX_DP<19>")
	)
	(gr_poly
		(pts
			(arc
				(start 178.802792 -274.999958)
				(mid 178.396392 -274.999958)
				(end 178.802792 -274.999958)
			)
		)
		(stroke
			(width 0)
			(type solid)
		)
		(fill yes)
		(layer "In1.Cu")
		(net "P5E_PEX1_STN1_RX_DN<19>")
	)
	(gr_poly
		(pts
			(arc
				(start 178.803046 -316.799722)
				(mid 178.396646 -316.799722)
				(end 178.803046 -316.799722)
			)
		)
		(stroke
			(width 0)
			(type solid)
		)
		(fill yes)
		(layer "In1.Cu")
		(net "P5E_PEX1_STN5_RX_DN<84>")
	)
	(gr_poly
		(pts
			(arc
				(start 178.803046 -315.849762)
				(mid 178.396646 -315.849762)
				(end 178.803046 -315.849762)
			)
		)
		(stroke
			(width 0)
			(type solid)
		)
		(fill yes)
		(layer "In1.Cu")
		(net "P5E_PEX1_STN5_RX_DP<84>")
	)
	(gr_poly
		(pts
			(arc
				(start 178.803046 -312.049922)
				(mid 178.396646 -312.049922)
				(end 178.803046 -312.049922)
			)
		)
		(stroke
			(width 0)
			(type solid)
		)
		(fill yes)
		(layer "In1.Cu")
		(net "P5E_PEX1_STN5_TX_DN<84>")
	)
	(gr_poly
		(pts
			(arc
				(start 178.803046 -311.099962)
				(mid 178.396646 -311.099962)
				(end 178.803046 -311.099962)
			)
		)
		(stroke
			(width 0)
			(type solid)
		)
		(fill yes)
		(layer "In1.Cu")
		(net "P5E_PEX1_STN5_TX_DP<84>")
	)
	(gr_poly
		(pts
			(arc
				(start 178.803046 -280.699718)
				(mid 178.396646 -280.699718)
				(end 178.803046 -280.699718)
			)
		)
		(stroke
			(width 0)
			(type solid)
		)
		(fill yes)
		(layer "In1.Cu")
		(net "P5E_PEX1_STN1_TX_DN<19>")
	)
	(gr_poly
		(pts
			(arc
				(start 178.803046 -279.749504)
				(mid 178.396646 -279.749504)
				(end 178.803046 -279.749504)
			)
		)
		(stroke
			(width 0)
			(type solid)
		)
		(fill yes)
		(layer "In1.Cu")
		(net "P5E_PEX1_STN1_TX_DP<19>")
	)
	(gr_poly
		(pts
			(arc
				(start 179.753006 -278.799798)
				(mid 179.346606 -278.799798)
				(end 179.753006 -278.799798)
			)
		)
		(stroke
			(width 0)
			(type solid)
		)
		(fill yes)
		(layer "In1.Cu")
		(net "P5E_PEX1_STN1_TX_DP<20>")
	)
	(gr_poly
		(pts
			(arc
				(start 179.753006 -277.849838)
				(mid 179.346606 -277.849838)
				(end 179.753006 -277.849838)
			)
		)
		(stroke
			(width 0)
			(type solid)
		)
		(fill yes)
		(layer "In1.Cu")
		(net "P5E_PEX1_STN1_TX_DN<20>")
	)
	(gr_poly
		(pts
			(arc
				(start 179.753006 -274.049744)
				(mid 179.346606 -274.049744)
				(end 179.753006 -274.049744)
			)
		)
		(stroke
			(width 0)
			(type solid)
		)
		(fill yes)
		(layer "In1.Cu")
		(net "P5E_PEX1_STN1_RX_DP<20>")
	)
	(gr_poly
		(pts
			(arc
				(start 179.753006 -273.099784)
				(mid 179.346606 -273.099784)
				(end 179.753006 -273.099784)
			)
		)
		(stroke
			(width 0)
			(type solid)
		)
		(fill yes)
		(layer "In1.Cu")
		(net "P5E_PEX1_STN1_RX_DN<20>")
	)
	(gr_poly
		(pts
			(arc
				(start 179.75326 -318.699896)
				(mid 179.34686 -318.699896)
				(end 179.75326 -318.699896)
			)
		)
		(stroke
			(width 0)
			(type solid)
		)
		(fill yes)
		(layer "In1.Cu")
		(net "P5E_PEX1_STN5_RX_DN<85>")
	)
	(gr_poly
		(pts
			(arc
				(start 179.75326 -317.749936)
				(mid 179.34686 -317.749936)
				(end 179.75326 -317.749936)
			)
		)
		(stroke
			(width 0)
			(type solid)
		)
		(fill yes)
		(layer "In1.Cu")
		(net "P5E_PEX1_STN5_RX_DP<85>")
	)
	(gr_poly
		(pts
			(arc
				(start 179.75326 -313.949842)
				(mid 179.34686 -313.949842)
				(end 179.75326 -313.949842)
			)
		)
		(stroke
			(width 0)
			(type solid)
		)
		(fill yes)
		(layer "In1.Cu")
		(net "P5E_PEX1_STN5_TX_DN<85>")
	)
	(gr_poly
		(pts
			(arc
				(start 179.75326 -312.999882)
				(mid 179.34686 -312.999882)
				(end 179.75326 -312.999882)
			)
		)
		(stroke
			(width 0)
			(type solid)
		)
		(fill yes)
		(layer "In1.Cu")
		(net "P5E_PEX1_STN5_TX_DP<85>")
	)
	(gr_poly
		(pts
			(arc
				(start 180.702966 -275.949664)
				(mid 180.296566 -275.949664)
				(end 180.702966 -275.949664)
			)
		)
		(stroke
			(width 0)
			(type solid)
		)
		(fill yes)
		(layer "In1.Cu")
		(net "P5E_PEX1_STN1_RX_DP<21>")
	)
	(gr_poly
		(pts
			(arc
				(start 180.702966 -274.999704)
				(mid 180.296566 -274.999704)
				(end 180.702966 -274.999704)
			)
		)
		(stroke
			(width 0)
			(type solid)
		)
		(fill yes)
		(layer "In1.Cu")
		(net "P5E_PEX1_STN1_RX_DN<21>")
	)
	(gr_poly
		(pts
			(arc
				(start 180.70322 -316.799722)
				(mid 180.29682 -316.799722)
				(end 180.70322 -316.799722)
			)
		)
		(stroke
			(width 0)
			(type solid)
		)
		(fill yes)
		(layer "In1.Cu")
		(net "P5E_PEX1_STN5_RX_DN<86>")
	)
	(gr_poly
		(pts
			(arc
				(start 180.70322 -315.849762)
				(mid 180.29682 -315.849762)
				(end 180.70322 -315.849762)
			)
		)
		(stroke
			(width 0)
			(type solid)
		)
		(fill yes)
		(layer "In1.Cu")
		(net "P5E_PEX1_STN5_RX_DP<86>")
	)
	(gr_poly
		(pts
			(arc
				(start 180.70322 -312.049922)
				(mid 180.29682 -312.049922)
				(end 180.70322 -312.049922)
			)
		)
		(stroke
			(width 0)
			(type solid)
		)
		(fill yes)
		(layer "In1.Cu")
		(net "P5E_PEX1_STN5_TX_DN<86>")
	)
	(gr_poly
		(pts
			(arc
				(start 180.70322 -311.099962)
				(mid 180.29682 -311.099962)
				(end 180.70322 -311.099962)
			)
		)
		(stroke
			(width 0)
			(type solid)
		)
		(fill yes)
		(layer "In1.Cu")
		(net "P5E_PEX1_STN5_TX_DP<86>")
	)
	(gr_poly
		(pts
			(arc
				(start 180.70322 -280.699718)
				(mid 180.29682 -280.699718)
				(end 180.70322 -280.699718)
			)
		)
		(stroke
			(width 0)
			(type solid)
		)
		(fill yes)
		(layer "In1.Cu")
		(net "P5E_PEX1_STN1_TX_DN<21>")
	)
	(gr_poly
		(pts
			(arc
				(start 180.70322 -279.749504)
				(mid 180.29682 -279.749504)
				(end 180.70322 -279.749504)
			)
		)
		(stroke
			(width 0)
			(type solid)
		)
		(fill yes)
		(layer "In1.Cu")
		(net "P5E_PEX1_STN1_TX_DP<21>")
	)
	(gr_poly
		(pts
			(arc
				(start 181.652926 -278.799798)
				(mid 181.246526 -278.799798)
				(end 181.652926 -278.799798)
			)
		)
		(stroke
			(width 0)
			(type solid)
		)
		(fill yes)
		(layer "In1.Cu")
		(net "P5E_PEX1_STN1_TX_DP<22>")
	)
	(gr_poly
		(pts
			(arc
				(start 181.652926 -277.849838)
				(mid 181.246526 -277.849838)
				(end 181.652926 -277.849838)
			)
		)
		(stroke
			(width 0)
			(type solid)
		)
		(fill yes)
		(layer "In1.Cu")
		(net "P5E_PEX1_STN1_TX_DN<22>")
	)
	(gr_poly
		(pts
			(arc
				(start 181.652926 -274.049744)
				(mid 181.246526 -274.049744)
				(end 181.652926 -274.049744)
			)
		)
		(stroke
			(width 0)
			(type solid)
		)
		(fill yes)
		(layer "In1.Cu")
		(net "P5E_PEX1_STN1_RX_DP<22>")
	)
	(gr_poly
		(pts
			(arc
				(start 181.652926 -273.099784)
				(mid 181.246526 -273.099784)
				(end 181.652926 -273.099784)
			)
		)
		(stroke
			(width 0)
			(type solid)
		)
		(fill yes)
		(layer "In1.Cu")
		(net "P5E_PEX1_STN1_RX_DN<22>")
	)
	(gr_poly
		(pts
			(arc
				(start 181.65318 -318.699896)
				(mid 181.24678 -318.699896)
				(end 181.65318 -318.699896)
			)
		)
		(stroke
			(width 0)
			(type solid)
		)
		(fill yes)
		(layer "In1.Cu")
		(net "P5E_PEX1_STN5_RX_DN<87>")
	)
	(gr_poly
		(pts
			(arc
				(start 181.65318 -317.749936)
				(mid 181.24678 -317.749936)
				(end 181.65318 -317.749936)
			)
		)
		(stroke
			(width 0)
			(type solid)
		)
		(fill yes)
		(layer "In1.Cu")
		(net "P5E_PEX1_STN5_RX_DP<87>")
	)
	(gr_poly
		(pts
			(arc
				(start 181.65318 -313.949842)
				(mid 181.24678 -313.949842)
				(end 181.65318 -313.949842)
			)
		)
		(stroke
			(width 0)
			(type solid)
		)
		(fill yes)
		(layer "In1.Cu")
		(net "P5E_PEX1_STN5_TX_DN<87>")
	)
	(gr_poly
		(pts
			(arc
				(start 181.65318 -312.999882)
				(mid 181.24678 -312.999882)
				(end 181.65318 -312.999882)
			)
		)
		(stroke
			(width 0)
			(type solid)
		)
		(fill yes)
		(layer "In1.Cu")
		(net "P5E_PEX1_STN5_TX_DP<87>")
	)
	(gr_poly
		(pts
			(arc
				(start 182.602886 -275.949918)
				(mid 182.196486 -275.949918)
				(end 182.602886 -275.949918)
			)
		)
		(stroke
			(width 0)
			(type solid)
		)
		(fill yes)
		(layer "In1.Cu")
		(net "P5E_PEX1_STN1_RX_DP<23>")
	)
	(gr_poly
		(pts
			(arc
				(start 182.602886 -274.999958)
				(mid 182.196486 -274.999958)
				(end 182.602886 -274.999958)
			)
		)
		(stroke
			(width 0)
			(type solid)
		)
		(fill yes)
		(layer "In1.Cu")
		(net "P5E_PEX1_STN1_RX_DN<23>")
	)
	(gr_poly
		(pts
			(arc
				(start 182.60314 -316.799722)
				(mid 182.19674 -316.799722)
				(end 182.60314 -316.799722)
			)
		)
		(stroke
			(width 0)
			(type solid)
		)
		(fill yes)
		(layer "In1.Cu")
		(net "P5E_PEX1_STN5_RX_DN<88>")
	)
	(gr_poly
		(pts
			(arc
				(start 182.60314 -315.849762)
				(mid 182.19674 -315.849762)
				(end 182.60314 -315.849762)
			)
		)
		(stroke
			(width 0)
			(type solid)
		)
		(fill yes)
		(layer "In1.Cu")
		(net "P5E_PEX1_STN5_RX_DP<88>")
	)
	(gr_poly
		(pts
			(arc
				(start 182.60314 -312.049922)
				(mid 182.19674 -312.049922)
				(end 182.60314 -312.049922)
			)
		)
		(stroke
			(width 0)
			(type solid)
		)
		(fill yes)
		(layer "In1.Cu")
		(net "P5E_PEX1_STN5_TX_DN<88>")
	)
	(gr_poly
		(pts
			(arc
				(start 182.60314 -311.099962)
				(mid 182.19674 -311.099962)
				(end 182.60314 -311.099962)
			)
		)
		(stroke
			(width 0)
			(type solid)
		)
		(fill yes)
		(layer "In1.Cu")
		(net "P5E_PEX1_STN5_TX_DP<88>")
	)
	(gr_poly
		(pts
			(arc
				(start 182.60314 -280.699718)
				(mid 182.19674 -280.699718)
				(end 182.60314 -280.699718)
			)
		)
		(stroke
			(width 0)
			(type solid)
		)
		(fill yes)
		(layer "In1.Cu")
		(net "P5E_PEX1_STN1_TX_DN<23>")
	)
	(gr_poly
		(pts
			(arc
				(start 182.60314 -279.749504)
				(mid 182.19674 -279.749504)
				(end 182.60314 -279.749504)
			)
		)
		(stroke
			(width 0)
			(type solid)
		)
		(fill yes)
		(layer "In1.Cu")
		(net "P5E_PEX1_STN1_TX_DP<23>")
	)
	(gr_poly
		(pts
			(arc
				(start 183.552846 -278.799798)
				(mid 183.146446 -278.799798)
				(end 183.552846 -278.799798)
			)
		)
		(stroke
			(width 0)
			(type solid)
		)
		(fill yes)
		(layer "In1.Cu")
		(net "P5E_PEX1_STN1_TX_DP<24>")
	)
	(gr_poly
		(pts
			(arc
				(start 183.552846 -277.849838)
				(mid 183.146446 -277.849838)
				(end 183.552846 -277.849838)
			)
		)
		(stroke
			(width 0)
			(type solid)
		)
		(fill yes)
		(layer "In1.Cu")
		(net "P5E_PEX1_STN1_TX_DN<24>")
	)
	(gr_poly
		(pts
			(arc
				(start 183.552846 -274.049744)
				(mid 183.146446 -274.049744)
				(end 183.552846 -274.049744)
			)
		)
		(stroke
			(width 0)
			(type solid)
		)
		(fill yes)
		(layer "In1.Cu")
		(net "P5E_PEX1_STN1_RX_DP<24>")
	)
	(gr_poly
		(pts
			(arc
				(start 183.552846 -273.099784)
				(mid 183.146446 -273.099784)
				(end 183.552846 -273.099784)
			)
		)
		(stroke
			(width 0)
			(type solid)
		)
		(fill yes)
		(layer "In1.Cu")
		(net "P5E_PEX1_STN1_RX_DN<24>")
	)
	(gr_poly
		(pts
			(arc
				(start 183.5531 -318.699896)
				(mid 183.1467 -318.699896)
				(end 183.5531 -318.699896)
			)
		)
		(stroke
			(width 0)
			(type solid)
		)
		(fill yes)
		(layer "In1.Cu")
		(net "P5E_PEX1_STN5_RX_DN<89>")
	)
	(gr_poly
		(pts
			(arc
				(start 183.5531 -317.749936)
				(mid 183.1467 -317.749936)
				(end 183.5531 -317.749936)
			)
		)
		(stroke
			(width 0)
			(type solid)
		)
		(fill yes)
		(layer "In1.Cu")
		(net "P5E_PEX1_STN5_RX_DP<89>")
	)
	(gr_poly
		(pts
			(arc
				(start 183.5531 -313.949842)
				(mid 183.1467 -313.949842)
				(end 183.5531 -313.949842)
			)
		)
		(stroke
			(width 0)
			(type solid)
		)
		(fill yes)
		(layer "In1.Cu")
		(net "P5E_PEX1_STN5_TX_DN<89>")
	)
	(gr_poly
		(pts
			(arc
				(start 183.5531 -312.999882)
				(mid 183.1467 -312.999882)
				(end 183.5531 -312.999882)
			)
		)
		(stroke
			(width 0)
			(type solid)
		)
		(fill yes)
		(layer "In1.Cu")
		(net "P5E_PEX1_STN5_TX_DP<89>")
	)
	(gr_poly
		(pts
			(arc
				(start 184.502806 -275.949664)
				(mid 184.096406 -275.949664)
				(end 184.502806 -275.949664)
			)
		)
		(stroke
			(width 0)
			(type solid)
		)
		(fill yes)
		(layer "In1.Cu")
		(net "P5E_PEX1_STN1_RX_DP<25>")
	)
	(gr_poly
		(pts
			(arc
				(start 184.502806 -274.999704)
				(mid 184.096406 -274.999704)
				(end 184.502806 -274.999704)
			)
		)
		(stroke
			(width 0)
			(type solid)
		)
		(fill yes)
		(layer "In1.Cu")
		(net "P5E_PEX1_STN1_RX_DN<25>")
	)
	(gr_poly
		(pts
			(arc
				(start 184.50306 -316.799722)
				(mid 184.09666 -316.799722)
				(end 184.50306 -316.799722)
			)
		)
		(stroke
			(width 0)
			(type solid)
		)
		(fill yes)
		(layer "In1.Cu")
		(net "P5E_PEX1_STN5_RX_DN<90>")
	)
	(gr_poly
		(pts
			(arc
				(start 184.50306 -315.849762)
				(mid 184.09666 -315.849762)
				(end 184.50306 -315.849762)
			)
		)
		(stroke
			(width 0)
			(type solid)
		)
		(fill yes)
		(layer "In1.Cu")
		(net "P5E_PEX1_STN5_RX_DP<90>")
	)
	(gr_poly
		(pts
			(arc
				(start 184.50306 -312.049922)
				(mid 184.09666 -312.049922)
				(end 184.50306 -312.049922)
			)
		)
		(stroke
			(width 0)
			(type solid)
		)
		(fill yes)
		(layer "In1.Cu")
		(net "P5E_PEX1_STN5_TX_DN<90>")
	)
	(gr_poly
		(pts
			(arc
				(start 184.50306 -311.099962)
				(mid 184.09666 -311.099962)
				(end 184.50306 -311.099962)
			)
		)
		(stroke
			(width 0)
			(type solid)
		)
		(fill yes)
		(layer "In1.Cu")
		(net "P5E_PEX1_STN5_TX_DP<90>")
	)
	(gr_poly
		(pts
			(arc
				(start 184.50306 -280.699718)
				(mid 184.09666 -280.699718)
				(end 184.50306 -280.699718)
			)
		)
		(stroke
			(width 0)
			(type solid)
		)
		(fill yes)
		(layer "In1.Cu")
		(net "P5E_PEX1_STN1_TX_DN<25>")
	)
	(gr_poly
		(pts
			(arc
				(start 184.50306 -279.749504)
				(mid 184.09666 -279.749504)
				(end 184.50306 -279.749504)
			)
		)
		(stroke
			(width 0)
			(type solid)
		)
		(fill yes)
		(layer "In1.Cu")
		(net "P5E_PEX1_STN1_TX_DP<25>")
	)
	(gr_poly
		(pts
			(arc
				(start 185.45302 -278.799798)
				(mid 185.04662 -278.799798)
				(end 185.45302 -278.799798)
			)
		)
		(stroke
			(width 0)
			(type solid)
		)
		(fill yes)
		(layer "In1.Cu")
		(net "P5E_PEX1_STN1_TX_DP<26>")
	)
	(gr_poly
		(pts
			(arc
				(start 185.45302 -277.849838)
				(mid 185.04662 -277.849838)
				(end 185.45302 -277.849838)
			)
		)
		(stroke
			(width 0)
			(type solid)
		)
		(fill yes)
		(layer "In1.Cu")
		(net "P5E_PEX1_STN1_TX_DN<26>")
	)
	(gr_poly
		(pts
			(arc
				(start 185.45302 -274.049744)
				(mid 185.04662 -274.049744)
				(end 185.45302 -274.049744)
			)
		)
		(stroke
			(width 0)
			(type solid)
		)
		(fill yes)
		(layer "In1.Cu")
		(net "P5E_PEX1_STN1_RX_DP<26>")
	)
	(gr_poly
		(pts
			(arc
				(start 185.45302 -273.099784)
				(mid 185.04662 -273.099784)
				(end 185.45302 -273.099784)
			)
		)
		(stroke
			(width 0)
			(type solid)
		)
		(fill yes)
		(layer "In1.Cu")
		(net "P5E_PEX1_STN1_RX_DN<26>")
	)
	(gr_poly
		(pts
			(arc
				(start 185.453274 -318.699896)
				(mid 185.046874 -318.699896)
				(end 185.453274 -318.699896)
			)
		)
		(stroke
			(width 0)
			(type solid)
		)
		(fill yes)
		(layer "In1.Cu")
		(net "P5E_PEX1_STN5_RX_DN<91>")
	)
	(gr_poly
		(pts
			(arc
				(start 185.453274 -317.749936)
				(mid 185.046874 -317.749936)
				(end 185.453274 -317.749936)
			)
		)
		(stroke
			(width 0)
			(type solid)
		)
		(fill yes)
		(layer "In1.Cu")
		(net "P5E_PEX1_STN5_RX_DP<91>")
	)
	(gr_poly
		(pts
			(arc
				(start 185.453274 -313.949842)
				(mid 185.046874 -313.949842)
				(end 185.453274 -313.949842)
			)
		)
		(stroke
			(width 0)
			(type solid)
		)
		(fill yes)
		(layer "In1.Cu")
		(net "P5E_PEX1_STN5_TX_DN<91>")
	)
	(gr_poly
		(pts
			(arc
				(start 185.453274 -312.999882)
				(mid 185.046874 -312.999882)
				(end 185.453274 -312.999882)
			)
		)
		(stroke
			(width 0)
			(type solid)
		)
		(fill yes)
		(layer "In1.Cu")
		(net "P5E_PEX1_STN5_TX_DP<91>")
	)
	(gr_poly
		(pts
			(arc
				(start 186.402726 -275.949918)
				(mid 185.996326 -275.949918)
				(end 186.402726 -275.949918)
			)
		)
		(stroke
			(width 0)
			(type solid)
		)
		(fill yes)
		(layer "In1.Cu")
		(net "P5E_PEX1_STN1_RX_DP<27>")
	)
	(gr_poly
		(pts
			(arc
				(start 186.402726 -274.999958)
				(mid 185.996326 -274.999958)
				(end 186.402726 -274.999958)
			)
		)
		(stroke
			(width 0)
			(type solid)
		)
		(fill yes)
		(layer "In1.Cu")
		(net "P5E_PEX1_STN1_RX_DN<27>")
	)
	(gr_poly
		(pts
			(arc
				(start 186.403234 -316.799722)
				(mid 185.996834 -316.799722)
				(end 186.403234 -316.799722)
			)
		)
		(stroke
			(width 0)
			(type solid)
		)
		(fill yes)
		(layer "In1.Cu")
		(net "P5E_PEX1_STN5_RX_DN<92>")
	)
	(gr_poly
		(pts
			(arc
				(start 186.403234 -315.849762)
				(mid 185.996834 -315.849762)
				(end 186.403234 -315.849762)
			)
		)
		(stroke
			(width 0)
			(type solid)
		)
		(fill yes)
		(layer "In1.Cu")
		(net "P5E_PEX1_STN5_RX_DP<92>")
	)
	(gr_poly
		(pts
			(arc
				(start 186.403234 -312.049922)
				(mid 185.996834 -312.049922)
				(end 186.403234 -312.049922)
			)
		)
		(stroke
			(width 0)
			(type solid)
		)
		(fill yes)
		(layer "In1.Cu")
		(net "P5E_PEX1_STN5_TX_DN<92>")
	)
	(gr_poly
		(pts
			(arc
				(start 186.403234 -311.099962)
				(mid 185.996834 -311.099962)
				(end 186.403234 -311.099962)
			)
		)
		(stroke
			(width 0)
			(type solid)
		)
		(fill yes)
		(layer "In1.Cu")
		(net "P5E_PEX1_STN5_TX_DP<92>")
	)
	(gr_poly
		(pts
			(arc
				(start 186.403234 -280.699718)
				(mid 185.996834 -280.699718)
				(end 186.403234 -280.699718)
			)
		)
		(stroke
			(width 0)
			(type solid)
		)
		(fill yes)
		(layer "In1.Cu")
		(net "P5E_PEX1_STN1_TX_DN<27>")
	)
	(gr_poly
		(pts
			(arc
				(start 186.403234 -279.749504)
				(mid 185.996834 -279.749504)
				(end 186.403234 -279.749504)
			)
		)
		(stroke
			(width 0)
			(type solid)
		)
		(fill yes)
		(layer "In1.Cu")
		(net "P5E_PEX1_STN1_TX_DP<27>")
	)
	(gr_poly
		(pts
			(arc
				(start 187.35294 -278.799798)
				(mid 186.94654 -278.799798)
				(end 187.35294 -278.799798)
			)
		)
		(stroke
			(width 0)
			(type solid)
		)
		(fill yes)
		(layer "In1.Cu")
		(net "P5E_PEX1_STN1_TX_DP<28>")
	)
	(gr_poly
		(pts
			(arc
				(start 187.35294 -277.849838)
				(mid 186.94654 -277.849838)
				(end 187.35294 -277.849838)
			)
		)
		(stroke
			(width 0)
			(type solid)
		)
		(fill yes)
		(layer "In1.Cu")
		(net "P5E_PEX1_STN1_TX_DN<28>")
	)
	(gr_poly
		(pts
			(arc
				(start 187.35294 -274.049744)
				(mid 186.94654 -274.049744)
				(end 187.35294 -274.049744)
			)
		)
		(stroke
			(width 0)
			(type solid)
		)
		(fill yes)
		(layer "In1.Cu")
		(net "P5E_PEX1_STN1_RX_DP<28>")
	)
	(gr_poly
		(pts
			(arc
				(start 187.35294 -273.099784)
				(mid 186.94654 -273.099784)
				(end 187.35294 -273.099784)
			)
		)
		(stroke
			(width 0)
			(type solid)
		)
		(fill yes)
		(layer "In1.Cu")
		(net "P5E_PEX1_STN1_RX_DN<28>")
	)
	(gr_poly
		(pts
			(arc
				(start 187.353194 -318.699896)
				(mid 186.946794 -318.699896)
				(end 187.353194 -318.699896)
			)
		)
		(stroke
			(width 0)
			(type solid)
		)
		(fill yes)
		(layer "In1.Cu")
		(net "P5E_PEX1_STN5_RX_DN<93>")
	)
	(gr_poly
		(pts
			(arc
				(start 187.353194 -317.749936)
				(mid 186.946794 -317.749936)
				(end 187.353194 -317.749936)
			)
		)
		(stroke
			(width 0)
			(type solid)
		)
		(fill yes)
		(layer "In1.Cu")
		(net "P5E_PEX1_STN5_RX_DP<93>")
	)
	(gr_poly
		(pts
			(arc
				(start 187.353194 -313.949842)
				(mid 186.946794 -313.949842)
				(end 187.353194 -313.949842)
			)
		)
		(stroke
			(width 0)
			(type solid)
		)
		(fill yes)
		(layer "In1.Cu")
		(net "P5E_PEX1_STN5_TX_DN<93>")
	)
	(gr_poly
		(pts
			(arc
				(start 187.353194 -312.999882)
				(mid 186.946794 -312.999882)
				(end 187.353194 -312.999882)
			)
		)
		(stroke
			(width 0)
			(type solid)
		)
		(fill yes)
		(layer "In1.Cu")
		(net "P5E_PEX1_STN5_TX_DP<93>")
	)
	(gr_poly
		(pts
			(arc
				(start 188.3029 -275.949664)
				(mid 187.8965 -275.949664)
				(end 188.3029 -275.949664)
			)
		)
		(stroke
			(width 0)
			(type solid)
		)
		(fill yes)
		(layer "In1.Cu")
		(net "P5E_PEX1_STN1_RX_DP<29>")
	)
	(gr_poly
		(pts
			(arc
				(start 188.3029 -274.999704)
				(mid 187.8965 -274.999704)
				(end 188.3029 -274.999704)
			)
		)
		(stroke
			(width 0)
			(type solid)
		)
		(fill yes)
		(layer "In1.Cu")
		(net "P5E_PEX1_STN1_RX_DN<29>")
	)
	(gr_poly
		(pts
			(arc
				(start 188.303154 -316.799722)
				(mid 187.896754 -316.799722)
				(end 188.303154 -316.799722)
			)
		)
		(stroke
			(width 0)
			(type solid)
		)
		(fill yes)
		(layer "In1.Cu")
		(net "P5E_PEX1_STN5_RX_DN<94>")
	)
	(gr_poly
		(pts
			(arc
				(start 188.303154 -315.849762)
				(mid 187.896754 -315.849762)
				(end 188.303154 -315.849762)
			)
		)
		(stroke
			(width 0)
			(type solid)
		)
		(fill yes)
		(layer "In1.Cu")
		(net "P5E_PEX1_STN5_RX_DP<94>")
	)
	(gr_poly
		(pts
			(arc
				(start 188.303154 -312.049922)
				(mid 187.896754 -312.049922)
				(end 188.303154 -312.049922)
			)
		)
		(stroke
			(width 0)
			(type solid)
		)
		(fill yes)
		(layer "In1.Cu")
		(net "P5E_PEX1_STN5_TX_DN<94>")
	)
	(gr_poly
		(pts
			(arc
				(start 188.303154 -311.099962)
				(mid 187.896754 -311.099962)
				(end 188.303154 -311.099962)
			)
		)
		(stroke
			(width 0)
			(type solid)
		)
		(fill yes)
		(layer "In1.Cu")
		(net "P5E_PEX1_STN5_TX_DP<94>")
	)
	(gr_poly
		(pts
			(arc
				(start 188.303154 -280.699718)
				(mid 187.896754 -280.699718)
				(end 188.303154 -280.699718)
			)
		)
		(stroke
			(width 0)
			(type solid)
		)
		(fill yes)
		(layer "In1.Cu")
		(net "P5E_PEX1_STN1_TX_DN<29>")
	)
	(gr_poly
		(pts
			(arc
				(start 188.303154 -279.749504)
				(mid 187.896754 -279.749504)
				(end 188.303154 -279.749504)
			)
		)
		(stroke
			(width 0)
			(type solid)
		)
		(fill yes)
		(layer "In1.Cu")
		(net "P5E_PEX1_STN1_TX_DP<29>")
	)
	(gr_poly
		(pts
			(arc
				(start 189.25286 -278.799798)
				(mid 188.84646 -278.799798)
				(end 189.25286 -278.799798)
			)
		)
		(stroke
			(width 0)
			(type solid)
		)
		(fill yes)
		(layer "In1.Cu")
		(net "P5E_PEX1_STN1_TX_DP<30>")
	)
	(gr_poly
		(pts
			(arc
				(start 189.25286 -277.849838)
				(mid 188.84646 -277.849838)
				(end 189.25286 -277.849838)
			)
		)
		(stroke
			(width 0)
			(type solid)
		)
		(fill yes)
		(layer "In1.Cu")
		(net "P5E_PEX1_STN1_TX_DN<30>")
	)
	(gr_poly
		(pts
			(arc
				(start 189.25286 -274.049744)
				(mid 188.84646 -274.049744)
				(end 189.25286 -274.049744)
			)
		)
		(stroke
			(width 0)
			(type solid)
		)
		(fill yes)
		(layer "In1.Cu")
		(net "P5E_PEX1_STN1_RX_DP<30>")
	)
	(gr_poly
		(pts
			(arc
				(start 189.25286 -273.099784)
				(mid 188.84646 -273.099784)
				(end 189.25286 -273.099784)
			)
		)
		(stroke
			(width 0)
			(type solid)
		)
		(fill yes)
		(layer "In1.Cu")
		(net "P5E_PEX1_STN1_RX_DN<30>")
	)
	(gr_poly
		(pts
			(arc
				(start 189.253114 -318.699896)
				(mid 188.846714 -318.699896)
				(end 189.253114 -318.699896)
			)
		)
		(stroke
			(width 0)
			(type solid)
		)
		(fill yes)
		(layer "In1.Cu")
		(net "P5E_PEX1_STN5_RX_DN<95>")
	)
	(gr_poly
		(pts
			(arc
				(start 189.253114 -317.749936)
				(mid 188.846714 -317.749936)
				(end 189.253114 -317.749936)
			)
		)
		(stroke
			(width 0)
			(type solid)
		)
		(fill yes)
		(layer "In1.Cu")
		(net "P5E_PEX1_STN5_RX_DP<95>")
	)
	(gr_poly
		(pts
			(arc
				(start 189.253114 -313.949842)
				(mid 188.846714 -313.949842)
				(end 189.253114 -313.949842)
			)
		)
		(stroke
			(width 0)
			(type solid)
		)
		(fill yes)
		(layer "In1.Cu")
		(net "P5E_PEX1_STN5_TX_DN<95>")
	)
	(gr_poly
		(pts
			(arc
				(start 189.253114 -312.999882)
				(mid 188.846714 -312.999882)
				(end 189.253114 -312.999882)
			)
		)
		(stroke
			(width 0)
			(type solid)
		)
		(fill yes)
		(layer "In1.Cu")
		(net "P5E_PEX1_STN5_TX_DP<95>")
	)
	(gr_poly
		(pts
			(arc
				(start 190.20282 -275.949918)
				(mid 189.79642 -275.949918)
				(end 190.20282 -275.949918)
			)
		)
		(stroke
			(width 0)
			(type solid)
		)
		(fill yes)
		(layer "In1.Cu")
		(net "P5E_PEX1_STN1_RX_DP<31>")
	)
	(gr_poly
		(pts
			(arc
				(start 190.20282 -274.999958)
				(mid 189.79642 -274.999958)
				(end 190.20282 -274.999958)
			)
		)
		(stroke
			(width 0)
			(type solid)
		)
		(fill yes)
		(layer "In1.Cu")
		(net "P5E_PEX1_STN1_RX_DN<31>")
	)
	(gr_poly
		(pts
			(arc
				(start 190.203074 -316.799722)
				(mid 189.796674 -316.799722)
				(end 190.203074 -316.799722)
			)
		)
		(stroke
			(width 0)
			(type solid)
		)
		(fill yes)
		(layer "In1.Cu")
		(net "P5E_PEX1_STN4_RX_DN<79>")
	)
	(gr_poly
		(pts
			(arc
				(start 190.203074 -315.849762)
				(mid 189.796674 -315.849762)
				(end 190.203074 -315.849762)
			)
		)
		(stroke
			(width 0)
			(type solid)
		)
		(fill yes)
		(layer "In1.Cu")
		(net "P5E_PEX1_STN4_RX_DP<79>")
	)
	(gr_poly
		(pts
			(arc
				(start 190.203074 -312.049922)
				(mid 189.796674 -312.049922)
				(end 190.203074 -312.049922)
			)
		)
		(stroke
			(width 0)
			(type solid)
		)
		(fill yes)
		(layer "In1.Cu")
		(net "P5E_PEX1_STN4_TX_DN<79>")
	)
	(gr_poly
		(pts
			(arc
				(start 190.203074 -311.099962)
				(mid 189.796674 -311.099962)
				(end 190.203074 -311.099962)
			)
		)
		(stroke
			(width 0)
			(type solid)
		)
		(fill yes)
		(layer "In1.Cu")
		(net "P5E_PEX1_STN4_TX_DP<79>")
	)
	(gr_poly
		(pts
			(arc
				(start 190.203074 -280.699718)
				(mid 189.796674 -280.699718)
				(end 190.203074 -280.699718)
			)
		)
		(stroke
			(width 0)
			(type solid)
		)
		(fill yes)
		(layer "In1.Cu")
		(net "P5E_PEX1_STN1_TX_DN<31>")
	)
	(gr_poly
		(pts
			(arc
				(start 190.203074 -279.749504)
				(mid 189.796674 -279.749504)
				(end 190.203074 -279.749504)
			)
		)
		(stroke
			(width 0)
			(type solid)
		)
		(fill yes)
		(layer "In1.Cu")
		(net "P5E_PEX1_STN1_TX_DP<31>")
	)
	(gr_poly
		(pts
			(arc
				(start 191.153034 -287.349946)
				(mid 190.746634 -287.349946)
				(end 191.153034 -287.349946)
			)
		)
		(stroke
			(width 0)
			(type solid)
		)
		(fill yes)
		(layer "In1.Cu")
		(net "P5E_PEX1_STN0_TX_DP<1>")
	)
	(gr_poly
		(pts
			(arc
				(start 191.153034 -285.449772)
				(mid 190.746634 -285.449772)
				(end 191.153034 -285.449772)
			)
		)
		(stroke
			(width 0)
			(type solid)
		)
		(fill yes)
		(layer "In1.Cu")
		(net "P5E_PEX1_STN0_TX_DP<3>")
	)
	(gr_poly
		(pts
			(arc
				(start 191.153034 -283.549852)
				(mid 190.746634 -283.549852)
				(end 191.153034 -283.549852)
			)
		)
		(stroke
			(width 0)
			(type solid)
		)
		(fill yes)
		(layer "In1.Cu")
		(net "P5E_PEX1_STN0_TX_DP<5>")
	)
	(gr_poly
		(pts
			(arc
				(start 191.153034 -278.799798)
				(mid 190.746634 -278.799798)
				(end 191.153034 -278.799798)
			)
		)
		(stroke
			(width 0)
			(type solid)
		)
		(fill yes)
		(layer "In1.Cu")
		(net "P5E_PEX1_STN0_TX_DP<15>")
	)
	(gr_poly
		(pts
			(arc
				(start 191.153034 -277.849838)
				(mid 190.746634 -277.849838)
				(end 191.153034 -277.849838)
			)
		)
		(stroke
			(width 0)
			(type solid)
		)
		(fill yes)
		(layer "In1.Cu")
		(net "P5E_PEX1_STN0_TX_DN<15>")
	)
	(gr_poly
		(pts
			(arc
				(start 191.153034 -274.049744)
				(mid 190.746634 -274.049744)
				(end 191.153034 -274.049744)
			)
		)
		(stroke
			(width 0)
			(type solid)
		)
		(fill yes)
		(layer "In1.Cu")
		(net "P5E_PEX1_STN0_RX_DP<15>")
	)
	(gr_poly
		(pts
			(arc
				(start 191.153034 -273.099784)
				(mid 190.746634 -273.099784)
				(end 191.153034 -273.099784)
			)
		)
		(stroke
			(width 0)
			(type solid)
		)
		(fill yes)
		(layer "In1.Cu")
		(net "P5E_PEX1_STN0_RX_DN<15>")
	)
	(gr_poly
		(pts
			(arc
				(start 191.153288 -318.699896)
				(mid 190.746888 -318.699896)
				(end 191.153288 -318.699896)
			)
		)
		(stroke
			(width 0)
			(type solid)
		)
		(fill yes)
		(layer "In1.Cu")
		(net "P5E_PEX1_STN4_RX_DN<78>")
	)
	(gr_poly
		(pts
			(arc
				(start 191.153288 -317.749936)
				(mid 190.746888 -317.749936)
				(end 191.153288 -317.749936)
			)
		)
		(stroke
			(width 0)
			(type solid)
		)
		(fill yes)
		(layer "In1.Cu")
		(net "P5E_PEX1_STN4_RX_DP<78>")
	)
	(gr_poly
		(pts
			(arc
				(start 191.153288 -313.949842)
				(mid 190.746888 -313.949842)
				(end 191.153288 -313.949842)
			)
		)
		(stroke
			(width 0)
			(type solid)
		)
		(fill yes)
		(layer "In1.Cu")
		(net "P5E_PEX1_STN4_TX_DN<78>")
	)
	(gr_poly
		(pts
			(arc
				(start 191.153288 -312.999882)
				(mid 190.746888 -312.999882)
				(end 191.153288 -312.999882)
			)
		)
		(stroke
			(width 0)
			(type solid)
		)
		(fill yes)
		(layer "In1.Cu")
		(net "P5E_PEX1_STN4_TX_DP<78>")
	)
	(gr_poly
		(pts
			(arc
				(start 191.153288 -308.249828)
				(mid 190.746888 -308.249828)
				(end 191.153288 -308.249828)
			)
		)
		(stroke
			(width 0)
			(type solid)
		)
		(fill yes)
		(layer "In1.Cu")
		(net "P5E_PEX1_STN4_TX_DP<68>")
	)
	(gr_poly
		(pts
			(arc
				(start 191.153288 -306.349908)
				(mid 190.746888 -306.349908)
				(end 191.153288 -306.349908)
			)
		)
		(stroke
			(width 0)
			(type solid)
		)
		(fill yes)
		(layer "In1.Cu")
		(net "P5E_PEX1_STN4_TX_DP<66>")
	)
	(gr_poly
		(pts
			(arc
				(start 191.153288 -304.449734)
				(mid 190.746888 -304.449734)
				(end 191.153288 -304.449734)
			)
		)
		(stroke
			(width 0)
			(type solid)
		)
		(fill yes)
		(layer "In1.Cu")
		(net "P5E_PEX1_STN4_TX_DP<64>")
	)
	(gr_poly
		(pts
			(arc
				(start 192.102994 -275.949664)
				(mid 191.696594 -275.949664)
				(end 192.102994 -275.949664)
			)
		)
		(stroke
			(width 0)
			(type solid)
		)
		(fill yes)
		(layer "In1.Cu")
		(net "P5E_PEX1_STN0_RX_DP<14>")
	)
	(gr_poly
		(pts
			(arc
				(start 192.102994 -274.999704)
				(mid 191.696594 -274.999704)
				(end 192.102994 -274.999704)
			)
		)
		(stroke
			(width 0)
			(type solid)
		)
		(fill yes)
		(layer "In1.Cu")
		(net "P5E_PEX1_STN0_RX_DN<14>")
	)
	(gr_poly
		(pts
			(arc
				(start 192.103248 -316.799722)
				(mid 191.696848 -316.799722)
				(end 192.103248 -316.799722)
			)
		)
		(stroke
			(width 0)
			(type solid)
		)
		(fill yes)
		(layer "In1.Cu")
		(net "P5E_PEX1_STN4_RX_DN<77>")
	)
	(gr_poly
		(pts
			(arc
				(start 192.103248 -315.849762)
				(mid 191.696848 -315.849762)
				(end 192.103248 -315.849762)
			)
		)
		(stroke
			(width 0)
			(type solid)
		)
		(fill yes)
		(layer "In1.Cu")
		(net "P5E_PEX1_STN4_RX_DP<77>")
	)
	(gr_poly
		(pts
			(arc
				(start 192.103248 -312.049922)
				(mid 191.696848 -312.049922)
				(end 192.103248 -312.049922)
			)
		)
		(stroke
			(width 0)
			(type solid)
		)
		(fill yes)
		(layer "In1.Cu")
		(net "P5E_PEX1_STN4_TX_DN<77>")
	)
	(gr_poly
		(pts
			(arc
				(start 192.103248 -311.099962)
				(mid 191.696848 -311.099962)
				(end 192.103248 -311.099962)
			)
		)
		(stroke
			(width 0)
			(type solid)
		)
		(fill yes)
		(layer "In1.Cu")
		(net "P5E_PEX1_STN4_TX_DP<77>")
	)
	(gr_poly
		(pts
			(arc
				(start 192.103248 -308.249828)
				(mid 191.696848 -308.249828)
				(end 192.103248 -308.249828)
			)
		)
		(stroke
			(width 0)
			(type solid)
		)
		(fill yes)
		(layer "In1.Cu")
		(net "P5E_PEX1_STN4_TX_DN<68>")
	)
	(gr_poly
		(pts
			(arc
				(start 192.103248 -306.349908)
				(mid 191.696848 -306.349908)
				(end 192.103248 -306.349908)
			)
		)
		(stroke
			(width 0)
			(type solid)
		)
		(fill yes)
		(layer "In1.Cu")
		(net "P5E_PEX1_STN4_TX_DN<66>")
	)
	(gr_poly
		(pts
			(arc
				(start 192.103248 -304.449734)
				(mid 191.696848 -304.449734)
				(end 192.103248 -304.449734)
			)
		)
		(stroke
			(width 0)
			(type solid)
		)
		(fill yes)
		(layer "In1.Cu")
		(net "P5E_PEX1_STN4_TX_DN<64>")
	)
	(gr_poly
		(pts
			(arc
				(start 192.103248 -287.349946)
				(mid 191.696848 -287.349946)
				(end 192.103248 -287.349946)
			)
		)
		(stroke
			(width 0)
			(type solid)
		)
		(fill yes)
		(layer "In1.Cu")
		(net "P5E_PEX1_STN0_TX_DN<1>")
	)
	(gr_poly
		(pts
			(arc
				(start 192.103248 -285.449772)
				(mid 191.696848 -285.449772)
				(end 192.103248 -285.449772)
			)
		)
		(stroke
			(width 0)
			(type solid)
		)
		(fill yes)
		(layer "In1.Cu")
		(net "P5E_PEX1_STN0_TX_DN<3>")
	)
	(gr_poly
		(pts
			(arc
				(start 192.103248 -283.549852)
				(mid 191.696848 -283.549852)
				(end 192.103248 -283.549852)
			)
		)
		(stroke
			(width 0)
			(type solid)
		)
		(fill yes)
		(layer "In1.Cu")
		(net "P5E_PEX1_STN0_TX_DN<5>")
	)
	(gr_poly
		(pts
			(arc
				(start 192.103248 -280.699718)
				(mid 191.696848 -280.699718)
				(end 192.103248 -280.699718)
			)
		)
		(stroke
			(width 0)
			(type solid)
		)
		(fill yes)
		(layer "In1.Cu")
		(net "P5E_PEX1_STN0_TX_DN<14>")
	)
	(gr_poly
		(pts
			(arc
				(start 192.103248 -279.749504)
				(mid 191.696848 -279.749504)
				(end 192.103248 -279.749504)
			)
		)
		(stroke
			(width 0)
			(type solid)
		)
		(fill yes)
		(layer "In1.Cu")
		(net "P5E_PEX1_STN0_TX_DP<14>")
	)
	(gr_poly
		(pts
			(arc
				(start 193.052954 -278.799798)
				(mid 192.646554 -278.799798)
				(end 193.052954 -278.799798)
			)
		)
		(stroke
			(width 0)
			(type solid)
		)
		(fill yes)
		(layer "In1.Cu")
		(net "P5E_PEX1_STN0_TX_DP<13>")
	)
	(gr_poly
		(pts
			(arc
				(start 193.052954 -277.849838)
				(mid 192.646554 -277.849838)
				(end 193.052954 -277.849838)
			)
		)
		(stroke
			(width 0)
			(type solid)
		)
		(fill yes)
		(layer "In1.Cu")
		(net "P5E_PEX1_STN0_TX_DN<13>")
	)
	(gr_poly
		(pts
			(arc
				(start 193.052954 -274.049744)
				(mid 192.646554 -274.049744)
				(end 193.052954 -274.049744)
			)
		)
		(stroke
			(width 0)
			(type solid)
		)
		(fill yes)
		(layer "In1.Cu")
		(net "P5E_PEX1_STN0_RX_DP<13>")
	)
	(gr_poly
		(pts
			(arc
				(start 193.052954 -273.099784)
				(mid 192.646554 -273.099784)
				(end 193.052954 -273.099784)
			)
		)
		(stroke
			(width 0)
			(type solid)
		)
		(fill yes)
		(layer "In1.Cu")
		(net "P5E_PEX1_STN0_RX_DN<13>")
	)
	(gr_poly
		(pts
			(arc
				(start 193.053208 -318.699896)
				(mid 192.646808 -318.699896)
				(end 193.053208 -318.699896)
			)
		)
		(stroke
			(width 0)
			(type solid)
		)
		(fill yes)
		(layer "In1.Cu")
		(net "P5E_PEX1_STN4_RX_DN<76>")
	)
	(gr_poly
		(pts
			(arc
				(start 193.053208 -317.749936)
				(mid 192.646808 -317.749936)
				(end 193.053208 -317.749936)
			)
		)
		(stroke
			(width 0)
			(type solid)
		)
		(fill yes)
		(layer "In1.Cu")
		(net "P5E_PEX1_STN4_RX_DP<76>")
	)
	(gr_poly
		(pts
			(arc
				(start 193.053208 -313.949842)
				(mid 192.646808 -313.949842)
				(end 193.053208 -313.949842)
			)
		)
		(stroke
			(width 0)
			(type solid)
		)
		(fill yes)
		(layer "In1.Cu")
		(net "P5E_PEX1_STN4_TX_DN<76>")
	)
	(gr_poly
		(pts
			(arc
				(start 193.053208 -312.999882)
				(mid 192.646808 -312.999882)
				(end 193.053208 -312.999882)
			)
		)
		(stroke
			(width 0)
			(type solid)
		)
		(fill yes)
		(layer "In1.Cu")
		(net "P5E_PEX1_STN4_TX_DP<76>")
	)
	(gr_poly
		(pts
			(arc
				(start 193.053208 -309.199788)
				(mid 192.646808 -309.199788)
				(end 193.053208 -309.199788)
			)
		)
		(stroke
			(width 0)
			(type solid)
		)
		(fill yes)
		(layer "In1.Cu")
		(net "P5E_PEX1_STN4_TX_DP<69>")
	)
	(gr_poly
		(pts
			(arc
				(start 193.053208 -307.299868)
				(mid 192.646808 -307.299868)
				(end 193.053208 -307.299868)
			)
		)
		(stroke
			(width 0)
			(type solid)
		)
		(fill yes)
		(layer "In1.Cu")
		(net "P5E_PEX1_STN4_TX_DP<67>")
	)
	(gr_poly
		(pts
			(arc
				(start 193.053208 -305.399948)
				(mid 192.646808 -305.399948)
				(end 193.053208 -305.399948)
			)
		)
		(stroke
			(width 0)
			(type solid)
		)
		(fill yes)
		(layer "In1.Cu")
		(net "P5E_PEX1_STN4_TX_DP<65>")
	)
	(gr_poly
		(pts
			(arc
				(start 193.053208 -288.299906)
				(mid 192.646808 -288.299906)
				(end 193.053208 -288.299906)
			)
		)
		(stroke
			(width 0)
			(type solid)
		)
		(fill yes)
		(layer "In1.Cu")
		(net "P5E_PEX1_STN0_TX_DP<0>")
	)
	(gr_poly
		(pts
			(arc
				(start 193.053208 -286.399986)
				(mid 192.646808 -286.399986)
				(end 193.053208 -286.399986)
			)
		)
		(stroke
			(width 0)
			(type solid)
		)
		(fill yes)
		(layer "In1.Cu")
		(net "P5E_PEX1_STN0_TX_DP<2>")
	)
	(gr_poly
		(pts
			(arc
				(start 193.053208 -284.499812)
				(mid 192.646808 -284.499812)
				(end 193.053208 -284.499812)
			)
		)
		(stroke
			(width 0)
			(type solid)
		)
		(fill yes)
		(layer "In1.Cu")
		(net "P5E_PEX1_STN0_TX_DP<4>")
	)
	(gr_poly
		(pts
			(arc
				(start 193.053208 -282.599892)
				(mid 192.646808 -282.599892)
				(end 193.053208 -282.599892)
			)
		)
		(stroke
			(width 0)
			(type solid)
		)
		(fill yes)
		(layer "In1.Cu")
		(net "P5E_PEX1_STN0_TX_DP<6>")
	)
	(gr_poly
		(pts
			(arc
				(start 194.002914 -275.949918)
				(mid 193.596514 -275.949918)
				(end 194.002914 -275.949918)
			)
		)
		(stroke
			(width 0)
			(type solid)
		)
		(fill yes)
		(layer "In1.Cu")
		(net "P5E_PEX1_STN0_RX_DP<12>")
	)
	(gr_poly
		(pts
			(arc
				(start 194.002914 -274.999958)
				(mid 193.596514 -274.999958)
				(end 194.002914 -274.999958)
			)
		)
		(stroke
			(width 0)
			(type solid)
		)
		(fill yes)
		(layer "In1.Cu")
		(net "P5E_PEX1_STN0_RX_DN<12>")
	)
	(gr_poly
		(pts
			(arc
				(start 194.003168 -316.799722)
				(mid 193.596768 -316.799722)
				(end 194.003168 -316.799722)
			)
		)
		(stroke
			(width 0)
			(type solid)
		)
		(fill yes)
		(layer "In1.Cu")
		(net "P5E_PEX1_STN4_RX_DN<75>")
	)
	(gr_poly
		(pts
			(arc
				(start 194.003168 -315.849762)
				(mid 193.596768 -315.849762)
				(end 194.003168 -315.849762)
			)
		)
		(stroke
			(width 0)
			(type solid)
		)
		(fill yes)
		(layer "In1.Cu")
		(net "P5E_PEX1_STN4_RX_DP<75>")
	)
	(gr_poly
		(pts
			(arc
				(start 194.003168 -312.049922)
				(mid 193.596768 -312.049922)
				(end 194.003168 -312.049922)
			)
		)
		(stroke
			(width 0)
			(type solid)
		)
		(fill yes)
		(layer "In1.Cu")
		(net "P5E_PEX1_STN4_TX_DN<75>")
	)
	(gr_poly
		(pts
			(arc
				(start 194.003168 -311.099962)
				(mid 193.596768 -311.099962)
				(end 194.003168 -311.099962)
			)
		)
		(stroke
			(width 0)
			(type solid)
		)
		(fill yes)
		(layer "In1.Cu")
		(net "P5E_PEX1_STN4_TX_DP<75>")
	)
	(gr_poly
		(pts
			(arc
				(start 194.003168 -309.199788)
				(mid 193.596768 -309.199788)
				(end 194.003168 -309.199788)
			)
		)
		(stroke
			(width 0)
			(type solid)
		)
		(fill yes)
		(layer "In1.Cu")
		(net "P5E_PEX1_STN4_TX_DN<69>")
	)
	(gr_poly
		(pts
			(arc
				(start 194.003168 -307.299868)
				(mid 193.596768 -307.299868)
				(end 194.003168 -307.299868)
			)
		)
		(stroke
			(width 0)
			(type solid)
		)
		(fill yes)
		(layer "In1.Cu")
		(net "P5E_PEX1_STN4_TX_DN<67>")
	)
	(gr_poly
		(pts
			(arc
				(start 194.003168 -305.399948)
				(mid 193.596768 -305.399948)
				(end 194.003168 -305.399948)
			)
		)
		(stroke
			(width 0)
			(type solid)
		)
		(fill yes)
		(layer "In1.Cu")
		(net "P5E_PEX1_STN4_TX_DN<65>")
	)
	(gr_poly
		(pts
			(arc
				(start 194.003168 -288.299906)
				(mid 193.596768 -288.299906)
				(end 194.003168 -288.299906)
			)
		)
		(stroke
			(width 0)
			(type solid)
		)
		(fill yes)
		(layer "In1.Cu")
		(net "P5E_PEX1_STN0_TX_DN<0>")
	)
	(gr_poly
		(pts
			(arc
				(start 194.003168 -286.399986)
				(mid 193.596768 -286.399986)
				(end 194.003168 -286.399986)
			)
		)
		(stroke
			(width 0)
			(type solid)
		)
		(fill yes)
		(layer "In1.Cu")
		(net "P5E_PEX1_STN0_TX_DN<2>")
	)
	(gr_poly
		(pts
			(arc
				(start 194.003168 -284.499812)
				(mid 193.596768 -284.499812)
				(end 194.003168 -284.499812)
			)
		)
		(stroke
			(width 0)
			(type solid)
		)
		(fill yes)
		(layer "In1.Cu")
		(net "P5E_PEX1_STN0_TX_DN<4>")
	)
	(gr_poly
		(pts
			(arc
				(start 194.003168 -282.599892)
				(mid 193.596768 -282.599892)
				(end 194.003168 -282.599892)
			)
		)
		(stroke
			(width 0)
			(type solid)
		)
		(fill yes)
		(layer "In1.Cu")
		(net "P5E_PEX1_STN0_TX_DN<6>")
	)
	(gr_poly
		(pts
			(arc
				(start 194.003168 -280.699718)
				(mid 193.596768 -280.699718)
				(end 194.003168 -280.699718)
			)
		)
		(stroke
			(width 0)
			(type solid)
		)
		(fill yes)
		(layer "In1.Cu")
		(net "P5E_PEX1_STN0_TX_DN<12>")
	)
	(gr_poly
		(pts
			(arc
				(start 194.003168 -279.749504)
				(mid 193.596768 -279.749504)
				(end 194.003168 -279.749504)
			)
		)
		(stroke
			(width 0)
			(type solid)
		)
		(fill yes)
		(layer "In1.Cu")
		(net "P5E_PEX1_STN0_TX_DP<12>")
	)
	(gr_poly
		(pts
			(arc
				(start 194.952874 -278.799798)
				(mid 194.546474 -278.799798)
				(end 194.952874 -278.799798)
			)
		)
		(stroke
			(width 0)
			(type solid)
		)
		(fill yes)
		(layer "In1.Cu")
		(net "P5E_PEX1_STN0_TX_DP<11>")
	)
	(gr_poly
		(pts
			(arc
				(start 194.952874 -277.849838)
				(mid 194.546474 -277.849838)
				(end 194.952874 -277.849838)
			)
		)
		(stroke
			(width 0)
			(type solid)
		)
		(fill yes)
		(layer "In1.Cu")
		(net "P5E_PEX1_STN0_TX_DN<11>")
	)
	(gr_poly
		(pts
			(arc
				(start 194.952874 -274.049744)
				(mid 194.546474 -274.049744)
				(end 194.952874 -274.049744)
			)
		)
		(stroke
			(width 0)
			(type solid)
		)
		(fill yes)
		(layer "In1.Cu")
		(net "P5E_PEX1_STN0_RX_DP<11>")
	)
	(gr_poly
		(pts
			(arc
				(start 194.952874 -273.099784)
				(mid 194.546474 -273.099784)
				(end 194.952874 -273.099784)
			)
		)
		(stroke
			(width 0)
			(type solid)
		)
		(fill yes)
		(layer "In1.Cu")
		(net "P5E_PEX1_STN0_RX_DN<11>")
	)
	(gr_poly
		(pts
			(arc
				(start 194.953128 -318.699896)
				(mid 194.546728 -318.699896)
				(end 194.953128 -318.699896)
			)
		)
		(stroke
			(width 0)
			(type solid)
		)
		(fill yes)
		(layer "In1.Cu")
		(net "P5E_PEX1_STN4_RX_DN<74>")
	)
	(gr_poly
		(pts
			(arc
				(start 194.953128 -317.749936)
				(mid 194.546728 -317.749936)
				(end 194.953128 -317.749936)
			)
		)
		(stroke
			(width 0)
			(type solid)
		)
		(fill yes)
		(layer "In1.Cu")
		(net "P5E_PEX1_STN4_RX_DP<74>")
	)
	(gr_poly
		(pts
			(arc
				(start 194.953128 -313.949842)
				(mid 194.546728 -313.949842)
				(end 194.953128 -313.949842)
			)
		)
		(stroke
			(width 0)
			(type solid)
		)
		(fill yes)
		(layer "In1.Cu")
		(net "P5E_PEX1_STN4_TX_DN<74>")
	)
	(gr_poly
		(pts
			(arc
				(start 194.953128 -312.999882)
				(mid 194.546728 -312.999882)
				(end 194.953128 -312.999882)
			)
		)
		(stroke
			(width 0)
			(type solid)
		)
		(fill yes)
		(layer "In1.Cu")
		(net "P5E_PEX1_STN4_TX_DP<74>")
	)
	(gr_poly
		(pts
			(arc
				(start 195.902834 -275.949918)
				(mid 195.496434 -275.949918)
				(end 195.902834 -275.949918)
			)
		)
		(stroke
			(width 0)
			(type solid)
		)
		(fill yes)
		(layer "In1.Cu")
		(net "P5E_PEX1_STN0_RX_DP<10>")
	)
	(gr_poly
		(pts
			(arc
				(start 195.902834 -274.999958)
				(mid 195.496434 -274.999958)
				(end 195.902834 -274.999958)
			)
		)
		(stroke
			(width 0)
			(type solid)
		)
		(fill yes)
		(layer "In1.Cu")
		(net "P5E_PEX1_STN0_RX_DN<10>")
	)
	(gr_poly
		(pts
			(arc
				(start 195.903088 -316.799722)
				(mid 195.496688 -316.799722)
				(end 195.903088 -316.799722)
			)
		)
		(stroke
			(width 0)
			(type solid)
		)
		(fill yes)
		(layer "In1.Cu")
		(net "P5E_PEX1_STN4_RX_DN<73>")
	)
	(gr_poly
		(pts
			(arc
				(start 195.903088 -315.849762)
				(mid 195.496688 -315.849762)
				(end 195.903088 -315.849762)
			)
		)
		(stroke
			(width 0)
			(type solid)
		)
		(fill yes)
		(layer "In1.Cu")
		(net "P5E_PEX1_STN4_RX_DP<73>")
	)
	(gr_poly
		(pts
			(arc
				(start 195.903088 -312.049922)
				(mid 195.496688 -312.049922)
				(end 195.903088 -312.049922)
			)
		)
		(stroke
			(width 0)
			(type solid)
		)
		(fill yes)
		(layer "In1.Cu")
		(net "P5E_PEX1_STN4_TX_DN<73>")
	)
	(gr_poly
		(pts
			(arc
				(start 195.903088 -311.099962)
				(mid 195.496688 -311.099962)
				(end 195.903088 -311.099962)
			)
		)
		(stroke
			(width 0)
			(type solid)
		)
		(fill yes)
		(layer "In1.Cu")
		(net "P5E_PEX1_STN4_TX_DP<73>")
	)
	(gr_poly
		(pts
			(arc
				(start 195.903088 -309.199788)
				(mid 195.496688 -309.199788)
				(end 195.903088 -309.199788)
			)
		)
		(stroke
			(width 0)
			(type solid)
		)
		(fill yes)
		(layer "In1.Cu")
		(net "P5E_PEX1_STN4_RX_DP<69>")
	)
	(gr_poly
		(pts
			(arc
				(start 195.903088 -307.299868)
				(mid 195.496688 -307.299868)
				(end 195.903088 -307.299868)
			)
		)
		(stroke
			(width 0)
			(type solid)
		)
		(fill yes)
		(layer "In1.Cu")
		(net "P5E_PEX1_STN4_RX_DP<67>")
	)
	(gr_poly
		(pts
			(arc
				(start 195.903088 -305.399948)
				(mid 195.496688 -305.399948)
				(end 195.903088 -305.399948)
			)
		)
		(stroke
			(width 0)
			(type solid)
		)
		(fill yes)
		(layer "In1.Cu")
		(net "P5E_PEX1_STN4_RX_DP<65>")
	)
	(gr_poly
		(pts
			(arc
				(start 195.903088 -288.299906)
				(mid 195.496688 -288.299906)
				(end 195.903088 -288.299906)
			)
		)
		(stroke
			(width 0)
			(type solid)
		)
		(fill yes)
		(layer "In1.Cu")
		(net "P5E_PEX1_STN0_RX_DP<0>")
	)
	(gr_poly
		(pts
			(arc
				(start 195.903088 -286.399732)
				(mid 195.496688 -286.399732)
				(end 195.903088 -286.399732)
			)
		)
		(stroke
			(width 0)
			(type solid)
		)
		(fill yes)
		(layer "In1.Cu")
		(net "P5E_PEX1_STN0_RX_DP<2>")
	)
	(gr_poly
		(pts
			(arc
				(start 195.903088 -284.499812)
				(mid 195.496688 -284.499812)
				(end 195.903088 -284.499812)
			)
		)
		(stroke
			(width 0)
			(type solid)
		)
		(fill yes)
		(layer "In1.Cu")
		(net "P5E_PEX1_STN0_RX_DP<4>")
	)
	(gr_poly
		(pts
			(arc
				(start 195.903088 -282.599892)
				(mid 195.496688 -282.599892)
				(end 195.903088 -282.599892)
			)
		)
		(stroke
			(width 0)
			(type solid)
		)
		(fill yes)
		(layer "In1.Cu")
		(net "P5E_PEX1_STN0_RX_DP<6>")
	)
	(gr_poly
		(pts
			(arc
				(start 195.903088 -280.699718)
				(mid 195.496688 -280.699718)
				(end 195.903088 -280.699718)
			)
		)
		(stroke
			(width 0)
			(type solid)
		)
		(fill yes)
		(layer "In1.Cu")
		(net "P5E_PEX1_STN0_TX_DP<10>")
	)
	(gr_poly
		(pts
			(arc
				(start 195.903088 -279.749758)
				(mid 195.496688 -279.749758)
				(end 195.903088 -279.749758)
			)
		)
		(stroke
			(width 0)
			(type solid)
		)
		(fill yes)
		(layer "In1.Cu")
		(net "P5E_PEX1_STN0_TX_DN<10>")
	)
	(gr_poly
		(pts
			(arc
				(start 196.852794 -274.049744)
				(mid 196.446394 -274.049744)
				(end 196.852794 -274.049744)
			)
		)
		(stroke
			(width 0)
			(type solid)
		)
		(fill yes)
		(layer "In1.Cu")
		(net "P5E_PEX1_STN0_RX_DP<9>")
	)
	(gr_poly
		(pts
			(arc
				(start 196.852794 -273.099784)
				(mid 196.446394 -273.099784)
				(end 196.852794 -273.099784)
			)
		)
		(stroke
			(width 0)
			(type solid)
		)
		(fill yes)
		(layer "In1.Cu")
		(net "P5E_PEX1_STN0_RX_DN<9>")
	)
	(gr_poly
		(pts
			(arc
				(start 196.853048 -318.699896)
				(mid 196.446648 -318.699896)
				(end 196.853048 -318.699896)
			)
		)
		(stroke
			(width 0)
			(type solid)
		)
		(fill yes)
		(layer "In1.Cu")
		(net "P5E_PEX1_STN4_RX_DN<72>")
	)
	(gr_poly
		(pts
			(arc
				(start 196.853048 -317.749936)
				(mid 196.446648 -317.749936)
				(end 196.853048 -317.749936)
			)
		)
		(stroke
			(width 0)
			(type solid)
		)
		(fill yes)
		(layer "In1.Cu")
		(net "P5E_PEX1_STN4_RX_DP<72>")
	)
	(gr_poly
		(pts
			(arc
				(start 196.853048 -313.949842)
				(mid 196.446648 -313.949842)
				(end 196.853048 -313.949842)
			)
		)
		(stroke
			(width 0)
			(type solid)
		)
		(fill yes)
		(layer "In1.Cu")
		(net "P5E_PEX1_STN4_TX_DN<72>")
	)
	(gr_poly
		(pts
			(arc
				(start 196.853048 -312.999882)
				(mid 196.446648 -312.999882)
				(end 196.853048 -312.999882)
			)
		)
		(stroke
			(width 0)
			(type solid)
		)
		(fill yes)
		(layer "In1.Cu")
		(net "P5E_PEX1_STN4_TX_DP<72>")
	)
	(gr_poly
		(pts
			(arc
				(start 196.853048 -309.199788)
				(mid 196.446648 -309.199788)
				(end 196.853048 -309.199788)
			)
		)
		(stroke
			(width 0)
			(type solid)
		)
		(fill yes)
		(layer "In1.Cu")
		(net "P5E_PEX1_STN4_RX_DN<69>")
	)
	(gr_poly
		(pts
			(arc
				(start 196.853048 -307.299868)
				(mid 196.446648 -307.299868)
				(end 196.853048 -307.299868)
			)
		)
		(stroke
			(width 0)
			(type solid)
		)
		(fill yes)
		(layer "In1.Cu")
		(net "P5E_PEX1_STN4_RX_DN<67>")
	)
	(gr_poly
		(pts
			(arc
				(start 196.853048 -305.399948)
				(mid 196.446648 -305.399948)
				(end 196.853048 -305.399948)
			)
		)
		(stroke
			(width 0)
			(type solid)
		)
		(fill yes)
		(layer "In1.Cu")
		(net "P5E_PEX1_STN4_RX_DN<65>")
	)
	(gr_poly
		(pts
			(arc
				(start 196.853048 -288.299906)
				(mid 196.446648 -288.299906)
				(end 196.853048 -288.299906)
			)
		)
		(stroke
			(width 0)
			(type solid)
		)
		(fill yes)
		(layer "In1.Cu")
		(net "P5E_PEX1_STN0_RX_DN<0>")
	)
	(gr_poly
		(pts
			(arc
				(start 196.853048 -286.399732)
				(mid 196.446648 -286.399732)
				(end 196.853048 -286.399732)
			)
		)
		(stroke
			(width 0)
			(type solid)
		)
		(fill yes)
		(layer "In1.Cu")
		(net "P5E_PEX1_STN0_RX_DN<2>")
	)
	(gr_poly
		(pts
			(arc
				(start 196.853048 -284.499812)
				(mid 196.446648 -284.499812)
				(end 196.853048 -284.499812)
			)
		)
		(stroke
			(width 0)
			(type solid)
		)
		(fill yes)
		(layer "In1.Cu")
		(net "P5E_PEX1_STN0_RX_DN<4>")
	)
	(gr_poly
		(pts
			(arc
				(start 196.853048 -282.599892)
				(mid 196.446648 -282.599892)
				(end 196.853048 -282.599892)
			)
		)
		(stroke
			(width 0)
			(type solid)
		)
		(fill yes)
		(layer "In1.Cu")
		(net "P5E_PEX1_STN0_RX_DN<6>")
	)
	(gr_poly
		(pts
			(arc
				(start 196.853048 -278.799798)
				(mid 196.446648 -278.799798)
				(end 196.853048 -278.799798)
			)
		)
		(stroke
			(width 0)
			(type solid)
		)
		(fill yes)
		(layer "In1.Cu")
		(net "P5E_PEX1_STN0_TX_DP<9>")
	)
	(gr_poly
		(pts
			(arc
				(start 196.853048 -277.849838)
				(mid 196.446648 -277.849838)
				(end 196.853048 -277.849838)
			)
		)
		(stroke
			(width 0)
			(type solid)
		)
		(fill yes)
		(layer "In1.Cu")
		(net "P5E_PEX1_STN0_TX_DN<9>")
	)
	(gr_poly
		(pts
			(arc
				(start 197.803262 -316.799722)
				(mid 197.396862 -316.799722)
				(end 197.803262 -316.799722)
			)
		)
		(stroke
			(width 0)
			(type solid)
		)
		(fill yes)
		(layer "In1.Cu")
		(net "P5E_PEX1_STN4_RX_DP<71>")
	)
	(gr_poly
		(pts
			(arc
				(start 197.803262 -314.899802)
				(mid 197.396862 -314.899802)
				(end 197.803262 -314.899802)
			)
		)
		(stroke
			(width 0)
			(type solid)
		)
		(fill yes)
		(layer "In1.Cu")
		(net "P5E_PEX1_STN4_TX_DP<71>")
	)
	(gr_poly
		(pts
			(arc
				(start 197.803262 -312.049922)
				(mid 197.396862 -312.049922)
				(end 197.803262 -312.049922)
			)
		)
		(stroke
			(width 0)
			(type solid)
		)
		(fill yes)
		(layer "In1.Cu")
		(net "P5E_PEX1_STN4_TX_DP<70>")
	)
	(gr_poly
		(pts
			(arc
				(start 197.803262 -310.149748)
				(mid 197.396862 -310.149748)
				(end 197.803262 -310.149748)
			)
		)
		(stroke
			(width 0)
			(type solid)
		)
		(fill yes)
		(layer "In1.Cu")
		(net "P5E_PEX1_STN4_RX_DP<70>")
	)
	(gr_poly
		(pts
			(arc
				(start 197.803262 -308.249828)
				(mid 197.396862 -308.249828)
				(end 197.803262 -308.249828)
			)
		)
		(stroke
			(width 0)
			(type solid)
		)
		(fill yes)
		(layer "In1.Cu")
		(net "P5E_PEX1_STN4_RX_DP<68>")
	)
	(gr_poly
		(pts
			(arc
				(start 197.803262 -306.349908)
				(mid 197.396862 -306.349908)
				(end 197.803262 -306.349908)
			)
		)
		(stroke
			(width 0)
			(type solid)
		)
		(fill yes)
		(layer "In1.Cu")
		(net "P5E_PEX1_STN4_RX_DP<66>")
	)
	(gr_poly
		(pts
			(arc
				(start 197.803262 -304.449734)
				(mid 197.396862 -304.449734)
				(end 197.803262 -304.449734)
			)
		)
		(stroke
			(width 0)
			(type solid)
		)
		(fill yes)
		(layer "In1.Cu")
		(net "P5E_PEX1_STN4_RX_DP<64>")
	)
	(gr_poly
		(pts
			(arc
				(start 197.803262 -287.349946)
				(mid 197.396862 -287.349946)
				(end 197.803262 -287.349946)
			)
		)
		(stroke
			(width 0)
			(type solid)
		)
		(fill yes)
		(layer "In1.Cu")
		(net "P5E_PEX1_STN0_RX_DP<1>")
	)
	(gr_poly
		(pts
			(arc
				(start 197.803262 -285.449772)
				(mid 197.396862 -285.449772)
				(end 197.803262 -285.449772)
			)
		)
		(stroke
			(width 0)
			(type solid)
		)
		(fill yes)
		(layer "In1.Cu")
		(net "P5E_PEX1_STN0_RX_DP<3>")
	)
	(gr_poly
		(pts
			(arc
				(start 197.803262 -283.549852)
				(mid 197.396862 -283.549852)
				(end 197.803262 -283.549852)
			)
		)
		(stroke
			(width 0)
			(type solid)
		)
		(fill yes)
		(layer "In1.Cu")
		(net "P5E_PEX1_STN0_RX_DP<5>")
	)
	(gr_poly
		(pts
			(arc
				(start 197.803262 -281.649932)
				(mid 197.396862 -281.649932)
				(end 197.803262 -281.649932)
			)
		)
		(stroke
			(width 0)
			(type solid)
		)
		(fill yes)
		(layer "In1.Cu")
		(net "P5E_PEX1_STN0_RX_DP<7>")
	)
	(gr_poly
		(pts
			(arc
				(start 197.803262 -279.749758)
				(mid 197.396862 -279.749758)
				(end 197.803262 -279.749758)
			)
		)
		(stroke
			(width 0)
			(type solid)
		)
		(fill yes)
		(layer "In1.Cu")
		(net "P5E_PEX1_STN0_TX_DP<7>")
	)
	(gr_poly
		(pts
			(arc
				(start 197.803262 -276.899878)
				(mid 197.396862 -276.899878)
				(end 197.803262 -276.899878)
			)
		)
		(stroke
			(width 0)
			(type solid)
		)
		(fill yes)
		(layer "In1.Cu")
		(net "P5E_PEX1_STN0_TX_DP<8>")
	)
	(gr_poly
		(pts
			(arc
				(start 197.803262 -274.999704)
				(mid 197.396862 -274.999704)
				(end 197.803262 -274.999704)
			)
		)
		(stroke
			(width 0)
			(type solid)
		)
		(fill yes)
		(layer "In1.Cu")
		(net "P5E_PEX1_STN0_RX_DP<8>")
	)
	(gr_poly
		(pts
			(arc
				(start 198.753222 -316.799722)
				(mid 198.346822 -316.799722)
				(end 198.753222 -316.799722)
			)
		)
		(stroke
			(width 0)
			(type solid)
		)
		(fill yes)
		(layer "In1.Cu")
		(net "P5E_PEX1_STN4_RX_DN<71>")
	)
	(gr_poly
		(pts
			(arc
				(start 198.753222 -314.899802)
				(mid 198.346822 -314.899802)
				(end 198.753222 -314.899802)
			)
		)
		(stroke
			(width 0)
			(type solid)
		)
		(fill yes)
		(layer "In1.Cu")
		(net "P5E_PEX1_STN4_TX_DN<71>")
	)
	(gr_poly
		(pts
			(arc
				(start 198.753222 -312.049922)
				(mid 198.346822 -312.049922)
				(end 198.753222 -312.049922)
			)
		)
		(stroke
			(width 0)
			(type solid)
		)
		(fill yes)
		(layer "In1.Cu")
		(net "P5E_PEX1_STN4_TX_DN<70>")
	)
	(gr_poly
		(pts
			(arc
				(start 198.753222 -310.149748)
				(mid 198.346822 -310.149748)
				(end 198.753222 -310.149748)
			)
		)
		(stroke
			(width 0)
			(type solid)
		)
		(fill yes)
		(layer "In1.Cu")
		(net "P5E_PEX1_STN4_RX_DN<70>")
	)
	(gr_poly
		(pts
			(arc
				(start 198.753222 -308.249828)
				(mid 198.346822 -308.249828)
				(end 198.753222 -308.249828)
			)
		)
		(stroke
			(width 0)
			(type solid)
		)
		(fill yes)
		(layer "In1.Cu")
		(net "P5E_PEX1_STN4_RX_DN<68>")
	)
	(gr_poly
		(pts
			(arc
				(start 198.753222 -306.349908)
				(mid 198.346822 -306.349908)
				(end 198.753222 -306.349908)
			)
		)
		(stroke
			(width 0)
			(type solid)
		)
		(fill yes)
		(layer "In1.Cu")
		(net "P5E_PEX1_STN4_RX_DN<66>")
	)
	(gr_poly
		(pts
			(arc
				(start 198.753222 -304.449734)
				(mid 198.346822 -304.449734)
				(end 198.753222 -304.449734)
			)
		)
		(stroke
			(width 0)
			(type solid)
		)
		(fill yes)
		(layer "In1.Cu")
		(net "P5E_PEX1_STN4_RX_DN<64>")
	)
	(gr_poly
		(pts
			(arc
				(start 198.753222 -287.349946)
				(mid 198.346822 -287.349946)
				(end 198.753222 -287.349946)
			)
		)
		(stroke
			(width 0)
			(type solid)
		)
		(fill yes)
		(layer "In1.Cu")
		(net "P5E_PEX1_STN0_RX_DN<1>")
	)
	(gr_poly
		(pts
			(arc
				(start 198.753222 -285.449772)
				(mid 198.346822 -285.449772)
				(end 198.753222 -285.449772)
			)
		)
		(stroke
			(width 0)
			(type solid)
		)
		(fill yes)
		(layer "In1.Cu")
		(net "P5E_PEX1_STN0_RX_DN<3>")
	)
	(gr_poly
		(pts
			(arc
				(start 198.753222 -283.549852)
				(mid 198.346822 -283.549852)
				(end 198.753222 -283.549852)
			)
		)
		(stroke
			(width 0)
			(type solid)
		)
		(fill yes)
		(layer "In1.Cu")
		(net "P5E_PEX1_STN0_RX_DN<5>")
	)
	(gr_poly
		(pts
			(arc
				(start 198.753222 -281.649932)
				(mid 198.346822 -281.649932)
				(end 198.753222 -281.649932)
			)
		)
		(stroke
			(width 0)
			(type solid)
		)
		(fill yes)
		(layer "In1.Cu")
		(net "P5E_PEX1_STN0_RX_DN<7>")
	)
	(gr_poly
		(pts
			(arc
				(start 198.753222 -279.749758)
				(mid 198.346822 -279.749758)
				(end 198.753222 -279.749758)
			)
		)
		(stroke
			(width 0)
			(type solid)
		)
		(fill yes)
		(layer "In1.Cu")
		(net "P5E_PEX1_STN0_TX_DN<7>")
	)
	(gr_poly
		(pts
			(arc
				(start 198.753222 -276.899878)
				(mid 198.346822 -276.899878)
				(end 198.753222 -276.899878)
			)
		)
		(stroke
			(width 0)
			(type solid)
		)
		(fill yes)
		(layer "In1.Cu")
		(net "P5E_PEX1_STN0_TX_DN<8>")
	)
	(gr_poly
		(pts
			(arc
				(start 198.753222 -274.999704)
				(mid 198.346822 -274.999704)
				(end 198.753222 -274.999704)
			)
		)
		(stroke
			(width 0)
			(type solid)
		)
		(fill yes)
		(layer "In1.Cu")
		(net "P5E_PEX1_STN0_RX_DN<8>")
	)
	(gr_poly
		(pts
			(arc
				(start 269.252954 -316.799722)
				(mid 268.846554 -316.799722)
				(end 269.252954 -316.799722)
			)
		)
		(stroke
			(width 0)
			(type solid)
		)
		(fill yes)
		(layer "In1.Cu")
		(net "P5E_PEX2_STN7_RX_DN<122>")
	)
	(gr_poly
		(pts
			(arc
				(start 269.252954 -314.899802)
				(mid 268.846554 -314.899802)
				(end 269.252954 -314.899802)
			)
		)
		(stroke
			(width 0)
			(type solid)
		)
		(fill yes)
		(layer "In1.Cu")
		(net "P5E_PEX2_STN7_TX_DN<122>")
	)
	(gr_poly
		(pts
			(arc
				(start 269.252954 -312.049922)
				(mid 268.846554 -312.049922)
				(end 269.252954 -312.049922)
			)
		)
		(stroke
			(width 0)
			(type solid)
		)
		(fill yes)
		(layer "In1.Cu")
		(net "P5E_PEX2_STN7_TX_DN<121>")
	)
	(gr_poly
		(pts
			(arc
				(start 269.252954 -310.149748)
				(mid 268.846554 -310.149748)
				(end 269.252954 -310.149748)
			)
		)
		(stroke
			(width 0)
			(type solid)
		)
		(fill yes)
		(layer "In1.Cu")
		(net "P5E_PEX2_STN7_RX_DN<121>")
	)
	(gr_poly
		(pts
			(arc
				(start 269.252954 -308.249828)
				(mid 268.846554 -308.249828)
				(end 269.252954 -308.249828)
			)
		)
		(stroke
			(width 0)
			(type solid)
		)
		(fill yes)
		(layer "In1.Cu")
		(net "P5E_PEX2_STN7_RX_DN<119>")
	)
	(gr_poly
		(pts
			(arc
				(start 269.252954 -306.349908)
				(mid 268.846554 -306.349908)
				(end 269.252954 -306.349908)
			)
		)
		(stroke
			(width 0)
			(type solid)
		)
		(fill yes)
		(layer "In1.Cu")
		(net "P5E_PEX2_STN7_RX_DN<117>")
	)
	(gr_poly
		(pts
			(arc
				(start 269.252954 -304.449734)
				(mid 268.846554 -304.449734)
				(end 269.252954 -304.449734)
			)
		)
		(stroke
			(width 0)
			(type solid)
		)
		(fill yes)
		(layer "In1.Cu")
		(net "P5E_PEX2_STN7_RX_DN<115>")
	)
	(gr_poly
		(pts
			(arc
				(start 269.252954 -302.549814)
				(mid 268.846554 -302.549814)
				(end 269.252954 -302.549814)
			)
		)
		(stroke
			(width 0)
			(type solid)
		)
		(fill yes)
		(layer "In1.Cu")
		(net "P5E_PEX2_STN7_RX_DN<113>")
	)
	(gr_poly
		(pts
			(arc
				(start 270.202914 -316.799722)
				(mid 269.796514 -316.799722)
				(end 270.202914 -316.799722)
			)
		)
		(stroke
			(width 0)
			(type solid)
		)
		(fill yes)
		(layer "In1.Cu")
		(net "P5E_PEX2_STN7_RX_DP<122>")
	)
	(gr_poly
		(pts
			(arc
				(start 270.202914 -314.899802)
				(mid 269.796514 -314.899802)
				(end 270.202914 -314.899802)
			)
		)
		(stroke
			(width 0)
			(type solid)
		)
		(fill yes)
		(layer "In1.Cu")
		(net "P5E_PEX2_STN7_TX_DP<122>")
	)
	(gr_poly
		(pts
			(arc
				(start 270.202914 -312.049922)
				(mid 269.796514 -312.049922)
				(end 270.202914 -312.049922)
			)
		)
		(stroke
			(width 0)
			(type solid)
		)
		(fill yes)
		(layer "In1.Cu")
		(net "P5E_PEX2_STN7_TX_DP<121>")
	)
	(gr_poly
		(pts
			(arc
				(start 270.202914 -310.149748)
				(mid 269.796514 -310.149748)
				(end 270.202914 -310.149748)
			)
		)
		(stroke
			(width 0)
			(type solid)
		)
		(fill yes)
		(layer "In1.Cu")
		(net "P5E_PEX2_STN7_RX_DP<121>")
	)
	(gr_poly
		(pts
			(arc
				(start 270.202914 -308.249828)
				(mid 269.796514 -308.249828)
				(end 270.202914 -308.249828)
			)
		)
		(stroke
			(width 0)
			(type solid)
		)
		(fill yes)
		(layer "In1.Cu")
		(net "P5E_PEX2_STN7_RX_DP<119>")
	)
	(gr_poly
		(pts
			(arc
				(start 270.202914 -306.349908)
				(mid 269.796514 -306.349908)
				(end 270.202914 -306.349908)
			)
		)
		(stroke
			(width 0)
			(type solid)
		)
		(fill yes)
		(layer "In1.Cu")
		(net "P5E_PEX2_STN7_RX_DP<117>")
	)
	(gr_poly
		(pts
			(arc
				(start 270.202914 -304.449734)
				(mid 269.796514 -304.449734)
				(end 270.202914 -304.449734)
			)
		)
		(stroke
			(width 0)
			(type solid)
		)
		(fill yes)
		(layer "In1.Cu")
		(net "P5E_PEX2_STN7_RX_DP<115>")
	)
	(gr_poly
		(pts
			(arc
				(start 270.202914 -302.549814)
				(mid 269.796514 -302.549814)
				(end 270.202914 -302.549814)
			)
		)
		(stroke
			(width 0)
			(type solid)
		)
		(fill yes)
		(layer "In1.Cu")
		(net "P5E_PEX2_STN7_RX_DP<113>")
	)
	(gr_poly
		(pts
			(arc
				(start 271.153128 -318.699896)
				(mid 270.746728 -318.699896)
				(end 271.153128 -318.699896)
			)
		)
		(stroke
			(width 0)
			(type solid)
		)
		(fill yes)
		(layer "In1.Cu")
		(net "P5E_PEX2_STN7_RX_DN<123>")
	)
	(gr_poly
		(pts
			(arc
				(start 271.153128 -317.749936)
				(mid 270.746728 -317.749936)
				(end 271.153128 -317.749936)
			)
		)
		(stroke
			(width 0)
			(type solid)
		)
		(fill yes)
		(layer "In1.Cu")
		(net "P5E_PEX2_STN7_RX_DP<123>")
	)
	(gr_poly
		(pts
			(arc
				(start 271.153128 -313.949842)
				(mid 270.746728 -313.949842)
				(end 271.153128 -313.949842)
			)
		)
		(stroke
			(width 0)
			(type solid)
		)
		(fill yes)
		(layer "In1.Cu")
		(net "P5E_PEX2_STN7_TX_DN<123>")
	)
	(gr_poly
		(pts
			(arc
				(start 271.153128 -312.999882)
				(mid 270.746728 -312.999882)
				(end 271.153128 -312.999882)
			)
		)
		(stroke
			(width 0)
			(type solid)
		)
		(fill yes)
		(layer "In1.Cu")
		(net "P5E_PEX2_STN7_TX_DP<123>")
	)
	(gr_poly
		(pts
			(arc
				(start 271.153128 -309.199788)
				(mid 270.746728 -309.199788)
				(end 271.153128 -309.199788)
			)
		)
		(stroke
			(width 0)
			(type solid)
		)
		(fill yes)
		(layer "In1.Cu")
		(net "P5E_PEX2_STN7_RX_DN<120>")
	)
	(gr_poly
		(pts
			(arc
				(start 271.153128 -307.299868)
				(mid 270.746728 -307.299868)
				(end 271.153128 -307.299868)
			)
		)
		(stroke
			(width 0)
			(type solid)
		)
		(fill yes)
		(layer "In1.Cu")
		(net "P5E_PEX2_STN7_RX_DN<118>")
	)
	(gr_poly
		(pts
			(arc
				(start 271.153128 -305.399948)
				(mid 270.746728 -305.399948)
				(end 271.153128 -305.399948)
			)
		)
		(stroke
			(width 0)
			(type solid)
		)
		(fill yes)
		(layer "In1.Cu")
		(net "P5E_PEX2_STN7_RX_DN<116>")
	)
	(gr_poly
		(pts
			(arc
				(start 271.153128 -303.499774)
				(mid 270.746728 -303.499774)
				(end 271.153128 -303.499774)
			)
		)
		(stroke
			(width 0)
			(type solid)
		)
		(fill yes)
		(layer "In1.Cu")
		(net "P5E_PEX2_STN7_RX_DN<114>")
	)
	(gr_poly
		(pts
			(arc
				(start 271.153128 -301.599854)
				(mid 270.746728 -301.599854)
				(end 271.153128 -301.599854)
			)
		)
		(stroke
			(width 0)
			(type solid)
		)
		(fill yes)
		(layer "In1.Cu")
		(net "P5E_PEX2_STN7_RX_DN<112>")
	)
	(gr_poly
		(pts
			(arc
				(start 272.103088 -316.799722)
				(mid 271.696688 -316.799722)
				(end 272.103088 -316.799722)
			)
		)
		(stroke
			(width 0)
			(type solid)
		)
		(fill yes)
		(layer "In1.Cu")
		(net "P5E_PEX2_STN7_RX_DN<124>")
	)
	(gr_poly
		(pts
			(arc
				(start 272.103088 -315.849762)
				(mid 271.696688 -315.849762)
				(end 272.103088 -315.849762)
			)
		)
		(stroke
			(width 0)
			(type solid)
		)
		(fill yes)
		(layer "In1.Cu")
		(net "P5E_PEX2_STN7_RX_DP<124>")
	)
	(gr_poly
		(pts
			(arc
				(start 272.103088 -312.049922)
				(mid 271.696688 -312.049922)
				(end 272.103088 -312.049922)
			)
		)
		(stroke
			(width 0)
			(type solid)
		)
		(fill yes)
		(layer "In1.Cu")
		(net "P5E_PEX2_STN7_TX_DN<124>")
	)
	(gr_poly
		(pts
			(arc
				(start 272.103088 -311.099962)
				(mid 271.696688 -311.099962)
				(end 272.103088 -311.099962)
			)
		)
		(stroke
			(width 0)
			(type solid)
		)
		(fill yes)
		(layer "In1.Cu")
		(net "P5E_PEX2_STN7_TX_DP<124>")
	)
	(gr_poly
		(pts
			(arc
				(start 272.103088 -309.199788)
				(mid 271.696688 -309.199788)
				(end 272.103088 -309.199788)
			)
		)
		(stroke
			(width 0)
			(type solid)
		)
		(fill yes)
		(layer "In1.Cu")
		(net "P5E_PEX2_STN7_RX_DP<120>")
	)
	(gr_poly
		(pts
			(arc
				(start 272.103088 -307.299868)
				(mid 271.696688 -307.299868)
				(end 272.103088 -307.299868)
			)
		)
		(stroke
			(width 0)
			(type solid)
		)
		(fill yes)
		(layer "In1.Cu")
		(net "P5E_PEX2_STN7_RX_DP<118>")
	)
	(gr_poly
		(pts
			(arc
				(start 272.103088 -305.399948)
				(mid 271.696688 -305.399948)
				(end 272.103088 -305.399948)
			)
		)
		(stroke
			(width 0)
			(type solid)
		)
		(fill yes)
		(layer "In1.Cu")
		(net "P5E_PEX2_STN7_RX_DP<116>")
	)
	(gr_poly
		(pts
			(arc
				(start 272.103088 -303.499774)
				(mid 271.696688 -303.499774)
				(end 272.103088 -303.499774)
			)
		)
		(stroke
			(width 0)
			(type solid)
		)
		(fill yes)
		(layer "In1.Cu")
		(net "P5E_PEX2_STN7_RX_DP<114>")
	)
	(gr_poly
		(pts
			(arc
				(start 272.103088 -301.599854)
				(mid 271.696688 -301.599854)
				(end 272.103088 -301.599854)
			)
		)
		(stroke
			(width 0)
			(type solid)
		)
		(fill yes)
		(layer "In1.Cu")
		(net "P5E_PEX2_STN7_RX_DP<112>")
	)
	(gr_poly
		(pts
			(arc
				(start 273.053048 -318.699896)
				(mid 272.646648 -318.699896)
				(end 273.053048 -318.699896)
			)
		)
		(stroke
			(width 0)
			(type solid)
		)
		(fill yes)
		(layer "In1.Cu")
		(net "P5E_PEX2_STN7_RX_DN<125>")
	)
	(gr_poly
		(pts
			(arc
				(start 273.053048 -317.749936)
				(mid 272.646648 -317.749936)
				(end 273.053048 -317.749936)
			)
		)
		(stroke
			(width 0)
			(type solid)
		)
		(fill yes)
		(layer "In1.Cu")
		(net "P5E_PEX2_STN7_RX_DP<125>")
	)
	(gr_poly
		(pts
			(arc
				(start 273.053048 -313.949842)
				(mid 272.646648 -313.949842)
				(end 273.053048 -313.949842)
			)
		)
		(stroke
			(width 0)
			(type solid)
		)
		(fill yes)
		(layer "In1.Cu")
		(net "P5E_PEX2_STN7_TX_DN<125>")
	)
	(gr_poly
		(pts
			(arc
				(start 273.053048 -312.999882)
				(mid 272.646648 -312.999882)
				(end 273.053048 -312.999882)
			)
		)
		(stroke
			(width 0)
			(type solid)
		)
		(fill yes)
		(layer "In1.Cu")
		(net "P5E_PEX2_STN7_TX_DP<125>")
	)
	(gr_poly
		(pts
			(arc
				(start 274.003008 -316.799722)
				(mid 273.596608 -316.799722)
				(end 274.003008 -316.799722)
			)
		)
		(stroke
			(width 0)
			(type solid)
		)
		(fill yes)
		(layer "In1.Cu")
		(net "P5E_PEX2_STN7_RX_DN<126>")
	)
	(gr_poly
		(pts
			(arc
				(start 274.003008 -315.849762)
				(mid 273.596608 -315.849762)
				(end 274.003008 -315.849762)
			)
		)
		(stroke
			(width 0)
			(type solid)
		)
		(fill yes)
		(layer "In1.Cu")
		(net "P5E_PEX2_STN7_RX_DP<126>")
	)
	(gr_poly
		(pts
			(arc
				(start 274.003008 -312.049922)
				(mid 273.596608 -312.049922)
				(end 274.003008 -312.049922)
			)
		)
		(stroke
			(width 0)
			(type solid)
		)
		(fill yes)
		(layer "In1.Cu")
		(net "P5E_PEX2_STN7_TX_DN<126>")
	)
	(gr_poly
		(pts
			(arc
				(start 274.003008 -311.099962)
				(mid 273.596608 -311.099962)
				(end 274.003008 -311.099962)
			)
		)
		(stroke
			(width 0)
			(type solid)
		)
		(fill yes)
		(layer "In1.Cu")
		(net "P5E_PEX2_STN7_TX_DP<126>")
	)
	(gr_poly
		(pts
			(arc
				(start 274.003008 -309.199788)
				(mid 273.596608 -309.199788)
				(end 274.003008 -309.199788)
			)
		)
		(stroke
			(width 0)
			(type solid)
		)
		(fill yes)
		(layer "In1.Cu")
		(net "P5E_PEX2_STN7_TX_DN<120>")
	)
	(gr_poly
		(pts
			(arc
				(start 274.003008 -307.299868)
				(mid 273.596608 -307.299868)
				(end 274.003008 -307.299868)
			)
		)
		(stroke
			(width 0)
			(type solid)
		)
		(fill yes)
		(layer "In1.Cu")
		(net "P5E_PEX2_STN7_TX_DN<118>")
	)
	(gr_poly
		(pts
			(arc
				(start 274.003008 -305.399948)
				(mid 273.596608 -305.399948)
				(end 274.003008 -305.399948)
			)
		)
		(stroke
			(width 0)
			(type solid)
		)
		(fill yes)
		(layer "In1.Cu")
		(net "P5E_PEX2_STN7_TX_DN<116>")
	)
	(gr_poly
		(pts
			(arc
				(start 274.003008 -303.499774)
				(mid 273.596608 -303.499774)
				(end 274.003008 -303.499774)
			)
		)
		(stroke
			(width 0)
			(type solid)
		)
		(fill yes)
		(layer "In1.Cu")
		(net "P5E_PEX2_STN7_TX_DN<114>")
	)
	(gr_poly
		(pts
			(arc
				(start 274.003008 -301.599854)
				(mid 273.596608 -301.599854)
				(end 274.003008 -301.599854)
			)
		)
		(stroke
			(width 0)
			(type solid)
		)
		(fill yes)
		(layer "In1.Cu")
		(net "P5E_PEX2_STN7_TX_DN<112>")
	)
	(gr_poly
		(pts
			(arc
				(start 274.952968 -318.699896)
				(mid 274.546568 -318.699896)
				(end 274.952968 -318.699896)
			)
		)
		(stroke
			(width 0)
			(type solid)
		)
		(fill yes)
		(layer "In1.Cu")
		(net "P5E_PEX2_STN7_RX_DN<127>")
	)
	(gr_poly
		(pts
			(arc
				(start 274.952968 -317.749936)
				(mid 274.546568 -317.749936)
				(end 274.952968 -317.749936)
			)
		)
		(stroke
			(width 0)
			(type solid)
		)
		(fill yes)
		(layer "In1.Cu")
		(net "P5E_PEX2_STN7_RX_DP<127>")
	)
	(gr_poly
		(pts
			(arc
				(start 274.952968 -313.949842)
				(mid 274.546568 -313.949842)
				(end 274.952968 -313.949842)
			)
		)
		(stroke
			(width 0)
			(type solid)
		)
		(fill yes)
		(layer "In1.Cu")
		(net "P5E_PEX2_STN7_TX_DN<127>")
	)
	(gr_poly
		(pts
			(arc
				(start 274.952968 -312.999882)
				(mid 274.546568 -312.999882)
				(end 274.952968 -312.999882)
			)
		)
		(stroke
			(width 0)
			(type solid)
		)
		(fill yes)
		(layer "In1.Cu")
		(net "P5E_PEX2_STN7_TX_DP<127>")
	)
	(gr_poly
		(pts
			(arc
				(start 274.952968 -309.199788)
				(mid 274.546568 -309.199788)
				(end 274.952968 -309.199788)
			)
		)
		(stroke
			(width 0)
			(type solid)
		)
		(fill yes)
		(layer "In1.Cu")
		(net "P5E_PEX2_STN7_TX_DP<120>")
	)
	(gr_poly
		(pts
			(arc
				(start 274.952968 -307.299868)
				(mid 274.546568 -307.299868)
				(end 274.952968 -307.299868)
			)
		)
		(stroke
			(width 0)
			(type solid)
		)
		(fill yes)
		(layer "In1.Cu")
		(net "P5E_PEX2_STN7_TX_DP<118>")
	)
	(gr_poly
		(pts
			(arc
				(start 274.952968 -305.399948)
				(mid 274.546568 -305.399948)
				(end 274.952968 -305.399948)
			)
		)
		(stroke
			(width 0)
			(type solid)
		)
		(fill yes)
		(layer "In1.Cu")
		(net "P5E_PEX2_STN7_TX_DP<116>")
	)
	(gr_poly
		(pts
			(arc
				(start 274.952968 -303.499774)
				(mid 274.546568 -303.499774)
				(end 274.952968 -303.499774)
			)
		)
		(stroke
			(width 0)
			(type solid)
		)
		(fill yes)
		(layer "In1.Cu")
		(net "P5E_PEX2_STN7_TX_DP<114>")
	)
	(gr_poly
		(pts
			(arc
				(start 274.952968 -301.599854)
				(mid 274.546568 -301.599854)
				(end 274.952968 -301.599854)
			)
		)
		(stroke
			(width 0)
			(type solid)
		)
		(fill yes)
		(layer "In1.Cu")
		(net "P5E_PEX2_STN7_TX_DP<112>")
	)
	(gr_poly
		(pts
			(arc
				(start 275.902928 -316.799722)
				(mid 275.496528 -316.799722)
				(end 275.902928 -316.799722)
			)
		)
		(stroke
			(width 0)
			(type solid)
		)
		(fill yes)
		(layer "In1.Cu")
		(net "P5E_PEX2_STN6_RX_DN<111>")
	)
	(gr_poly
		(pts
			(arc
				(start 275.902928 -315.849762)
				(mid 275.496528 -315.849762)
				(end 275.902928 -315.849762)
			)
		)
		(stroke
			(width 0)
			(type solid)
		)
		(fill yes)
		(layer "In1.Cu")
		(net "P5E_PEX2_STN6_RX_DP<111>")
	)
	(gr_poly
		(pts
			(arc
				(start 275.902928 -312.049922)
				(mid 275.496528 -312.049922)
				(end 275.902928 -312.049922)
			)
		)
		(stroke
			(width 0)
			(type solid)
		)
		(fill yes)
		(layer "In1.Cu")
		(net "P5E_PEX2_STN6_TX_DN<111>")
	)
	(gr_poly
		(pts
			(arc
				(start 275.902928 -311.099962)
				(mid 275.496528 -311.099962)
				(end 275.902928 -311.099962)
			)
		)
		(stroke
			(width 0)
			(type solid)
		)
		(fill yes)
		(layer "In1.Cu")
		(net "P5E_PEX2_STN6_TX_DP<111>")
	)
	(gr_poly
		(pts
			(arc
				(start 275.902928 -308.249828)
				(mid 275.496528 -308.249828)
				(end 275.902928 -308.249828)
			)
		)
		(stroke
			(width 0)
			(type solid)
		)
		(fill yes)
		(layer "In1.Cu")
		(net "P5E_PEX2_STN7_TX_DN<119>")
	)
	(gr_poly
		(pts
			(arc
				(start 275.902928 -306.349908)
				(mid 275.496528 -306.349908)
				(end 275.902928 -306.349908)
			)
		)
		(stroke
			(width 0)
			(type solid)
		)
		(fill yes)
		(layer "In1.Cu")
		(net "P5E_PEX2_STN7_TX_DN<117>")
	)
	(gr_poly
		(pts
			(arc
				(start 275.902928 -304.449734)
				(mid 275.496528 -304.449734)
				(end 275.902928 -304.449734)
			)
		)
		(stroke
			(width 0)
			(type solid)
		)
		(fill yes)
		(layer "In1.Cu")
		(net "P5E_PEX2_STN7_TX_DN<115>")
	)
	(gr_poly
		(pts
			(arc
				(start 275.902928 -302.549814)
				(mid 275.496528 -302.549814)
				(end 275.902928 -302.549814)
			)
		)
		(stroke
			(width 0)
			(type solid)
		)
		(fill yes)
		(layer "In1.Cu")
		(net "P5E_PEX2_STN7_TX_DN<113>")
	)
	(gr_poly
		(pts
			(arc
				(start 276.852888 -318.699896)
				(mid 276.446488 -318.699896)
				(end 276.852888 -318.699896)
			)
		)
		(stroke
			(width 0)
			(type solid)
		)
		(fill yes)
		(layer "In1.Cu")
		(net "P5E_PEX2_STN6_RX_DN<110>")
	)
	(gr_poly
		(pts
			(arc
				(start 276.852888 -317.749936)
				(mid 276.446488 -317.749936)
				(end 276.852888 -317.749936)
			)
		)
		(stroke
			(width 0)
			(type solid)
		)
		(fill yes)
		(layer "In1.Cu")
		(net "P5E_PEX2_STN6_RX_DP<110>")
	)
	(gr_poly
		(pts
			(arc
				(start 276.852888 -313.949842)
				(mid 276.446488 -313.949842)
				(end 276.852888 -313.949842)
			)
		)
		(stroke
			(width 0)
			(type solid)
		)
		(fill yes)
		(layer "In1.Cu")
		(net "P5E_PEX2_STN6_TX_DN<110>")
	)
	(gr_poly
		(pts
			(arc
				(start 276.852888 -312.999882)
				(mid 276.446488 -312.999882)
				(end 276.852888 -312.999882)
			)
		)
		(stroke
			(width 0)
			(type solid)
		)
		(fill yes)
		(layer "In1.Cu")
		(net "P5E_PEX2_STN6_TX_DP<110>")
	)
	(gr_poly
		(pts
			(arc
				(start 276.852888 -308.249828)
				(mid 276.446488 -308.249828)
				(end 276.852888 -308.249828)
			)
		)
		(stroke
			(width 0)
			(type solid)
		)
		(fill yes)
		(layer "In1.Cu")
		(net "P5E_PEX2_STN7_TX_DP<119>")
	)
	(gr_poly
		(pts
			(arc
				(start 276.852888 -306.349908)
				(mid 276.446488 -306.349908)
				(end 276.852888 -306.349908)
			)
		)
		(stroke
			(width 0)
			(type solid)
		)
		(fill yes)
		(layer "In1.Cu")
		(net "P5E_PEX2_STN7_TX_DP<117>")
	)
	(gr_poly
		(pts
			(arc
				(start 276.852888 -304.449734)
				(mid 276.446488 -304.449734)
				(end 276.852888 -304.449734)
			)
		)
		(stroke
			(width 0)
			(type solid)
		)
		(fill yes)
		(layer "In1.Cu")
		(net "P5E_PEX2_STN7_TX_DP<115>")
	)
	(gr_poly
		(pts
			(arc
				(start 276.852888 -302.549814)
				(mid 276.446488 -302.549814)
				(end 276.852888 -302.549814)
			)
		)
		(stroke
			(width 0)
			(type solid)
		)
		(fill yes)
		(layer "In1.Cu")
		(net "P5E_PEX2_STN7_TX_DP<113>")
	)
	(gr_poly
		(pts
			(arc
				(start 276.852888 -278.799798)
				(mid 276.446488 -278.799798)
				(end 276.852888 -278.799798)
			)
		)
		(stroke
			(width 0)
			(type solid)
		)
		(fill yes)
		(layer "In1.Cu")
		(net "P5E_PEX2_STN2_TX_DP<47>")
	)
	(gr_poly
		(pts
			(arc
				(start 276.852888 -277.849838)
				(mid 276.446488 -277.849838)
				(end 276.852888 -277.849838)
			)
		)
		(stroke
			(width 0)
			(type solid)
		)
		(fill yes)
		(layer "In1.Cu")
		(net "P5E_PEX2_STN2_TX_DN<47>")
	)
	(gr_poly
		(pts
			(arc
				(start 276.852888 -274.049744)
				(mid 276.446488 -274.049744)
				(end 276.852888 -274.049744)
			)
		)
		(stroke
			(width 0)
			(type solid)
		)
		(fill yes)
		(layer "In1.Cu")
		(net "P5E_PEX2_STN2_RX_DP<47>")
	)
	(gr_poly
		(pts
			(arc
				(start 276.852888 -273.099784)
				(mid 276.446488 -273.099784)
				(end 276.852888 -273.099784)
			)
		)
		(stroke
			(width 0)
			(type solid)
		)
		(fill yes)
		(layer "In1.Cu")
		(net "P5E_PEX2_STN2_RX_DN<47>")
	)
	(gr_poly
		(pts
			(arc
				(start 277.803102 -316.799722)
				(mid 277.396702 -316.799722)
				(end 277.803102 -316.799722)
			)
		)
		(stroke
			(width 0)
			(type solid)
		)
		(fill yes)
		(layer "In1.Cu")
		(net "P5E_PEX2_STN6_RX_DN<109>")
	)
	(gr_poly
		(pts
			(arc
				(start 277.803102 -315.849762)
				(mid 277.396702 -315.849762)
				(end 277.803102 -315.849762)
			)
		)
		(stroke
			(width 0)
			(type solid)
		)
		(fill yes)
		(layer "In1.Cu")
		(net "P5E_PEX2_STN6_RX_DP<109>")
	)
	(gr_poly
		(pts
			(arc
				(start 277.803102 -312.049922)
				(mid 277.396702 -312.049922)
				(end 277.803102 -312.049922)
			)
		)
		(stroke
			(width 0)
			(type solid)
		)
		(fill yes)
		(layer "In1.Cu")
		(net "P5E_PEX2_STN6_TX_DN<109>")
	)
	(gr_poly
		(pts
			(arc
				(start 277.803102 -311.099962)
				(mid 277.396702 -311.099962)
				(end 277.803102 -311.099962)
			)
		)
		(stroke
			(width 0)
			(type solid)
		)
		(fill yes)
		(layer "In1.Cu")
		(net "P5E_PEX2_STN6_TX_DP<109>")
	)
	(gr_poly
		(pts
			(arc
				(start 277.803102 -280.699464)
				(mid 277.396702 -280.699464)
				(end 277.803102 -280.699464)
			)
		)
		(stroke
			(width 0)
			(type solid)
		)
		(fill yes)
		(layer "In1.Cu")
		(net "P5E_PEX2_STN2_TX_DP<46>")
	)
	(gr_poly
		(pts
			(arc
				(start 277.803102 -279.749504)
				(mid 277.396702 -279.749504)
				(end 277.803102 -279.749504)
			)
		)
		(stroke
			(width 0)
			(type solid)
		)
		(fill yes)
		(layer "In1.Cu")
		(net "P5E_PEX2_STN2_TX_DN<46>")
	)
	(gr_poly
		(pts
			(arc
				(start 277.803102 -275.949918)
				(mid 277.396702 -275.949918)
				(end 277.803102 -275.949918)
			)
		)
		(stroke
			(width 0)
			(type solid)
		)
		(fill yes)
		(layer "In1.Cu")
		(net "P5E_PEX2_STN2_RX_DP<46>")
	)
	(gr_poly
		(pts
			(arc
				(start 277.803102 -274.999958)
				(mid 277.396702 -274.999958)
				(end 277.803102 -274.999958)
			)
		)
		(stroke
			(width 0)
			(type solid)
		)
		(fill yes)
		(layer "In1.Cu")
		(net "P5E_PEX2_STN2_RX_DN<46>")
	)
	(gr_poly
		(pts
			(arc
				(start 278.753062 -318.699896)
				(mid 278.346662 -318.699896)
				(end 278.753062 -318.699896)
			)
		)
		(stroke
			(width 0)
			(type solid)
		)
		(fill yes)
		(layer "In1.Cu")
		(net "P5E_PEX2_STN6_RX_DN<108>")
	)
	(gr_poly
		(pts
			(arc
				(start 278.753062 -317.749936)
				(mid 278.346662 -317.749936)
				(end 278.753062 -317.749936)
			)
		)
		(stroke
			(width 0)
			(type solid)
		)
		(fill yes)
		(layer "In1.Cu")
		(net "P5E_PEX2_STN6_RX_DP<108>")
	)
	(gr_poly
		(pts
			(arc
				(start 278.753062 -313.949842)
				(mid 278.346662 -313.949842)
				(end 278.753062 -313.949842)
			)
		)
		(stroke
			(width 0)
			(type solid)
		)
		(fill yes)
		(layer "In1.Cu")
		(net "P5E_PEX2_STN6_TX_DN<108>")
	)
	(gr_poly
		(pts
			(arc
				(start 278.753062 -312.999882)
				(mid 278.346662 -312.999882)
				(end 278.753062 -312.999882)
			)
		)
		(stroke
			(width 0)
			(type solid)
		)
		(fill yes)
		(layer "In1.Cu")
		(net "P5E_PEX2_STN6_TX_DP<108>")
	)
	(gr_poly
		(pts
			(arc
				(start 278.753062 -278.799798)
				(mid 278.346662 -278.799798)
				(end 278.753062 -278.799798)
			)
		)
		(stroke
			(width 0)
			(type solid)
		)
		(fill yes)
		(layer "In1.Cu")
		(net "P5E_PEX2_STN2_TX_DP<45>")
	)
	(gr_poly
		(pts
			(arc
				(start 278.753062 -277.849838)
				(mid 278.346662 -277.849838)
				(end 278.753062 -277.849838)
			)
		)
		(stroke
			(width 0)
			(type solid)
		)
		(fill yes)
		(layer "In1.Cu")
		(net "P5E_PEX2_STN2_TX_DN<45>")
	)
	(gr_poly
		(pts
			(arc
				(start 278.753062 -274.049744)
				(mid 278.346662 -274.049744)
				(end 278.753062 -274.049744)
			)
		)
		(stroke
			(width 0)
			(type solid)
		)
		(fill yes)
		(layer "In1.Cu")
		(net "P5E_PEX2_STN2_RX_DP<45>")
	)
	(gr_poly
		(pts
			(arc
				(start 278.753062 -273.099784)
				(mid 278.346662 -273.099784)
				(end 278.753062 -273.099784)
			)
		)
		(stroke
			(width 0)
			(type solid)
		)
		(fill yes)
		(layer "In1.Cu")
		(net "P5E_PEX2_STN2_RX_DN<45>")
	)
	(gr_poly
		(pts
			(arc
				(start 279.703022 -316.799722)
				(mid 279.296622 -316.799722)
				(end 279.703022 -316.799722)
			)
		)
		(stroke
			(width 0)
			(type solid)
		)
		(fill yes)
		(layer "In1.Cu")
		(net "P5E_PEX2_STN6_RX_DN<107>")
	)
	(gr_poly
		(pts
			(arc
				(start 279.703022 -315.849762)
				(mid 279.296622 -315.849762)
				(end 279.703022 -315.849762)
			)
		)
		(stroke
			(width 0)
			(type solid)
		)
		(fill yes)
		(layer "In1.Cu")
		(net "P5E_PEX2_STN6_RX_DP<107>")
	)
	(gr_poly
		(pts
			(arc
				(start 279.703022 -312.049922)
				(mid 279.296622 -312.049922)
				(end 279.703022 -312.049922)
			)
		)
		(stroke
			(width 0)
			(type solid)
		)
		(fill yes)
		(layer "In1.Cu")
		(net "P5E_PEX2_STN6_TX_DN<107>")
	)
	(gr_poly
		(pts
			(arc
				(start 279.703022 -311.099962)
				(mid 279.296622 -311.099962)
				(end 279.703022 -311.099962)
			)
		)
		(stroke
			(width 0)
			(type solid)
		)
		(fill yes)
		(layer "In1.Cu")
		(net "P5E_PEX2_STN6_TX_DP<107>")
	)
	(gr_poly
		(pts
			(arc
				(start 279.703022 -280.699464)
				(mid 279.296622 -280.699464)
				(end 279.703022 -280.699464)
			)
		)
		(stroke
			(width 0)
			(type solid)
		)
		(fill yes)
		(layer "In1.Cu")
		(net "P5E_PEX2_STN2_TX_DP<44>")
	)
	(gr_poly
		(pts
			(arc
				(start 279.703022 -279.749504)
				(mid 279.296622 -279.749504)
				(end 279.703022 -279.749504)
			)
		)
		(stroke
			(width 0)
			(type solid)
		)
		(fill yes)
		(layer "In1.Cu")
		(net "P5E_PEX2_STN2_TX_DN<44>")
	)
	(gr_poly
		(pts
			(arc
				(start 279.703022 -275.949918)
				(mid 279.296622 -275.949918)
				(end 279.703022 -275.949918)
			)
		)
		(stroke
			(width 0)
			(type solid)
		)
		(fill yes)
		(layer "In1.Cu")
		(net "P5E_PEX2_STN2_RX_DP<44>")
	)
	(gr_poly
		(pts
			(arc
				(start 279.703022 -274.999958)
				(mid 279.296622 -274.999958)
				(end 279.703022 -274.999958)
			)
		)
		(stroke
			(width 0)
			(type solid)
		)
		(fill yes)
		(layer "In1.Cu")
		(net "P5E_PEX2_STN2_RX_DN<44>")
	)
	(gr_poly
		(pts
			(arc
				(start 280.652982 -318.699896)
				(mid 280.246582 -318.699896)
				(end 280.652982 -318.699896)
			)
		)
		(stroke
			(width 0)
			(type solid)
		)
		(fill yes)
		(layer "In1.Cu")
		(net "P5E_PEX2_STN6_RX_DN<106>")
	)
	(gr_poly
		(pts
			(arc
				(start 280.652982 -317.749936)
				(mid 280.246582 -317.749936)
				(end 280.652982 -317.749936)
			)
		)
		(stroke
			(width 0)
			(type solid)
		)
		(fill yes)
		(layer "In1.Cu")
		(net "P5E_PEX2_STN6_RX_DP<106>")
	)
	(gr_poly
		(pts
			(arc
				(start 280.652982 -313.949842)
				(mid 280.246582 -313.949842)
				(end 280.652982 -313.949842)
			)
		)
		(stroke
			(width 0)
			(type solid)
		)
		(fill yes)
		(layer "In1.Cu")
		(net "P5E_PEX2_STN6_TX_DN<106>")
	)
	(gr_poly
		(pts
			(arc
				(start 280.652982 -312.999882)
				(mid 280.246582 -312.999882)
				(end 280.652982 -312.999882)
			)
		)
		(stroke
			(width 0)
			(type solid)
		)
		(fill yes)
		(layer "In1.Cu")
		(net "P5E_PEX2_STN6_TX_DP<106>")
	)
	(gr_poly
		(pts
			(arc
				(start 280.652982 -278.799798)
				(mid 280.246582 -278.799798)
				(end 280.652982 -278.799798)
			)
		)
		(stroke
			(width 0)
			(type solid)
		)
		(fill yes)
		(layer "In1.Cu")
		(net "P5E_PEX2_STN2_TX_DP<43>")
	)
	(gr_poly
		(pts
			(arc
				(start 280.652982 -277.849838)
				(mid 280.246582 -277.849838)
				(end 280.652982 -277.849838)
			)
		)
		(stroke
			(width 0)
			(type solid)
		)
		(fill yes)
		(layer "In1.Cu")
		(net "P5E_PEX2_STN2_TX_DN<43>")
	)
	(gr_poly
		(pts
			(arc
				(start 280.652982 -274.049744)
				(mid 280.246582 -274.049744)
				(end 280.652982 -274.049744)
			)
		)
		(stroke
			(width 0)
			(type solid)
		)
		(fill yes)
		(layer "In1.Cu")
		(net "P5E_PEX2_STN2_RX_DP<43>")
	)
	(gr_poly
		(pts
			(arc
				(start 280.652982 -273.099784)
				(mid 280.246582 -273.099784)
				(end 280.652982 -273.099784)
			)
		)
		(stroke
			(width 0)
			(type solid)
		)
		(fill yes)
		(layer "In1.Cu")
		(net "P5E_PEX2_STN2_RX_DN<43>")
	)
	(gr_poly
		(pts
			(arc
				(start 281.602942 -316.799722)
				(mid 281.196542 -316.799722)
				(end 281.602942 -316.799722)
			)
		)
		(stroke
			(width 0)
			(type solid)
		)
		(fill yes)
		(layer "In1.Cu")
		(net "P5E_PEX2_STN6_RX_DN<105>")
	)
	(gr_poly
		(pts
			(arc
				(start 281.602942 -315.849762)
				(mid 281.196542 -315.849762)
				(end 281.602942 -315.849762)
			)
		)
		(stroke
			(width 0)
			(type solid)
		)
		(fill yes)
		(layer "In1.Cu")
		(net "P5E_PEX2_STN6_RX_DP<105>")
	)
	(gr_poly
		(pts
			(arc
				(start 281.602942 -312.049922)
				(mid 281.196542 -312.049922)
				(end 281.602942 -312.049922)
			)
		)
		(stroke
			(width 0)
			(type solid)
		)
		(fill yes)
		(layer "In1.Cu")
		(net "P5E_PEX2_STN6_TX_DN<105>")
	)
	(gr_poly
		(pts
			(arc
				(start 281.602942 -311.099962)
				(mid 281.196542 -311.099962)
				(end 281.602942 -311.099962)
			)
		)
		(stroke
			(width 0)
			(type solid)
		)
		(fill yes)
		(layer "In1.Cu")
		(net "P5E_PEX2_STN6_TX_DP<105>")
	)
	(gr_poly
		(pts
			(arc
				(start 281.602942 -280.699464)
				(mid 281.196542 -280.699464)
				(end 281.602942 -280.699464)
			)
		)
		(stroke
			(width 0)
			(type solid)
		)
		(fill yes)
		(layer "In1.Cu")
		(net "P5E_PEX2_STN2_TX_DP<42>")
	)
	(gr_poly
		(pts
			(arc
				(start 281.602942 -279.749504)
				(mid 281.196542 -279.749504)
				(end 281.602942 -279.749504)
			)
		)
		(stroke
			(width 0)
			(type solid)
		)
		(fill yes)
		(layer "In1.Cu")
		(net "P5E_PEX2_STN2_TX_DN<42>")
	)
	(gr_poly
		(pts
			(arc
				(start 281.602942 -275.949918)
				(mid 281.196542 -275.949918)
				(end 281.602942 -275.949918)
			)
		)
		(stroke
			(width 0)
			(type solid)
		)
		(fill yes)
		(layer "In1.Cu")
		(net "P5E_PEX2_STN2_RX_DP<42>")
	)
	(gr_poly
		(pts
			(arc
				(start 281.602942 -274.999958)
				(mid 281.196542 -274.999958)
				(end 281.602942 -274.999958)
			)
		)
		(stroke
			(width 0)
			(type solid)
		)
		(fill yes)
		(layer "In1.Cu")
		(net "P5E_PEX2_STN2_RX_DN<42>")
	)
	(gr_poly
		(pts
			(arc
				(start 282.552902 -318.699896)
				(mid 282.146502 -318.699896)
				(end 282.552902 -318.699896)
			)
		)
		(stroke
			(width 0)
			(type solid)
		)
		(fill yes)
		(layer "In1.Cu")
		(net "P5E_PEX2_STN6_RX_DN<104>")
	)
	(gr_poly
		(pts
			(arc
				(start 282.552902 -317.749936)
				(mid 282.146502 -317.749936)
				(end 282.552902 -317.749936)
			)
		)
		(stroke
			(width 0)
			(type solid)
		)
		(fill yes)
		(layer "In1.Cu")
		(net "P5E_PEX2_STN6_RX_DP<104>")
	)
	(gr_poly
		(pts
			(arc
				(start 282.552902 -313.949842)
				(mid 282.146502 -313.949842)
				(end 282.552902 -313.949842)
			)
		)
		(stroke
			(width 0)
			(type solid)
		)
		(fill yes)
		(layer "In1.Cu")
		(net "P5E_PEX2_STN6_TX_DN<104>")
	)
	(gr_poly
		(pts
			(arc
				(start 282.552902 -312.999882)
				(mid 282.146502 -312.999882)
				(end 282.552902 -312.999882)
			)
		)
		(stroke
			(width 0)
			(type solid)
		)
		(fill yes)
		(layer "In1.Cu")
		(net "P5E_PEX2_STN6_TX_DP<104>")
	)
	(gr_poly
		(pts
			(arc
				(start 282.552902 -278.799798)
				(mid 282.146502 -278.799798)
				(end 282.552902 -278.799798)
			)
		)
		(stroke
			(width 0)
			(type solid)
		)
		(fill yes)
		(layer "In1.Cu")
		(net "P5E_PEX2_STN2_TX_DP<41>")
	)
	(gr_poly
		(pts
			(arc
				(start 282.552902 -277.849838)
				(mid 282.146502 -277.849838)
				(end 282.552902 -277.849838)
			)
		)
		(stroke
			(width 0)
			(type solid)
		)
		(fill yes)
		(layer "In1.Cu")
		(net "P5E_PEX2_STN2_TX_DN<41>")
	)
	(gr_poly
		(pts
			(arc
				(start 282.552902 -274.049744)
				(mid 282.146502 -274.049744)
				(end 282.552902 -274.049744)
			)
		)
		(stroke
			(width 0)
			(type solid)
		)
		(fill yes)
		(layer "In1.Cu")
		(net "P5E_PEX2_STN2_RX_DP<41>")
	)
	(gr_poly
		(pts
			(arc
				(start 282.552902 -273.099784)
				(mid 282.146502 -273.099784)
				(end 282.552902 -273.099784)
			)
		)
		(stroke
			(width 0)
			(type solid)
		)
		(fill yes)
		(layer "In1.Cu")
		(net "P5E_PEX2_STN2_RX_DN<41>")
	)
	(gr_poly
		(pts
			(arc
				(start 283.503116 -316.799722)
				(mid 283.096716 -316.799722)
				(end 283.503116 -316.799722)
			)
		)
		(stroke
			(width 0)
			(type solid)
		)
		(fill yes)
		(layer "In1.Cu")
		(net "P5E_PEX2_STN6_RX_DN<103>")
	)
	(gr_poly
		(pts
			(arc
				(start 283.503116 -315.849762)
				(mid 283.096716 -315.849762)
				(end 283.503116 -315.849762)
			)
		)
		(stroke
			(width 0)
			(type solid)
		)
		(fill yes)
		(layer "In1.Cu")
		(net "P5E_PEX2_STN6_RX_DP<103>")
	)
	(gr_poly
		(pts
			(arc
				(start 283.503116 -312.049922)
				(mid 283.096716 -312.049922)
				(end 283.503116 -312.049922)
			)
		)
		(stroke
			(width 0)
			(type solid)
		)
		(fill yes)
		(layer "In1.Cu")
		(net "P5E_PEX2_STN6_TX_DN<103>")
	)
	(gr_poly
		(pts
			(arc
				(start 283.503116 -311.099962)
				(mid 283.096716 -311.099962)
				(end 283.503116 -311.099962)
			)
		)
		(stroke
			(width 0)
			(type solid)
		)
		(fill yes)
		(layer "In1.Cu")
		(net "P5E_PEX2_STN6_TX_DP<103>")
	)
	(gr_poly
		(pts
			(arc
				(start 283.503116 -280.699464)
				(mid 283.096716 -280.699464)
				(end 283.503116 -280.699464)
			)
		)
		(stroke
			(width 0)
			(type solid)
		)
		(fill yes)
		(layer "In1.Cu")
		(net "P5E_PEX2_STN2_TX_DP<40>")
	)
	(gr_poly
		(pts
			(arc
				(start 283.503116 -279.749504)
				(mid 283.096716 -279.749504)
				(end 283.503116 -279.749504)
			)
		)
		(stroke
			(width 0)
			(type solid)
		)
		(fill yes)
		(layer "In1.Cu")
		(net "P5E_PEX2_STN2_TX_DN<40>")
	)
	(gr_poly
		(pts
			(arc
				(start 283.503116 -275.949918)
				(mid 283.096716 -275.949918)
				(end 283.503116 -275.949918)
			)
		)
		(stroke
			(width 0)
			(type solid)
		)
		(fill yes)
		(layer "In1.Cu")
		(net "P5E_PEX2_STN2_RX_DP<40>")
	)
	(gr_poly
		(pts
			(arc
				(start 283.503116 -274.999958)
				(mid 283.096716 -274.999958)
				(end 283.503116 -274.999958)
			)
		)
		(stroke
			(width 0)
			(type solid)
		)
		(fill yes)
		(layer "In1.Cu")
		(net "P5E_PEX2_STN2_RX_DN<40>")
	)
	(gr_poly
		(pts
			(arc
				(start 284.453076 -318.699896)
				(mid 284.046676 -318.699896)
				(end 284.453076 -318.699896)
			)
		)
		(stroke
			(width 0)
			(type solid)
		)
		(fill yes)
		(layer "In1.Cu")
		(net "P5E_PEX2_STN6_RX_DN<102>")
	)
	(gr_poly
		(pts
			(arc
				(start 284.453076 -317.749936)
				(mid 284.046676 -317.749936)
				(end 284.453076 -317.749936)
			)
		)
		(stroke
			(width 0)
			(type solid)
		)
		(fill yes)
		(layer "In1.Cu")
		(net "P5E_PEX2_STN6_RX_DP<102>")
	)
	(gr_poly
		(pts
			(arc
				(start 284.453076 -313.949842)
				(mid 284.046676 -313.949842)
				(end 284.453076 -313.949842)
			)
		)
		(stroke
			(width 0)
			(type solid)
		)
		(fill yes)
		(layer "In1.Cu")
		(net "P5E_PEX2_STN6_TX_DN<102>")
	)
	(gr_poly
		(pts
			(arc
				(start 284.453076 -312.999882)
				(mid 284.046676 -312.999882)
				(end 284.453076 -312.999882)
			)
		)
		(stroke
			(width 0)
			(type solid)
		)
		(fill yes)
		(layer "In1.Cu")
		(net "P5E_PEX2_STN6_TX_DP<102>")
	)
	(gr_poly
		(pts
			(arc
				(start 284.453076 -278.799798)
				(mid 284.046676 -278.799798)
				(end 284.453076 -278.799798)
			)
		)
		(stroke
			(width 0)
			(type solid)
		)
		(fill yes)
		(layer "In1.Cu")
		(net "P5E_PEX2_STN2_TX_DP<39>")
	)
	(gr_poly
		(pts
			(arc
				(start 284.453076 -277.849838)
				(mid 284.046676 -277.849838)
				(end 284.453076 -277.849838)
			)
		)
		(stroke
			(width 0)
			(type solid)
		)
		(fill yes)
		(layer "In1.Cu")
		(net "P5E_PEX2_STN2_TX_DN<39>")
	)
	(gr_poly
		(pts
			(arc
				(start 284.453076 -274.049744)
				(mid 284.046676 -274.049744)
				(end 284.453076 -274.049744)
			)
		)
		(stroke
			(width 0)
			(type solid)
		)
		(fill yes)
		(layer "In1.Cu")
		(net "P5E_PEX2_STN2_RX_DP<39>")
	)
	(gr_poly
		(pts
			(arc
				(start 284.453076 -273.099784)
				(mid 284.046676 -273.099784)
				(end 284.453076 -273.099784)
			)
		)
		(stroke
			(width 0)
			(type solid)
		)
		(fill yes)
		(layer "In1.Cu")
		(net "P5E_PEX2_STN2_RX_DN<39>")
	)
	(gr_poly
		(pts
			(arc
				(start 285.403036 -316.799722)
				(mid 284.996636 -316.799722)
				(end 285.403036 -316.799722)
			)
		)
		(stroke
			(width 0)
			(type solid)
		)
		(fill yes)
		(layer "In1.Cu")
		(net "P5E_PEX2_STN6_RX_DN<101>")
	)
	(gr_poly
		(pts
			(arc
				(start 285.403036 -315.849762)
				(mid 284.996636 -315.849762)
				(end 285.403036 -315.849762)
			)
		)
		(stroke
			(width 0)
			(type solid)
		)
		(fill yes)
		(layer "In1.Cu")
		(net "P5E_PEX2_STN6_RX_DP<101>")
	)
	(gr_poly
		(pts
			(arc
				(start 285.403036 -312.049922)
				(mid 284.996636 -312.049922)
				(end 285.403036 -312.049922)
			)
		)
		(stroke
			(width 0)
			(type solid)
		)
		(fill yes)
		(layer "In1.Cu")
		(net "P5E_PEX2_STN6_TX_DN<101>")
	)
	(gr_poly
		(pts
			(arc
				(start 285.403036 -311.099962)
				(mid 284.996636 -311.099962)
				(end 285.403036 -311.099962)
			)
		)
		(stroke
			(width 0)
			(type solid)
		)
		(fill yes)
		(layer "In1.Cu")
		(net "P5E_PEX2_STN6_TX_DP<101>")
	)
	(gr_poly
		(pts
			(arc
				(start 285.403036 -280.699464)
				(mid 284.996636 -280.699464)
				(end 285.403036 -280.699464)
			)
		)
		(stroke
			(width 0)
			(type solid)
		)
		(fill yes)
		(layer "In1.Cu")
		(net "P5E_PEX2_STN2_TX_DP<38>")
	)
	(gr_poly
		(pts
			(arc
				(start 285.403036 -279.749504)
				(mid 284.996636 -279.749504)
				(end 285.403036 -279.749504)
			)
		)
		(stroke
			(width 0)
			(type solid)
		)
		(fill yes)
		(layer "In1.Cu")
		(net "P5E_PEX2_STN2_TX_DN<38>")
	)
	(gr_poly
		(pts
			(arc
				(start 285.403036 -275.949918)
				(mid 284.996636 -275.949918)
				(end 285.403036 -275.949918)
			)
		)
		(stroke
			(width 0)
			(type solid)
		)
		(fill yes)
		(layer "In1.Cu")
		(net "P5E_PEX2_STN2_RX_DP<38>")
	)
	(gr_poly
		(pts
			(arc
				(start 285.403036 -274.999958)
				(mid 284.996636 -274.999958)
				(end 285.403036 -274.999958)
			)
		)
		(stroke
			(width 0)
			(type solid)
		)
		(fill yes)
		(layer "In1.Cu")
		(net "P5E_PEX2_STN2_RX_DN<38>")
	)
	(gr_poly
		(pts
			(arc
				(start 286.352996 -318.699896)
				(mid 285.946596 -318.699896)
				(end 286.352996 -318.699896)
			)
		)
		(stroke
			(width 0)
			(type solid)
		)
		(fill yes)
		(layer "In1.Cu")
		(net "P5E_PEX2_STN6_RX_DN<100>")
	)
	(gr_poly
		(pts
			(arc
				(start 286.352996 -317.749936)
				(mid 285.946596 -317.749936)
				(end 286.352996 -317.749936)
			)
		)
		(stroke
			(width 0)
			(type solid)
		)
		(fill yes)
		(layer "In1.Cu")
		(net "P5E_PEX2_STN6_RX_DP<100>")
	)
	(gr_poly
		(pts
			(arc
				(start 286.352996 -313.949842)
				(mid 285.946596 -313.949842)
				(end 286.352996 -313.949842)
			)
		)
		(stroke
			(width 0)
			(type solid)
		)
		(fill yes)
		(layer "In1.Cu")
		(net "P5E_PEX2_STN6_TX_DN<100>")
	)
	(gr_poly
		(pts
			(arc
				(start 286.352996 -312.999882)
				(mid 285.946596 -312.999882)
				(end 286.352996 -312.999882)
			)
		)
		(stroke
			(width 0)
			(type solid)
		)
		(fill yes)
		(layer "In1.Cu")
		(net "P5E_PEX2_STN6_TX_DP<100>")
	)
	(gr_poly
		(pts
			(arc
				(start 286.352996 -278.799798)
				(mid 285.946596 -278.799798)
				(end 286.352996 -278.799798)
			)
		)
		(stroke
			(width 0)
			(type solid)
		)
		(fill yes)
		(layer "In1.Cu")
		(net "P5E_PEX2_STN2_TX_DP<37>")
	)
	(gr_poly
		(pts
			(arc
				(start 286.352996 -277.849838)
				(mid 285.946596 -277.849838)
				(end 286.352996 -277.849838)
			)
		)
		(stroke
			(width 0)
			(type solid)
		)
		(fill yes)
		(layer "In1.Cu")
		(net "P5E_PEX2_STN2_TX_DN<37>")
	)
	(gr_poly
		(pts
			(arc
				(start 286.352996 -274.049744)
				(mid 285.946596 -274.049744)
				(end 286.352996 -274.049744)
			)
		)
		(stroke
			(width 0)
			(type solid)
		)
		(fill yes)
		(layer "In1.Cu")
		(net "P5E_PEX2_STN2_RX_DP<37>")
	)
	(gr_poly
		(pts
			(arc
				(start 286.352996 -273.099784)
				(mid 285.946596 -273.099784)
				(end 286.352996 -273.099784)
			)
		)
		(stroke
			(width 0)
			(type solid)
		)
		(fill yes)
		(layer "In1.Cu")
		(net "P5E_PEX2_STN2_RX_DN<37>")
	)
	(gr_poly
		(pts
			(arc
				(start 287.302956 -316.799722)
				(mid 286.896556 -316.799722)
				(end 287.302956 -316.799722)
			)
		)
		(stroke
			(width 0)
			(type solid)
		)
		(fill yes)
		(layer "In1.Cu")
		(net "P5E_PEX2_STN6_RX_DN<99>")
	)
	(gr_poly
		(pts
			(arc
				(start 287.302956 -315.849762)
				(mid 286.896556 -315.849762)
				(end 287.302956 -315.849762)
			)
		)
		(stroke
			(width 0)
			(type solid)
		)
		(fill yes)
		(layer "In1.Cu")
		(net "P5E_PEX2_STN6_RX_DP<99>")
	)
	(gr_poly
		(pts
			(arc
				(start 287.302956 -312.049922)
				(mid 286.896556 -312.049922)
				(end 287.302956 -312.049922)
			)
		)
		(stroke
			(width 0)
			(type solid)
		)
		(fill yes)
		(layer "In1.Cu")
		(net "P5E_PEX2_STN6_TX_DN<99>")
	)
	(gr_poly
		(pts
			(arc
				(start 287.302956 -311.099962)
				(mid 286.896556 -311.099962)
				(end 287.302956 -311.099962)
			)
		)
		(stroke
			(width 0)
			(type solid)
		)
		(fill yes)
		(layer "In1.Cu")
		(net "P5E_PEX2_STN6_TX_DP<99>")
	)
	(gr_poly
		(pts
			(arc
				(start 287.302956 -280.699464)
				(mid 286.896556 -280.699464)
				(end 287.302956 -280.699464)
			)
		)
		(stroke
			(width 0)
			(type solid)
		)
		(fill yes)
		(layer "In1.Cu")
		(net "P5E_PEX2_STN2_TX_DP<36>")
	)
	(gr_poly
		(pts
			(arc
				(start 287.302956 -279.749504)
				(mid 286.896556 -279.749504)
				(end 287.302956 -279.749504)
			)
		)
		(stroke
			(width 0)
			(type solid)
		)
		(fill yes)
		(layer "In1.Cu")
		(net "P5E_PEX2_STN2_TX_DN<36>")
	)
	(gr_poly
		(pts
			(arc
				(start 287.302956 -275.949918)
				(mid 286.896556 -275.949918)
				(end 287.302956 -275.949918)
			)
		)
		(stroke
			(width 0)
			(type solid)
		)
		(fill yes)
		(layer "In1.Cu")
		(net "P5E_PEX2_STN2_RX_DP<36>")
	)
	(gr_poly
		(pts
			(arc
				(start 287.302956 -274.999958)
				(mid 286.896556 -274.999958)
				(end 287.302956 -274.999958)
			)
		)
		(stroke
			(width 0)
			(type solid)
		)
		(fill yes)
		(layer "In1.Cu")
		(net "P5E_PEX2_STN2_RX_DN<36>")
	)
	(gr_poly
		(pts
			(arc
				(start 288.252916 -318.699896)
				(mid 287.846516 -318.699896)
				(end 288.252916 -318.699896)
			)
		)
		(stroke
			(width 0)
			(type solid)
		)
		(fill yes)
		(layer "In1.Cu")
		(net "P5E_PEX2_STN6_RX_DN<98>")
	)
	(gr_poly
		(pts
			(arc
				(start 288.252916 -317.749936)
				(mid 287.846516 -317.749936)
				(end 288.252916 -317.749936)
			)
		)
		(stroke
			(width 0)
			(type solid)
		)
		(fill yes)
		(layer "In1.Cu")
		(net "P5E_PEX2_STN6_RX_DP<98>")
	)
	(gr_poly
		(pts
			(arc
				(start 288.252916 -313.949842)
				(mid 287.846516 -313.949842)
				(end 288.252916 -313.949842)
			)
		)
		(stroke
			(width 0)
			(type solid)
		)
		(fill yes)
		(layer "In1.Cu")
		(net "P5E_PEX2_STN6_TX_DN<98>")
	)
	(gr_poly
		(pts
			(arc
				(start 288.252916 -312.999882)
				(mid 287.846516 -312.999882)
				(end 288.252916 -312.999882)
			)
		)
		(stroke
			(width 0)
			(type solid)
		)
		(fill yes)
		(layer "In1.Cu")
		(net "P5E_PEX2_STN6_TX_DP<98>")
	)
	(gr_poly
		(pts
			(arc
				(start 288.252916 -278.799798)
				(mid 287.846516 -278.799798)
				(end 288.252916 -278.799798)
			)
		)
		(stroke
			(width 0)
			(type solid)
		)
		(fill yes)
		(layer "In1.Cu")
		(net "P5E_PEX2_STN2_TX_DP<35>")
	)
	(gr_poly
		(pts
			(arc
				(start 288.252916 -277.849838)
				(mid 287.846516 -277.849838)
				(end 288.252916 -277.849838)
			)
		)
		(stroke
			(width 0)
			(type solid)
		)
		(fill yes)
		(layer "In1.Cu")
		(net "P5E_PEX2_STN2_TX_DN<35>")
	)
	(gr_poly
		(pts
			(arc
				(start 288.252916 -274.049744)
				(mid 287.846516 -274.049744)
				(end 288.252916 -274.049744)
			)
		)
		(stroke
			(width 0)
			(type solid)
		)
		(fill yes)
		(layer "In1.Cu")
		(net "P5E_PEX2_STN2_RX_DP<35>")
	)
	(gr_poly
		(pts
			(arc
				(start 288.252916 -273.099784)
				(mid 287.846516 -273.099784)
				(end 288.252916 -273.099784)
			)
		)
		(stroke
			(width 0)
			(type solid)
		)
		(fill yes)
		(layer "In1.Cu")
		(net "P5E_PEX2_STN2_RX_DN<35>")
	)
	(gr_poly
		(pts
			(arc
				(start 289.202876 -280.699464)
				(mid 288.796476 -280.699464)
				(end 289.202876 -280.699464)
			)
		)
		(stroke
			(width 0)
			(type solid)
		)
		(fill yes)
		(layer "In1.Cu")
		(net "P5E_PEX2_STN2_TX_DP<34>")
	)
	(gr_poly
		(pts
			(arc
				(start 289.202876 -279.749504)
				(mid 288.796476 -279.749504)
				(end 289.202876 -279.749504)
			)
		)
		(stroke
			(width 0)
			(type solid)
		)
		(fill yes)
		(layer "In1.Cu")
		(net "P5E_PEX2_STN2_TX_DN<34>")
	)
	(gr_poly
		(pts
			(arc
				(start 289.20313 -316.799722)
				(mid 288.79673 -316.799722)
				(end 289.20313 -316.799722)
			)
		)
		(stroke
			(width 0)
			(type solid)
		)
		(fill yes)
		(layer "In1.Cu")
		(net "P5E_PEX2_STN6_RX_DN<97>")
	)
	(gr_poly
		(pts
			(arc
				(start 289.20313 -315.849762)
				(mid 288.79673 -315.849762)
				(end 289.20313 -315.849762)
			)
		)
		(stroke
			(width 0)
			(type solid)
		)
		(fill yes)
		(layer "In1.Cu")
		(net "P5E_PEX2_STN6_RX_DP<97>")
	)
	(gr_poly
		(pts
			(arc
				(start 289.20313 -312.049922)
				(mid 288.79673 -312.049922)
				(end 289.20313 -312.049922)
			)
		)
		(stroke
			(width 0)
			(type solid)
		)
		(fill yes)
		(layer "In1.Cu")
		(net "P5E_PEX2_STN6_TX_DN<97>")
	)
	(gr_poly
		(pts
			(arc
				(start 289.20313 -311.099962)
				(mid 288.79673 -311.099962)
				(end 289.20313 -311.099962)
			)
		)
		(stroke
			(width 0)
			(type solid)
		)
		(fill yes)
		(layer "In1.Cu")
		(net "P5E_PEX2_STN6_TX_DP<97>")
	)
	(gr_poly
		(pts
			(arc
				(start 289.20313 -275.949918)
				(mid 288.79673 -275.949918)
				(end 289.20313 -275.949918)
			)
		)
		(stroke
			(width 0)
			(type solid)
		)
		(fill yes)
		(layer "In1.Cu")
		(net "P5E_PEX2_STN2_RX_DP<34>")
	)
	(gr_poly
		(pts
			(arc
				(start 289.20313 -274.999958)
				(mid 288.79673 -274.999958)
				(end 289.20313 -274.999958)
			)
		)
		(stroke
			(width 0)
			(type solid)
		)
		(fill yes)
		(layer "In1.Cu")
		(net "P5E_PEX2_STN2_RX_DN<34>")
	)
	(gr_poly
		(pts
			(arc
				(start 290.15309 -318.699896)
				(mid 289.74669 -318.699896)
				(end 290.15309 -318.699896)
			)
		)
		(stroke
			(width 0)
			(type solid)
		)
		(fill yes)
		(layer "In1.Cu")
		(net "P5E_PEX2_STN6_RX_DN<96>")
	)
	(gr_poly
		(pts
			(arc
				(start 290.15309 -317.749936)
				(mid 289.74669 -317.749936)
				(end 290.15309 -317.749936)
			)
		)
		(stroke
			(width 0)
			(type solid)
		)
		(fill yes)
		(layer "In1.Cu")
		(net "P5E_PEX2_STN6_RX_DP<96>")
	)
	(gr_poly
		(pts
			(arc
				(start 290.15309 -313.949842)
				(mid 289.74669 -313.949842)
				(end 290.15309 -313.949842)
			)
		)
		(stroke
			(width 0)
			(type solid)
		)
		(fill yes)
		(layer "In1.Cu")
		(net "P5E_PEX2_STN6_TX_DN<96>")
	)
	(gr_poly
		(pts
			(arc
				(start 290.15309 -312.999882)
				(mid 289.74669 -312.999882)
				(end 290.15309 -312.999882)
			)
		)
		(stroke
			(width 0)
			(type solid)
		)
		(fill yes)
		(layer "In1.Cu")
		(net "P5E_PEX2_STN6_TX_DP<96>")
	)
	(gr_poly
		(pts
			(arc
				(start 290.15309 -278.799798)
				(mid 289.74669 -278.799798)
				(end 290.15309 -278.799798)
			)
		)
		(stroke
			(width 0)
			(type solid)
		)
		(fill yes)
		(layer "In1.Cu")
		(net "P5E_PEX2_STN2_TX_DP<33>")
	)
	(gr_poly
		(pts
			(arc
				(start 290.15309 -277.849838)
				(mid 289.74669 -277.849838)
				(end 290.15309 -277.849838)
			)
		)
		(stroke
			(width 0)
			(type solid)
		)
		(fill yes)
		(layer "In1.Cu")
		(net "P5E_PEX2_STN2_TX_DN<33>")
	)
	(gr_poly
		(pts
			(arc
				(start 290.15309 -274.049744)
				(mid 289.74669 -274.049744)
				(end 290.15309 -274.049744)
			)
		)
		(stroke
			(width 0)
			(type solid)
		)
		(fill yes)
		(layer "In1.Cu")
		(net "P5E_PEX2_STN2_RX_DP<33>")
	)
	(gr_poly
		(pts
			(arc
				(start 290.15309 -273.099784)
				(mid 289.74669 -273.099784)
				(end 290.15309 -273.099784)
			)
		)
		(stroke
			(width 0)
			(type solid)
		)
		(fill yes)
		(layer "In1.Cu")
		(net "P5E_PEX2_STN2_RX_DN<33>")
	)
	(gr_poly
		(pts
			(arc
				(start 291.10305 -316.799722)
				(mid 290.69665 -316.799722)
				(end 291.10305 -316.799722)
			)
		)
		(stroke
			(width 0)
			(type solid)
		)
		(fill yes)
		(layer "In1.Cu")
		(net "P5E_PEX2_STN5_RX_DN<80>")
	)
	(gr_poly
		(pts
			(arc
				(start 291.10305 -315.849762)
				(mid 290.69665 -315.849762)
				(end 291.10305 -315.849762)
			)
		)
		(stroke
			(width 0)
			(type solid)
		)
		(fill yes)
		(layer "In1.Cu")
		(net "P5E_PEX2_STN5_RX_DP<80>")
	)
	(gr_poly
		(pts
			(arc
				(start 291.10305 -312.049922)
				(mid 290.69665 -312.049922)
				(end 291.10305 -312.049922)
			)
		)
		(stroke
			(width 0)
			(type solid)
		)
		(fill yes)
		(layer "In1.Cu")
		(net "P5E_PEX2_STN5_TX_DN<80>")
	)
	(gr_poly
		(pts
			(arc
				(start 291.10305 -311.099962)
				(mid 290.69665 -311.099962)
				(end 291.10305 -311.099962)
			)
		)
		(stroke
			(width 0)
			(type solid)
		)
		(fill yes)
		(layer "In1.Cu")
		(net "P5E_PEX2_STN5_TX_DP<80>")
	)
	(gr_poly
		(pts
			(arc
				(start 291.10305 -280.699464)
				(mid 290.69665 -280.699464)
				(end 291.10305 -280.699464)
			)
		)
		(stroke
			(width 0)
			(type solid)
		)
		(fill yes)
		(layer "In1.Cu")
		(net "P5E_PEX2_STN2_TX_DP<32>")
	)
	(gr_poly
		(pts
			(arc
				(start 291.10305 -279.749504)
				(mid 290.69665 -279.749504)
				(end 291.10305 -279.749504)
			)
		)
		(stroke
			(width 0)
			(type solid)
		)
		(fill yes)
		(layer "In1.Cu")
		(net "P5E_PEX2_STN2_TX_DN<32>")
	)
	(gr_poly
		(pts
			(arc
				(start 291.10305 -275.949918)
				(mid 290.69665 -275.949918)
				(end 291.10305 -275.949918)
			)
		)
		(stroke
			(width 0)
			(type solid)
		)
		(fill yes)
		(layer "In1.Cu")
		(net "P5E_PEX2_STN2_RX_DP<32>")
	)
	(gr_poly
		(pts
			(arc
				(start 291.10305 -274.999958)
				(mid 290.69665 -274.999958)
				(end 291.10305 -274.999958)
			)
		)
		(stroke
			(width 0)
			(type solid)
		)
		(fill yes)
		(layer "In1.Cu")
		(net "P5E_PEX2_STN2_RX_DN<32>")
	)
	(gr_poly
		(pts
			(arc
				(start 292.052756 -278.799798)
				(mid 291.646356 -278.799798)
				(end 292.052756 -278.799798)
			)
		)
		(stroke
			(width 0)
			(type solid)
		)
		(fill yes)
		(layer "In1.Cu")
		(net "P5E_PEX2_STN1_TX_DP<16>")
	)
	(gr_poly
		(pts
			(arc
				(start 292.052756 -277.849838)
				(mid 291.646356 -277.849838)
				(end 292.052756 -277.849838)
			)
		)
		(stroke
			(width 0)
			(type solid)
		)
		(fill yes)
		(layer "In1.Cu")
		(net "P5E_PEX2_STN1_TX_DN<16>")
	)
	(gr_poly
		(pts
			(arc
				(start 292.052756 -274.04949)
				(mid 291.646356 -274.04949)
				(end 292.052756 -274.04949)
			)
		)
		(stroke
			(width 0)
			(type solid)
		)
		(fill yes)
		(layer "In1.Cu")
		(net "P5E_PEX2_STN1_RX_DP<16>")
	)
	(gr_poly
		(pts
			(arc
				(start 292.052756 -273.09953)
				(mid 291.646356 -273.09953)
				(end 292.052756 -273.09953)
			)
		)
		(stroke
			(width 0)
			(type solid)
		)
		(fill yes)
		(layer "In1.Cu")
		(net "P5E_PEX2_STN1_RX_DN<16>")
	)
	(gr_poly
		(pts
			(arc
				(start 292.05301 -318.699896)
				(mid 291.64661 -318.699896)
				(end 292.05301 -318.699896)
			)
		)
		(stroke
			(width 0)
			(type solid)
		)
		(fill yes)
		(layer "In1.Cu")
		(net "P5E_PEX2_STN5_RX_DN<81>")
	)
	(gr_poly
		(pts
			(arc
				(start 292.05301 -317.749936)
				(mid 291.64661 -317.749936)
				(end 292.05301 -317.749936)
			)
		)
		(stroke
			(width 0)
			(type solid)
		)
		(fill yes)
		(layer "In1.Cu")
		(net "P5E_PEX2_STN5_RX_DP<81>")
	)
	(gr_poly
		(pts
			(arc
				(start 292.05301 -313.949842)
				(mid 291.64661 -313.949842)
				(end 292.05301 -313.949842)
			)
		)
		(stroke
			(width 0)
			(type solid)
		)
		(fill yes)
		(layer "In1.Cu")
		(net "P5E_PEX2_STN5_TX_DN<81>")
	)
	(gr_poly
		(pts
			(arc
				(start 292.05301 -312.999882)
				(mid 291.64661 -312.999882)
				(end 292.05301 -312.999882)
			)
		)
		(stroke
			(width 0)
			(type solid)
		)
		(fill yes)
		(layer "In1.Cu")
		(net "P5E_PEX2_STN5_TX_DP<81>")
	)
	(gr_poly
		(pts
			(arc
				(start 293.002716 -275.949664)
				(mid 292.596316 -275.949664)
				(end 293.002716 -275.949664)
			)
		)
		(stroke
			(width 0)
			(type solid)
		)
		(fill yes)
		(layer "In1.Cu")
		(net "P5E_PEX2_STN1_RX_DP<17>")
	)
	(gr_poly
		(pts
			(arc
				(start 293.002716 -274.999704)
				(mid 292.596316 -274.999704)
				(end 293.002716 -274.999704)
			)
		)
		(stroke
			(width 0)
			(type solid)
		)
		(fill yes)
		(layer "In1.Cu")
		(net "P5E_PEX2_STN1_RX_DN<17>")
	)
	(gr_poly
		(pts
			(arc
				(start 293.00297 -316.799722)
				(mid 292.59657 -316.799722)
				(end 293.00297 -316.799722)
			)
		)
		(stroke
			(width 0)
			(type solid)
		)
		(fill yes)
		(layer "In1.Cu")
		(net "P5E_PEX2_STN5_RX_DN<82>")
	)
	(gr_poly
		(pts
			(arc
				(start 293.00297 -315.849762)
				(mid 292.59657 -315.849762)
				(end 293.00297 -315.849762)
			)
		)
		(stroke
			(width 0)
			(type solid)
		)
		(fill yes)
		(layer "In1.Cu")
		(net "P5E_PEX2_STN5_RX_DP<82>")
	)
	(gr_poly
		(pts
			(arc
				(start 293.00297 -312.049922)
				(mid 292.59657 -312.049922)
				(end 293.00297 -312.049922)
			)
		)
		(stroke
			(width 0)
			(type solid)
		)
		(fill yes)
		(layer "In1.Cu")
		(net "P5E_PEX2_STN5_TX_DN<82>")
	)
	(gr_poly
		(pts
			(arc
				(start 293.00297 -311.099962)
				(mid 292.59657 -311.099962)
				(end 293.00297 -311.099962)
			)
		)
		(stroke
			(width 0)
			(type solid)
		)
		(fill yes)
		(layer "In1.Cu")
		(net "P5E_PEX2_STN5_TX_DP<82>")
	)
	(gr_poly
		(pts
			(arc
				(start 293.00297 -280.699464)
				(mid 292.59657 -280.699464)
				(end 293.00297 -280.699464)
			)
		)
		(stroke
			(width 0)
			(type solid)
		)
		(fill yes)
		(layer "In1.Cu")
		(net "P5E_PEX2_STN1_TX_DN<17>")
	)
	(gr_poly
		(pts
			(arc
				(start 293.00297 -279.749504)
				(mid 292.59657 -279.749504)
				(end 293.00297 -279.749504)
			)
		)
		(stroke
			(width 0)
			(type solid)
		)
		(fill yes)
		(layer "In1.Cu")
		(net "P5E_PEX2_STN1_TX_DP<17>")
	)
	(gr_poly
		(pts
			(arc
				(start 293.952676 -278.799798)
				(mid 293.546276 -278.799798)
				(end 293.952676 -278.799798)
			)
		)
		(stroke
			(width 0)
			(type solid)
		)
		(fill yes)
		(layer "In1.Cu")
		(net "P5E_PEX2_STN1_TX_DP<18>")
	)
	(gr_poly
		(pts
			(arc
				(start 293.952676 -277.849838)
				(mid 293.546276 -277.849838)
				(end 293.952676 -277.849838)
			)
		)
		(stroke
			(width 0)
			(type solid)
		)
		(fill yes)
		(layer "In1.Cu")
		(net "P5E_PEX2_STN1_TX_DN<18>")
	)
	(gr_poly
		(pts
			(arc
				(start 293.952676 -274.049744)
				(mid 293.546276 -274.049744)
				(end 293.952676 -274.049744)
			)
		)
		(stroke
			(width 0)
			(type solid)
		)
		(fill yes)
		(layer "In1.Cu")
		(net "P5E_PEX2_STN1_RX_DP<18>")
	)
	(gr_poly
		(pts
			(arc
				(start 293.952676 -273.099784)
				(mid 293.546276 -273.099784)
				(end 293.952676 -273.099784)
			)
		)
		(stroke
			(width 0)
			(type solid)
		)
		(fill yes)
		(layer "In1.Cu")
		(net "P5E_PEX2_STN1_RX_DN<18>")
	)
	(gr_poly
		(pts
			(arc
				(start 293.95293 -318.699896)
				(mid 293.54653 -318.699896)
				(end 293.95293 -318.699896)
			)
		)
		(stroke
			(width 0)
			(type solid)
		)
		(fill yes)
		(layer "In1.Cu")
		(net "P5E_PEX2_STN5_RX_DN<83>")
	)
	(gr_poly
		(pts
			(arc
				(start 293.95293 -317.749936)
				(mid 293.54653 -317.749936)
				(end 293.95293 -317.749936)
			)
		)
		(stroke
			(width 0)
			(type solid)
		)
		(fill yes)
		(layer "In1.Cu")
		(net "P5E_PEX2_STN5_RX_DP<83>")
	)
	(gr_poly
		(pts
			(arc
				(start 293.95293 -313.949842)
				(mid 293.54653 -313.949842)
				(end 293.95293 -313.949842)
			)
		)
		(stroke
			(width 0)
			(type solid)
		)
		(fill yes)
		(layer "In1.Cu")
		(net "P5E_PEX2_STN5_TX_DN<83>")
	)
	(gr_poly
		(pts
			(arc
				(start 293.95293 -312.999882)
				(mid 293.54653 -312.999882)
				(end 293.95293 -312.999882)
			)
		)
		(stroke
			(width 0)
			(type solid)
		)
		(fill yes)
		(layer "In1.Cu")
		(net "P5E_PEX2_STN5_TX_DP<83>")
	)
	(gr_poly
		(pts
			(arc
				(start 294.902636 -275.949918)
				(mid 294.496236 -275.949918)
				(end 294.902636 -275.949918)
			)
		)
		(stroke
			(width 0)
			(type solid)
		)
		(fill yes)
		(layer "In1.Cu")
		(net "P5E_PEX2_STN1_RX_DP<19>")
	)
	(gr_poly
		(pts
			(arc
				(start 294.902636 -274.999958)
				(mid 294.496236 -274.999958)
				(end 294.902636 -274.999958)
			)
		)
		(stroke
			(width 0)
			(type solid)
		)
		(fill yes)
		(layer "In1.Cu")
		(net "P5E_PEX2_STN1_RX_DN<19>")
	)
	(gr_poly
		(pts
			(arc
				(start 294.90289 -316.799722)
				(mid 294.49649 -316.799722)
				(end 294.90289 -316.799722)
			)
		)
		(stroke
			(width 0)
			(type solid)
		)
		(fill yes)
		(layer "In1.Cu")
		(net "P5E_PEX2_STN5_RX_DN<84>")
	)
	(gr_poly
		(pts
			(arc
				(start 294.90289 -315.849762)
				(mid 294.49649 -315.849762)
				(end 294.90289 -315.849762)
			)
		)
		(stroke
			(width 0)
			(type solid)
		)
		(fill yes)
		(layer "In1.Cu")
		(net "P5E_PEX2_STN5_RX_DP<84>")
	)
	(gr_poly
		(pts
			(arc
				(start 294.90289 -312.049922)
				(mid 294.49649 -312.049922)
				(end 294.90289 -312.049922)
			)
		)
		(stroke
			(width 0)
			(type solid)
		)
		(fill yes)
		(layer "In1.Cu")
		(net "P5E_PEX2_STN5_TX_DN<84>")
	)
	(gr_poly
		(pts
			(arc
				(start 294.90289 -311.099962)
				(mid 294.49649 -311.099962)
				(end 294.90289 -311.099962)
			)
		)
		(stroke
			(width 0)
			(type solid)
		)
		(fill yes)
		(layer "In1.Cu")
		(net "P5E_PEX2_STN5_TX_DP<84>")
	)
	(gr_poly
		(pts
			(arc
				(start 294.90289 -280.699464)
				(mid 294.49649 -280.699464)
				(end 294.90289 -280.699464)
			)
		)
		(stroke
			(width 0)
			(type solid)
		)
		(fill yes)
		(layer "In1.Cu")
		(net "P5E_PEX2_STN1_TX_DN<19>")
	)
	(gr_poly
		(pts
			(arc
				(start 294.90289 -279.749504)
				(mid 294.49649 -279.749504)
				(end 294.90289 -279.749504)
			)
		)
		(stroke
			(width 0)
			(type solid)
		)
		(fill yes)
		(layer "In1.Cu")
		(net "P5E_PEX2_STN1_TX_DP<19>")
	)
	(gr_poly
		(pts
			(arc
				(start 295.85285 -278.799798)
				(mid 295.44645 -278.799798)
				(end 295.85285 -278.799798)
			)
		)
		(stroke
			(width 0)
			(type solid)
		)
		(fill yes)
		(layer "In1.Cu")
		(net "P5E_PEX2_STN1_TX_DP<20>")
	)
	(gr_poly
		(pts
			(arc
				(start 295.85285 -277.849838)
				(mid 295.44645 -277.849838)
				(end 295.85285 -277.849838)
			)
		)
		(stroke
			(width 0)
			(type solid)
		)
		(fill yes)
		(layer "In1.Cu")
		(net "P5E_PEX2_STN1_TX_DN<20>")
	)
	(gr_poly
		(pts
			(arc
				(start 295.85285 -274.049744)
				(mid 295.44645 -274.049744)
				(end 295.85285 -274.049744)
			)
		)
		(stroke
			(width 0)
			(type solid)
		)
		(fill yes)
		(layer "In1.Cu")
		(net "P5E_PEX2_STN1_RX_DP<20>")
	)
	(gr_poly
		(pts
			(arc
				(start 295.85285 -273.099784)
				(mid 295.44645 -273.099784)
				(end 295.85285 -273.099784)
			)
		)
		(stroke
			(width 0)
			(type solid)
		)
		(fill yes)
		(layer "In1.Cu")
		(net "P5E_PEX2_STN1_RX_DN<20>")
	)
	(gr_poly
		(pts
			(arc
				(start 295.853104 -318.699896)
				(mid 295.446704 -318.699896)
				(end 295.853104 -318.699896)
			)
		)
		(stroke
			(width 0)
			(type solid)
		)
		(fill yes)
		(layer "In1.Cu")
		(net "P5E_PEX2_STN5_RX_DN<85>")
	)
	(gr_poly
		(pts
			(arc
				(start 295.853104 -317.749936)
				(mid 295.446704 -317.749936)
				(end 295.853104 -317.749936)
			)
		)
		(stroke
			(width 0)
			(type solid)
		)
		(fill yes)
		(layer "In1.Cu")
		(net "P5E_PEX2_STN5_RX_DP<85>")
	)
	(gr_poly
		(pts
			(arc
				(start 295.853104 -313.949842)
				(mid 295.446704 -313.949842)
				(end 295.853104 -313.949842)
			)
		)
		(stroke
			(width 0)
			(type solid)
		)
		(fill yes)
		(layer "In1.Cu")
		(net "P5E_PEX2_STN5_TX_DN<85>")
	)
	(gr_poly
		(pts
			(arc
				(start 295.853104 -312.999882)
				(mid 295.446704 -312.999882)
				(end 295.853104 -312.999882)
			)
		)
		(stroke
			(width 0)
			(type solid)
		)
		(fill yes)
		(layer "In1.Cu")
		(net "P5E_PEX2_STN5_TX_DP<85>")
	)
	(gr_poly
		(pts
			(arc
				(start 296.80281 -275.949664)
				(mid 296.39641 -275.949664)
				(end 296.80281 -275.949664)
			)
		)
		(stroke
			(width 0)
			(type solid)
		)
		(fill yes)
		(layer "In1.Cu")
		(net "P5E_PEX2_STN1_RX_DP<21>")
	)
	(gr_poly
		(pts
			(arc
				(start 296.80281 -274.999704)
				(mid 296.39641 -274.999704)
				(end 296.80281 -274.999704)
			)
		)
		(stroke
			(width 0)
			(type solid)
		)
		(fill yes)
		(layer "In1.Cu")
		(net "P5E_PEX2_STN1_RX_DN<21>")
	)
	(gr_poly
		(pts
			(arc
				(start 296.803064 -316.799722)
				(mid 296.396664 -316.799722)
				(end 296.803064 -316.799722)
			)
		)
		(stroke
			(width 0)
			(type solid)
		)
		(fill yes)
		(layer "In1.Cu")
		(net "P5E_PEX2_STN5_RX_DN<86>")
	)
	(gr_poly
		(pts
			(arc
				(start 296.803064 -315.849762)
				(mid 296.396664 -315.849762)
				(end 296.803064 -315.849762)
			)
		)
		(stroke
			(width 0)
			(type solid)
		)
		(fill yes)
		(layer "In1.Cu")
		(net "P5E_PEX2_STN5_RX_DP<86>")
	)
	(gr_poly
		(pts
			(arc
				(start 296.803064 -312.049922)
				(mid 296.396664 -312.049922)
				(end 296.803064 -312.049922)
			)
		)
		(stroke
			(width 0)
			(type solid)
		)
		(fill yes)
		(layer "In1.Cu")
		(net "P5E_PEX2_STN5_TX_DN<86>")
	)
	(gr_poly
		(pts
			(arc
				(start 296.803064 -311.099962)
				(mid 296.396664 -311.099962)
				(end 296.803064 -311.099962)
			)
		)
		(stroke
			(width 0)
			(type solid)
		)
		(fill yes)
		(layer "In1.Cu")
		(net "P5E_PEX2_STN5_TX_DP<86>")
	)
	(gr_poly
		(pts
			(arc
				(start 296.803064 -280.699464)
				(mid 296.396664 -280.699464)
				(end 296.803064 -280.699464)
			)
		)
		(stroke
			(width 0)
			(type solid)
		)
		(fill yes)
		(layer "In1.Cu")
		(net "P5E_PEX2_STN1_TX_DN<21>")
	)
	(gr_poly
		(pts
			(arc
				(start 296.803064 -279.749504)
				(mid 296.396664 -279.749504)
				(end 296.803064 -279.749504)
			)
		)
		(stroke
			(width 0)
			(type solid)
		)
		(fill yes)
		(layer "In1.Cu")
		(net "P5E_PEX2_STN1_TX_DP<21>")
	)
	(gr_poly
		(pts
			(arc
				(start 297.75277 -278.799798)
				(mid 297.34637 -278.799798)
				(end 297.75277 -278.799798)
			)
		)
		(stroke
			(width 0)
			(type solid)
		)
		(fill yes)
		(layer "In1.Cu")
		(net "P5E_PEX2_STN1_TX_DP<22>")
	)
	(gr_poly
		(pts
			(arc
				(start 297.75277 -277.849838)
				(mid 297.34637 -277.849838)
				(end 297.75277 -277.849838)
			)
		)
		(stroke
			(width 0)
			(type solid)
		)
		(fill yes)
		(layer "In1.Cu")
		(net "P5E_PEX2_STN1_TX_DN<22>")
	)
	(gr_poly
		(pts
			(arc
				(start 297.75277 -274.049744)
				(mid 297.34637 -274.049744)
				(end 297.75277 -274.049744)
			)
		)
		(stroke
			(width 0)
			(type solid)
		)
		(fill yes)
		(layer "In1.Cu")
		(net "P5E_PEX2_STN1_RX_DP<22>")
	)
	(gr_poly
		(pts
			(arc
				(start 297.75277 -273.099784)
				(mid 297.34637 -273.099784)
				(end 297.75277 -273.099784)
			)
		)
		(stroke
			(width 0)
			(type solid)
		)
		(fill yes)
		(layer "In1.Cu")
		(net "P5E_PEX2_STN1_RX_DN<22>")
	)
	(gr_poly
		(pts
			(arc
				(start 297.753024 -318.699896)
				(mid 297.346624 -318.699896)
				(end 297.753024 -318.699896)
			)
		)
		(stroke
			(width 0)
			(type solid)
		)
		(fill yes)
		(layer "In1.Cu")
		(net "P5E_PEX2_STN5_RX_DN<87>")
	)
	(gr_poly
		(pts
			(arc
				(start 297.753024 -317.749936)
				(mid 297.346624 -317.749936)
				(end 297.753024 -317.749936)
			)
		)
		(stroke
			(width 0)
			(type solid)
		)
		(fill yes)
		(layer "In1.Cu")
		(net "P5E_PEX2_STN5_RX_DP<87>")
	)
	(gr_poly
		(pts
			(arc
				(start 297.753024 -313.949842)
				(mid 297.346624 -313.949842)
				(end 297.753024 -313.949842)
			)
		)
		(stroke
			(width 0)
			(type solid)
		)
		(fill yes)
		(layer "In1.Cu")
		(net "P5E_PEX2_STN5_TX_DN<87>")
	)
	(gr_poly
		(pts
			(arc
				(start 297.753024 -312.999882)
				(mid 297.346624 -312.999882)
				(end 297.753024 -312.999882)
			)
		)
		(stroke
			(width 0)
			(type solid)
		)
		(fill yes)
		(layer "In1.Cu")
		(net "P5E_PEX2_STN5_TX_DP<87>")
	)
	(gr_poly
		(pts
			(arc
				(start 298.70273 -275.949918)
				(mid 298.29633 -275.949918)
				(end 298.70273 -275.949918)
			)
		)
		(stroke
			(width 0)
			(type solid)
		)
		(fill yes)
		(layer "In1.Cu")
		(net "P5E_PEX2_STN1_RX_DP<23>")
	)
	(gr_poly
		(pts
			(arc
				(start 298.70273 -274.999958)
				(mid 298.29633 -274.999958)
				(end 298.70273 -274.999958)
			)
		)
		(stroke
			(width 0)
			(type solid)
		)
		(fill yes)
		(layer "In1.Cu")
		(net "P5E_PEX2_STN1_RX_DN<23>")
	)
	(gr_poly
		(pts
			(arc
				(start 298.702984 -316.799722)
				(mid 298.296584 -316.799722)
				(end 298.702984 -316.799722)
			)
		)
		(stroke
			(width 0)
			(type solid)
		)
		(fill yes)
		(layer "In1.Cu")
		(net "P5E_PEX2_STN5_RX_DN<88>")
	)
	(gr_poly
		(pts
			(arc
				(start 298.702984 -315.849762)
				(mid 298.296584 -315.849762)
				(end 298.702984 -315.849762)
			)
		)
		(stroke
			(width 0)
			(type solid)
		)
		(fill yes)
		(layer "In1.Cu")
		(net "P5E_PEX2_STN5_RX_DP<88>")
	)
	(gr_poly
		(pts
			(arc
				(start 298.702984 -312.049922)
				(mid 298.296584 -312.049922)
				(end 298.702984 -312.049922)
			)
		)
		(stroke
			(width 0)
			(type solid)
		)
		(fill yes)
		(layer "In1.Cu")
		(net "P5E_PEX2_STN5_TX_DN<88>")
	)
	(gr_poly
		(pts
			(arc
				(start 298.702984 -311.099962)
				(mid 298.296584 -311.099962)
				(end 298.702984 -311.099962)
			)
		)
		(stroke
			(width 0)
			(type solid)
		)
		(fill yes)
		(layer "In1.Cu")
		(net "P5E_PEX2_STN5_TX_DP<88>")
	)
	(gr_poly
		(pts
			(arc
				(start 298.702984 -280.699464)
				(mid 298.296584 -280.699464)
				(end 298.702984 -280.699464)
			)
		)
		(stroke
			(width 0)
			(type solid)
		)
		(fill yes)
		(layer "In1.Cu")
		(net "P5E_PEX2_STN1_TX_DN<23>")
	)
	(gr_poly
		(pts
			(arc
				(start 298.702984 -279.749504)
				(mid 298.296584 -279.749504)
				(end 298.702984 -279.749504)
			)
		)
		(stroke
			(width 0)
			(type solid)
		)
		(fill yes)
		(layer "In1.Cu")
		(net "P5E_PEX2_STN1_TX_DP<23>")
	)
	(gr_poly
		(pts
			(arc
				(start 299.65269 -278.799798)
				(mid 299.24629 -278.799798)
				(end 299.65269 -278.799798)
			)
		)
		(stroke
			(width 0)
			(type solid)
		)
		(fill yes)
		(layer "In1.Cu")
		(net "P5E_PEX2_STN1_TX_DP<24>")
	)
	(gr_poly
		(pts
			(arc
				(start 299.65269 -277.849838)
				(mid 299.24629 -277.849838)
				(end 299.65269 -277.849838)
			)
		)
		(stroke
			(width 0)
			(type solid)
		)
		(fill yes)
		(layer "In1.Cu")
		(net "P5E_PEX2_STN1_TX_DN<24>")
	)
	(gr_poly
		(pts
			(arc
				(start 299.65269 -274.049744)
				(mid 299.24629 -274.049744)
				(end 299.65269 -274.049744)
			)
		)
		(stroke
			(width 0)
			(type solid)
		)
		(fill yes)
		(layer "In1.Cu")
		(net "P5E_PEX2_STN1_RX_DP<24>")
	)
	(gr_poly
		(pts
			(arc
				(start 299.65269 -273.099784)
				(mid 299.24629 -273.099784)
				(end 299.65269 -273.099784)
			)
		)
		(stroke
			(width 0)
			(type solid)
		)
		(fill yes)
		(layer "In1.Cu")
		(net "P5E_PEX2_STN1_RX_DN<24>")
	)
	(gr_poly
		(pts
			(arc
				(start 299.652944 -318.699896)
				(mid 299.246544 -318.699896)
				(end 299.652944 -318.699896)
			)
		)
		(stroke
			(width 0)
			(type solid)
		)
		(fill yes)
		(layer "In1.Cu")
		(net "P5E_PEX2_STN5_RX_DN<89>")
	)
	(gr_poly
		(pts
			(arc
				(start 299.652944 -317.749936)
				(mid 299.246544 -317.749936)
				(end 299.652944 -317.749936)
			)
		)
		(stroke
			(width 0)
			(type solid)
		)
		(fill yes)
		(layer "In1.Cu")
		(net "P5E_PEX2_STN5_RX_DP<89>")
	)
	(gr_poly
		(pts
			(arc
				(start 299.652944 -313.949842)
				(mid 299.246544 -313.949842)
				(end 299.652944 -313.949842)
			)
		)
		(stroke
			(width 0)
			(type solid)
		)
		(fill yes)
		(layer "In1.Cu")
		(net "P5E_PEX2_STN5_TX_DN<89>")
	)
	(gr_poly
		(pts
			(arc
				(start 299.652944 -312.999882)
				(mid 299.246544 -312.999882)
				(end 299.652944 -312.999882)
			)
		)
		(stroke
			(width 0)
			(type solid)
		)
		(fill yes)
		(layer "In1.Cu")
		(net "P5E_PEX2_STN5_TX_DP<89>")
	)
	(gr_poly
		(pts
			(arc
				(start 300.60265 -275.949664)
				(mid 300.19625 -275.949664)
				(end 300.60265 -275.949664)
			)
		)
		(stroke
			(width 0)
			(type solid)
		)
		(fill yes)
		(layer "In1.Cu")
		(net "P5E_PEX2_STN1_RX_DP<25>")
	)
	(gr_poly
		(pts
			(arc
				(start 300.60265 -274.999704)
				(mid 300.19625 -274.999704)
				(end 300.60265 -274.999704)
			)
		)
		(stroke
			(width 0)
			(type solid)
		)
		(fill yes)
		(layer "In1.Cu")
		(net "P5E_PEX2_STN1_RX_DN<25>")
	)
	(gr_poly
		(pts
			(arc
				(start 300.602904 -316.799722)
				(mid 300.196504 -316.799722)
				(end 300.602904 -316.799722)
			)
		)
		(stroke
			(width 0)
			(type solid)
		)
		(fill yes)
		(layer "In1.Cu")
		(net "P5E_PEX2_STN5_RX_DN<90>")
	)
	(gr_poly
		(pts
			(arc
				(start 300.602904 -315.849762)
				(mid 300.196504 -315.849762)
				(end 300.602904 -315.849762)
			)
		)
		(stroke
			(width 0)
			(type solid)
		)
		(fill yes)
		(layer "In1.Cu")
		(net "P5E_PEX2_STN5_RX_DP<90>")
	)
	(gr_poly
		(pts
			(arc
				(start 300.602904 -312.049922)
				(mid 300.196504 -312.049922)
				(end 300.602904 -312.049922)
			)
		)
		(stroke
			(width 0)
			(type solid)
		)
		(fill yes)
		(layer "In1.Cu")
		(net "P5E_PEX2_STN5_TX_DN<90>")
	)
	(gr_poly
		(pts
			(arc
				(start 300.602904 -311.099962)
				(mid 300.196504 -311.099962)
				(end 300.602904 -311.099962)
			)
		)
		(stroke
			(width 0)
			(type solid)
		)
		(fill yes)
		(layer "In1.Cu")
		(net "P5E_PEX2_STN5_TX_DP<90>")
	)
	(gr_poly
		(pts
			(arc
				(start 300.602904 -280.699464)
				(mid 300.196504 -280.699464)
				(end 300.602904 -280.699464)
			)
		)
		(stroke
			(width 0)
			(type solid)
		)
		(fill yes)
		(layer "In1.Cu")
		(net "P5E_PEX2_STN1_TX_DN<25>")
	)
	(gr_poly
		(pts
			(arc
				(start 300.602904 -279.749504)
				(mid 300.196504 -279.749504)
				(end 300.602904 -279.749504)
			)
		)
		(stroke
			(width 0)
			(type solid)
		)
		(fill yes)
		(layer "In1.Cu")
		(net "P5E_PEX2_STN1_TX_DP<25>")
	)
	(gr_poly
		(pts
			(arc
				(start 301.552864 -278.799798)
				(mid 301.146464 -278.799798)
				(end 301.552864 -278.799798)
			)
		)
		(stroke
			(width 0)
			(type solid)
		)
		(fill yes)
		(layer "In1.Cu")
		(net "P5E_PEX2_STN1_TX_DP<26>")
	)
	(gr_poly
		(pts
			(arc
				(start 301.552864 -277.849838)
				(mid 301.146464 -277.849838)
				(end 301.552864 -277.849838)
			)
		)
		(stroke
			(width 0)
			(type solid)
		)
		(fill yes)
		(layer "In1.Cu")
		(net "P5E_PEX2_STN1_TX_DN<26>")
	)
	(gr_poly
		(pts
			(arc
				(start 301.552864 -274.049744)
				(mid 301.146464 -274.049744)
				(end 301.552864 -274.049744)
			)
		)
		(stroke
			(width 0)
			(type solid)
		)
		(fill yes)
		(layer "In1.Cu")
		(net "P5E_PEX2_STN1_RX_DP<26>")
	)
	(gr_poly
		(pts
			(arc
				(start 301.552864 -273.099784)
				(mid 301.146464 -273.099784)
				(end 301.552864 -273.099784)
			)
		)
		(stroke
			(width 0)
			(type solid)
		)
		(fill yes)
		(layer "In1.Cu")
		(net "P5E_PEX2_STN1_RX_DN<26>")
	)
	(gr_poly
		(pts
			(arc
				(start 301.553118 -318.699896)
				(mid 301.146718 -318.699896)
				(end 301.553118 -318.699896)
			)
		)
		(stroke
			(width 0)
			(type solid)
		)
		(fill yes)
		(layer "In1.Cu")
		(net "P5E_PEX2_STN5_RX_DN<91>")
	)
	(gr_poly
		(pts
			(arc
				(start 301.553118 -317.749936)
				(mid 301.146718 -317.749936)
				(end 301.553118 -317.749936)
			)
		)
		(stroke
			(width 0)
			(type solid)
		)
		(fill yes)
		(layer "In1.Cu")
		(net "P5E_PEX2_STN5_RX_DP<91>")
	)
	(gr_poly
		(pts
			(arc
				(start 301.553118 -313.949842)
				(mid 301.146718 -313.949842)
				(end 301.553118 -313.949842)
			)
		)
		(stroke
			(width 0)
			(type solid)
		)
		(fill yes)
		(layer "In1.Cu")
		(net "P5E_PEX2_STN5_TX_DN<91>")
	)
	(gr_poly
		(pts
			(arc
				(start 301.553118 -312.999882)
				(mid 301.146718 -312.999882)
				(end 301.553118 -312.999882)
			)
		)
		(stroke
			(width 0)
			(type solid)
		)
		(fill yes)
		(layer "In1.Cu")
		(net "P5E_PEX2_STN5_TX_DP<91>")
	)
	(gr_poly
		(pts
			(arc
				(start 302.50257 -275.949918)
				(mid 302.09617 -275.949918)
				(end 302.50257 -275.949918)
			)
		)
		(stroke
			(width 0)
			(type solid)
		)
		(fill yes)
		(layer "In1.Cu")
		(net "P5E_PEX2_STN1_RX_DP<27>")
	)
	(gr_poly
		(pts
			(arc
				(start 302.50257 -274.999958)
				(mid 302.09617 -274.999958)
				(end 302.50257 -274.999958)
			)
		)
		(stroke
			(width 0)
			(type solid)
		)
		(fill yes)
		(layer "In1.Cu")
		(net "P5E_PEX2_STN1_RX_DN<27>")
	)
	(gr_poly
		(pts
			(arc
				(start 302.503078 -316.799722)
				(mid 302.096678 -316.799722)
				(end 302.503078 -316.799722)
			)
		)
		(stroke
			(width 0)
			(type solid)
		)
		(fill yes)
		(layer "In1.Cu")
		(net "P5E_PEX2_STN5_RX_DN<92>")
	)
	(gr_poly
		(pts
			(arc
				(start 302.503078 -315.849762)
				(mid 302.096678 -315.849762)
				(end 302.503078 -315.849762)
			)
		)
		(stroke
			(width 0)
			(type solid)
		)
		(fill yes)
		(layer "In1.Cu")
		(net "P5E_PEX2_STN5_RX_DP<92>")
	)
	(gr_poly
		(pts
			(arc
				(start 302.503078 -312.049922)
				(mid 302.096678 -312.049922)
				(end 302.503078 -312.049922)
			)
		)
		(stroke
			(width 0)
			(type solid)
		)
		(fill yes)
		(layer "In1.Cu")
		(net "P5E_PEX2_STN5_TX_DN<92>")
	)
	(gr_poly
		(pts
			(arc
				(start 302.503078 -311.099962)
				(mid 302.096678 -311.099962)
				(end 302.503078 -311.099962)
			)
		)
		(stroke
			(width 0)
			(type solid)
		)
		(fill yes)
		(layer "In1.Cu")
		(net "P5E_PEX2_STN5_TX_DP<92>")
	)
	(gr_poly
		(pts
			(arc
				(start 302.503078 -280.699464)
				(mid 302.096678 -280.699464)
				(end 302.503078 -280.699464)
			)
		)
		(stroke
			(width 0)
			(type solid)
		)
		(fill yes)
		(layer "In1.Cu")
		(net "P5E_PEX2_STN1_TX_DN<27>")
	)
	(gr_poly
		(pts
			(arc
				(start 302.503078 -279.749504)
				(mid 302.096678 -279.749504)
				(end 302.503078 -279.749504)
			)
		)
		(stroke
			(width 0)
			(type solid)
		)
		(fill yes)
		(layer "In1.Cu")
		(net "P5E_PEX2_STN1_TX_DP<27>")
	)
	(gr_poly
		(pts
			(arc
				(start 303.452784 -278.799798)
				(mid 303.046384 -278.799798)
				(end 303.452784 -278.799798)
			)
		)
		(stroke
			(width 0)
			(type solid)
		)
		(fill yes)
		(layer "In1.Cu")
		(net "P5E_PEX2_STN1_TX_DP<28>")
	)
	(gr_poly
		(pts
			(arc
				(start 303.452784 -277.849838)
				(mid 303.046384 -277.849838)
				(end 303.452784 -277.849838)
			)
		)
		(stroke
			(width 0)
			(type solid)
		)
		(fill yes)
		(layer "In1.Cu")
		(net "P5E_PEX2_STN1_TX_DN<28>")
	)
	(gr_poly
		(pts
			(arc
				(start 303.452784 -274.049744)
				(mid 303.046384 -274.049744)
				(end 303.452784 -274.049744)
			)
		)
		(stroke
			(width 0)
			(type solid)
		)
		(fill yes)
		(layer "In1.Cu")
		(net "P5E_PEX2_STN1_RX_DP<28>")
	)
	(gr_poly
		(pts
			(arc
				(start 303.452784 -273.099784)
				(mid 303.046384 -273.099784)
				(end 303.452784 -273.099784)
			)
		)
		(stroke
			(width 0)
			(type solid)
		)
		(fill yes)
		(layer "In1.Cu")
		(net "P5E_PEX2_STN1_RX_DN<28>")
	)
	(gr_poly
		(pts
			(arc
				(start 303.453038 -318.699896)
				(mid 303.046638 -318.699896)
				(end 303.453038 -318.699896)
			)
		)
		(stroke
			(width 0)
			(type solid)
		)
		(fill yes)
		(layer "In1.Cu")
		(net "P5E_PEX2_STN5_RX_DN<93>")
	)
	(gr_poly
		(pts
			(arc
				(start 303.453038 -317.749936)
				(mid 303.046638 -317.749936)
				(end 303.453038 -317.749936)
			)
		)
		(stroke
			(width 0)
			(type solid)
		)
		(fill yes)
		(layer "In1.Cu")
		(net "P5E_PEX2_STN5_RX_DP<93>")
	)
	(gr_poly
		(pts
			(arc
				(start 303.453038 -313.949842)
				(mid 303.046638 -313.949842)
				(end 303.453038 -313.949842)
			)
		)
		(stroke
			(width 0)
			(type solid)
		)
		(fill yes)
		(layer "In1.Cu")
		(net "P5E_PEX2_STN5_TX_DN<93>")
	)
	(gr_poly
		(pts
			(arc
				(start 303.453038 -312.999882)
				(mid 303.046638 -312.999882)
				(end 303.453038 -312.999882)
			)
		)
		(stroke
			(width 0)
			(type solid)
		)
		(fill yes)
		(layer "In1.Cu")
		(net "P5E_PEX2_STN5_TX_DP<93>")
	)
	(gr_poly
		(pts
			(arc
				(start 304.402744 -275.949664)
				(mid 303.996344 -275.949664)
				(end 304.402744 -275.949664)
			)
		)
		(stroke
			(width 0)
			(type solid)
		)
		(fill yes)
		(layer "In1.Cu")
		(net "P5E_PEX2_STN1_RX_DP<29>")
	)
	(gr_poly
		(pts
			(arc
				(start 304.402744 -274.999704)
				(mid 303.996344 -274.999704)
				(end 304.402744 -274.999704)
			)
		)
		(stroke
			(width 0)
			(type solid)
		)
		(fill yes)
		(layer "In1.Cu")
		(net "P5E_PEX2_STN1_RX_DN<29>")
	)
	(gr_poly
		(pts
			(arc
				(start 304.402998 -316.799722)
				(mid 303.996598 -316.799722)
				(end 304.402998 -316.799722)
			)
		)
		(stroke
			(width 0)
			(type solid)
		)
		(fill yes)
		(layer "In1.Cu")
		(net "P5E_PEX2_STN5_RX_DN<94>")
	)
	(gr_poly
		(pts
			(arc
				(start 304.402998 -315.849762)
				(mid 303.996598 -315.849762)
				(end 304.402998 -315.849762)
			)
		)
		(stroke
			(width 0)
			(type solid)
		)
		(fill yes)
		(layer "In1.Cu")
		(net "P5E_PEX2_STN5_RX_DP<94>")
	)
	(gr_poly
		(pts
			(arc
				(start 304.402998 -312.049922)
				(mid 303.996598 -312.049922)
				(end 304.402998 -312.049922)
			)
		)
		(stroke
			(width 0)
			(type solid)
		)
		(fill yes)
		(layer "In1.Cu")
		(net "P5E_PEX2_STN5_TX_DN<94>")
	)
	(gr_poly
		(pts
			(arc
				(start 304.402998 -311.099962)
				(mid 303.996598 -311.099962)
				(end 304.402998 -311.099962)
			)
		)
		(stroke
			(width 0)
			(type solid)
		)
		(fill yes)
		(layer "In1.Cu")
		(net "P5E_PEX2_STN5_TX_DP<94>")
	)
	(gr_poly
		(pts
			(arc
				(start 304.402998 -280.699464)
				(mid 303.996598 -280.699464)
				(end 304.402998 -280.699464)
			)
		)
		(stroke
			(width 0)
			(type solid)
		)
		(fill yes)
		(layer "In1.Cu")
		(net "P5E_PEX2_STN1_TX_DN<29>")
	)
	(gr_poly
		(pts
			(arc
				(start 304.402998 -279.749504)
				(mid 303.996598 -279.749504)
				(end 304.402998 -279.749504)
			)
		)
		(stroke
			(width 0)
			(type solid)
		)
		(fill yes)
		(layer "In1.Cu")
		(net "P5E_PEX2_STN1_TX_DP<29>")
	)
	(gr_poly
		(pts
			(arc
				(start 305.352704 -278.799798)
				(mid 304.946304 -278.799798)
				(end 305.352704 -278.799798)
			)
		)
		(stroke
			(width 0)
			(type solid)
		)
		(fill yes)
		(layer "In1.Cu")
		(net "P5E_PEX2_STN1_TX_DP<30>")
	)
	(gr_poly
		(pts
			(arc
				(start 305.352704 -277.849838)
				(mid 304.946304 -277.849838)
				(end 305.352704 -277.849838)
			)
		)
		(stroke
			(width 0)
			(type solid)
		)
		(fill yes)
		(layer "In1.Cu")
		(net "P5E_PEX2_STN1_TX_DN<30>")
	)
	(gr_poly
		(pts
			(arc
				(start 305.352704 -274.049744)
				(mid 304.946304 -274.049744)
				(end 305.352704 -274.049744)
			)
		)
		(stroke
			(width 0)
			(type solid)
		)
		(fill yes)
		(layer "In1.Cu")
		(net "P5E_PEX2_STN1_RX_DP<30>")
	)
	(gr_poly
		(pts
			(arc
				(start 305.352704 -273.099784)
				(mid 304.946304 -273.099784)
				(end 305.352704 -273.099784)
			)
		)
		(stroke
			(width 0)
			(type solid)
		)
		(fill yes)
		(layer "In1.Cu")
		(net "P5E_PEX2_STN1_RX_DN<30>")
	)
	(gr_poly
		(pts
			(arc
				(start 305.352958 -318.699896)
				(mid 304.946558 -318.699896)
				(end 305.352958 -318.699896)
			)
		)
		(stroke
			(width 0)
			(type solid)
		)
		(fill yes)
		(layer "In1.Cu")
		(net "P5E_PEX2_STN5_RX_DN<95>")
	)
	(gr_poly
		(pts
			(arc
				(start 305.352958 -317.749936)
				(mid 304.946558 -317.749936)
				(end 305.352958 -317.749936)
			)
		)
		(stroke
			(width 0)
			(type solid)
		)
		(fill yes)
		(layer "In1.Cu")
		(net "P5E_PEX2_STN5_RX_DP<95>")
	)
	(gr_poly
		(pts
			(arc
				(start 305.352958 -313.949842)
				(mid 304.946558 -313.949842)
				(end 305.352958 -313.949842)
			)
		)
		(stroke
			(width 0)
			(type solid)
		)
		(fill yes)
		(layer "In1.Cu")
		(net "P5E_PEX2_STN5_TX_DN<95>")
	)
	(gr_poly
		(pts
			(arc
				(start 305.352958 -312.999882)
				(mid 304.946558 -312.999882)
				(end 305.352958 -312.999882)
			)
		)
		(stroke
			(width 0)
			(type solid)
		)
		(fill yes)
		(layer "In1.Cu")
		(net "P5E_PEX2_STN5_TX_DP<95>")
	)
	(gr_poly
		(pts
			(arc
				(start 306.302664 -275.949918)
				(mid 305.896264 -275.949918)
				(end 306.302664 -275.949918)
			)
		)
		(stroke
			(width 0)
			(type solid)
		)
		(fill yes)
		(layer "In1.Cu")
		(net "P5E_PEX2_STN1_RX_DP<31>")
	)
	(gr_poly
		(pts
			(arc
				(start 306.302664 -274.999958)
				(mid 305.896264 -274.999958)
				(end 306.302664 -274.999958)
			)
		)
		(stroke
			(width 0)
			(type solid)
		)
		(fill yes)
		(layer "In1.Cu")
		(net "P5E_PEX2_STN1_RX_DN<31>")
	)
	(gr_poly
		(pts
			(arc
				(start 306.302918 -316.799722)
				(mid 305.896518 -316.799722)
				(end 306.302918 -316.799722)
			)
		)
		(stroke
			(width 0)
			(type solid)
		)
		(fill yes)
		(layer "In1.Cu")
		(net "P5E_PEX2_STN4_RX_DN<79>")
	)
	(gr_poly
		(pts
			(arc
				(start 306.302918 -315.849762)
				(mid 305.896518 -315.849762)
				(end 306.302918 -315.849762)
			)
		)
		(stroke
			(width 0)
			(type solid)
		)
		(fill yes)
		(layer "In1.Cu")
		(net "P5E_PEX2_STN4_RX_DP<79>")
	)
	(gr_poly
		(pts
			(arc
				(start 306.302918 -312.049922)
				(mid 305.896518 -312.049922)
				(end 306.302918 -312.049922)
			)
		)
		(stroke
			(width 0)
			(type solid)
		)
		(fill yes)
		(layer "In1.Cu")
		(net "P5E_PEX2_STN4_TX_DN<79>")
	)
	(gr_poly
		(pts
			(arc
				(start 306.302918 -311.099962)
				(mid 305.896518 -311.099962)
				(end 306.302918 -311.099962)
			)
		)
		(stroke
			(width 0)
			(type solid)
		)
		(fill yes)
		(layer "In1.Cu")
		(net "P5E_PEX2_STN4_TX_DP<79>")
	)
	(gr_poly
		(pts
			(arc
				(start 306.302918 -280.699464)
				(mid 305.896518 -280.699464)
				(end 306.302918 -280.699464)
			)
		)
		(stroke
			(width 0)
			(type solid)
		)
		(fill yes)
		(layer "In1.Cu")
		(net "P5E_PEX2_STN1_TX_DN<31>")
	)
	(gr_poly
		(pts
			(arc
				(start 306.302918 -279.749504)
				(mid 305.896518 -279.749504)
				(end 306.302918 -279.749504)
			)
		)
		(stroke
			(width 0)
			(type solid)
		)
		(fill yes)
		(layer "In1.Cu")
		(net "P5E_PEX2_STN1_TX_DP<31>")
	)
	(gr_poly
		(pts
			(arc
				(start 307.252878 -278.799798)
				(mid 306.846478 -278.799798)
				(end 307.252878 -278.799798)
			)
		)
		(stroke
			(width 0)
			(type solid)
		)
		(fill yes)
		(layer "In1.Cu")
		(net "P5E_PEX2_STN0_TX_DP<15>")
	)
	(gr_poly
		(pts
			(arc
				(start 307.252878 -277.849838)
				(mid 306.846478 -277.849838)
				(end 307.252878 -277.849838)
			)
		)
		(stroke
			(width 0)
			(type solid)
		)
		(fill yes)
		(layer "In1.Cu")
		(net "P5E_PEX2_STN0_TX_DN<15>")
	)
	(gr_poly
		(pts
			(arc
				(start 307.252878 -274.049744)
				(mid 306.846478 -274.049744)
				(end 307.252878 -274.049744)
			)
		)
		(stroke
			(width 0)
			(type solid)
		)
		(fill yes)
		(layer "In1.Cu")
		(net "P5E_PEX2_STN0_RX_DP<15>")
	)
	(gr_poly
		(pts
			(arc
				(start 307.252878 -273.099784)
				(mid 306.846478 -273.099784)
				(end 307.252878 -273.099784)
			)
		)
		(stroke
			(width 0)
			(type solid)
		)
		(fill yes)
		(layer "In1.Cu")
		(net "P5E_PEX2_STN0_RX_DN<15>")
	)
	(gr_poly
		(pts
			(arc
				(start 307.253132 -318.699896)
				(mid 306.846732 -318.699896)
				(end 307.253132 -318.699896)
			)
		)
		(stroke
			(width 0)
			(type solid)
		)
		(fill yes)
		(layer "In1.Cu")
		(net "P5E_PEX2_STN4_RX_DN<78>")
	)
	(gr_poly
		(pts
			(arc
				(start 307.253132 -317.749936)
				(mid 306.846732 -317.749936)
				(end 307.253132 -317.749936)
			)
		)
		(stroke
			(width 0)
			(type solid)
		)
		(fill yes)
		(layer "In1.Cu")
		(net "P5E_PEX2_STN4_RX_DP<78>")
	)
	(gr_poly
		(pts
			(arc
				(start 307.253132 -313.949842)
				(mid 306.846732 -313.949842)
				(end 307.253132 -313.949842)
			)
		)
		(stroke
			(width 0)
			(type solid)
		)
		(fill yes)
		(layer "In1.Cu")
		(net "P5E_PEX2_STN4_TX_DN<78>")
	)
	(gr_poly
		(pts
			(arc
				(start 307.253132 -312.999882)
				(mid 306.846732 -312.999882)
				(end 307.253132 -312.999882)
			)
		)
		(stroke
			(width 0)
			(type solid)
		)
		(fill yes)
		(layer "In1.Cu")
		(net "P5E_PEX2_STN4_TX_DP<78>")
	)
	(gr_poly
		(pts
			(arc
				(start 307.253132 -308.249828)
				(mid 306.846732 -308.249828)
				(end 307.253132 -308.249828)
			)
		)
		(stroke
			(width 0)
			(type solid)
		)
		(fill yes)
		(layer "In1.Cu")
		(net "P5E_PEX2_STN4_TX_DP<68>")
	)
	(gr_poly
		(pts
			(arc
				(start 307.253132 -306.349908)
				(mid 306.846732 -306.349908)
				(end 307.253132 -306.349908)
			)
		)
		(stroke
			(width 0)
			(type solid)
		)
		(fill yes)
		(layer "In1.Cu")
		(net "P5E_PEX2_STN4_TX_DP<66>")
	)
	(gr_poly
		(pts
			(arc
				(start 307.253132 -304.449734)
				(mid 306.846732 -304.449734)
				(end 307.253132 -304.449734)
			)
		)
		(stroke
			(width 0)
			(type solid)
		)
		(fill yes)
		(layer "In1.Cu")
		(net "P5E_PEX2_STN4_TX_DP<64>")
	)
	(gr_poly
		(pts
			(arc
				(start 307.253132 -287.349946)
				(mid 306.846732 -287.349946)
				(end 307.253132 -287.349946)
			)
		)
		(stroke
			(width 0)
			(type solid)
		)
		(fill yes)
		(layer "In1.Cu")
		(net "P5E_PEX2_STN0_TX_DP<1>")
	)
	(gr_poly
		(pts
			(arc
				(start 307.253132 -285.449772)
				(mid 306.846732 -285.449772)
				(end 307.253132 -285.449772)
			)
		)
		(stroke
			(width 0)
			(type solid)
		)
		(fill yes)
		(layer "In1.Cu")
		(net "P5E_PEX2_STN0_TX_DP<3>")
	)
	(gr_poly
		(pts
			(arc
				(start 307.253132 -283.549852)
				(mid 306.846732 -283.549852)
				(end 307.253132 -283.549852)
			)
		)
		(stroke
			(width 0)
			(type solid)
		)
		(fill yes)
		(layer "In1.Cu")
		(net "P5E_PEX2_STN0_TX_DP<5>")
	)
	(gr_poly
		(pts
			(arc
				(start 308.202838 -275.949664)
				(mid 307.796438 -275.949664)
				(end 308.202838 -275.949664)
			)
		)
		(stroke
			(width 0)
			(type solid)
		)
		(fill yes)
		(layer "In1.Cu")
		(net "P5E_PEX2_STN0_RX_DP<14>")
	)
	(gr_poly
		(pts
			(arc
				(start 308.202838 -274.999704)
				(mid 307.796438 -274.999704)
				(end 308.202838 -274.999704)
			)
		)
		(stroke
			(width 0)
			(type solid)
		)
		(fill yes)
		(layer "In1.Cu")
		(net "P5E_PEX2_STN0_RX_DN<14>")
	)
	(gr_poly
		(pts
			(arc
				(start 308.203092 -316.799722)
				(mid 307.796692 -316.799722)
				(end 308.203092 -316.799722)
			)
		)
		(stroke
			(width 0)
			(type solid)
		)
		(fill yes)
		(layer "In1.Cu")
		(net "P5E_PEX2_STN4_RX_DN<77>")
	)
	(gr_poly
		(pts
			(arc
				(start 308.203092 -315.849762)
				(mid 307.796692 -315.849762)
				(end 308.203092 -315.849762)
			)
		)
		(stroke
			(width 0)
			(type solid)
		)
		(fill yes)
		(layer "In1.Cu")
		(net "P5E_PEX2_STN4_RX_DP<77>")
	)
	(gr_poly
		(pts
			(arc
				(start 308.203092 -312.049922)
				(mid 307.796692 -312.049922)
				(end 308.203092 -312.049922)
			)
		)
		(stroke
			(width 0)
			(type solid)
		)
		(fill yes)
		(layer "In1.Cu")
		(net "P5E_PEX2_STN4_TX_DN<77>")
	)
	(gr_poly
		(pts
			(arc
				(start 308.203092 -311.099962)
				(mid 307.796692 -311.099962)
				(end 308.203092 -311.099962)
			)
		)
		(stroke
			(width 0)
			(type solid)
		)
		(fill yes)
		(layer "In1.Cu")
		(net "P5E_PEX2_STN4_TX_DP<77>")
	)
	(gr_poly
		(pts
			(arc
				(start 308.203092 -308.249828)
				(mid 307.796692 -308.249828)
				(end 308.203092 -308.249828)
			)
		)
		(stroke
			(width 0)
			(type solid)
		)
		(fill yes)
		(layer "In1.Cu")
		(net "P5E_PEX2_STN4_TX_DN<68>")
	)
	(gr_poly
		(pts
			(arc
				(start 308.203092 -306.349908)
				(mid 307.796692 -306.349908)
				(end 308.203092 -306.349908)
			)
		)
		(stroke
			(width 0)
			(type solid)
		)
		(fill yes)
		(layer "In1.Cu")
		(net "P5E_PEX2_STN4_TX_DN<66>")
	)
	(gr_poly
		(pts
			(arc
				(start 308.203092 -304.449734)
				(mid 307.796692 -304.449734)
				(end 308.203092 -304.449734)
			)
		)
		(stroke
			(width 0)
			(type solid)
		)
		(fill yes)
		(layer "In1.Cu")
		(net "P5E_PEX2_STN4_TX_DN<64>")
	)
	(gr_poly
		(pts
			(arc
				(start 308.203092 -287.349946)
				(mid 307.796692 -287.349946)
				(end 308.203092 -287.349946)
			)
		)
		(stroke
			(width 0)
			(type solid)
		)
		(fill yes)
		(layer "In1.Cu")
		(net "P5E_PEX2_STN0_TX_DN<1>")
	)
	(gr_poly
		(pts
			(arc
				(start 308.203092 -285.449772)
				(mid 307.796692 -285.449772)
				(end 308.203092 -285.449772)
			)
		)
		(stroke
			(width 0)
			(type solid)
		)
		(fill yes)
		(layer "In1.Cu")
		(net "P5E_PEX2_STN0_TX_DN<3>")
	)
	(gr_poly
		(pts
			(arc
				(start 308.203092 -283.549852)
				(mid 307.796692 -283.549852)
				(end 308.203092 -283.549852)
			)
		)
		(stroke
			(width 0)
			(type solid)
		)
		(fill yes)
		(layer "In1.Cu")
		(net "P5E_PEX2_STN0_TX_DN<5>")
	)
	(gr_poly
		(pts
			(arc
				(start 308.203092 -280.699464)
				(mid 307.796692 -280.699464)
				(end 308.203092 -280.699464)
			)
		)
		(stroke
			(width 0)
			(type solid)
		)
		(fill yes)
		(layer "In1.Cu")
		(net "P5E_PEX2_STN0_TX_DN<14>")
	)
	(gr_poly
		(pts
			(arc
				(start 308.203092 -279.749504)
				(mid 307.796692 -279.749504)
				(end 308.203092 -279.749504)
			)
		)
		(stroke
			(width 0)
			(type solid)
		)
		(fill yes)
		(layer "In1.Cu")
		(net "P5E_PEX2_STN0_TX_DP<14>")
	)
	(gr_poly
		(pts
			(arc
				(start 309.152798 -278.799798)
				(mid 308.746398 -278.799798)
				(end 309.152798 -278.799798)
			)
		)
		(stroke
			(width 0)
			(type solid)
		)
		(fill yes)
		(layer "In1.Cu")
		(net "P5E_PEX2_STN0_TX_DP<13>")
	)
	(gr_poly
		(pts
			(arc
				(start 309.152798 -277.849838)
				(mid 308.746398 -277.849838)
				(end 309.152798 -277.849838)
			)
		)
		(stroke
			(width 0)
			(type solid)
		)
		(fill yes)
		(layer "In1.Cu")
		(net "P5E_PEX2_STN0_TX_DN<13>")
	)
	(gr_poly
		(pts
			(arc
				(start 309.152798 -274.049744)
				(mid 308.746398 -274.049744)
				(end 309.152798 -274.049744)
			)
		)
		(stroke
			(width 0)
			(type solid)
		)
		(fill yes)
		(layer "In1.Cu")
		(net "P5E_PEX2_STN0_RX_DP<13>")
	)
	(gr_poly
		(pts
			(arc
				(start 309.152798 -273.099784)
				(mid 308.746398 -273.099784)
				(end 309.152798 -273.099784)
			)
		)
		(stroke
			(width 0)
			(type solid)
		)
		(fill yes)
		(layer "In1.Cu")
		(net "P5E_PEX2_STN0_RX_DN<13>")
	)
	(gr_poly
		(pts
			(arc
				(start 309.153052 -318.699896)
				(mid 308.746652 -318.699896)
				(end 309.153052 -318.699896)
			)
		)
		(stroke
			(width 0)
			(type solid)
		)
		(fill yes)
		(layer "In1.Cu")
		(net "P5E_PEX2_STN4_RX_DN<76>")
	)
	(gr_poly
		(pts
			(arc
				(start 309.153052 -317.749936)
				(mid 308.746652 -317.749936)
				(end 309.153052 -317.749936)
			)
		)
		(stroke
			(width 0)
			(type solid)
		)
		(fill yes)
		(layer "In1.Cu")
		(net "P5E_PEX2_STN4_RX_DP<76>")
	)
	(gr_poly
		(pts
			(arc
				(start 309.153052 -313.949842)
				(mid 308.746652 -313.949842)
				(end 309.153052 -313.949842)
			)
		)
		(stroke
			(width 0)
			(type solid)
		)
		(fill yes)
		(layer "In1.Cu")
		(net "P5E_PEX2_STN4_TX_DN<76>")
	)
	(gr_poly
		(pts
			(arc
				(start 309.153052 -312.999882)
				(mid 308.746652 -312.999882)
				(end 309.153052 -312.999882)
			)
		)
		(stroke
			(width 0)
			(type solid)
		)
		(fill yes)
		(layer "In1.Cu")
		(net "P5E_PEX2_STN4_TX_DP<76>")
	)
	(gr_poly
		(pts
			(arc
				(start 309.153052 -309.199788)
				(mid 308.746652 -309.199788)
				(end 309.153052 -309.199788)
			)
		)
		(stroke
			(width 0)
			(type solid)
		)
		(fill yes)
		(layer "In1.Cu")
		(net "P5E_PEX2_STN4_TX_DP<69>")
	)
	(gr_poly
		(pts
			(arc
				(start 309.153052 -307.299868)
				(mid 308.746652 -307.299868)
				(end 309.153052 -307.299868)
			)
		)
		(stroke
			(width 0)
			(type solid)
		)
		(fill yes)
		(layer "In1.Cu")
		(net "P5E_PEX2_STN4_TX_DP<67>")
	)
	(gr_poly
		(pts
			(arc
				(start 309.153052 -305.399948)
				(mid 308.746652 -305.399948)
				(end 309.153052 -305.399948)
			)
		)
		(stroke
			(width 0)
			(type solid)
		)
		(fill yes)
		(layer "In1.Cu")
		(net "P5E_PEX2_STN4_TX_DP<65>")
	)
	(gr_poly
		(pts
			(arc
				(start 309.153052 -288.299906)
				(mid 308.746652 -288.299906)
				(end 309.153052 -288.299906)
			)
		)
		(stroke
			(width 0)
			(type solid)
		)
		(fill yes)
		(layer "In1.Cu")
		(net "P5E_PEX2_STN0_TX_DP<0>")
	)
	(gr_poly
		(pts
			(arc
				(start 309.153052 -286.399986)
				(mid 308.746652 -286.399986)
				(end 309.153052 -286.399986)
			)
		)
		(stroke
			(width 0)
			(type solid)
		)
		(fill yes)
		(layer "In1.Cu")
		(net "P5E_PEX2_STN0_TX_DP<2>")
	)
	(gr_poly
		(pts
			(arc
				(start 309.153052 -284.499812)
				(mid 308.746652 -284.499812)
				(end 309.153052 -284.499812)
			)
		)
		(stroke
			(width 0)
			(type solid)
		)
		(fill yes)
		(layer "In1.Cu")
		(net "P5E_PEX2_STN0_TX_DP<4>")
	)
	(gr_poly
		(pts
			(arc
				(start 309.153052 -282.599892)
				(mid 308.746652 -282.599892)
				(end 309.153052 -282.599892)
			)
		)
		(stroke
			(width 0)
			(type solid)
		)
		(fill yes)
		(layer "In1.Cu")
		(net "P5E_PEX2_STN0_TX_DP<6>")
	)
	(gr_poly
		(pts
			(arc
				(start 310.102758 -275.949918)
				(mid 309.696358 -275.949918)
				(end 310.102758 -275.949918)
			)
		)
		(stroke
			(width 0)
			(type solid)
		)
		(fill yes)
		(layer "In1.Cu")
		(net "P5E_PEX2_STN0_RX_DP<12>")
	)
	(gr_poly
		(pts
			(arc
				(start 310.102758 -274.999958)
				(mid 309.696358 -274.999958)
				(end 310.102758 -274.999958)
			)
		)
		(stroke
			(width 0)
			(type solid)
		)
		(fill yes)
		(layer "In1.Cu")
		(net "P5E_PEX2_STN0_RX_DN<12>")
	)
	(gr_poly
		(pts
			(arc
				(start 310.103012 -316.799722)
				(mid 309.696612 -316.799722)
				(end 310.103012 -316.799722)
			)
		)
		(stroke
			(width 0)
			(type solid)
		)
		(fill yes)
		(layer "In1.Cu")
		(net "P5E_PEX2_STN4_RX_DN<75>")
	)
	(gr_poly
		(pts
			(arc
				(start 310.103012 -315.849762)
				(mid 309.696612 -315.849762)
				(end 310.103012 -315.849762)
			)
		)
		(stroke
			(width 0)
			(type solid)
		)
		(fill yes)
		(layer "In1.Cu")
		(net "P5E_PEX2_STN4_RX_DP<75>")
	)
	(gr_poly
		(pts
			(arc
				(start 310.103012 -312.049922)
				(mid 309.696612 -312.049922)
				(end 310.103012 -312.049922)
			)
		)
		(stroke
			(width 0)
			(type solid)
		)
		(fill yes)
		(layer "In1.Cu")
		(net "P5E_PEX2_STN4_TX_DN<75>")
	)
	(gr_poly
		(pts
			(arc
				(start 310.103012 -311.099962)
				(mid 309.696612 -311.099962)
				(end 310.103012 -311.099962)
			)
		)
		(stroke
			(width 0)
			(type solid)
		)
		(fill yes)
		(layer "In1.Cu")
		(net "P5E_PEX2_STN4_TX_DP<75>")
	)
	(gr_poly
		(pts
			(arc
				(start 310.103012 -309.199788)
				(mid 309.696612 -309.199788)
				(end 310.103012 -309.199788)
			)
		)
		(stroke
			(width 0)
			(type solid)
		)
		(fill yes)
		(layer "In1.Cu")
		(net "P5E_PEX2_STN4_TX_DN<69>")
	)
	(gr_poly
		(pts
			(arc
				(start 310.103012 -307.299868)
				(mid 309.696612 -307.299868)
				(end 310.103012 -307.299868)
			)
		)
		(stroke
			(width 0)
			(type solid)
		)
		(fill yes)
		(layer "In1.Cu")
		(net "P5E_PEX2_STN4_TX_DN<67>")
	)
	(gr_poly
		(pts
			(arc
				(start 310.103012 -305.399948)
				(mid 309.696612 -305.399948)
				(end 310.103012 -305.399948)
			)
		)
		(stroke
			(width 0)
			(type solid)
		)
		(fill yes)
		(layer "In1.Cu")
		(net "P5E_PEX2_STN4_TX_DN<65>")
	)
	(gr_poly
		(pts
			(arc
				(start 310.103012 -288.299906)
				(mid 309.696612 -288.299906)
				(end 310.103012 -288.299906)
			)
		)
		(stroke
			(width 0)
			(type solid)
		)
		(fill yes)
		(layer "In1.Cu")
		(net "P5E_PEX2_STN0_TX_DN<0>")
	)
	(gr_poly
		(pts
			(arc
				(start 310.103012 -286.399986)
				(mid 309.696612 -286.399986)
				(end 310.103012 -286.399986)
			)
		)
		(stroke
			(width 0)
			(type solid)
		)
		(fill yes)
		(layer "In1.Cu")
		(net "P5E_PEX2_STN0_TX_DN<2>")
	)
	(gr_poly
		(pts
			(arc
				(start 310.103012 -284.499812)
				(mid 309.696612 -284.499812)
				(end 310.103012 -284.499812)
			)
		)
		(stroke
			(width 0)
			(type solid)
		)
		(fill yes)
		(layer "In1.Cu")
		(net "P5E_PEX2_STN0_TX_DN<4>")
	)
	(gr_poly
		(pts
			(arc
				(start 310.103012 -282.599892)
				(mid 309.696612 -282.599892)
				(end 310.103012 -282.599892)
			)
		)
		(stroke
			(width 0)
			(type solid)
		)
		(fill yes)
		(layer "In1.Cu")
		(net "P5E_PEX2_STN0_TX_DN<6>")
	)
	(gr_poly
		(pts
			(arc
				(start 310.103012 -280.699464)
				(mid 309.696612 -280.699464)
				(end 310.103012 -280.699464)
			)
		)
		(stroke
			(width 0)
			(type solid)
		)
		(fill yes)
		(layer "In1.Cu")
		(net "P5E_PEX2_STN0_TX_DN<12>")
	)
	(gr_poly
		(pts
			(arc
				(start 310.103012 -279.749504)
				(mid 309.696612 -279.749504)
				(end 310.103012 -279.749504)
			)
		)
		(stroke
			(width 0)
			(type solid)
		)
		(fill yes)
		(layer "In1.Cu")
		(net "P5E_PEX2_STN0_TX_DP<12>")
	)
	(gr_poly
		(pts
			(arc
				(start 311.052718 -278.799798)
				(mid 310.646318 -278.799798)
				(end 311.052718 -278.799798)
			)
		)
		(stroke
			(width 0)
			(type solid)
		)
		(fill yes)
		(layer "In1.Cu")
		(net "P5E_PEX2_STN0_TX_DP<11>")
	)
	(gr_poly
		(pts
			(arc
				(start 311.052718 -277.849838)
				(mid 310.646318 -277.849838)
				(end 311.052718 -277.849838)
			)
		)
		(stroke
			(width 0)
			(type solid)
		)
		(fill yes)
		(layer "In1.Cu")
		(net "P5E_PEX2_STN0_TX_DN<11>")
	)
	(gr_poly
		(pts
			(arc
				(start 311.052718 -274.049744)
				(mid 310.646318 -274.049744)
				(end 311.052718 -274.049744)
			)
		)
		(stroke
			(width 0)
			(type solid)
		)
		(fill yes)
		(layer "In1.Cu")
		(net "P5E_PEX2_STN0_RX_DP<11>")
	)
	(gr_poly
		(pts
			(arc
				(start 311.052718 -273.099784)
				(mid 310.646318 -273.099784)
				(end 311.052718 -273.099784)
			)
		)
		(stroke
			(width 0)
			(type solid)
		)
		(fill yes)
		(layer "In1.Cu")
		(net "P5E_PEX2_STN0_RX_DN<11>")
	)
	(gr_poly
		(pts
			(arc
				(start 311.052972 -318.699896)
				(mid 310.646572 -318.699896)
				(end 311.052972 -318.699896)
			)
		)
		(stroke
			(width 0)
			(type solid)
		)
		(fill yes)
		(layer "In1.Cu")
		(net "P5E_PEX2_STN4_RX_DN<74>")
	)
	(gr_poly
		(pts
			(arc
				(start 311.052972 -317.749936)
				(mid 310.646572 -317.749936)
				(end 311.052972 -317.749936)
			)
		)
		(stroke
			(width 0)
			(type solid)
		)
		(fill yes)
		(layer "In1.Cu")
		(net "P5E_PEX2_STN4_RX_DP<74>")
	)
	(gr_poly
		(pts
			(arc
				(start 311.052972 -313.949842)
				(mid 310.646572 -313.949842)
				(end 311.052972 -313.949842)
			)
		)
		(stroke
			(width 0)
			(type solid)
		)
		(fill yes)
		(layer "In1.Cu")
		(net "P5E_PEX2_STN4_TX_DN<74>")
	)
	(gr_poly
		(pts
			(arc
				(start 311.052972 -312.999882)
				(mid 310.646572 -312.999882)
				(end 311.052972 -312.999882)
			)
		)
		(stroke
			(width 0)
			(type solid)
		)
		(fill yes)
		(layer "In1.Cu")
		(net "P5E_PEX2_STN4_TX_DP<74>")
	)
	(gr_poly
		(pts
			(arc
				(start 312.002678 -275.949918)
				(mid 311.596278 -275.949918)
				(end 312.002678 -275.949918)
			)
		)
		(stroke
			(width 0)
			(type solid)
		)
		(fill yes)
		(layer "In1.Cu")
		(net "P5E_PEX2_STN0_RX_DP<10>")
	)
	(gr_poly
		(pts
			(arc
				(start 312.002678 -274.999958)
				(mid 311.596278 -274.999958)
				(end 312.002678 -274.999958)
			)
		)
		(stroke
			(width 0)
			(type solid)
		)
		(fill yes)
		(layer "In1.Cu")
		(net "P5E_PEX2_STN0_RX_DN<10>")
	)
	(gr_poly
		(pts
			(arc
				(start 312.002932 -316.799722)
				(mid 311.596532 -316.799722)
				(end 312.002932 -316.799722)
			)
		)
		(stroke
			(width 0)
			(type solid)
		)
		(fill yes)
		(layer "In1.Cu")
		(net "P5E_PEX2_STN4_RX_DN<73>")
	)
	(gr_poly
		(pts
			(arc
				(start 312.002932 -315.849762)
				(mid 311.596532 -315.849762)
				(end 312.002932 -315.849762)
			)
		)
		(stroke
			(width 0)
			(type solid)
		)
		(fill yes)
		(layer "In1.Cu")
		(net "P5E_PEX2_STN4_RX_DP<73>")
	)
	(gr_poly
		(pts
			(arc
				(start 312.002932 -312.049922)
				(mid 311.596532 -312.049922)
				(end 312.002932 -312.049922)
			)
		)
		(stroke
			(width 0)
			(type solid)
		)
		(fill yes)
		(layer "In1.Cu")
		(net "P5E_PEX2_STN4_TX_DN<73>")
	)
	(gr_poly
		(pts
			(arc
				(start 312.002932 -311.099962)
				(mid 311.596532 -311.099962)
				(end 312.002932 -311.099962)
			)
		)
		(stroke
			(width 0)
			(type solid)
		)
		(fill yes)
		(layer "In1.Cu")
		(net "P5E_PEX2_STN4_TX_DP<73>")
	)
	(gr_poly
		(pts
			(arc
				(start 312.002932 -309.199788)
				(mid 311.596532 -309.199788)
				(end 312.002932 -309.199788)
			)
		)
		(stroke
			(width 0)
			(type solid)
		)
		(fill yes)
		(layer "In1.Cu")
		(net "P5E_PEX2_STN4_RX_DP<69>")
	)
	(gr_poly
		(pts
			(arc
				(start 312.002932 -307.299868)
				(mid 311.596532 -307.299868)
				(end 312.002932 -307.299868)
			)
		)
		(stroke
			(width 0)
			(type solid)
		)
		(fill yes)
		(layer "In1.Cu")
		(net "P5E_PEX2_STN4_RX_DP<67>")
	)
	(gr_poly
		(pts
			(arc
				(start 312.002932 -305.399948)
				(mid 311.596532 -305.399948)
				(end 312.002932 -305.399948)
			)
		)
		(stroke
			(width 0)
			(type solid)
		)
		(fill yes)
		(layer "In1.Cu")
		(net "P5E_PEX2_STN4_RX_DP<65>")
	)
	(gr_poly
		(pts
			(arc
				(start 312.002932 -288.299906)
				(mid 311.596532 -288.299906)
				(end 312.002932 -288.299906)
			)
		)
		(stroke
			(width 0)
			(type solid)
		)
		(fill yes)
		(layer "In1.Cu")
		(net "P5E_PEX2_STN0_RX_DP<0>")
	)
	(gr_poly
		(pts
			(arc
				(start 312.002932 -286.399732)
				(mid 311.596532 -286.399732)
				(end 312.002932 -286.399732)
			)
		)
		(stroke
			(width 0)
			(type solid)
		)
		(fill yes)
		(layer "In1.Cu")
		(net "P5E_PEX2_STN0_RX_DP<2>")
	)
	(gr_poly
		(pts
			(arc
				(start 312.002932 -284.499812)
				(mid 311.596532 -284.499812)
				(end 312.002932 -284.499812)
			)
		)
		(stroke
			(width 0)
			(type solid)
		)
		(fill yes)
		(layer "In1.Cu")
		(net "P5E_PEX2_STN0_RX_DP<4>")
	)
	(gr_poly
		(pts
			(arc
				(start 312.002932 -282.599892)
				(mid 311.596532 -282.599892)
				(end 312.002932 -282.599892)
			)
		)
		(stroke
			(width 0)
			(type solid)
		)
		(fill yes)
		(layer "In1.Cu")
		(net "P5E_PEX2_STN0_RX_DP<6>")
	)
	(gr_poly
		(pts
			(arc
				(start 312.002932 -280.699718)
				(mid 311.596532 -280.699718)
				(end 312.002932 -280.699718)
			)
		)
		(stroke
			(width 0)
			(type solid)
		)
		(fill yes)
		(layer "In1.Cu")
		(net "P5E_PEX2_STN0_TX_DP<10>")
	)
	(gr_poly
		(pts
			(arc
				(start 312.002932 -279.749758)
				(mid 311.596532 -279.749758)
				(end 312.002932 -279.749758)
			)
		)
		(stroke
			(width 0)
			(type solid)
		)
		(fill yes)
		(layer "In1.Cu")
		(net "P5E_PEX2_STN0_TX_DN<10>")
	)
	(gr_poly
		(pts
			(arc
				(start 312.952638 -274.049744)
				(mid 312.546238 -274.049744)
				(end 312.952638 -274.049744)
			)
		)
		(stroke
			(width 0)
			(type solid)
		)
		(fill yes)
		(layer "In1.Cu")
		(net "P5E_PEX2_STN0_RX_DP<9>")
	)
	(gr_poly
		(pts
			(arc
				(start 312.952638 -273.099784)
				(mid 312.546238 -273.099784)
				(end 312.952638 -273.099784)
			)
		)
		(stroke
			(width 0)
			(type solid)
		)
		(fill yes)
		(layer "In1.Cu")
		(net "P5E_PEX2_STN0_RX_DN<9>")
	)
	(gr_poly
		(pts
			(arc
				(start 312.952892 -318.699896)
				(mid 312.546492 -318.699896)
				(end 312.952892 -318.699896)
			)
		)
		(stroke
			(width 0)
			(type solid)
		)
		(fill yes)
		(layer "In1.Cu")
		(net "P5E_PEX2_STN4_RX_DN<72>")
	)
	(gr_poly
		(pts
			(arc
				(start 312.952892 -317.749936)
				(mid 312.546492 -317.749936)
				(end 312.952892 -317.749936)
			)
		)
		(stroke
			(width 0)
			(type solid)
		)
		(fill yes)
		(layer "In1.Cu")
		(net "P5E_PEX2_STN4_RX_DP<72>")
	)
	(gr_poly
		(pts
			(arc
				(start 312.952892 -313.949842)
				(mid 312.546492 -313.949842)
				(end 312.952892 -313.949842)
			)
		)
		(stroke
			(width 0)
			(type solid)
		)
		(fill yes)
		(layer "In1.Cu")
		(net "P5E_PEX2_STN4_TX_DN<72>")
	)
	(gr_poly
		(pts
			(arc
				(start 312.952892 -312.999882)
				(mid 312.546492 -312.999882)
				(end 312.952892 -312.999882)
			)
		)
		(stroke
			(width 0)
			(type solid)
		)
		(fill yes)
		(layer "In1.Cu")
		(net "P5E_PEX2_STN4_TX_DP<72>")
	)
	(gr_poly
		(pts
			(arc
				(start 312.952892 -309.199788)
				(mid 312.546492 -309.199788)
				(end 312.952892 -309.199788)
			)
		)
		(stroke
			(width 0)
			(type solid)
		)
		(fill yes)
		(layer "In1.Cu")
		(net "P5E_PEX2_STN4_RX_DN<69>")
	)
	(gr_poly
		(pts
			(arc
				(start 312.952892 -307.299868)
				(mid 312.546492 -307.299868)
				(end 312.952892 -307.299868)
			)
		)
		(stroke
			(width 0)
			(type solid)
		)
		(fill yes)
		(layer "In1.Cu")
		(net "P5E_PEX2_STN4_RX_DN<67>")
	)
	(gr_poly
		(pts
			(arc
				(start 312.952892 -305.399948)
				(mid 312.546492 -305.399948)
				(end 312.952892 -305.399948)
			)
		)
		(stroke
			(width 0)
			(type solid)
		)
		(fill yes)
		(layer "In1.Cu")
		(net "P5E_PEX2_STN4_RX_DN<65>")
	)
	(gr_poly
		(pts
			(arc
				(start 312.952892 -288.299906)
				(mid 312.546492 -288.299906)
				(end 312.952892 -288.299906)
			)
		)
		(stroke
			(width 0)
			(type solid)
		)
		(fill yes)
		(layer "In1.Cu")
		(net "P5E_PEX2_STN0_RX_DN<0>")
	)
	(gr_poly
		(pts
			(arc
				(start 312.952892 -286.399732)
				(mid 312.546492 -286.399732)
				(end 312.952892 -286.399732)
			)
		)
		(stroke
			(width 0)
			(type solid)
		)
		(fill yes)
		(layer "In1.Cu")
		(net "P5E_PEX2_STN0_RX_DN<2>")
	)
	(gr_poly
		(pts
			(arc
				(start 312.952892 -284.499812)
				(mid 312.546492 -284.499812)
				(end 312.952892 -284.499812)
			)
		)
		(stroke
			(width 0)
			(type solid)
		)
		(fill yes)
		(layer "In1.Cu")
		(net "P5E_PEX2_STN0_RX_DN<4>")
	)
	(gr_poly
		(pts
			(arc
				(start 312.952892 -282.599892)
				(mid 312.546492 -282.599892)
				(end 312.952892 -282.599892)
			)
		)
		(stroke
			(width 0)
			(type solid)
		)
		(fill yes)
		(layer "In1.Cu")
		(net "P5E_PEX2_STN0_RX_DN<6>")
	)
	(gr_poly
		(pts
			(arc
				(start 312.952892 -278.799798)
				(mid 312.546492 -278.799798)
				(end 312.952892 -278.799798)
			)
		)
		(stroke
			(width 0)
			(type solid)
		)
		(fill yes)
		(layer "In1.Cu")
		(net "P5E_PEX2_STN0_TX_DP<9>")
	)
	(gr_poly
		(pts
			(arc
				(start 312.952892 -277.849838)
				(mid 312.546492 -277.849838)
				(end 312.952892 -277.849838)
			)
		)
		(stroke
			(width 0)
			(type solid)
		)
		(fill yes)
		(layer "In1.Cu")
		(net "P5E_PEX2_STN0_TX_DN<9>")
	)
	(gr_poly
		(pts
			(arc
				(start 313.903106 -316.799722)
				(mid 313.496706 -316.799722)
				(end 313.903106 -316.799722)
			)
		)
		(stroke
			(width 0)
			(type solid)
		)
		(fill yes)
		(layer "In1.Cu")
		(net "P5E_PEX2_STN4_RX_DP<71>")
	)
	(gr_poly
		(pts
			(arc
				(start 313.903106 -314.899802)
				(mid 313.496706 -314.899802)
				(end 313.903106 -314.899802)
			)
		)
		(stroke
			(width 0)
			(type solid)
		)
		(fill yes)
		(layer "In1.Cu")
		(net "P5E_PEX2_STN4_TX_DP<71>")
	)
	(gr_poly
		(pts
			(arc
				(start 313.903106 -312.049922)
				(mid 313.496706 -312.049922)
				(end 313.903106 -312.049922)
			)
		)
		(stroke
			(width 0)
			(type solid)
		)
		(fill yes)
		(layer "In1.Cu")
		(net "P5E_PEX2_STN4_TX_DP<70>")
	)
	(gr_poly
		(pts
			(arc
				(start 313.903106 -310.149748)
				(mid 313.496706 -310.149748)
				(end 313.903106 -310.149748)
			)
		)
		(stroke
			(width 0)
			(type solid)
		)
		(fill yes)
		(layer "In1.Cu")
		(net "P5E_PEX2_STN4_RX_DP<70>")
	)
	(gr_poly
		(pts
			(arc
				(start 313.903106 -308.249828)
				(mid 313.496706 -308.249828)
				(end 313.903106 -308.249828)
			)
		)
		(stroke
			(width 0)
			(type solid)
		)
		(fill yes)
		(layer "In1.Cu")
		(net "P5E_PEX2_STN4_RX_DP<68>")
	)
	(gr_poly
		(pts
			(arc
				(start 313.903106 -306.349908)
				(mid 313.496706 -306.349908)
				(end 313.903106 -306.349908)
			)
		)
		(stroke
			(width 0)
			(type solid)
		)
		(fill yes)
		(layer "In1.Cu")
		(net "P5E_PEX2_STN4_RX_DP<66>")
	)
	(gr_poly
		(pts
			(arc
				(start 313.903106 -304.449734)
				(mid 313.496706 -304.449734)
				(end 313.903106 -304.449734)
			)
		)
		(stroke
			(width 0)
			(type solid)
		)
		(fill yes)
		(layer "In1.Cu")
		(net "P5E_PEX2_STN4_RX_DP<64>")
	)
	(gr_poly
		(pts
			(arc
				(start 313.903106 -287.349946)
				(mid 313.496706 -287.349946)
				(end 313.903106 -287.349946)
			)
		)
		(stroke
			(width 0)
			(type solid)
		)
		(fill yes)
		(layer "In1.Cu")
		(net "P5E_PEX2_STN0_RX_DP<1>")
	)
	(gr_poly
		(pts
			(arc
				(start 313.903106 -285.449772)
				(mid 313.496706 -285.449772)
				(end 313.903106 -285.449772)
			)
		)
		(stroke
			(width 0)
			(type solid)
		)
		(fill yes)
		(layer "In1.Cu")
		(net "P5E_PEX2_STN0_RX_DP<3>")
	)
	(gr_poly
		(pts
			(arc
				(start 313.903106 -283.549852)
				(mid 313.496706 -283.549852)
				(end 313.903106 -283.549852)
			)
		)
		(stroke
			(width 0)
			(type solid)
		)
		(fill yes)
		(layer "In1.Cu")
		(net "P5E_PEX2_STN0_RX_DP<5>")
	)
	(gr_poly
		(pts
			(arc
				(start 313.903106 -281.649932)
				(mid 313.496706 -281.649932)
				(end 313.903106 -281.649932)
			)
		)
		(stroke
			(width 0)
			(type solid)
		)
		(fill yes)
		(layer "In1.Cu")
		(net "P5E_PEX2_STN0_RX_DP<7>")
	)
	(gr_poly
		(pts
			(arc
				(start 313.903106 -279.749758)
				(mid 313.496706 -279.749758)
				(end 313.903106 -279.749758)
			)
		)
		(stroke
			(width 0)
			(type solid)
		)
		(fill yes)
		(layer "In1.Cu")
		(net "P5E_PEX2_STN0_TX_DP<7>")
	)
	(gr_poly
		(pts
			(arc
				(start 313.903106 -276.899878)
				(mid 313.496706 -276.899878)
				(end 313.903106 -276.899878)
			)
		)
		(stroke
			(width 0)
			(type solid)
		)
		(fill yes)
		(layer "In1.Cu")
		(net "P5E_PEX2_STN0_TX_DP<8>")
	)
	(gr_poly
		(pts
			(arc
				(start 313.903106 -274.999704)
				(mid 313.496706 -274.999704)
				(end 313.903106 -274.999704)
			)
		)
		(stroke
			(width 0)
			(type solid)
		)
		(fill yes)
		(layer "In1.Cu")
		(net "P5E_PEX2_STN0_RX_DP<8>")
	)
	(gr_poly
		(pts
			(arc
				(start 314.853066 -316.799722)
				(mid 314.446666 -316.799722)
				(end 314.853066 -316.799722)
			)
		)
		(stroke
			(width 0)
			(type solid)
		)
		(fill yes)
		(layer "In1.Cu")
		(net "P5E_PEX2_STN4_RX_DN<71>")
	)
	(gr_poly
		(pts
			(arc
				(start 314.853066 -314.899802)
				(mid 314.446666 -314.899802)
				(end 314.853066 -314.899802)
			)
		)
		(stroke
			(width 0)
			(type solid)
		)
		(fill yes)
		(layer "In1.Cu")
		(net "P5E_PEX2_STN4_TX_DN<71>")
	)
	(gr_poly
		(pts
			(arc
				(start 314.853066 -312.049922)
				(mid 314.446666 -312.049922)
				(end 314.853066 -312.049922)
			)
		)
		(stroke
			(width 0)
			(type solid)
		)
		(fill yes)
		(layer "In1.Cu")
		(net "P5E_PEX2_STN4_TX_DN<70>")
	)
	(gr_poly
		(pts
			(arc
				(start 314.853066 -310.149748)
				(mid 314.446666 -310.149748)
				(end 314.853066 -310.149748)
			)
		)
		(stroke
			(width 0)
			(type solid)
		)
		(fill yes)
		(layer "In1.Cu")
		(net "P5E_PEX2_STN4_RX_DN<70>")
	)
	(gr_poly
		(pts
			(arc
				(start 314.853066 -308.249828)
				(mid 314.446666 -308.249828)
				(end 314.853066 -308.249828)
			)
		)
		(stroke
			(width 0)
			(type solid)
		)
		(fill yes)
		(layer "In1.Cu")
		(net "P5E_PEX2_STN4_RX_DN<68>")
	)
	(gr_poly
		(pts
			(arc
				(start 314.853066 -306.349908)
				(mid 314.446666 -306.349908)
				(end 314.853066 -306.349908)
			)
		)
		(stroke
			(width 0)
			(type solid)
		)
		(fill yes)
		(layer "In1.Cu")
		(net "P5E_PEX2_STN4_RX_DN<66>")
	)
	(gr_poly
		(pts
			(arc
				(start 314.853066 -304.449734)
				(mid 314.446666 -304.449734)
				(end 314.853066 -304.449734)
			)
		)
		(stroke
			(width 0)
			(type solid)
		)
		(fill yes)
		(layer "In1.Cu")
		(net "P5E_PEX2_STN4_RX_DN<64>")
	)
	(gr_poly
		(pts
			(arc
				(start 314.853066 -287.349946)
				(mid 314.446666 -287.349946)
				(end 314.853066 -287.349946)
			)
		)
		(stroke
			(width 0)
			(type solid)
		)
		(fill yes)
		(layer "In1.Cu")
		(net "P5E_PEX2_STN0_RX_DN<1>")
	)
	(gr_poly
		(pts
			(arc
				(start 314.853066 -285.449772)
				(mid 314.446666 -285.449772)
				(end 314.853066 -285.449772)
			)
		)
		(stroke
			(width 0)
			(type solid)
		)
		(fill yes)
		(layer "In1.Cu")
		(net "P5E_PEX2_STN0_RX_DN<3>")
	)
	(gr_poly
		(pts
			(arc
				(start 314.853066 -283.549852)
				(mid 314.446666 -283.549852)
				(end 314.853066 -283.549852)
			)
		)
		(stroke
			(width 0)
			(type solid)
		)
		(fill yes)
		(layer "In1.Cu")
		(net "P5E_PEX2_STN0_RX_DN<5>")
	)
	(gr_poly
		(pts
			(arc
				(start 314.853066 -281.649932)
				(mid 314.446666 -281.649932)
				(end 314.853066 -281.649932)
			)
		)
		(stroke
			(width 0)
			(type solid)
		)
		(fill yes)
		(layer "In1.Cu")
		(net "P5E_PEX2_STN0_RX_DN<7>")
	)
	(gr_poly
		(pts
			(arc
				(start 314.853066 -279.749758)
				(mid 314.446666 -279.749758)
				(end 314.853066 -279.749758)
			)
		)
		(stroke
			(width 0)
			(type solid)
		)
		(fill yes)
		(layer "In1.Cu")
		(net "P5E_PEX2_STN0_TX_DN<7>")
	)
	(gr_poly
		(pts
			(arc
				(start 314.853066 -276.899878)
				(mid 314.446666 -276.899878)
				(end 314.853066 -276.899878)
			)
		)
		(stroke
			(width 0)
			(type solid)
		)
		(fill yes)
		(layer "In1.Cu")
		(net "P5E_PEX2_STN0_TX_DN<8>")
	)
	(gr_poly
		(pts
			(arc
				(start 314.853066 -274.999704)
				(mid 314.446666 -274.999704)
				(end 314.853066 -274.999704)
			)
		)
		(stroke
			(width 0)
			(type solid)
		)
		(fill yes)
		(layer "In1.Cu")
		(net "P5E_PEX2_STN0_RX_DN<8>")
	)
	(gr_poly
		(pts
			(arc
				(start 385.353052 -316.799722)
				(mid 384.946652 -316.799722)
				(end 385.353052 -316.799722)
			)
		)
		(stroke
			(width 0)
			(type solid)
		)
		(fill yes)
		(layer "In1.Cu")
		(net "P5E_PEX3_STN7_RX_DN<122>")
	)
	(gr_poly
		(pts
			(arc
				(start 385.353052 -314.899802)
				(mid 384.946652 -314.899802)
				(end 385.353052 -314.899802)
			)
		)
		(stroke
			(width 0)
			(type solid)
		)
		(fill yes)
		(layer "In1.Cu")
		(net "P5E_PEX3_STN7_TX_DN<122>")
	)
	(gr_poly
		(pts
			(arc
				(start 385.353052 -312.049922)
				(mid 384.946652 -312.049922)
				(end 385.353052 -312.049922)
			)
		)
		(stroke
			(width 0)
			(type solid)
		)
		(fill yes)
		(layer "In1.Cu")
		(net "P5E_PEX3_STN7_TX_DN<121>")
	)
	(gr_poly
		(pts
			(arc
				(start 385.353052 -310.149748)
				(mid 384.946652 -310.149748)
				(end 385.353052 -310.149748)
			)
		)
		(stroke
			(width 0)
			(type solid)
		)
		(fill yes)
		(layer "In1.Cu")
		(net "P5E_PEX3_STN7_RX_DN<121>")
	)
	(gr_poly
		(pts
			(arc
				(start 385.353052 -308.249828)
				(mid 384.946652 -308.249828)
				(end 385.353052 -308.249828)
			)
		)
		(stroke
			(width 0)
			(type solid)
		)
		(fill yes)
		(layer "In1.Cu")
		(net "P5E_PEX3_STN7_RX_DN<119>")
	)
	(gr_poly
		(pts
			(arc
				(start 385.353052 -306.349908)
				(mid 384.946652 -306.349908)
				(end 385.353052 -306.349908)
			)
		)
		(stroke
			(width 0)
			(type solid)
		)
		(fill yes)
		(layer "In1.Cu")
		(net "P5E_PEX3_STN7_RX_DN<117>")
	)
	(gr_poly
		(pts
			(arc
				(start 385.353052 -304.449734)
				(mid 384.946652 -304.449734)
				(end 385.353052 -304.449734)
			)
		)
		(stroke
			(width 0)
			(type solid)
		)
		(fill yes)
		(layer "In1.Cu")
		(net "P5E_PEX3_STN7_RX_DN<115>")
	)
	(gr_poly
		(pts
			(arc
				(start 385.353052 -302.549814)
				(mid 384.946652 -302.549814)
				(end 385.353052 -302.549814)
			)
		)
		(stroke
			(width 0)
			(type solid)
		)
		(fill yes)
		(layer "In1.Cu")
		(net "P5E_PEX3_STN7_RX_DN<113>")
	)
	(gr_poly
		(pts
			(arc
				(start 386.303012 -316.799722)
				(mid 385.896612 -316.799722)
				(end 386.303012 -316.799722)
			)
		)
		(stroke
			(width 0)
			(type solid)
		)
		(fill yes)
		(layer "In1.Cu")
		(net "P5E_PEX3_STN7_RX_DP<122>")
	)
	(gr_poly
		(pts
			(arc
				(start 386.303012 -314.899802)
				(mid 385.896612 -314.899802)
				(end 386.303012 -314.899802)
			)
		)
		(stroke
			(width 0)
			(type solid)
		)
		(fill yes)
		(layer "In1.Cu")
		(net "P5E_PEX3_STN7_TX_DP<122>")
	)
	(gr_poly
		(pts
			(arc
				(start 386.303012 -312.049922)
				(mid 385.896612 -312.049922)
				(end 386.303012 -312.049922)
			)
		)
		(stroke
			(width 0)
			(type solid)
		)
		(fill yes)
		(layer "In1.Cu")
		(net "P5E_PEX3_STN7_TX_DP<121>")
	)
	(gr_poly
		(pts
			(arc
				(start 386.303012 -310.149748)
				(mid 385.896612 -310.149748)
				(end 386.303012 -310.149748)
			)
		)
		(stroke
			(width 0)
			(type solid)
		)
		(fill yes)
		(layer "In1.Cu")
		(net "P5E_PEX3_STN7_RX_DP<121>")
	)
	(gr_poly
		(pts
			(arc
				(start 386.303012 -308.249828)
				(mid 385.896612 -308.249828)
				(end 386.303012 -308.249828)
			)
		)
		(stroke
			(width 0)
			(type solid)
		)
		(fill yes)
		(layer "In1.Cu")
		(net "P5E_PEX3_STN7_RX_DP<119>")
	)
	(gr_poly
		(pts
			(arc
				(start 386.303012 -306.349908)
				(mid 385.896612 -306.349908)
				(end 386.303012 -306.349908)
			)
		)
		(stroke
			(width 0)
			(type solid)
		)
		(fill yes)
		(layer "In1.Cu")
		(net "P5E_PEX3_STN7_RX_DP<117>")
	)
	(gr_poly
		(pts
			(arc
				(start 386.303012 -304.449734)
				(mid 385.896612 -304.449734)
				(end 386.303012 -304.449734)
			)
		)
		(stroke
			(width 0)
			(type solid)
		)
		(fill yes)
		(layer "In1.Cu")
		(net "P5E_PEX3_STN7_RX_DP<115>")
	)
	(gr_poly
		(pts
			(arc
				(start 386.303012 -302.549814)
				(mid 385.896612 -302.549814)
				(end 386.303012 -302.549814)
			)
		)
		(stroke
			(width 0)
			(type solid)
		)
		(fill yes)
		(layer "In1.Cu")
		(net "P5E_PEX3_STN7_RX_DP<113>")
	)
	(gr_poly
		(pts
			(arc
				(start 387.253226 -318.699896)
				(mid 386.846826 -318.699896)
				(end 387.253226 -318.699896)
			)
		)
		(stroke
			(width 0)
			(type solid)
		)
		(fill yes)
		(layer "In1.Cu")
		(net "P5E_PEX3_STN7_RX_DN<123>")
	)
	(gr_poly
		(pts
			(arc
				(start 387.253226 -317.749936)
				(mid 386.846826 -317.749936)
				(end 387.253226 -317.749936)
			)
		)
		(stroke
			(width 0)
			(type solid)
		)
		(fill yes)
		(layer "In1.Cu")
		(net "P5E_PEX3_STN7_RX_DP<123>")
	)
	(gr_poly
		(pts
			(arc
				(start 387.253226 -313.949842)
				(mid 386.846826 -313.949842)
				(end 387.253226 -313.949842)
			)
		)
		(stroke
			(width 0)
			(type solid)
		)
		(fill yes)
		(layer "In1.Cu")
		(net "P5E_PEX3_STN7_TX_DN<123>")
	)
	(gr_poly
		(pts
			(arc
				(start 387.253226 -312.999882)
				(mid 386.846826 -312.999882)
				(end 387.253226 -312.999882)
			)
		)
		(stroke
			(width 0)
			(type solid)
		)
		(fill yes)
		(layer "In1.Cu")
		(net "P5E_PEX3_STN7_TX_DP<123>")
	)
	(gr_poly
		(pts
			(arc
				(start 387.253226 -309.199788)
				(mid 386.846826 -309.199788)
				(end 387.253226 -309.199788)
			)
		)
		(stroke
			(width 0)
			(type solid)
		)
		(fill yes)
		(layer "In1.Cu")
		(net "P5E_PEX3_STN7_RX_DN<120>")
	)
	(gr_poly
		(pts
			(arc
				(start 387.253226 -307.299868)
				(mid 386.846826 -307.299868)
				(end 387.253226 -307.299868)
			)
		)
		(stroke
			(width 0)
			(type solid)
		)
		(fill yes)
		(layer "In1.Cu")
		(net "P5E_PEX3_STN7_RX_DN<118>")
	)
	(gr_poly
		(pts
			(arc
				(start 387.253226 -305.399948)
				(mid 386.846826 -305.399948)
				(end 387.253226 -305.399948)
			)
		)
		(stroke
			(width 0)
			(type solid)
		)
		(fill yes)
		(layer "In1.Cu")
		(net "P5E_PEX3_STN7_RX_DN<116>")
	)
	(gr_poly
		(pts
			(arc
				(start 387.253226 -303.499774)
				(mid 386.846826 -303.499774)
				(end 387.253226 -303.499774)
			)
		)
		(stroke
			(width 0)
			(type solid)
		)
		(fill yes)
		(layer "In1.Cu")
		(net "P5E_PEX3_STN7_RX_DN<114>")
	)
	(gr_poly
		(pts
			(arc
				(start 387.253226 -301.599854)
				(mid 386.846826 -301.599854)
				(end 387.253226 -301.599854)
			)
		)
		(stroke
			(width 0)
			(type solid)
		)
		(fill yes)
		(layer "In1.Cu")
		(net "P5E_PEX3_STN7_RX_DN<112>")
	)
	(gr_poly
		(pts
			(arc
				(start 388.203186 -316.799722)
				(mid 387.796786 -316.799722)
				(end 388.203186 -316.799722)
			)
		)
		(stroke
			(width 0)
			(type solid)
		)
		(fill yes)
		(layer "In1.Cu")
		(net "P5E_PEX3_STN7_RX_DN<124>")
	)
	(gr_poly
		(pts
			(arc
				(start 388.203186 -315.849762)
				(mid 387.796786 -315.849762)
				(end 388.203186 -315.849762)
			)
		)
		(stroke
			(width 0)
			(type solid)
		)
		(fill yes)
		(layer "In1.Cu")
		(net "P5E_PEX3_STN7_RX_DP<124>")
	)
	(gr_poly
		(pts
			(arc
				(start 388.203186 -312.049922)
				(mid 387.796786 -312.049922)
				(end 388.203186 -312.049922)
			)
		)
		(stroke
			(width 0)
			(type solid)
		)
		(fill yes)
		(layer "In1.Cu")
		(net "P5E_PEX3_STN7_TX_DN<124>")
	)
	(gr_poly
		(pts
			(arc
				(start 388.203186 -311.099962)
				(mid 387.796786 -311.099962)
				(end 388.203186 -311.099962)
			)
		)
		(stroke
			(width 0)
			(type solid)
		)
		(fill yes)
		(layer "In1.Cu")
		(net "P5E_PEX3_STN7_TX_DP<124>")
	)
	(gr_poly
		(pts
			(arc
				(start 388.203186 -309.199788)
				(mid 387.796786 -309.199788)
				(end 388.203186 -309.199788)
			)
		)
		(stroke
			(width 0)
			(type solid)
		)
		(fill yes)
		(layer "In1.Cu")
		(net "P5E_PEX3_STN7_RX_DP<120>")
	)
	(gr_poly
		(pts
			(arc
				(start 388.203186 -307.299868)
				(mid 387.796786 -307.299868)
				(end 388.203186 -307.299868)
			)
		)
		(stroke
			(width 0)
			(type solid)
		)
		(fill yes)
		(layer "In1.Cu")
		(net "P5E_PEX3_STN7_RX_DP<118>")
	)
	(gr_poly
		(pts
			(arc
				(start 388.203186 -305.399948)
				(mid 387.796786 -305.399948)
				(end 388.203186 -305.399948)
			)
		)
		(stroke
			(width 0)
			(type solid)
		)
		(fill yes)
		(layer "In1.Cu")
		(net "P5E_PEX3_STN7_RX_DP<116>")
	)
	(gr_poly
		(pts
			(arc
				(start 388.203186 -303.499774)
				(mid 387.796786 -303.499774)
				(end 388.203186 -303.499774)
			)
		)
		(stroke
			(width 0)
			(type solid)
		)
		(fill yes)
		(layer "In1.Cu")
		(net "P5E_PEX3_STN7_RX_DP<114>")
	)
	(gr_poly
		(pts
			(arc
				(start 388.203186 -301.599854)
				(mid 387.796786 -301.599854)
				(end 388.203186 -301.599854)
			)
		)
		(stroke
			(width 0)
			(type solid)
		)
		(fill yes)
		(layer "In1.Cu")
		(net "P5E_PEX3_STN7_RX_DP<112>")
	)
	(gr_poly
		(pts
			(arc
				(start 389.153146 -318.699896)
				(mid 388.746746 -318.699896)
				(end 389.153146 -318.699896)
			)
		)
		(stroke
			(width 0)
			(type solid)
		)
		(fill yes)
		(layer "In1.Cu")
		(net "P5E_PEX3_STN7_RX_DN<125>")
	)
	(gr_poly
		(pts
			(arc
				(start 389.153146 -317.749936)
				(mid 388.746746 -317.749936)
				(end 389.153146 -317.749936)
			)
		)
		(stroke
			(width 0)
			(type solid)
		)
		(fill yes)
		(layer "In1.Cu")
		(net "P5E_PEX3_STN7_RX_DP<125>")
	)
	(gr_poly
		(pts
			(arc
				(start 389.153146 -313.949842)
				(mid 388.746746 -313.949842)
				(end 389.153146 -313.949842)
			)
		)
		(stroke
			(width 0)
			(type solid)
		)
		(fill yes)
		(layer "In1.Cu")
		(net "P5E_PEX3_STN7_TX_DN<125>")
	)
	(gr_poly
		(pts
			(arc
				(start 389.153146 -312.999882)
				(mid 388.746746 -312.999882)
				(end 389.153146 -312.999882)
			)
		)
		(stroke
			(width 0)
			(type solid)
		)
		(fill yes)
		(layer "In1.Cu")
		(net "P5E_PEX3_STN7_TX_DP<125>")
	)
	(gr_poly
		(pts
			(arc
				(start 390.103106 -316.799722)
				(mid 389.696706 -316.799722)
				(end 390.103106 -316.799722)
			)
		)
		(stroke
			(width 0)
			(type solid)
		)
		(fill yes)
		(layer "In1.Cu")
		(net "P5E_PEX3_STN7_RX_DN<126>")
	)
	(gr_poly
		(pts
			(arc
				(start 390.103106 -315.849762)
				(mid 389.696706 -315.849762)
				(end 390.103106 -315.849762)
			)
		)
		(stroke
			(width 0)
			(type solid)
		)
		(fill yes)
		(layer "In1.Cu")
		(net "P5E_PEX3_STN7_RX_DP<126>")
	)
	(gr_poly
		(pts
			(arc
				(start 390.103106 -312.049922)
				(mid 389.696706 -312.049922)
				(end 390.103106 -312.049922)
			)
		)
		(stroke
			(width 0)
			(type solid)
		)
		(fill yes)
		(layer "In1.Cu")
		(net "P5E_PEX3_STN7_TX_DN<126>")
	)
	(gr_poly
		(pts
			(arc
				(start 390.103106 -311.099962)
				(mid 389.696706 -311.099962)
				(end 390.103106 -311.099962)
			)
		)
		(stroke
			(width 0)
			(type solid)
		)
		(fill yes)
		(layer "In1.Cu")
		(net "P5E_PEX3_STN7_TX_DP<126>")
	)
	(gr_poly
		(pts
			(arc
				(start 390.103106 -309.199788)
				(mid 389.696706 -309.199788)
				(end 390.103106 -309.199788)
			)
		)
		(stroke
			(width 0)
			(type solid)
		)
		(fill yes)
		(layer "In1.Cu")
		(net "P5E_PEX3_STN7_TX_DN<120>")
	)
	(gr_poly
		(pts
			(arc
				(start 390.103106 -307.299868)
				(mid 389.696706 -307.299868)
				(end 390.103106 -307.299868)
			)
		)
		(stroke
			(width 0)
			(type solid)
		)
		(fill yes)
		(layer "In1.Cu")
		(net "P5E_PEX3_STN7_TX_DN<118>")
	)
	(gr_poly
		(pts
			(arc
				(start 390.103106 -305.399948)
				(mid 389.696706 -305.399948)
				(end 390.103106 -305.399948)
			)
		)
		(stroke
			(width 0)
			(type solid)
		)
		(fill yes)
		(layer "In1.Cu")
		(net "P5E_PEX3_STN7_TX_DN<116>")
	)
	(gr_poly
		(pts
			(arc
				(start 390.103106 -303.499774)
				(mid 389.696706 -303.499774)
				(end 390.103106 -303.499774)
			)
		)
		(stroke
			(width 0)
			(type solid)
		)
		(fill yes)
		(layer "In1.Cu")
		(net "P5E_PEX3_STN7_TX_DN<114>")
	)
	(gr_poly
		(pts
			(arc
				(start 390.103106 -301.599854)
				(mid 389.696706 -301.599854)
				(end 390.103106 -301.599854)
			)
		)
		(stroke
			(width 0)
			(type solid)
		)
		(fill yes)
		(layer "In1.Cu")
		(net "P5E_PEX3_STN7_TX_DN<112>")
	)
	(gr_poly
		(pts
			(arc
				(start 391.053066 -318.699896)
				(mid 390.646666 -318.699896)
				(end 391.053066 -318.699896)
			)
		)
		(stroke
			(width 0)
			(type solid)
		)
		(fill yes)
		(layer "In1.Cu")
		(net "P5E_PEX3_STN7_RX_DN<127>")
	)
	(gr_poly
		(pts
			(arc
				(start 391.053066 -317.749936)
				(mid 390.646666 -317.749936)
				(end 391.053066 -317.749936)
			)
		)
		(stroke
			(width 0)
			(type solid)
		)
		(fill yes)
		(layer "In1.Cu")
		(net "P5E_PEX3_STN7_RX_DP<127>")
	)
	(gr_poly
		(pts
			(arc
				(start 391.053066 -313.949842)
				(mid 390.646666 -313.949842)
				(end 391.053066 -313.949842)
			)
		)
		(stroke
			(width 0)
			(type solid)
		)
		(fill yes)
		(layer "In1.Cu")
		(net "P5E_PEX3_STN7_TX_DN<127>")
	)
	(gr_poly
		(pts
			(arc
				(start 391.053066 -312.999882)
				(mid 390.646666 -312.999882)
				(end 391.053066 -312.999882)
			)
		)
		(stroke
			(width 0)
			(type solid)
		)
		(fill yes)
		(layer "In1.Cu")
		(net "P5E_PEX3_STN7_TX_DP<127>")
	)
	(gr_poly
		(pts
			(arc
				(start 391.053066 -309.199788)
				(mid 390.646666 -309.199788)
				(end 391.053066 -309.199788)
			)
		)
		(stroke
			(width 0)
			(type solid)
		)
		(fill yes)
		(layer "In1.Cu")
		(net "P5E_PEX3_STN7_TX_DP<120>")
	)
	(gr_poly
		(pts
			(arc
				(start 391.053066 -307.299868)
				(mid 390.646666 -307.299868)
				(end 391.053066 -307.299868)
			)
		)
		(stroke
			(width 0)
			(type solid)
		)
		(fill yes)
		(layer "In1.Cu")
		(net "P5E_PEX3_STN7_TX_DP<118>")
	)
	(gr_poly
		(pts
			(arc
				(start 391.053066 -305.399948)
				(mid 390.646666 -305.399948)
				(end 391.053066 -305.399948)
			)
		)
		(stroke
			(width 0)
			(type solid)
		)
		(fill yes)
		(layer "In1.Cu")
		(net "P5E_PEX3_STN7_TX_DP<116>")
	)
	(gr_poly
		(pts
			(arc
				(start 391.053066 -303.499774)
				(mid 390.646666 -303.499774)
				(end 391.053066 -303.499774)
			)
		)
		(stroke
			(width 0)
			(type solid)
		)
		(fill yes)
		(layer "In1.Cu")
		(net "P5E_PEX3_STN7_TX_DP<114>")
	)
	(gr_poly
		(pts
			(arc
				(start 391.053066 -301.599854)
				(mid 390.646666 -301.599854)
				(end 391.053066 -301.599854)
			)
		)
		(stroke
			(width 0)
			(type solid)
		)
		(fill yes)
		(layer "In1.Cu")
		(net "P5E_PEX3_STN7_TX_DP<112>")
	)
	(gr_poly
		(pts
			(arc
				(start 392.003026 -316.799722)
				(mid 391.596626 -316.799722)
				(end 392.003026 -316.799722)
			)
		)
		(stroke
			(width 0)
			(type solid)
		)
		(fill yes)
		(layer "In1.Cu")
		(net "P5E_PEX3_STN6_RX_DN<111>")
	)
	(gr_poly
		(pts
			(arc
				(start 392.003026 -315.849762)
				(mid 391.596626 -315.849762)
				(end 392.003026 -315.849762)
			)
		)
		(stroke
			(width 0)
			(type solid)
		)
		(fill yes)
		(layer "In1.Cu")
		(net "P5E_PEX3_STN6_RX_DP<111>")
	)
	(gr_poly
		(pts
			(arc
				(start 392.003026 -312.049922)
				(mid 391.596626 -312.049922)
				(end 392.003026 -312.049922)
			)
		)
		(stroke
			(width 0)
			(type solid)
		)
		(fill yes)
		(layer "In1.Cu")
		(net "P5E_PEX3_STN6_TX_DN<111>")
	)
	(gr_poly
		(pts
			(arc
				(start 392.003026 -311.099962)
				(mid 391.596626 -311.099962)
				(end 392.003026 -311.099962)
			)
		)
		(stroke
			(width 0)
			(type solid)
		)
		(fill yes)
		(layer "In1.Cu")
		(net "P5E_PEX3_STN6_TX_DP<111>")
	)
	(gr_poly
		(pts
			(arc
				(start 392.003026 -308.249828)
				(mid 391.596626 -308.249828)
				(end 392.003026 -308.249828)
			)
		)
		(stroke
			(width 0)
			(type solid)
		)
		(fill yes)
		(layer "In1.Cu")
		(net "P5E_PEX3_STN7_TX_DN<119>")
	)
	(gr_poly
		(pts
			(arc
				(start 392.003026 -306.349908)
				(mid 391.596626 -306.349908)
				(end 392.003026 -306.349908)
			)
		)
		(stroke
			(width 0)
			(type solid)
		)
		(fill yes)
		(layer "In1.Cu")
		(net "P5E_PEX3_STN7_TX_DN<117>")
	)
	(gr_poly
		(pts
			(arc
				(start 392.003026 -304.449734)
				(mid 391.596626 -304.449734)
				(end 392.003026 -304.449734)
			)
		)
		(stroke
			(width 0)
			(type solid)
		)
		(fill yes)
		(layer "In1.Cu")
		(net "P5E_PEX3_STN7_TX_DN<115>")
	)
	(gr_poly
		(pts
			(arc
				(start 392.003026 -302.549814)
				(mid 391.596626 -302.549814)
				(end 392.003026 -302.549814)
			)
		)
		(stroke
			(width 0)
			(type solid)
		)
		(fill yes)
		(layer "In1.Cu")
		(net "P5E_PEX3_STN7_TX_DN<113>")
	)
	(gr_poly
		(pts
			(arc
				(start 392.952986 -318.699896)
				(mid 392.546586 -318.699896)
				(end 392.952986 -318.699896)
			)
		)
		(stroke
			(width 0)
			(type solid)
		)
		(fill yes)
		(layer "In1.Cu")
		(net "P5E_PEX3_STN6_RX_DN<110>")
	)
	(gr_poly
		(pts
			(arc
				(start 392.952986 -317.749936)
				(mid 392.546586 -317.749936)
				(end 392.952986 -317.749936)
			)
		)
		(stroke
			(width 0)
			(type solid)
		)
		(fill yes)
		(layer "In1.Cu")
		(net "P5E_PEX3_STN6_RX_DP<110>")
	)
	(gr_poly
		(pts
			(arc
				(start 392.952986 -313.949842)
				(mid 392.546586 -313.949842)
				(end 392.952986 -313.949842)
			)
		)
		(stroke
			(width 0)
			(type solid)
		)
		(fill yes)
		(layer "In1.Cu")
		(net "P5E_PEX3_STN6_TX_DN<110>")
	)
	(gr_poly
		(pts
			(arc
				(start 392.952986 -312.999882)
				(mid 392.546586 -312.999882)
				(end 392.952986 -312.999882)
			)
		)
		(stroke
			(width 0)
			(type solid)
		)
		(fill yes)
		(layer "In1.Cu")
		(net "P5E_PEX3_STN6_TX_DP<110>")
	)
	(gr_poly
		(pts
			(arc
				(start 392.952986 -308.249828)
				(mid 392.546586 -308.249828)
				(end 392.952986 -308.249828)
			)
		)
		(stroke
			(width 0)
			(type solid)
		)
		(fill yes)
		(layer "In1.Cu")
		(net "P5E_PEX3_STN7_TX_DP<119>")
	)
	(gr_poly
		(pts
			(arc
				(start 392.952986 -306.349908)
				(mid 392.546586 -306.349908)
				(end 392.952986 -306.349908)
			)
		)
		(stroke
			(width 0)
			(type solid)
		)
		(fill yes)
		(layer "In1.Cu")
		(net "P5E_PEX3_STN7_TX_DP<117>")
	)
	(gr_poly
		(pts
			(arc
				(start 392.952986 -304.449734)
				(mid 392.546586 -304.449734)
				(end 392.952986 -304.449734)
			)
		)
		(stroke
			(width 0)
			(type solid)
		)
		(fill yes)
		(layer "In1.Cu")
		(net "P5E_PEX3_STN7_TX_DP<115>")
	)
	(gr_poly
		(pts
			(arc
				(start 392.952986 -302.549814)
				(mid 392.546586 -302.549814)
				(end 392.952986 -302.549814)
			)
		)
		(stroke
			(width 0)
			(type solid)
		)
		(fill yes)
		(layer "In1.Cu")
		(net "P5E_PEX3_STN7_TX_DP<113>")
	)
	(gr_poly
		(pts
			(arc
				(start 392.952986 -278.799798)
				(mid 392.546586 -278.799798)
				(end 392.952986 -278.799798)
			)
		)
		(stroke
			(width 0)
			(type solid)
		)
		(fill yes)
		(layer "In1.Cu")
		(net "P5E_PEX3_STN2_TX_DP<47>")
	)
	(gr_poly
		(pts
			(arc
				(start 392.952986 -277.849838)
				(mid 392.546586 -277.849838)
				(end 392.952986 -277.849838)
			)
		)
		(stroke
			(width 0)
			(type solid)
		)
		(fill yes)
		(layer "In1.Cu")
		(net "P5E_PEX3_STN2_TX_DN<47>")
	)
	(gr_poly
		(pts
			(arc
				(start 392.952986 -274.049744)
				(mid 392.546586 -274.049744)
				(end 392.952986 -274.049744)
			)
		)
		(stroke
			(width 0)
			(type solid)
		)
		(fill yes)
		(layer "In1.Cu")
		(net "P5E_PEX3_STN2_RX_DP<47>")
	)
	(gr_poly
		(pts
			(arc
				(start 392.952986 -273.099784)
				(mid 392.546586 -273.099784)
				(end 392.952986 -273.099784)
			)
		)
		(stroke
			(width 0)
			(type solid)
		)
		(fill yes)
		(layer "In1.Cu")
		(net "P5E_PEX3_STN2_RX_DN<47>")
	)
	(gr_poly
		(pts
			(arc
				(start 393.9032 -316.799722)
				(mid 393.4968 -316.799722)
				(end 393.9032 -316.799722)
			)
		)
		(stroke
			(width 0)
			(type solid)
		)
		(fill yes)
		(layer "In1.Cu")
		(net "P5E_PEX3_STN6_RX_DN<109>")
	)
	(gr_poly
		(pts
			(arc
				(start 393.9032 -315.849762)
				(mid 393.4968 -315.849762)
				(end 393.9032 -315.849762)
			)
		)
		(stroke
			(width 0)
			(type solid)
		)
		(fill yes)
		(layer "In1.Cu")
		(net "P5E_PEX3_STN6_RX_DP<109>")
	)
	(gr_poly
		(pts
			(arc
				(start 393.9032 -312.049922)
				(mid 393.4968 -312.049922)
				(end 393.9032 -312.049922)
			)
		)
		(stroke
			(width 0)
			(type solid)
		)
		(fill yes)
		(layer "In1.Cu")
		(net "P5E_PEX3_STN6_TX_DN<109>")
	)
	(gr_poly
		(pts
			(arc
				(start 393.9032 -311.099962)
				(mid 393.4968 -311.099962)
				(end 393.9032 -311.099962)
			)
		)
		(stroke
			(width 0)
			(type solid)
		)
		(fill yes)
		(layer "In1.Cu")
		(net "P5E_PEX3_STN6_TX_DP<109>")
	)
	(gr_poly
		(pts
			(arc
				(start 393.9032 -280.699464)
				(mid 393.4968 -280.699464)
				(end 393.9032 -280.699464)
			)
		)
		(stroke
			(width 0)
			(type solid)
		)
		(fill yes)
		(layer "In1.Cu")
		(net "P5E_PEX3_STN2_TX_DP<46>")
	)
	(gr_poly
		(pts
			(arc
				(start 393.9032 -279.749504)
				(mid 393.4968 -279.749504)
				(end 393.9032 -279.749504)
			)
		)
		(stroke
			(width 0)
			(type solid)
		)
		(fill yes)
		(layer "In1.Cu")
		(net "P5E_PEX3_STN2_TX_DN<46>")
	)
	(gr_poly
		(pts
			(arc
				(start 393.9032 -275.949918)
				(mid 393.4968 -275.949918)
				(end 393.9032 -275.949918)
			)
		)
		(stroke
			(width 0)
			(type solid)
		)
		(fill yes)
		(layer "In1.Cu")
		(net "P5E_PEX3_STN2_RX_DP<46>")
	)
	(gr_poly
		(pts
			(arc
				(start 393.9032 -274.999958)
				(mid 393.4968 -274.999958)
				(end 393.9032 -274.999958)
			)
		)
		(stroke
			(width 0)
			(type solid)
		)
		(fill yes)
		(layer "In1.Cu")
		(net "P5E_PEX3_STN2_RX_DN<46>")
	)
	(gr_poly
		(pts
			(arc
				(start 394.85316 -318.699896)
				(mid 394.44676 -318.699896)
				(end 394.85316 -318.699896)
			)
		)
		(stroke
			(width 0)
			(type solid)
		)
		(fill yes)
		(layer "In1.Cu")
		(net "P5E_PEX3_STN6_RX_DN<108>")
	)
	(gr_poly
		(pts
			(arc
				(start 394.85316 -317.749936)
				(mid 394.44676 -317.749936)
				(end 394.85316 -317.749936)
			)
		)
		(stroke
			(width 0)
			(type solid)
		)
		(fill yes)
		(layer "In1.Cu")
		(net "P5E_PEX3_STN6_RX_DP<108>")
	)
	(gr_poly
		(pts
			(arc
				(start 394.85316 -313.949842)
				(mid 394.44676 -313.949842)
				(end 394.85316 -313.949842)
			)
		)
		(stroke
			(width 0)
			(type solid)
		)
		(fill yes)
		(layer "In1.Cu")
		(net "P5E_PEX3_STN6_TX_DN<108>")
	)
	(gr_poly
		(pts
			(arc
				(start 394.85316 -312.999882)
				(mid 394.44676 -312.999882)
				(end 394.85316 -312.999882)
			)
		)
		(stroke
			(width 0)
			(type solid)
		)
		(fill yes)
		(layer "In1.Cu")
		(net "P5E_PEX3_STN6_TX_DP<108>")
	)
	(gr_poly
		(pts
			(arc
				(start 394.85316 -278.799798)
				(mid 394.44676 -278.799798)
				(end 394.85316 -278.799798)
			)
		)
		(stroke
			(width 0)
			(type solid)
		)
		(fill yes)
		(layer "In1.Cu")
		(net "P5E_PEX3_STN2_TX_DP<45>")
	)
	(gr_poly
		(pts
			(arc
				(start 394.85316 -277.849838)
				(mid 394.44676 -277.849838)
				(end 394.85316 -277.849838)
			)
		)
		(stroke
			(width 0)
			(type solid)
		)
		(fill yes)
		(layer "In1.Cu")
		(net "P5E_PEX3_STN2_TX_DN<45>")
	)
	(gr_poly
		(pts
			(arc
				(start 394.85316 -274.049744)
				(mid 394.44676 -274.049744)
				(end 394.85316 -274.049744)
			)
		)
		(stroke
			(width 0)
			(type solid)
		)
		(fill yes)
		(layer "In1.Cu")
		(net "P5E_PEX3_STN2_RX_DP<45>")
	)
	(gr_poly
		(pts
			(arc
				(start 394.85316 -273.099784)
				(mid 394.44676 -273.099784)
				(end 394.85316 -273.099784)
			)
		)
		(stroke
			(width 0)
			(type solid)
		)
		(fill yes)
		(layer "In1.Cu")
		(net "P5E_PEX3_STN2_RX_DN<45>")
	)
	(gr_poly
		(pts
			(arc
				(start 395.80312 -316.799722)
				(mid 395.39672 -316.799722)
				(end 395.80312 -316.799722)
			)
		)
		(stroke
			(width 0)
			(type solid)
		)
		(fill yes)
		(layer "In1.Cu")
		(net "P5E_PEX3_STN6_RX_DN<107>")
	)
	(gr_poly
		(pts
			(arc
				(start 395.80312 -315.849762)
				(mid 395.39672 -315.849762)
				(end 395.80312 -315.849762)
			)
		)
		(stroke
			(width 0)
			(type solid)
		)
		(fill yes)
		(layer "In1.Cu")
		(net "P5E_PEX3_STN6_RX_DP<107>")
	)
	(gr_poly
		(pts
			(arc
				(start 395.80312 -312.049922)
				(mid 395.39672 -312.049922)
				(end 395.80312 -312.049922)
			)
		)
		(stroke
			(width 0)
			(type solid)
		)
		(fill yes)
		(layer "In1.Cu")
		(net "P5E_PEX3_STN6_TX_DN<107>")
	)
	(gr_poly
		(pts
			(arc
				(start 395.80312 -311.099962)
				(mid 395.39672 -311.099962)
				(end 395.80312 -311.099962)
			)
		)
		(stroke
			(width 0)
			(type solid)
		)
		(fill yes)
		(layer "In1.Cu")
		(net "P5E_PEX3_STN6_TX_DP<107>")
	)
	(gr_poly
		(pts
			(arc
				(start 395.80312 -280.699464)
				(mid 395.39672 -280.699464)
				(end 395.80312 -280.699464)
			)
		)
		(stroke
			(width 0)
			(type solid)
		)
		(fill yes)
		(layer "In1.Cu")
		(net "P5E_PEX3_STN2_TX_DP<44>")
	)
	(gr_poly
		(pts
			(arc
				(start 395.80312 -279.749504)
				(mid 395.39672 -279.749504)
				(end 395.80312 -279.749504)
			)
		)
		(stroke
			(width 0)
			(type solid)
		)
		(fill yes)
		(layer "In1.Cu")
		(net "P5E_PEX3_STN2_TX_DN<44>")
	)
	(gr_poly
		(pts
			(arc
				(start 395.80312 -275.949918)
				(mid 395.39672 -275.949918)
				(end 395.80312 -275.949918)
			)
		)
		(stroke
			(width 0)
			(type solid)
		)
		(fill yes)
		(layer "In1.Cu")
		(net "P5E_PEX3_STN2_RX_DP<44>")
	)
	(gr_poly
		(pts
			(arc
				(start 395.80312 -274.999958)
				(mid 395.39672 -274.999958)
				(end 395.80312 -274.999958)
			)
		)
		(stroke
			(width 0)
			(type solid)
		)
		(fill yes)
		(layer "In1.Cu")
		(net "P5E_PEX3_STN2_RX_DN<44>")
	)
	(gr_poly
		(pts
			(arc
				(start 396.75308 -318.699896)
				(mid 396.34668 -318.699896)
				(end 396.75308 -318.699896)
			)
		)
		(stroke
			(width 0)
			(type solid)
		)
		(fill yes)
		(layer "In1.Cu")
		(net "P5E_PEX3_STN6_RX_DN<106>")
	)
	(gr_poly
		(pts
			(arc
				(start 396.75308 -317.749936)
				(mid 396.34668 -317.749936)
				(end 396.75308 -317.749936)
			)
		)
		(stroke
			(width 0)
			(type solid)
		)
		(fill yes)
		(layer "In1.Cu")
		(net "P5E_PEX3_STN6_RX_DP<106>")
	)
	(gr_poly
		(pts
			(arc
				(start 396.75308 -313.949842)
				(mid 396.34668 -313.949842)
				(end 396.75308 -313.949842)
			)
		)
		(stroke
			(width 0)
			(type solid)
		)
		(fill yes)
		(layer "In1.Cu")
		(net "P5E_PEX3_STN6_TX_DN<106>")
	)
	(gr_poly
		(pts
			(arc
				(start 396.75308 -312.999882)
				(mid 396.34668 -312.999882)
				(end 396.75308 -312.999882)
			)
		)
		(stroke
			(width 0)
			(type solid)
		)
		(fill yes)
		(layer "In1.Cu")
		(net "P5E_PEX3_STN6_TX_DP<106>")
	)
	(gr_poly
		(pts
			(arc
				(start 396.75308 -278.799798)
				(mid 396.34668 -278.799798)
				(end 396.75308 -278.799798)
			)
		)
		(stroke
			(width 0)
			(type solid)
		)
		(fill yes)
		(layer "In1.Cu")
		(net "P5E_PEX3_STN2_TX_DP<43>")
	)
	(gr_poly
		(pts
			(arc
				(start 396.75308 -277.849838)
				(mid 396.34668 -277.849838)
				(end 396.75308 -277.849838)
			)
		)
		(stroke
			(width 0)
			(type solid)
		)
		(fill yes)
		(layer "In1.Cu")
		(net "P5E_PEX3_STN2_TX_DN<43>")
	)
	(gr_poly
		(pts
			(arc
				(start 396.75308 -274.049744)
				(mid 396.34668 -274.049744)
				(end 396.75308 -274.049744)
			)
		)
		(stroke
			(width 0)
			(type solid)
		)
		(fill yes)
		(layer "In1.Cu")
		(net "P5E_PEX3_STN2_RX_DP<43>")
	)
	(gr_poly
		(pts
			(arc
				(start 396.75308 -273.099784)
				(mid 396.34668 -273.099784)
				(end 396.75308 -273.099784)
			)
		)
		(stroke
			(width 0)
			(type solid)
		)
		(fill yes)
		(layer "In1.Cu")
		(net "P5E_PEX3_STN2_RX_DN<43>")
	)
	(gr_poly
		(pts
			(arc
				(start 397.70304 -316.799722)
				(mid 397.29664 -316.799722)
				(end 397.70304 -316.799722)
			)
		)
		(stroke
			(width 0)
			(type solid)
		)
		(fill yes)
		(layer "In1.Cu")
		(net "P5E_PEX3_STN6_RX_DN<105>")
	)
	(gr_poly
		(pts
			(arc
				(start 397.70304 -315.849762)
				(mid 397.29664 -315.849762)
				(end 397.70304 -315.849762)
			)
		)
		(stroke
			(width 0)
			(type solid)
		)
		(fill yes)
		(layer "In1.Cu")
		(net "P5E_PEX3_STN6_RX_DP<105>")
	)
	(gr_poly
		(pts
			(arc
				(start 397.70304 -312.049922)
				(mid 397.29664 -312.049922)
				(end 397.70304 -312.049922)
			)
		)
		(stroke
			(width 0)
			(type solid)
		)
		(fill yes)
		(layer "In1.Cu")
		(net "P5E_PEX3_STN6_TX_DN<105>")
	)
	(gr_poly
		(pts
			(arc
				(start 397.70304 -311.099962)
				(mid 397.29664 -311.099962)
				(end 397.70304 -311.099962)
			)
		)
		(stroke
			(width 0)
			(type solid)
		)
		(fill yes)
		(layer "In1.Cu")
		(net "P5E_PEX3_STN6_TX_DP<105>")
	)
	(gr_poly
		(pts
			(arc
				(start 397.70304 -280.699464)
				(mid 397.29664 -280.699464)
				(end 397.70304 -280.699464)
			)
		)
		(stroke
			(width 0)
			(type solid)
		)
		(fill yes)
		(layer "In1.Cu")
		(net "P5E_PEX3_STN2_TX_DP<42>")
	)
	(gr_poly
		(pts
			(arc
				(start 397.70304 -279.749504)
				(mid 397.29664 -279.749504)
				(end 397.70304 -279.749504)
			)
		)
		(stroke
			(width 0)
			(type solid)
		)
		(fill yes)
		(layer "In1.Cu")
		(net "P5E_PEX3_STN2_TX_DN<42>")
	)
	(gr_poly
		(pts
			(arc
				(start 397.70304 -275.949918)
				(mid 397.29664 -275.949918)
				(end 397.70304 -275.949918)
			)
		)
		(stroke
			(width 0)
			(type solid)
		)
		(fill yes)
		(layer "In1.Cu")
		(net "P5E_PEX3_STN2_RX_DP<42>")
	)
	(gr_poly
		(pts
			(arc
				(start 397.70304 -274.999958)
				(mid 397.29664 -274.999958)
				(end 397.70304 -274.999958)
			)
		)
		(stroke
			(width 0)
			(type solid)
		)
		(fill yes)
		(layer "In1.Cu")
		(net "P5E_PEX3_STN2_RX_DN<42>")
	)
	(gr_poly
		(pts
			(arc
				(start 398.653 -318.699896)
				(mid 398.2466 -318.699896)
				(end 398.653 -318.699896)
			)
		)
		(stroke
			(width 0)
			(type solid)
		)
		(fill yes)
		(layer "In1.Cu")
		(net "P5E_PEX3_STN6_RX_DN<104>")
	)
	(gr_poly
		(pts
			(arc
				(start 398.653 -317.749936)
				(mid 398.2466 -317.749936)
				(end 398.653 -317.749936)
			)
		)
		(stroke
			(width 0)
			(type solid)
		)
		(fill yes)
		(layer "In1.Cu")
		(net "P5E_PEX3_STN6_RX_DP<104>")
	)
	(gr_poly
		(pts
			(arc
				(start 398.653 -313.949842)
				(mid 398.2466 -313.949842)
				(end 398.653 -313.949842)
			)
		)
		(stroke
			(width 0)
			(type solid)
		)
		(fill yes)
		(layer "In1.Cu")
		(net "P5E_PEX3_STN6_TX_DN<104>")
	)
	(gr_poly
		(pts
			(arc
				(start 398.653 -312.999882)
				(mid 398.2466 -312.999882)
				(end 398.653 -312.999882)
			)
		)
		(stroke
			(width 0)
			(type solid)
		)
		(fill yes)
		(layer "In1.Cu")
		(net "P5E_PEX3_STN6_TX_DP<104>")
	)
	(gr_poly
		(pts
			(arc
				(start 398.653 -278.799798)
				(mid 398.2466 -278.799798)
				(end 398.653 -278.799798)
			)
		)
		(stroke
			(width 0)
			(type solid)
		)
		(fill yes)
		(layer "In1.Cu")
		(net "P5E_PEX3_STN2_TX_DP<41>")
	)
	(gr_poly
		(pts
			(arc
				(start 398.653 -277.849838)
				(mid 398.2466 -277.849838)
				(end 398.653 -277.849838)
			)
		)
		(stroke
			(width 0)
			(type solid)
		)
		(fill yes)
		(layer "In1.Cu")
		(net "P5E_PEX3_STN2_TX_DN<41>")
	)
	(gr_poly
		(pts
			(arc
				(start 398.653 -274.049744)
				(mid 398.2466 -274.049744)
				(end 398.653 -274.049744)
			)
		)
		(stroke
			(width 0)
			(type solid)
		)
		(fill yes)
		(layer "In1.Cu")
		(net "P5E_PEX3_STN2_RX_DP<41>")
	)
	(gr_poly
		(pts
			(arc
				(start 398.653 -273.099784)
				(mid 398.2466 -273.099784)
				(end 398.653 -273.099784)
			)
		)
		(stroke
			(width 0)
			(type solid)
		)
		(fill yes)
		(layer "In1.Cu")
		(net "P5E_PEX3_STN2_RX_DN<41>")
	)
	(gr_poly
		(pts
			(arc
				(start 399.603214 -316.799722)
				(mid 399.196814 -316.799722)
				(end 399.603214 -316.799722)
			)
		)
		(stroke
			(width 0)
			(type solid)
		)
		(fill yes)
		(layer "In1.Cu")
		(net "P5E_PEX3_STN6_RX_DN<103>")
	)
	(gr_poly
		(pts
			(arc
				(start 399.603214 -315.849762)
				(mid 399.196814 -315.849762)
				(end 399.603214 -315.849762)
			)
		)
		(stroke
			(width 0)
			(type solid)
		)
		(fill yes)
		(layer "In1.Cu")
		(net "P5E_PEX3_STN6_RX_DP<103>")
	)
	(gr_poly
		(pts
			(arc
				(start 399.603214 -312.049922)
				(mid 399.196814 -312.049922)
				(end 399.603214 -312.049922)
			)
		)
		(stroke
			(width 0)
			(type solid)
		)
		(fill yes)
		(layer "In1.Cu")
		(net "P5E_PEX3_STN6_TX_DN<103>")
	)
	(gr_poly
		(pts
			(arc
				(start 399.603214 -311.099962)
				(mid 399.196814 -311.099962)
				(end 399.603214 -311.099962)
			)
		)
		(stroke
			(width 0)
			(type solid)
		)
		(fill yes)
		(layer "In1.Cu")
		(net "P5E_PEX3_STN6_TX_DP<103>")
	)
	(gr_poly
		(pts
			(arc
				(start 399.603214 -280.699464)
				(mid 399.196814 -280.699464)
				(end 399.603214 -280.699464)
			)
		)
		(stroke
			(width 0)
			(type solid)
		)
		(fill yes)
		(layer "In1.Cu")
		(net "P5E_PEX3_STN2_TX_DP<40>")
	)
	(gr_poly
		(pts
			(arc
				(start 399.603214 -279.749504)
				(mid 399.196814 -279.749504)
				(end 399.603214 -279.749504)
			)
		)
		(stroke
			(width 0)
			(type solid)
		)
		(fill yes)
		(layer "In1.Cu")
		(net "P5E_PEX3_STN2_TX_DN<40>")
	)
	(gr_poly
		(pts
			(arc
				(start 399.603214 -275.949918)
				(mid 399.196814 -275.949918)
				(end 399.603214 -275.949918)
			)
		)
		(stroke
			(width 0)
			(type solid)
		)
		(fill yes)
		(layer "In1.Cu")
		(net "P5E_PEX3_STN2_RX_DP<40>")
	)
	(gr_poly
		(pts
			(arc
				(start 399.603214 -274.999958)
				(mid 399.196814 -274.999958)
				(end 399.603214 -274.999958)
			)
		)
		(stroke
			(width 0)
			(type solid)
		)
		(fill yes)
		(layer "In1.Cu")
		(net "P5E_PEX3_STN2_RX_DN<40>")
	)
	(gr_poly
		(pts
			(arc
				(start 400.553174 -318.699896)
				(mid 400.146774 -318.699896)
				(end 400.553174 -318.699896)
			)
		)
		(stroke
			(width 0)
			(type solid)
		)
		(fill yes)
		(layer "In1.Cu")
		(net "P5E_PEX3_STN6_RX_DN<102>")
	)
	(gr_poly
		(pts
			(arc
				(start 400.553174 -317.749936)
				(mid 400.146774 -317.749936)
				(end 400.553174 -317.749936)
			)
		)
		(stroke
			(width 0)
			(type solid)
		)
		(fill yes)
		(layer "In1.Cu")
		(net "P5E_PEX3_STN6_RX_DP<102>")
	)
	(gr_poly
		(pts
			(arc
				(start 400.553174 -313.949842)
				(mid 400.146774 -313.949842)
				(end 400.553174 -313.949842)
			)
		)
		(stroke
			(width 0)
			(type solid)
		)
		(fill yes)
		(layer "In1.Cu")
		(net "P5E_PEX3_STN6_TX_DN<102>")
	)
	(gr_poly
		(pts
			(arc
				(start 400.553174 -312.999882)
				(mid 400.146774 -312.999882)
				(end 400.553174 -312.999882)
			)
		)
		(stroke
			(width 0)
			(type solid)
		)
		(fill yes)
		(layer "In1.Cu")
		(net "P5E_PEX3_STN6_TX_DP<102>")
	)
	(gr_poly
		(pts
			(arc
				(start 400.553174 -278.799798)
				(mid 400.146774 -278.799798)
				(end 400.553174 -278.799798)
			)
		)
		(stroke
			(width 0)
			(type solid)
		)
		(fill yes)
		(layer "In1.Cu")
		(net "P5E_PEX3_STN2_TX_DP<39>")
	)
	(gr_poly
		(pts
			(arc
				(start 400.553174 -277.849838)
				(mid 400.146774 -277.849838)
				(end 400.553174 -277.849838)
			)
		)
		(stroke
			(width 0)
			(type solid)
		)
		(fill yes)
		(layer "In1.Cu")
		(net "P5E_PEX3_STN2_TX_DN<39>")
	)
	(gr_poly
		(pts
			(arc
				(start 400.553174 -274.049744)
				(mid 400.146774 -274.049744)
				(end 400.553174 -274.049744)
			)
		)
		(stroke
			(width 0)
			(type solid)
		)
		(fill yes)
		(layer "In1.Cu")
		(net "P5E_PEX3_STN2_RX_DP<39>")
	)
	(gr_poly
		(pts
			(arc
				(start 400.553174 -273.099784)
				(mid 400.146774 -273.099784)
				(end 400.553174 -273.099784)
			)
		)
		(stroke
			(width 0)
			(type solid)
		)
		(fill yes)
		(layer "In1.Cu")
		(net "P5E_PEX3_STN2_RX_DN<39>")
	)
	(gr_poly
		(pts
			(arc
				(start 401.503134 -316.799722)
				(mid 401.096734 -316.799722)
				(end 401.503134 -316.799722)
			)
		)
		(stroke
			(width 0)
			(type solid)
		)
		(fill yes)
		(layer "In1.Cu")
		(net "P5E_PEX3_STN6_RX_DN<101>")
	)
	(gr_poly
		(pts
			(arc
				(start 401.503134 -315.849762)
				(mid 401.096734 -315.849762)
				(end 401.503134 -315.849762)
			)
		)
		(stroke
			(width 0)
			(type solid)
		)
		(fill yes)
		(layer "In1.Cu")
		(net "P5E_PEX3_STN6_RX_DP<101>")
	)
	(gr_poly
		(pts
			(arc
				(start 401.503134 -312.049922)
				(mid 401.096734 -312.049922)
				(end 401.503134 -312.049922)
			)
		)
		(stroke
			(width 0)
			(type solid)
		)
		(fill yes)
		(layer "In1.Cu")
		(net "P5E_PEX3_STN6_TX_DN<101>")
	)
	(gr_poly
		(pts
			(arc
				(start 401.503134 -311.099962)
				(mid 401.096734 -311.099962)
				(end 401.503134 -311.099962)
			)
		)
		(stroke
			(width 0)
			(type solid)
		)
		(fill yes)
		(layer "In1.Cu")
		(net "P5E_PEX3_STN6_TX_DP<101>")
	)
	(gr_poly
		(pts
			(arc
				(start 401.503134 -280.699464)
				(mid 401.096734 -280.699464)
				(end 401.503134 -280.699464)
			)
		)
		(stroke
			(width 0)
			(type solid)
		)
		(fill yes)
		(layer "In1.Cu")
		(net "P5E_PEX3_STN2_TX_DP<38>")
	)
	(gr_poly
		(pts
			(arc
				(start 401.503134 -279.749504)
				(mid 401.096734 -279.749504)
				(end 401.503134 -279.749504)
			)
		)
		(stroke
			(width 0)
			(type solid)
		)
		(fill yes)
		(layer "In1.Cu")
		(net "P5E_PEX3_STN2_TX_DN<38>")
	)
	(gr_poly
		(pts
			(arc
				(start 401.503134 -275.949918)
				(mid 401.096734 -275.949918)
				(end 401.503134 -275.949918)
			)
		)
		(stroke
			(width 0)
			(type solid)
		)
		(fill yes)
		(layer "In1.Cu")
		(net "P5E_PEX3_STN2_RX_DP<38>")
	)
	(gr_poly
		(pts
			(arc
				(start 401.503134 -274.999958)
				(mid 401.096734 -274.999958)
				(end 401.503134 -274.999958)
			)
		)
		(stroke
			(width 0)
			(type solid)
		)
		(fill yes)
		(layer "In1.Cu")
		(net "P5E_PEX3_STN2_RX_DN<38>")
	)
	(gr_poly
		(pts
			(arc
				(start 402.453094 -318.699896)
				(mid 402.046694 -318.699896)
				(end 402.453094 -318.699896)
			)
		)
		(stroke
			(width 0)
			(type solid)
		)
		(fill yes)
		(layer "In1.Cu")
		(net "P5E_PEX3_STN6_RX_DN<100>")
	)
	(gr_poly
		(pts
			(arc
				(start 402.453094 -317.749936)
				(mid 402.046694 -317.749936)
				(end 402.453094 -317.749936)
			)
		)
		(stroke
			(width 0)
			(type solid)
		)
		(fill yes)
		(layer "In1.Cu")
		(net "P5E_PEX3_STN6_RX_DP<100>")
	)
	(gr_poly
		(pts
			(arc
				(start 402.453094 -313.949842)
				(mid 402.046694 -313.949842)
				(end 402.453094 -313.949842)
			)
		)
		(stroke
			(width 0)
			(type solid)
		)
		(fill yes)
		(layer "In1.Cu")
		(net "P5E_PEX3_STN6_TX_DN<100>")
	)
	(gr_poly
		(pts
			(arc
				(start 402.453094 -312.999882)
				(mid 402.046694 -312.999882)
				(end 402.453094 -312.999882)
			)
		)
		(stroke
			(width 0)
			(type solid)
		)
		(fill yes)
		(layer "In1.Cu")
		(net "P5E_PEX3_STN6_TX_DP<100>")
	)
	(gr_poly
		(pts
			(arc
				(start 402.453094 -278.799798)
				(mid 402.046694 -278.799798)
				(end 402.453094 -278.799798)
			)
		)
		(stroke
			(width 0)
			(type solid)
		)
		(fill yes)
		(layer "In1.Cu")
		(net "P5E_PEX3_STN2_TX_DP<37>")
	)
	(gr_poly
		(pts
			(arc
				(start 402.453094 -277.849838)
				(mid 402.046694 -277.849838)
				(end 402.453094 -277.849838)
			)
		)
		(stroke
			(width 0)
			(type solid)
		)
		(fill yes)
		(layer "In1.Cu")
		(net "P5E_PEX3_STN2_TX_DN<37>")
	)
	(gr_poly
		(pts
			(arc
				(start 402.453094 -274.049744)
				(mid 402.046694 -274.049744)
				(end 402.453094 -274.049744)
			)
		)
		(stroke
			(width 0)
			(type solid)
		)
		(fill yes)
		(layer "In1.Cu")
		(net "P5E_PEX3_STN2_RX_DP<37>")
	)
	(gr_poly
		(pts
			(arc
				(start 402.453094 -273.099784)
				(mid 402.046694 -273.099784)
				(end 402.453094 -273.099784)
			)
		)
		(stroke
			(width 0)
			(type solid)
		)
		(fill yes)
		(layer "In1.Cu")
		(net "P5E_PEX3_STN2_RX_DN<37>")
	)
	(gr_poly
		(pts
			(arc
				(start 403.403054 -316.799722)
				(mid 402.996654 -316.799722)
				(end 403.403054 -316.799722)
			)
		)
		(stroke
			(width 0)
			(type solid)
		)
		(fill yes)
		(layer "In1.Cu")
		(net "P5E_PEX3_STN6_RX_DN<99>")
	)
	(gr_poly
		(pts
			(arc
				(start 403.403054 -315.849762)
				(mid 402.996654 -315.849762)
				(end 403.403054 -315.849762)
			)
		)
		(stroke
			(width 0)
			(type solid)
		)
		(fill yes)
		(layer "In1.Cu")
		(net "P5E_PEX3_STN6_RX_DP<99>")
	)
	(gr_poly
		(pts
			(arc
				(start 403.403054 -312.049922)
				(mid 402.996654 -312.049922)
				(end 403.403054 -312.049922)
			)
		)
		(stroke
			(width 0)
			(type solid)
		)
		(fill yes)
		(layer "In1.Cu")
		(net "P5E_PEX3_STN6_TX_DN<99>")
	)
	(gr_poly
		(pts
			(arc
				(start 403.403054 -311.099962)
				(mid 402.996654 -311.099962)
				(end 403.403054 -311.099962)
			)
		)
		(stroke
			(width 0)
			(type solid)
		)
		(fill yes)
		(layer "In1.Cu")
		(net "P5E_PEX3_STN6_TX_DP<99>")
	)
	(gr_poly
		(pts
			(arc
				(start 403.403054 -280.699464)
				(mid 402.996654 -280.699464)
				(end 403.403054 -280.699464)
			)
		)
		(stroke
			(width 0)
			(type solid)
		)
		(fill yes)
		(layer "In1.Cu")
		(net "P5E_PEX3_STN2_TX_DP<36>")
	)
	(gr_poly
		(pts
			(arc
				(start 403.403054 -279.749504)
				(mid 402.996654 -279.749504)
				(end 403.403054 -279.749504)
			)
		)
		(stroke
			(width 0)
			(type solid)
		)
		(fill yes)
		(layer "In1.Cu")
		(net "P5E_PEX3_STN2_TX_DN<36>")
	)
	(gr_poly
		(pts
			(arc
				(start 403.403054 -275.949918)
				(mid 402.996654 -275.949918)
				(end 403.403054 -275.949918)
			)
		)
		(stroke
			(width 0)
			(type solid)
		)
		(fill yes)
		(layer "In1.Cu")
		(net "P5E_PEX3_STN2_RX_DP<36>")
	)
	(gr_poly
		(pts
			(arc
				(start 403.403054 -274.999958)
				(mid 402.996654 -274.999958)
				(end 403.403054 -274.999958)
			)
		)
		(stroke
			(width 0)
			(type solid)
		)
		(fill yes)
		(layer "In1.Cu")
		(net "P5E_PEX3_STN2_RX_DN<36>")
	)
	(gr_poly
		(pts
			(arc
				(start 404.353014 -318.699896)
				(mid 403.946614 -318.699896)
				(end 404.353014 -318.699896)
			)
		)
		(stroke
			(width 0)
			(type solid)
		)
		(fill yes)
		(layer "In1.Cu")
		(net "P5E_PEX3_STN6_RX_DN<98>")
	)
	(gr_poly
		(pts
			(arc
				(start 404.353014 -317.749936)
				(mid 403.946614 -317.749936)
				(end 404.353014 -317.749936)
			)
		)
		(stroke
			(width 0)
			(type solid)
		)
		(fill yes)
		(layer "In1.Cu")
		(net "P5E_PEX3_STN6_RX_DP<98>")
	)
	(gr_poly
		(pts
			(arc
				(start 404.353014 -313.949842)
				(mid 403.946614 -313.949842)
				(end 404.353014 -313.949842)
			)
		)
		(stroke
			(width 0)
			(type solid)
		)
		(fill yes)
		(layer "In1.Cu")
		(net "P5E_PEX3_STN6_TX_DN<98>")
	)
	(gr_poly
		(pts
			(arc
				(start 404.353014 -312.999882)
				(mid 403.946614 -312.999882)
				(end 404.353014 -312.999882)
			)
		)
		(stroke
			(width 0)
			(type solid)
		)
		(fill yes)
		(layer "In1.Cu")
		(net "P5E_PEX3_STN6_TX_DP<98>")
	)
	(gr_poly
		(pts
			(arc
				(start 404.353014 -278.799798)
				(mid 403.946614 -278.799798)
				(end 404.353014 -278.799798)
			)
		)
		(stroke
			(width 0)
			(type solid)
		)
		(fill yes)
		(layer "In1.Cu")
		(net "P5E_PEX3_STN2_TX_DP<35>")
	)
	(gr_poly
		(pts
			(arc
				(start 404.353014 -277.849838)
				(mid 403.946614 -277.849838)
				(end 404.353014 -277.849838)
			)
		)
		(stroke
			(width 0)
			(type solid)
		)
		(fill yes)
		(layer "In1.Cu")
		(net "P5E_PEX3_STN2_TX_DN<35>")
	)
	(gr_poly
		(pts
			(arc
				(start 404.353014 -274.049744)
				(mid 403.946614 -274.049744)
				(end 404.353014 -274.049744)
			)
		)
		(stroke
			(width 0)
			(type solid)
		)
		(fill yes)
		(layer "In1.Cu")
		(net "P5E_PEX3_STN2_RX_DP<35>")
	)
	(gr_poly
		(pts
			(arc
				(start 404.353014 -273.099784)
				(mid 403.946614 -273.099784)
				(end 404.353014 -273.099784)
			)
		)
		(stroke
			(width 0)
			(type solid)
		)
		(fill yes)
		(layer "In1.Cu")
		(net "P5E_PEX3_STN2_RX_DN<35>")
	)
	(gr_poly
		(pts
			(arc
				(start 405.302974 -280.699464)
				(mid 404.896574 -280.699464)
				(end 405.302974 -280.699464)
			)
		)
		(stroke
			(width 0)
			(type solid)
		)
		(fill yes)
		(layer "In1.Cu")
		(net "P5E_PEX3_STN2_TX_DP<34>")
	)
	(gr_poly
		(pts
			(arc
				(start 405.302974 -279.749504)
				(mid 404.896574 -279.749504)
				(end 405.302974 -279.749504)
			)
		)
		(stroke
			(width 0)
			(type solid)
		)
		(fill yes)
		(layer "In1.Cu")
		(net "P5E_PEX3_STN2_TX_DN<34>")
	)
	(gr_poly
		(pts
			(arc
				(start 405.303228 -316.799722)
				(mid 404.896828 -316.799722)
				(end 405.303228 -316.799722)
			)
		)
		(stroke
			(width 0)
			(type solid)
		)
		(fill yes)
		(layer "In1.Cu")
		(net "P5E_PEX3_STN6_RX_DN<97>")
	)
	(gr_poly
		(pts
			(arc
				(start 405.303228 -315.849762)
				(mid 404.896828 -315.849762)
				(end 405.303228 -315.849762)
			)
		)
		(stroke
			(width 0)
			(type solid)
		)
		(fill yes)
		(layer "In1.Cu")
		(net "P5E_PEX3_STN6_RX_DP<97>")
	)
	(gr_poly
		(pts
			(arc
				(start 405.303228 -312.049922)
				(mid 404.896828 -312.049922)
				(end 405.303228 -312.049922)
			)
		)
		(stroke
			(width 0)
			(type solid)
		)
		(fill yes)
		(layer "In1.Cu")
		(net "P5E_PEX3_STN6_TX_DN<97>")
	)
	(gr_poly
		(pts
			(arc
				(start 405.303228 -311.099962)
				(mid 404.896828 -311.099962)
				(end 405.303228 -311.099962)
			)
		)
		(stroke
			(width 0)
			(type solid)
		)
		(fill yes)
		(layer "In1.Cu")
		(net "P5E_PEX3_STN6_TX_DP<97>")
	)
	(gr_poly
		(pts
			(arc
				(start 405.303228 -275.949918)
				(mid 404.896828 -275.949918)
				(end 405.303228 -275.949918)
			)
		)
		(stroke
			(width 0)
			(type solid)
		)
		(fill yes)
		(layer "In1.Cu")
		(net "P5E_PEX3_STN2_RX_DP<34>")
	)
	(gr_poly
		(pts
			(arc
				(start 405.303228 -274.999958)
				(mid 404.896828 -274.999958)
				(end 405.303228 -274.999958)
			)
		)
		(stroke
			(width 0)
			(type solid)
		)
		(fill yes)
		(layer "In1.Cu")
		(net "P5E_PEX3_STN2_RX_DN<34>")
	)
	(gr_poly
		(pts
			(arc
				(start 406.253188 -318.699896)
				(mid 405.846788 -318.699896)
				(end 406.253188 -318.699896)
			)
		)
		(stroke
			(width 0)
			(type solid)
		)
		(fill yes)
		(layer "In1.Cu")
		(net "P5E_PEX3_STN6_RX_DN<96>")
	)
	(gr_poly
		(pts
			(arc
				(start 406.253188 -317.749936)
				(mid 405.846788 -317.749936)
				(end 406.253188 -317.749936)
			)
		)
		(stroke
			(width 0)
			(type solid)
		)
		(fill yes)
		(layer "In1.Cu")
		(net "P5E_PEX3_STN6_RX_DP<96>")
	)
	(gr_poly
		(pts
			(arc
				(start 406.253188 -313.949842)
				(mid 405.846788 -313.949842)
				(end 406.253188 -313.949842)
			)
		)
		(stroke
			(width 0)
			(type solid)
		)
		(fill yes)
		(layer "In1.Cu")
		(net "P5E_PEX3_STN6_TX_DN<96>")
	)
	(gr_poly
		(pts
			(arc
				(start 406.253188 -312.999882)
				(mid 405.846788 -312.999882)
				(end 406.253188 -312.999882)
			)
		)
		(stroke
			(width 0)
			(type solid)
		)
		(fill yes)
		(layer "In1.Cu")
		(net "P5E_PEX3_STN6_TX_DP<96>")
	)
	(gr_poly
		(pts
			(arc
				(start 406.253188 -278.799798)
				(mid 405.846788 -278.799798)
				(end 406.253188 -278.799798)
			)
		)
		(stroke
			(width 0)
			(type solid)
		)
		(fill yes)
		(layer "In1.Cu")
		(net "P5E_PEX3_STN2_TX_DP<33>")
	)
	(gr_poly
		(pts
			(arc
				(start 406.253188 -277.849838)
				(mid 405.846788 -277.849838)
				(end 406.253188 -277.849838)
			)
		)
		(stroke
			(width 0)
			(type solid)
		)
		(fill yes)
		(layer "In1.Cu")
		(net "P5E_PEX3_STN2_TX_DN<33>")
	)
	(gr_poly
		(pts
			(arc
				(start 406.253188 -274.049744)
				(mid 405.846788 -274.049744)
				(end 406.253188 -274.049744)
			)
		)
		(stroke
			(width 0)
			(type solid)
		)
		(fill yes)
		(layer "In1.Cu")
		(net "P5E_PEX3_STN2_RX_DP<33>")
	)
	(gr_poly
		(pts
			(arc
				(start 406.253188 -273.099784)
				(mid 405.846788 -273.099784)
				(end 406.253188 -273.099784)
			)
		)
		(stroke
			(width 0)
			(type solid)
		)
		(fill yes)
		(layer "In1.Cu")
		(net "P5E_PEX3_STN2_RX_DN<33>")
	)
	(gr_poly
		(pts
			(arc
				(start 407.203148 -316.799722)
				(mid 406.796748 -316.799722)
				(end 407.203148 -316.799722)
			)
		)
		(stroke
			(width 0)
			(type solid)
		)
		(fill yes)
		(layer "In1.Cu")
		(net "P5E_PEX3_STN5_RX_DN<80>")
	)
	(gr_poly
		(pts
			(arc
				(start 407.203148 -315.849762)
				(mid 406.796748 -315.849762)
				(end 407.203148 -315.849762)
			)
		)
		(stroke
			(width 0)
			(type solid)
		)
		(fill yes)
		(layer "In1.Cu")
		(net "P5E_PEX3_STN5_RX_DP<80>")
	)
	(gr_poly
		(pts
			(arc
				(start 407.203148 -312.049922)
				(mid 406.796748 -312.049922)
				(end 407.203148 -312.049922)
			)
		)
		(stroke
			(width 0)
			(type solid)
		)
		(fill yes)
		(layer "In1.Cu")
		(net "P5E_PEX3_STN5_TX_DN<80>")
	)
	(gr_poly
		(pts
			(arc
				(start 407.203148 -311.099962)
				(mid 406.796748 -311.099962)
				(end 407.203148 -311.099962)
			)
		)
		(stroke
			(width 0)
			(type solid)
		)
		(fill yes)
		(layer "In1.Cu")
		(net "P5E_PEX3_STN5_TX_DP<80>")
	)
	(gr_poly
		(pts
			(arc
				(start 407.203148 -280.699464)
				(mid 406.796748 -280.699464)
				(end 407.203148 -280.699464)
			)
		)
		(stroke
			(width 0)
			(type solid)
		)
		(fill yes)
		(layer "In1.Cu")
		(net "P5E_PEX3_STN2_TX_DP<32>")
	)
	(gr_poly
		(pts
			(arc
				(start 407.203148 -279.749504)
				(mid 406.796748 -279.749504)
				(end 407.203148 -279.749504)
			)
		)
		(stroke
			(width 0)
			(type solid)
		)
		(fill yes)
		(layer "In1.Cu")
		(net "P5E_PEX3_STN2_TX_DN<32>")
	)
	(gr_poly
		(pts
			(arc
				(start 407.203148 -275.949918)
				(mid 406.796748 -275.949918)
				(end 407.203148 -275.949918)
			)
		)
		(stroke
			(width 0)
			(type solid)
		)
		(fill yes)
		(layer "In1.Cu")
		(net "P5E_PEX3_STN2_RX_DP<32>")
	)
	(gr_poly
		(pts
			(arc
				(start 407.203148 -274.999958)
				(mid 406.796748 -274.999958)
				(end 407.203148 -274.999958)
			)
		)
		(stroke
			(width 0)
			(type solid)
		)
		(fill yes)
		(layer "In1.Cu")
		(net "P5E_PEX3_STN2_RX_DN<32>")
	)
	(gr_poly
		(pts
			(arc
				(start 408.152854 -278.799798)
				(mid 407.746454 -278.799798)
				(end 408.152854 -278.799798)
			)
		)
		(stroke
			(width 0)
			(type solid)
		)
		(fill yes)
		(layer "In1.Cu")
		(net "P5E_PEX3_STN1_TX_DP<16>")
	)
	(gr_poly
		(pts
			(arc
				(start 408.152854 -277.849838)
				(mid 407.746454 -277.849838)
				(end 408.152854 -277.849838)
			)
		)
		(stroke
			(width 0)
			(type solid)
		)
		(fill yes)
		(layer "In1.Cu")
		(net "P5E_PEX3_STN1_TX_DN<16>")
	)
	(gr_poly
		(pts
			(arc
				(start 408.152854 -274.04949)
				(mid 407.746454 -274.04949)
				(end 408.152854 -274.04949)
			)
		)
		(stroke
			(width 0)
			(type solid)
		)
		(fill yes)
		(layer "In1.Cu")
		(net "P5E_PEX3_STN1_RX_DP<16>")
	)
	(gr_poly
		(pts
			(arc
				(start 408.152854 -273.09953)
				(mid 407.746454 -273.09953)
				(end 408.152854 -273.09953)
			)
		)
		(stroke
			(width 0)
			(type solid)
		)
		(fill yes)
		(layer "In1.Cu")
		(net "P5E_PEX3_STN1_RX_DN<16>")
	)
	(gr_poly
		(pts
			(arc
				(start 408.153108 -318.699896)
				(mid 407.746708 -318.699896)
				(end 408.153108 -318.699896)
			)
		)
		(stroke
			(width 0)
			(type solid)
		)
		(fill yes)
		(layer "In1.Cu")
		(net "P5E_PEX3_STN5_RX_DN<81>")
	)
	(gr_poly
		(pts
			(arc
				(start 408.153108 -317.749936)
				(mid 407.746708 -317.749936)
				(end 408.153108 -317.749936)
			)
		)
		(stroke
			(width 0)
			(type solid)
		)
		(fill yes)
		(layer "In1.Cu")
		(net "P5E_PEX3_STN5_RX_DP<81>")
	)
	(gr_poly
		(pts
			(arc
				(start 408.153108 -313.949842)
				(mid 407.746708 -313.949842)
				(end 408.153108 -313.949842)
			)
		)
		(stroke
			(width 0)
			(type solid)
		)
		(fill yes)
		(layer "In1.Cu")
		(net "P5E_PEX3_STN5_TX_DN<81>")
	)
	(gr_poly
		(pts
			(arc
				(start 408.153108 -312.999882)
				(mid 407.746708 -312.999882)
				(end 408.153108 -312.999882)
			)
		)
		(stroke
			(width 0)
			(type solid)
		)
		(fill yes)
		(layer "In1.Cu")
		(net "P5E_PEX3_STN5_TX_DP<81>")
	)
	(gr_poly
		(pts
			(arc
				(start 409.102814 -275.949664)
				(mid 408.696414 -275.949664)
				(end 409.102814 -275.949664)
			)
		)
		(stroke
			(width 0)
			(type solid)
		)
		(fill yes)
		(layer "In1.Cu")
		(net "P5E_PEX3_STN1_RX_DP<17>")
	)
	(gr_poly
		(pts
			(arc
				(start 409.102814 -274.999704)
				(mid 408.696414 -274.999704)
				(end 409.102814 -274.999704)
			)
		)
		(stroke
			(width 0)
			(type solid)
		)
		(fill yes)
		(layer "In1.Cu")
		(net "P5E_PEX3_STN1_RX_DN<17>")
	)
	(gr_poly
		(pts
			(arc
				(start 409.103068 -316.799722)
				(mid 408.696668 -316.799722)
				(end 409.103068 -316.799722)
			)
		)
		(stroke
			(width 0)
			(type solid)
		)
		(fill yes)
		(layer "In1.Cu")
		(net "P5E_PEX3_STN5_RX_DN<82>")
	)
	(gr_poly
		(pts
			(arc
				(start 409.103068 -315.849762)
				(mid 408.696668 -315.849762)
				(end 409.103068 -315.849762)
			)
		)
		(stroke
			(width 0)
			(type solid)
		)
		(fill yes)
		(layer "In1.Cu")
		(net "P5E_PEX3_STN5_RX_DP<82>")
	)
	(gr_poly
		(pts
			(arc
				(start 409.103068 -312.049922)
				(mid 408.696668 -312.049922)
				(end 409.103068 -312.049922)
			)
		)
		(stroke
			(width 0)
			(type solid)
		)
		(fill yes)
		(layer "In1.Cu")
		(net "P5E_PEX3_STN5_TX_DN<82>")
	)
	(gr_poly
		(pts
			(arc
				(start 409.103068 -311.099962)
				(mid 408.696668 -311.099962)
				(end 409.103068 -311.099962)
			)
		)
		(stroke
			(width 0)
			(type solid)
		)
		(fill yes)
		(layer "In1.Cu")
		(net "P5E_PEX3_STN5_TX_DP<82>")
	)
	(gr_poly
		(pts
			(arc
				(start 409.103068 -280.699464)
				(mid 408.696668 -280.699464)
				(end 409.103068 -280.699464)
			)
		)
		(stroke
			(width 0)
			(type solid)
		)
		(fill yes)
		(layer "In1.Cu")
		(net "P5E_PEX3_STN1_TX_DN<17>")
	)
	(gr_poly
		(pts
			(arc
				(start 409.103068 -279.749504)
				(mid 408.696668 -279.749504)
				(end 409.103068 -279.749504)
			)
		)
		(stroke
			(width 0)
			(type solid)
		)
		(fill yes)
		(layer "In1.Cu")
		(net "P5E_PEX3_STN1_TX_DP<17>")
	)
	(gr_poly
		(pts
			(arc
				(start 410.052774 -278.799798)
				(mid 409.646374 -278.799798)
				(end 410.052774 -278.799798)
			)
		)
		(stroke
			(width 0)
			(type solid)
		)
		(fill yes)
		(layer "In1.Cu")
		(net "P5E_PEX3_STN1_TX_DP<18>")
	)
	(gr_poly
		(pts
			(arc
				(start 410.052774 -277.849838)
				(mid 409.646374 -277.849838)
				(end 410.052774 -277.849838)
			)
		)
		(stroke
			(width 0)
			(type solid)
		)
		(fill yes)
		(layer "In1.Cu")
		(net "P5E_PEX3_STN1_TX_DN<18>")
	)
	(gr_poly
		(pts
			(arc
				(start 410.052774 -274.049744)
				(mid 409.646374 -274.049744)
				(end 410.052774 -274.049744)
			)
		)
		(stroke
			(width 0)
			(type solid)
		)
		(fill yes)
		(layer "In1.Cu")
		(net "P5E_PEX3_STN1_RX_DP<18>")
	)
	(gr_poly
		(pts
			(arc
				(start 410.052774 -273.099784)
				(mid 409.646374 -273.099784)
				(end 410.052774 -273.099784)
			)
		)
		(stroke
			(width 0)
			(type solid)
		)
		(fill yes)
		(layer "In1.Cu")
		(net "P5E_PEX3_STN1_RX_DN<18>")
	)
	(gr_poly
		(pts
			(arc
				(start 410.053028 -318.699896)
				(mid 409.646628 -318.699896)
				(end 410.053028 -318.699896)
			)
		)
		(stroke
			(width 0)
			(type solid)
		)
		(fill yes)
		(layer "In1.Cu")
		(net "P5E_PEX3_STN5_RX_DN<83>")
	)
	(gr_poly
		(pts
			(arc
				(start 410.053028 -317.749936)
				(mid 409.646628 -317.749936)
				(end 410.053028 -317.749936)
			)
		)
		(stroke
			(width 0)
			(type solid)
		)
		(fill yes)
		(layer "In1.Cu")
		(net "P5E_PEX3_STN5_RX_DP<83>")
	)
	(gr_poly
		(pts
			(arc
				(start 410.053028 -313.949842)
				(mid 409.646628 -313.949842)
				(end 410.053028 -313.949842)
			)
		)
		(stroke
			(width 0)
			(type solid)
		)
		(fill yes)
		(layer "In1.Cu")
		(net "P5E_PEX3_STN5_TX_DN<83>")
	)
	(gr_poly
		(pts
			(arc
				(start 410.053028 -312.999882)
				(mid 409.646628 -312.999882)
				(end 410.053028 -312.999882)
			)
		)
		(stroke
			(width 0)
			(type solid)
		)
		(fill yes)
		(layer "In1.Cu")
		(net "P5E_PEX3_STN5_TX_DP<83>")
	)
	(gr_poly
		(pts
			(arc
				(start 411.002734 -275.949918)
				(mid 410.596334 -275.949918)
				(end 411.002734 -275.949918)
			)
		)
		(stroke
			(width 0)
			(type solid)
		)
		(fill yes)
		(layer "In1.Cu")
		(net "P5E_PEX3_STN1_RX_DP<19>")
	)
	(gr_poly
		(pts
			(arc
				(start 411.002734 -274.999958)
				(mid 410.596334 -274.999958)
				(end 411.002734 -274.999958)
			)
		)
		(stroke
			(width 0)
			(type solid)
		)
		(fill yes)
		(layer "In1.Cu")
		(net "P5E_PEX3_STN1_RX_DN<19>")
	)
	(gr_poly
		(pts
			(arc
				(start 411.002988 -316.799722)
				(mid 410.596588 -316.799722)
				(end 411.002988 -316.799722)
			)
		)
		(stroke
			(width 0)
			(type solid)
		)
		(fill yes)
		(layer "In1.Cu")
		(net "P5E_PEX3_STN5_RX_DN<84>")
	)
	(gr_poly
		(pts
			(arc
				(start 411.002988 -315.849762)
				(mid 410.596588 -315.849762)
				(end 411.002988 -315.849762)
			)
		)
		(stroke
			(width 0)
			(type solid)
		)
		(fill yes)
		(layer "In1.Cu")
		(net "P5E_PEX3_STN5_RX_DP<84>")
	)
	(gr_poly
		(pts
			(arc
				(start 411.002988 -312.049922)
				(mid 410.596588 -312.049922)
				(end 411.002988 -312.049922)
			)
		)
		(stroke
			(width 0)
			(type solid)
		)
		(fill yes)
		(layer "In1.Cu")
		(net "P5E_PEX3_STN5_TX_DN<84>")
	)
	(gr_poly
		(pts
			(arc
				(start 411.002988 -311.099962)
				(mid 410.596588 -311.099962)
				(end 411.002988 -311.099962)
			)
		)
		(stroke
			(width 0)
			(type solid)
		)
		(fill yes)
		(layer "In1.Cu")
		(net "P5E_PEX3_STN5_TX_DP<84>")
	)
	(gr_poly
		(pts
			(arc
				(start 411.002988 -280.699464)
				(mid 410.596588 -280.699464)
				(end 411.002988 -280.699464)
			)
		)
		(stroke
			(width 0)
			(type solid)
		)
		(fill yes)
		(layer "In1.Cu")
		(net "P5E_PEX3_STN1_TX_DN<19>")
	)
	(gr_poly
		(pts
			(arc
				(start 411.002988 -279.749504)
				(mid 410.596588 -279.749504)
				(end 411.002988 -279.749504)
			)
		)
		(stroke
			(width 0)
			(type solid)
		)
		(fill yes)
		(layer "In1.Cu")
		(net "P5E_PEX3_STN1_TX_DP<19>")
	)
	(gr_poly
		(pts
			(arc
				(start 411.952948 -278.799798)
				(mid 411.546548 -278.799798)
				(end 411.952948 -278.799798)
			)
		)
		(stroke
			(width 0)
			(type solid)
		)
		(fill yes)
		(layer "In1.Cu")
		(net "P5E_PEX3_STN1_TX_DP<20>")
	)
	(gr_poly
		(pts
			(arc
				(start 411.952948 -277.849838)
				(mid 411.546548 -277.849838)
				(end 411.952948 -277.849838)
			)
		)
		(stroke
			(width 0)
			(type solid)
		)
		(fill yes)
		(layer "In1.Cu")
		(net "P5E_PEX3_STN1_TX_DN<20>")
	)
	(gr_poly
		(pts
			(arc
				(start 411.952948 -274.049744)
				(mid 411.546548 -274.049744)
				(end 411.952948 -274.049744)
			)
		)
		(stroke
			(width 0)
			(type solid)
		)
		(fill yes)
		(layer "In1.Cu")
		(net "P5E_PEX3_STN1_RX_DP<20>")
	)
	(gr_poly
		(pts
			(arc
				(start 411.952948 -273.099784)
				(mid 411.546548 -273.099784)
				(end 411.952948 -273.099784)
			)
		)
		(stroke
			(width 0)
			(type solid)
		)
		(fill yes)
		(layer "In1.Cu")
		(net "P5E_PEX3_STN1_RX_DN<20>")
	)
	(gr_poly
		(pts
			(arc
				(start 411.953202 -318.699896)
				(mid 411.546802 -318.699896)
				(end 411.953202 -318.699896)
			)
		)
		(stroke
			(width 0)
			(type solid)
		)
		(fill yes)
		(layer "In1.Cu")
		(net "P5E_PEX3_STN5_RX_DN<85>")
	)
	(gr_poly
		(pts
			(arc
				(start 411.953202 -317.749936)
				(mid 411.546802 -317.749936)
				(end 411.953202 -317.749936)
			)
		)
		(stroke
			(width 0)
			(type solid)
		)
		(fill yes)
		(layer "In1.Cu")
		(net "P5E_PEX3_STN5_RX_DP<85>")
	)
	(gr_poly
		(pts
			(arc
				(start 411.953202 -313.949842)
				(mid 411.546802 -313.949842)
				(end 411.953202 -313.949842)
			)
		)
		(stroke
			(width 0)
			(type solid)
		)
		(fill yes)
		(layer "In1.Cu")
		(net "P5E_PEX3_STN5_TX_DN<85>")
	)
	(gr_poly
		(pts
			(arc
				(start 411.953202 -312.999882)
				(mid 411.546802 -312.999882)
				(end 411.953202 -312.999882)
			)
		)
		(stroke
			(width 0)
			(type solid)
		)
		(fill yes)
		(layer "In1.Cu")
		(net "P5E_PEX3_STN5_TX_DP<85>")
	)
	(gr_poly
		(pts
			(arc
				(start 412.902908 -275.949664)
				(mid 412.496508 -275.949664)
				(end 412.902908 -275.949664)
			)
		)
		(stroke
			(width 0)
			(type solid)
		)
		(fill yes)
		(layer "In1.Cu")
		(net "P5E_PEX3_STN1_RX_DP<21>")
	)
	(gr_poly
		(pts
			(arc
				(start 412.902908 -274.999704)
				(mid 412.496508 -274.999704)
				(end 412.902908 -274.999704)
			)
		)
		(stroke
			(width 0)
			(type solid)
		)
		(fill yes)
		(layer "In1.Cu")
		(net "P5E_PEX3_STN1_RX_DN<21>")
	)
	(gr_poly
		(pts
			(arc
				(start 412.903162 -316.799722)
				(mid 412.496762 -316.799722)
				(end 412.903162 -316.799722)
			)
		)
		(stroke
			(width 0)
			(type solid)
		)
		(fill yes)
		(layer "In1.Cu")
		(net "P5E_PEX3_STN5_RX_DN<86>")
	)
	(gr_poly
		(pts
			(arc
				(start 412.903162 -315.849762)
				(mid 412.496762 -315.849762)
				(end 412.903162 -315.849762)
			)
		)
		(stroke
			(width 0)
			(type solid)
		)
		(fill yes)
		(layer "In1.Cu")
		(net "P5E_PEX3_STN5_RX_DP<86>")
	)
	(gr_poly
		(pts
			(arc
				(start 412.903162 -312.049922)
				(mid 412.496762 -312.049922)
				(end 412.903162 -312.049922)
			)
		)
		(stroke
			(width 0)
			(type solid)
		)
		(fill yes)
		(layer "In1.Cu")
		(net "P5E_PEX3_STN5_TX_DN<86>")
	)
	(gr_poly
		(pts
			(arc
				(start 412.903162 -311.099962)
				(mid 412.496762 -311.099962)
				(end 412.903162 -311.099962)
			)
		)
		(stroke
			(width 0)
			(type solid)
		)
		(fill yes)
		(layer "In1.Cu")
		(net "P5E_PEX3_STN5_TX_DP<86>")
	)
	(gr_poly
		(pts
			(arc
				(start 412.903162 -280.699464)
				(mid 412.496762 -280.699464)
				(end 412.903162 -280.699464)
			)
		)
		(stroke
			(width 0)
			(type solid)
		)
		(fill yes)
		(layer "In1.Cu")
		(net "P5E_PEX3_STN1_TX_DN<21>")
	)
	(gr_poly
		(pts
			(arc
				(start 412.903162 -279.749504)
				(mid 412.496762 -279.749504)
				(end 412.903162 -279.749504)
			)
		)
		(stroke
			(width 0)
			(type solid)
		)
		(fill yes)
		(layer "In1.Cu")
		(net "P5E_PEX3_STN1_TX_DP<21>")
	)
	(gr_poly
		(pts
			(arc
				(start 413.852868 -278.799798)
				(mid 413.446468 -278.799798)
				(end 413.852868 -278.799798)
			)
		)
		(stroke
			(width 0)
			(type solid)
		)
		(fill yes)
		(layer "In1.Cu")
		(net "P5E_PEX3_STN1_TX_DP<22>")
	)
	(gr_poly
		(pts
			(arc
				(start 413.852868 -277.849838)
				(mid 413.446468 -277.849838)
				(end 413.852868 -277.849838)
			)
		)
		(stroke
			(width 0)
			(type solid)
		)
		(fill yes)
		(layer "In1.Cu")
		(net "P5E_PEX3_STN1_TX_DN<22>")
	)
	(gr_poly
		(pts
			(arc
				(start 413.852868 -274.049744)
				(mid 413.446468 -274.049744)
				(end 413.852868 -274.049744)
			)
		)
		(stroke
			(width 0)
			(type solid)
		)
		(fill yes)
		(layer "In1.Cu")
		(net "P5E_PEX3_STN1_RX_DP<22>")
	)
	(gr_poly
		(pts
			(arc
				(start 413.852868 -273.099784)
				(mid 413.446468 -273.099784)
				(end 413.852868 -273.099784)
			)
		)
		(stroke
			(width 0)
			(type solid)
		)
		(fill yes)
		(layer "In1.Cu")
		(net "P5E_PEX3_STN1_RX_DN<22>")
	)
	(gr_poly
		(pts
			(arc
				(start 413.853122 -318.699896)
				(mid 413.446722 -318.699896)
				(end 413.853122 -318.699896)
			)
		)
		(stroke
			(width 0)
			(type solid)
		)
		(fill yes)
		(layer "In1.Cu")
		(net "P5E_PEX3_STN5_RX_DN<87>")
	)
	(gr_poly
		(pts
			(arc
				(start 413.853122 -317.749936)
				(mid 413.446722 -317.749936)
				(end 413.853122 -317.749936)
			)
		)
		(stroke
			(width 0)
			(type solid)
		)
		(fill yes)
		(layer "In1.Cu")
		(net "P5E_PEX3_STN5_RX_DP<87>")
	)
	(gr_poly
		(pts
			(arc
				(start 413.853122 -313.949842)
				(mid 413.446722 -313.949842)
				(end 413.853122 -313.949842)
			)
		)
		(stroke
			(width 0)
			(type solid)
		)
		(fill yes)
		(layer "In1.Cu")
		(net "P5E_PEX3_STN5_TX_DN<87>")
	)
	(gr_poly
		(pts
			(arc
				(start 413.853122 -312.999882)
				(mid 413.446722 -312.999882)
				(end 413.853122 -312.999882)
			)
		)
		(stroke
			(width 0)
			(type solid)
		)
		(fill yes)
		(layer "In1.Cu")
		(net "P5E_PEX3_STN5_TX_DP<87>")
	)
	(gr_poly
		(pts
			(arc
				(start 414.802828 -275.949918)
				(mid 414.396428 -275.949918)
				(end 414.802828 -275.949918)
			)
		)
		(stroke
			(width 0)
			(type solid)
		)
		(fill yes)
		(layer "In1.Cu")
		(net "P5E_PEX3_STN1_RX_DP<23>")
	)
	(gr_poly
		(pts
			(arc
				(start 414.802828 -274.999958)
				(mid 414.396428 -274.999958)
				(end 414.802828 -274.999958)
			)
		)
		(stroke
			(width 0)
			(type solid)
		)
		(fill yes)
		(layer "In1.Cu")
		(net "P5E_PEX3_STN1_RX_DN<23>")
	)
	(gr_poly
		(pts
			(arc
				(start 414.803082 -316.799722)
				(mid 414.396682 -316.799722)
				(end 414.803082 -316.799722)
			)
		)
		(stroke
			(width 0)
			(type solid)
		)
		(fill yes)
		(layer "In1.Cu")
		(net "P5E_PEX3_STN5_RX_DN<88>")
	)
	(gr_poly
		(pts
			(arc
				(start 414.803082 -315.849762)
				(mid 414.396682 -315.849762)
				(end 414.803082 -315.849762)
			)
		)
		(stroke
			(width 0)
			(type solid)
		)
		(fill yes)
		(layer "In1.Cu")
		(net "P5E_PEX3_STN5_RX_DP<88>")
	)
	(gr_poly
		(pts
			(arc
				(start 414.803082 -312.049922)
				(mid 414.396682 -312.049922)
				(end 414.803082 -312.049922)
			)
		)
		(stroke
			(width 0)
			(type solid)
		)
		(fill yes)
		(layer "In1.Cu")
		(net "P5E_PEX3_STN5_TX_DN<88>")
	)
	(gr_poly
		(pts
			(arc
				(start 414.803082 -311.099962)
				(mid 414.396682 -311.099962)
				(end 414.803082 -311.099962)
			)
		)
		(stroke
			(width 0)
			(type solid)
		)
		(fill yes)
		(layer "In1.Cu")
		(net "P5E_PEX3_STN5_TX_DP<88>")
	)
	(gr_poly
		(pts
			(arc
				(start 414.803082 -280.699464)
				(mid 414.396682 -280.699464)
				(end 414.803082 -280.699464)
			)
		)
		(stroke
			(width 0)
			(type solid)
		)
		(fill yes)
		(layer "In1.Cu")
		(net "P5E_PEX3_STN1_TX_DN<23>")
	)
	(gr_poly
		(pts
			(arc
				(start 414.803082 -279.749504)
				(mid 414.396682 -279.749504)
				(end 414.803082 -279.749504)
			)
		)
		(stroke
			(width 0)
			(type solid)
		)
		(fill yes)
		(layer "In1.Cu")
		(net "P5E_PEX3_STN1_TX_DP<23>")
	)
	(gr_poly
		(pts
			(arc
				(start 415.752788 -278.799798)
				(mid 415.346388 -278.799798)
				(end 415.752788 -278.799798)
			)
		)
		(stroke
			(width 0)
			(type solid)
		)
		(fill yes)
		(layer "In1.Cu")
		(net "P5E_PEX3_STN1_TX_DP<24>")
	)
	(gr_poly
		(pts
			(arc
				(start 415.752788 -277.849838)
				(mid 415.346388 -277.849838)
				(end 415.752788 -277.849838)
			)
		)
		(stroke
			(width 0)
			(type solid)
		)
		(fill yes)
		(layer "In1.Cu")
		(net "P5E_PEX3_STN1_TX_DN<24>")
	)
	(gr_poly
		(pts
			(arc
				(start 415.752788 -274.049744)
				(mid 415.346388 -274.049744)
				(end 415.752788 -274.049744)
			)
		)
		(stroke
			(width 0)
			(type solid)
		)
		(fill yes)
		(layer "In1.Cu")
		(net "P5E_PEX3_STN1_RX_DP<24>")
	)
	(gr_poly
		(pts
			(arc
				(start 415.752788 -273.099784)
				(mid 415.346388 -273.099784)
				(end 415.752788 -273.099784)
			)
		)
		(stroke
			(width 0)
			(type solid)
		)
		(fill yes)
		(layer "In1.Cu")
		(net "P5E_PEX3_STN1_RX_DN<24>")
	)
	(gr_poly
		(pts
			(arc
				(start 415.753042 -318.699896)
				(mid 415.346642 -318.699896)
				(end 415.753042 -318.699896)
			)
		)
		(stroke
			(width 0)
			(type solid)
		)
		(fill yes)
		(layer "In1.Cu")
		(net "P5E_PEX3_STN5_RX_DN<89>")
	)
	(gr_poly
		(pts
			(arc
				(start 415.753042 -317.749936)
				(mid 415.346642 -317.749936)
				(end 415.753042 -317.749936)
			)
		)
		(stroke
			(width 0)
			(type solid)
		)
		(fill yes)
		(layer "In1.Cu")
		(net "P5E_PEX3_STN5_RX_DP<89>")
	)
	(gr_poly
		(pts
			(arc
				(start 415.753042 -313.949842)
				(mid 415.346642 -313.949842)
				(end 415.753042 -313.949842)
			)
		)
		(stroke
			(width 0)
			(type solid)
		)
		(fill yes)
		(layer "In1.Cu")
		(net "P5E_PEX3_STN5_TX_DN<89>")
	)
	(gr_poly
		(pts
			(arc
				(start 415.753042 -312.999882)
				(mid 415.346642 -312.999882)
				(end 415.753042 -312.999882)
			)
		)
		(stroke
			(width 0)
			(type solid)
		)
		(fill yes)
		(layer "In1.Cu")
		(net "P5E_PEX3_STN5_TX_DP<89>")
	)
	(gr_poly
		(pts
			(arc
				(start 416.702748 -275.949664)
				(mid 416.296348 -275.949664)
				(end 416.702748 -275.949664)
			)
		)
		(stroke
			(width 0)
			(type solid)
		)
		(fill yes)
		(layer "In1.Cu")
		(net "P5E_PEX3_STN1_RX_DP<25>")
	)
	(gr_poly
		(pts
			(arc
				(start 416.702748 -274.999704)
				(mid 416.296348 -274.999704)
				(end 416.702748 -274.999704)
			)
		)
		(stroke
			(width 0)
			(type solid)
		)
		(fill yes)
		(layer "In1.Cu")
		(net "P5E_PEX3_STN1_RX_DN<25>")
	)
	(gr_poly
		(pts
			(arc
				(start 416.703002 -316.799722)
				(mid 416.296602 -316.799722)
				(end 416.703002 -316.799722)
			)
		)
		(stroke
			(width 0)
			(type solid)
		)
		(fill yes)
		(layer "In1.Cu")
		(net "P5E_PEX3_STN5_RX_DN<90>")
	)
	(gr_poly
		(pts
			(arc
				(start 416.703002 -315.849762)
				(mid 416.296602 -315.849762)
				(end 416.703002 -315.849762)
			)
		)
		(stroke
			(width 0)
			(type solid)
		)
		(fill yes)
		(layer "In1.Cu")
		(net "P5E_PEX3_STN5_RX_DP<90>")
	)
	(gr_poly
		(pts
			(arc
				(start 416.703002 -312.049922)
				(mid 416.296602 -312.049922)
				(end 416.703002 -312.049922)
			)
		)
		(stroke
			(width 0)
			(type solid)
		)
		(fill yes)
		(layer "In1.Cu")
		(net "P5E_PEX3_STN5_TX_DN<90>")
	)
	(gr_poly
		(pts
			(arc
				(start 416.703002 -311.099962)
				(mid 416.296602 -311.099962)
				(end 416.703002 -311.099962)
			)
		)
		(stroke
			(width 0)
			(type solid)
		)
		(fill yes)
		(layer "In1.Cu")
		(net "P5E_PEX3_STN5_TX_DP<90>")
	)
	(gr_poly
		(pts
			(arc
				(start 416.703002 -280.699464)
				(mid 416.296602 -280.699464)
				(end 416.703002 -280.699464)
			)
		)
		(stroke
			(width 0)
			(type solid)
		)
		(fill yes)
		(layer "In1.Cu")
		(net "P5E_PEX3_STN1_TX_DN<25>")
	)
	(gr_poly
		(pts
			(arc
				(start 416.703002 -279.749504)
				(mid 416.296602 -279.749504)
				(end 416.703002 -279.749504)
			)
		)
		(stroke
			(width 0)
			(type solid)
		)
		(fill yes)
		(layer "In1.Cu")
		(net "P5E_PEX3_STN1_TX_DP<25>")
	)
	(gr_poly
		(pts
			(arc
				(start 417.652962 -278.799798)
				(mid 417.246562 -278.799798)
				(end 417.652962 -278.799798)
			)
		)
		(stroke
			(width 0)
			(type solid)
		)
		(fill yes)
		(layer "In1.Cu")
		(net "P5E_PEX3_STN1_TX_DP<26>")
	)
	(gr_poly
		(pts
			(arc
				(start 417.652962 -277.849838)
				(mid 417.246562 -277.849838)
				(end 417.652962 -277.849838)
			)
		)
		(stroke
			(width 0)
			(type solid)
		)
		(fill yes)
		(layer "In1.Cu")
		(net "P5E_PEX3_STN1_TX_DN<26>")
	)
	(gr_poly
		(pts
			(arc
				(start 417.652962 -274.049744)
				(mid 417.246562 -274.049744)
				(end 417.652962 -274.049744)
			)
		)
		(stroke
			(width 0)
			(type solid)
		)
		(fill yes)
		(layer "In1.Cu")
		(net "P5E_PEX3_STN1_RX_DP<26>")
	)
	(gr_poly
		(pts
			(arc
				(start 417.652962 -273.099784)
				(mid 417.246562 -273.099784)
				(end 417.652962 -273.099784)
			)
		)
		(stroke
			(width 0)
			(type solid)
		)
		(fill yes)
		(layer "In1.Cu")
		(net "P5E_PEX3_STN1_RX_DN<26>")
	)
	(gr_poly
		(pts
			(arc
				(start 417.653216 -318.699896)
				(mid 417.246816 -318.699896)
				(end 417.653216 -318.699896)
			)
		)
		(stroke
			(width 0)
			(type solid)
		)
		(fill yes)
		(layer "In1.Cu")
		(net "P5E_PEX3_STN5_RX_DN<91>")
	)
	(gr_poly
		(pts
			(arc
				(start 417.653216 -317.749936)
				(mid 417.246816 -317.749936)
				(end 417.653216 -317.749936)
			)
		)
		(stroke
			(width 0)
			(type solid)
		)
		(fill yes)
		(layer "In1.Cu")
		(net "P5E_PEX3_STN5_RX_DP<91>")
	)
	(gr_poly
		(pts
			(arc
				(start 417.653216 -313.949842)
				(mid 417.246816 -313.949842)
				(end 417.653216 -313.949842)
			)
		)
		(stroke
			(width 0)
			(type solid)
		)
		(fill yes)
		(layer "In1.Cu")
		(net "P5E_PEX3_STN5_TX_DN<91>")
	)
	(gr_poly
		(pts
			(arc
				(start 417.653216 -312.999882)
				(mid 417.246816 -312.999882)
				(end 417.653216 -312.999882)
			)
		)
		(stroke
			(width 0)
			(type solid)
		)
		(fill yes)
		(layer "In1.Cu")
		(net "P5E_PEX3_STN5_TX_DP<91>")
	)
	(gr_poly
		(pts
			(arc
				(start 418.602668 -275.949918)
				(mid 418.196268 -275.949918)
				(end 418.602668 -275.949918)
			)
		)
		(stroke
			(width 0)
			(type solid)
		)
		(fill yes)
		(layer "In1.Cu")
		(net "P5E_PEX3_STN1_RX_DP<27>")
	)
	(gr_poly
		(pts
			(arc
				(start 418.602668 -274.999958)
				(mid 418.196268 -274.999958)
				(end 418.602668 -274.999958)
			)
		)
		(stroke
			(width 0)
			(type solid)
		)
		(fill yes)
		(layer "In1.Cu")
		(net "P5E_PEX3_STN1_RX_DN<27>")
	)
	(gr_poly
		(pts
			(arc
				(start 418.603176 -316.799722)
				(mid 418.196776 -316.799722)
				(end 418.603176 -316.799722)
			)
		)
		(stroke
			(width 0)
			(type solid)
		)
		(fill yes)
		(layer "In1.Cu")
		(net "P5E_PEX3_STN5_RX_DN<92>")
	)
	(gr_poly
		(pts
			(arc
				(start 418.603176 -315.849762)
				(mid 418.196776 -315.849762)
				(end 418.603176 -315.849762)
			)
		)
		(stroke
			(width 0)
			(type solid)
		)
		(fill yes)
		(layer "In1.Cu")
		(net "P5E_PEX3_STN5_RX_DP<92>")
	)
	(gr_poly
		(pts
			(arc
				(start 418.603176 -312.049922)
				(mid 418.196776 -312.049922)
				(end 418.603176 -312.049922)
			)
		)
		(stroke
			(width 0)
			(type solid)
		)
		(fill yes)
		(layer "In1.Cu")
		(net "P5E_PEX3_STN5_TX_DN<92>")
	)
	(gr_poly
		(pts
			(arc
				(start 418.603176 -311.099962)
				(mid 418.196776 -311.099962)
				(end 418.603176 -311.099962)
			)
		)
		(stroke
			(width 0)
			(type solid)
		)
		(fill yes)
		(layer "In1.Cu")
		(net "P5E_PEX3_STN5_TX_DP<92>")
	)
	(gr_poly
		(pts
			(arc
				(start 418.603176 -280.699464)
				(mid 418.196776 -280.699464)
				(end 418.603176 -280.699464)
			)
		)
		(stroke
			(width 0)
			(type solid)
		)
		(fill yes)
		(layer "In1.Cu")
		(net "P5E_PEX3_STN1_TX_DN<27>")
	)
	(gr_poly
		(pts
			(arc
				(start 418.603176 -279.749504)
				(mid 418.196776 -279.749504)
				(end 418.603176 -279.749504)
			)
		)
		(stroke
			(width 0)
			(type solid)
		)
		(fill yes)
		(layer "In1.Cu")
		(net "P5E_PEX3_STN1_TX_DP<27>")
	)
	(gr_poly
		(pts
			(arc
				(start 419.552882 -278.799798)
				(mid 419.146482 -278.799798)
				(end 419.552882 -278.799798)
			)
		)
		(stroke
			(width 0)
			(type solid)
		)
		(fill yes)
		(layer "In1.Cu")
		(net "P5E_PEX3_STN1_TX_DP<28>")
	)
	(gr_poly
		(pts
			(arc
				(start 419.552882 -277.849838)
				(mid 419.146482 -277.849838)
				(end 419.552882 -277.849838)
			)
		)
		(stroke
			(width 0)
			(type solid)
		)
		(fill yes)
		(layer "In1.Cu")
		(net "P5E_PEX3_STN1_TX_DN<28>")
	)
	(gr_poly
		(pts
			(arc
				(start 419.552882 -274.049744)
				(mid 419.146482 -274.049744)
				(end 419.552882 -274.049744)
			)
		)
		(stroke
			(width 0)
			(type solid)
		)
		(fill yes)
		(layer "In1.Cu")
		(net "P5E_PEX3_STN1_RX_DP<28>")
	)
	(gr_poly
		(pts
			(arc
				(start 419.552882 -273.099784)
				(mid 419.146482 -273.099784)
				(end 419.552882 -273.099784)
			)
		)
		(stroke
			(width 0)
			(type solid)
		)
		(fill yes)
		(layer "In1.Cu")
		(net "P5E_PEX3_STN1_RX_DN<28>")
	)
	(gr_poly
		(pts
			(arc
				(start 419.553136 -318.699896)
				(mid 419.146736 -318.699896)
				(end 419.553136 -318.699896)
			)
		)
		(stroke
			(width 0)
			(type solid)
		)
		(fill yes)
		(layer "In1.Cu")
		(net "P5E_PEX3_STN5_RX_DN<93>")
	)
	(gr_poly
		(pts
			(arc
				(start 419.553136 -317.749936)
				(mid 419.146736 -317.749936)
				(end 419.553136 -317.749936)
			)
		)
		(stroke
			(width 0)
			(type solid)
		)
		(fill yes)
		(layer "In1.Cu")
		(net "P5E_PEX3_STN5_RX_DP<93>")
	)
	(gr_poly
		(pts
			(arc
				(start 419.553136 -313.949842)
				(mid 419.146736 -313.949842)
				(end 419.553136 -313.949842)
			)
		)
		(stroke
			(width 0)
			(type solid)
		)
		(fill yes)
		(layer "In1.Cu")
		(net "P5E_PEX3_STN5_TX_DN<93>")
	)
	(gr_poly
		(pts
			(arc
				(start 419.553136 -312.999882)
				(mid 419.146736 -312.999882)
				(end 419.553136 -312.999882)
			)
		)
		(stroke
			(width 0)
			(type solid)
		)
		(fill yes)
		(layer "In1.Cu")
		(net "P5E_PEX3_STN5_TX_DP<93>")
	)
	(gr_poly
		(pts
			(arc
				(start 420.502842 -275.949664)
				(mid 420.096442 -275.949664)
				(end 420.502842 -275.949664)
			)
		)
		(stroke
			(width 0)
			(type solid)
		)
		(fill yes)
		(layer "In1.Cu")
		(net "P5E_PEX3_STN1_RX_DP<29>")
	)
	(gr_poly
		(pts
			(arc
				(start 420.502842 -274.999704)
				(mid 420.096442 -274.999704)
				(end 420.502842 -274.999704)
			)
		)
		(stroke
			(width 0)
			(type solid)
		)
		(fill yes)
		(layer "In1.Cu")
		(net "P5E_PEX3_STN1_RX_DN<29>")
	)
	(gr_poly
		(pts
			(arc
				(start 420.503096 -316.799722)
				(mid 420.096696 -316.799722)
				(end 420.503096 -316.799722)
			)
		)
		(stroke
			(width 0)
			(type solid)
		)
		(fill yes)
		(layer "In1.Cu")
		(net "P5E_PEX3_STN5_RX_DN<94>")
	)
	(gr_poly
		(pts
			(arc
				(start 420.503096 -315.849762)
				(mid 420.096696 -315.849762)
				(end 420.503096 -315.849762)
			)
		)
		(stroke
			(width 0)
			(type solid)
		)
		(fill yes)
		(layer "In1.Cu")
		(net "P5E_PEX3_STN5_RX_DP<94>")
	)
	(gr_poly
		(pts
			(arc
				(start 420.503096 -312.049922)
				(mid 420.096696 -312.049922)
				(end 420.503096 -312.049922)
			)
		)
		(stroke
			(width 0)
			(type solid)
		)
		(fill yes)
		(layer "In1.Cu")
		(net "P5E_PEX3_STN5_TX_DN<94>")
	)
	(gr_poly
		(pts
			(arc
				(start 420.503096 -311.099962)
				(mid 420.096696 -311.099962)
				(end 420.503096 -311.099962)
			)
		)
		(stroke
			(width 0)
			(type solid)
		)
		(fill yes)
		(layer "In1.Cu")
		(net "P5E_PEX3_STN5_TX_DP<94>")
	)
	(gr_poly
		(pts
			(arc
				(start 420.503096 -280.699464)
				(mid 420.096696 -280.699464)
				(end 420.503096 -280.699464)
			)
		)
		(stroke
			(width 0)
			(type solid)
		)
		(fill yes)
		(layer "In1.Cu")
		(net "P5E_PEX3_STN1_TX_DN<29>")
	)
	(gr_poly
		(pts
			(arc
				(start 420.503096 -279.749504)
				(mid 420.096696 -279.749504)
				(end 420.503096 -279.749504)
			)
		)
		(stroke
			(width 0)
			(type solid)
		)
		(fill yes)
		(layer "In1.Cu")
		(net "P5E_PEX3_STN1_TX_DP<29>")
	)
	(gr_poly
		(pts
			(arc
				(start 421.452802 -278.799798)
				(mid 421.046402 -278.799798)
				(end 421.452802 -278.799798)
			)
		)
		(stroke
			(width 0)
			(type solid)
		)
		(fill yes)
		(layer "In1.Cu")
		(net "P5E_PEX3_STN1_TX_DP<30>")
	)
	(gr_poly
		(pts
			(arc
				(start 421.452802 -277.849838)
				(mid 421.046402 -277.849838)
				(end 421.452802 -277.849838)
			)
		)
		(stroke
			(width 0)
			(type solid)
		)
		(fill yes)
		(layer "In1.Cu")
		(net "P5E_PEX3_STN1_TX_DN<30>")
	)
	(gr_poly
		(pts
			(arc
				(start 421.452802 -274.049744)
				(mid 421.046402 -274.049744)
				(end 421.452802 -274.049744)
			)
		)
		(stroke
			(width 0)
			(type solid)
		)
		(fill yes)
		(layer "In1.Cu")
		(net "P5E_PEX3_STN1_RX_DP<30>")
	)
	(gr_poly
		(pts
			(arc
				(start 421.452802 -273.099784)
				(mid 421.046402 -273.099784)
				(end 421.452802 -273.099784)
			)
		)
		(stroke
			(width 0)
			(type solid)
		)
		(fill yes)
		(layer "In1.Cu")
		(net "P5E_PEX3_STN1_RX_DN<30>")
	)
	(gr_poly
		(pts
			(arc
				(start 421.453056 -318.699896)
				(mid 421.046656 -318.699896)
				(end 421.453056 -318.699896)
			)
		)
		(stroke
			(width 0)
			(type solid)
		)
		(fill yes)
		(layer "In1.Cu")
		(net "P5E_PEX3_STN5_RX_DN<95>")
	)
	(gr_poly
		(pts
			(arc
				(start 421.453056 -317.749936)
				(mid 421.046656 -317.749936)
				(end 421.453056 -317.749936)
			)
		)
		(stroke
			(width 0)
			(type solid)
		)
		(fill yes)
		(layer "In1.Cu")
		(net "P5E_PEX3_STN5_RX_DP<95>")
	)
	(gr_poly
		(pts
			(arc
				(start 421.453056 -313.949842)
				(mid 421.046656 -313.949842)
				(end 421.453056 -313.949842)
			)
		)
		(stroke
			(width 0)
			(type solid)
		)
		(fill yes)
		(layer "In1.Cu")
		(net "P5E_PEX3_STN5_TX_DN<95>")
	)
	(gr_poly
		(pts
			(arc
				(start 421.453056 -312.999882)
				(mid 421.046656 -312.999882)
				(end 421.453056 -312.999882)
			)
		)
		(stroke
			(width 0)
			(type solid)
		)
		(fill yes)
		(layer "In1.Cu")
		(net "P5E_PEX3_STN5_TX_DP<95>")
	)
	(gr_poly
		(pts
			(arc
				(start 422.402762 -275.949918)
				(mid 421.996362 -275.949918)
				(end 422.402762 -275.949918)
			)
		)
		(stroke
			(width 0)
			(type solid)
		)
		(fill yes)
		(layer "In1.Cu")
		(net "P5E_PEX3_STN1_RX_DP<31>")
	)
	(gr_poly
		(pts
			(arc
				(start 422.402762 -274.999958)
				(mid 421.996362 -274.999958)
				(end 422.402762 -274.999958)
			)
		)
		(stroke
			(width 0)
			(type solid)
		)
		(fill yes)
		(layer "In1.Cu")
		(net "P5E_PEX3_STN1_RX_DN<31>")
	)
	(gr_poly
		(pts
			(arc
				(start 422.403016 -316.799722)
				(mid 421.996616 -316.799722)
				(end 422.403016 -316.799722)
			)
		)
		(stroke
			(width 0)
			(type solid)
		)
		(fill yes)
		(layer "In1.Cu")
		(net "P5E_PEX3_STN4_RX_DN<79>")
	)
	(gr_poly
		(pts
			(arc
				(start 422.403016 -315.849762)
				(mid 421.996616 -315.849762)
				(end 422.403016 -315.849762)
			)
		)
		(stroke
			(width 0)
			(type solid)
		)
		(fill yes)
		(layer "In1.Cu")
		(net "P5E_PEX3_STN4_RX_DP<79>")
	)
	(gr_poly
		(pts
			(arc
				(start 422.403016 -312.049922)
				(mid 421.996616 -312.049922)
				(end 422.403016 -312.049922)
			)
		)
		(stroke
			(width 0)
			(type solid)
		)
		(fill yes)
		(layer "In1.Cu")
		(net "P5E_PEX3_STN4_TX_DN<79>")
	)
	(gr_poly
		(pts
			(arc
				(start 422.403016 -311.099962)
				(mid 421.996616 -311.099962)
				(end 422.403016 -311.099962)
			)
		)
		(stroke
			(width 0)
			(type solid)
		)
		(fill yes)
		(layer "In1.Cu")
		(net "P5E_PEX3_STN4_TX_DP<79>")
	)
	(gr_poly
		(pts
			(arc
				(start 422.403016 -280.699464)
				(mid 421.996616 -280.699464)
				(end 422.403016 -280.699464)
			)
		)
		(stroke
			(width 0)
			(type solid)
		)
		(fill yes)
		(layer "In1.Cu")
		(net "P5E_PEX3_STN1_TX_DN<31>")
	)
	(gr_poly
		(pts
			(arc
				(start 422.403016 -279.749504)
				(mid 421.996616 -279.749504)
				(end 422.403016 -279.749504)
			)
		)
		(stroke
			(width 0)
			(type solid)
		)
		(fill yes)
		(layer "In1.Cu")
		(net "P5E_PEX3_STN1_TX_DP<31>")
	)
	(gr_poly
		(pts
			(arc
				(start 423.352976 -278.799798)
				(mid 422.946576 -278.799798)
				(end 423.352976 -278.799798)
			)
		)
		(stroke
			(width 0)
			(type solid)
		)
		(fill yes)
		(layer "In1.Cu")
		(net "P5E_PEX3_STN0_TX_DP<15>")
	)
	(gr_poly
		(pts
			(arc
				(start 423.352976 -277.849838)
				(mid 422.946576 -277.849838)
				(end 423.352976 -277.849838)
			)
		)
		(stroke
			(width 0)
			(type solid)
		)
		(fill yes)
		(layer "In1.Cu")
		(net "P5E_PEX3_STN0_TX_DN<15>")
	)
	(gr_poly
		(pts
			(arc
				(start 423.352976 -274.049744)
				(mid 422.946576 -274.049744)
				(end 423.352976 -274.049744)
			)
		)
		(stroke
			(width 0)
			(type solid)
		)
		(fill yes)
		(layer "In1.Cu")
		(net "P5E_PEX3_STN0_RX_DP<15>")
	)
	(gr_poly
		(pts
			(arc
				(start 423.352976 -273.099784)
				(mid 422.946576 -273.099784)
				(end 423.352976 -273.099784)
			)
		)
		(stroke
			(width 0)
			(type solid)
		)
		(fill yes)
		(layer "In1.Cu")
		(net "P5E_PEX3_STN0_RX_DN<15>")
	)
	(gr_poly
		(pts
			(arc
				(start 423.35323 -318.699896)
				(mid 422.94683 -318.699896)
				(end 423.35323 -318.699896)
			)
		)
		(stroke
			(width 0)
			(type solid)
		)
		(fill yes)
		(layer "In1.Cu")
		(net "P5E_PEX3_STN4_RX_DN<78>")
	)
	(gr_poly
		(pts
			(arc
				(start 423.35323 -317.749936)
				(mid 422.94683 -317.749936)
				(end 423.35323 -317.749936)
			)
		)
		(stroke
			(width 0)
			(type solid)
		)
		(fill yes)
		(layer "In1.Cu")
		(net "P5E_PEX3_STN4_RX_DP<78>")
	)
	(gr_poly
		(pts
			(arc
				(start 423.35323 -313.949842)
				(mid 422.94683 -313.949842)
				(end 423.35323 -313.949842)
			)
		)
		(stroke
			(width 0)
			(type solid)
		)
		(fill yes)
		(layer "In1.Cu")
		(net "P5E_PEX3_STN4_TX_DN<78>")
	)
	(gr_poly
		(pts
			(arc
				(start 423.35323 -312.999882)
				(mid 422.94683 -312.999882)
				(end 423.35323 -312.999882)
			)
		)
		(stroke
			(width 0)
			(type solid)
		)
		(fill yes)
		(layer "In1.Cu")
		(net "P5E_PEX3_STN4_TX_DP<78>")
	)
	(gr_poly
		(pts
			(arc
				(start 423.35323 -308.249828)
				(mid 422.94683 -308.249828)
				(end 423.35323 -308.249828)
			)
		)
		(stroke
			(width 0)
			(type solid)
		)
		(fill yes)
		(layer "In1.Cu")
		(net "P5E_PEX3_STN4_TX_DP<68>")
	)
	(gr_poly
		(pts
			(arc
				(start 423.35323 -306.349908)
				(mid 422.94683 -306.349908)
				(end 423.35323 -306.349908)
			)
		)
		(stroke
			(width 0)
			(type solid)
		)
		(fill yes)
		(layer "In1.Cu")
		(net "P5E_PEX3_STN4_TX_DP<66>")
	)
	(gr_poly
		(pts
			(arc
				(start 423.35323 -304.449734)
				(mid 422.94683 -304.449734)
				(end 423.35323 -304.449734)
			)
		)
		(stroke
			(width 0)
			(type solid)
		)
		(fill yes)
		(layer "In1.Cu")
		(net "P5E_PEX3_STN4_TX_DP<64>")
	)
	(gr_poly
		(pts
			(arc
				(start 423.35323 -287.349946)
				(mid 422.94683 -287.349946)
				(end 423.35323 -287.349946)
			)
		)
		(stroke
			(width 0)
			(type solid)
		)
		(fill yes)
		(layer "In1.Cu")
		(net "P5E_PEX3_STN0_TX_DP<1>")
	)
	(gr_poly
		(pts
			(arc
				(start 423.35323 -285.449772)
				(mid 422.94683 -285.449772)
				(end 423.35323 -285.449772)
			)
		)
		(stroke
			(width 0)
			(type solid)
		)
		(fill yes)
		(layer "In1.Cu")
		(net "P5E_PEX3_STN0_TX_DP<3>")
	)
	(gr_poly
		(pts
			(arc
				(start 423.35323 -283.549852)
				(mid 422.94683 -283.549852)
				(end 423.35323 -283.549852)
			)
		)
		(stroke
			(width 0)
			(type solid)
		)
		(fill yes)
		(layer "In1.Cu")
		(net "P5E_PEX3_STN0_TX_DP<5>")
	)
	(gr_poly
		(pts
			(arc
				(start 424.302936 -275.949664)
				(mid 423.896536 -275.949664)
				(end 424.302936 -275.949664)
			)
		)
		(stroke
			(width 0)
			(type solid)
		)
		(fill yes)
		(layer "In1.Cu")
		(net "P5E_PEX3_STN0_RX_DP<14>")
	)
	(gr_poly
		(pts
			(arc
				(start 424.302936 -274.999704)
				(mid 423.896536 -274.999704)
				(end 424.302936 -274.999704)
			)
		)
		(stroke
			(width 0)
			(type solid)
		)
		(fill yes)
		(layer "In1.Cu")
		(net "P5E_PEX3_STN0_RX_DN<14>")
	)
	(gr_poly
		(pts
			(arc
				(start 424.30319 -316.799722)
				(mid 423.89679 -316.799722)
				(end 424.30319 -316.799722)
			)
		)
		(stroke
			(width 0)
			(type solid)
		)
		(fill yes)
		(layer "In1.Cu")
		(net "P5E_PEX3_STN4_RX_DN<77>")
	)
	(gr_poly
		(pts
			(arc
				(start 424.30319 -315.849762)
				(mid 423.89679 -315.849762)
				(end 424.30319 -315.849762)
			)
		)
		(stroke
			(width 0)
			(type solid)
		)
		(fill yes)
		(layer "In1.Cu")
		(net "P5E_PEX3_STN4_RX_DP<77>")
	)
	(gr_poly
		(pts
			(arc
				(start 424.30319 -312.049922)
				(mid 423.89679 -312.049922)
				(end 424.30319 -312.049922)
			)
		)
		(stroke
			(width 0)
			(type solid)
		)
		(fill yes)
		(layer "In1.Cu")
		(net "P5E_PEX3_STN4_TX_DN<77>")
	)
	(gr_poly
		(pts
			(arc
				(start 424.30319 -311.099962)
				(mid 423.89679 -311.099962)
				(end 424.30319 -311.099962)
			)
		)
		(stroke
			(width 0)
			(type solid)
		)
		(fill yes)
		(layer "In1.Cu")
		(net "P5E_PEX3_STN4_TX_DP<77>")
	)
	(gr_poly
		(pts
			(arc
				(start 424.30319 -308.249828)
				(mid 423.89679 -308.249828)
				(end 424.30319 -308.249828)
			)
		)
		(stroke
			(width 0)
			(type solid)
		)
		(fill yes)
		(layer "In1.Cu")
		(net "P5E_PEX3_STN4_TX_DN<68>")
	)
	(gr_poly
		(pts
			(arc
				(start 424.30319 -306.349908)
				(mid 423.89679 -306.349908)
				(end 424.30319 -306.349908)
			)
		)
		(stroke
			(width 0)
			(type solid)
		)
		(fill yes)
		(layer "In1.Cu")
		(net "P5E_PEX3_STN4_TX_DN<66>")
	)
	(gr_poly
		(pts
			(arc
				(start 424.30319 -304.449734)
				(mid 423.89679 -304.449734)
				(end 424.30319 -304.449734)
			)
		)
		(stroke
			(width 0)
			(type solid)
		)
		(fill yes)
		(layer "In1.Cu")
		(net "P5E_PEX3_STN4_TX_DN<64>")
	)
	(gr_poly
		(pts
			(arc
				(start 424.30319 -287.349946)
				(mid 423.89679 -287.349946)
				(end 424.30319 -287.349946)
			)
		)
		(stroke
			(width 0)
			(type solid)
		)
		(fill yes)
		(layer "In1.Cu")
		(net "P5E_PEX3_STN0_TX_DN<1>")
	)
	(gr_poly
		(pts
			(arc
				(start 424.30319 -285.449772)
				(mid 423.89679 -285.449772)
				(end 424.30319 -285.449772)
			)
		)
		(stroke
			(width 0)
			(type solid)
		)
		(fill yes)
		(layer "In1.Cu")
		(net "P5E_PEX3_STN0_TX_DN<3>")
	)
	(gr_poly
		(pts
			(arc
				(start 424.30319 -283.549852)
				(mid 423.89679 -283.549852)
				(end 424.30319 -283.549852)
			)
		)
		(stroke
			(width 0)
			(type solid)
		)
		(fill yes)
		(layer "In1.Cu")
		(net "P5E_PEX3_STN0_TX_DN<5>")
	)
	(gr_poly
		(pts
			(arc
				(start 424.30319 -280.699464)
				(mid 423.89679 -280.699464)
				(end 424.30319 -280.699464)
			)
		)
		(stroke
			(width 0)
			(type solid)
		)
		(fill yes)
		(layer "In1.Cu")
		(net "P5E_PEX3_STN0_TX_DN<14>")
	)
	(gr_poly
		(pts
			(arc
				(start 424.30319 -279.749504)
				(mid 423.89679 -279.749504)
				(end 424.30319 -279.749504)
			)
		)
		(stroke
			(width 0)
			(type solid)
		)
		(fill yes)
		(layer "In1.Cu")
		(net "P5E_PEX3_STN0_TX_DP<14>")
	)
	(gr_poly
		(pts
			(arc
				(start 425.252896 -278.799798)
				(mid 424.846496 -278.799798)
				(end 425.252896 -278.799798)
			)
		)
		(stroke
			(width 0)
			(type solid)
		)
		(fill yes)
		(layer "In1.Cu")
		(net "P5E_PEX3_STN0_TX_DP<13>")
	)
	(gr_poly
		(pts
			(arc
				(start 425.252896 -277.849838)
				(mid 424.846496 -277.849838)
				(end 425.252896 -277.849838)
			)
		)
		(stroke
			(width 0)
			(type solid)
		)
		(fill yes)
		(layer "In1.Cu")
		(net "P5E_PEX3_STN0_TX_DN<13>")
	)
	(gr_poly
		(pts
			(arc
				(start 425.252896 -274.049744)
				(mid 424.846496 -274.049744)
				(end 425.252896 -274.049744)
			)
		)
		(stroke
			(width 0)
			(type solid)
		)
		(fill yes)
		(layer "In1.Cu")
		(net "P5E_PEX3_STN0_RX_DP<13>")
	)
	(gr_poly
		(pts
			(arc
				(start 425.252896 -273.099784)
				(mid 424.846496 -273.099784)
				(end 425.252896 -273.099784)
			)
		)
		(stroke
			(width 0)
			(type solid)
		)
		(fill yes)
		(layer "In1.Cu")
		(net "P5E_PEX3_STN0_RX_DN<13>")
	)
	(gr_poly
		(pts
			(arc
				(start 425.25315 -318.699896)
				(mid 424.84675 -318.699896)
				(end 425.25315 -318.699896)
			)
		)
		(stroke
			(width 0)
			(type solid)
		)
		(fill yes)
		(layer "In1.Cu")
		(net "P5E_PEX3_STN4_RX_DN<76>")
	)
	(gr_poly
		(pts
			(arc
				(start 425.25315 -317.749936)
				(mid 424.84675 -317.749936)
				(end 425.25315 -317.749936)
			)
		)
		(stroke
			(width 0)
			(type solid)
		)
		(fill yes)
		(layer "In1.Cu")
		(net "P5E_PEX3_STN4_RX_DP<76>")
	)
	(gr_poly
		(pts
			(arc
				(start 425.25315 -313.949842)
				(mid 424.84675 -313.949842)
				(end 425.25315 -313.949842)
			)
		)
		(stroke
			(width 0)
			(type solid)
		)
		(fill yes)
		(layer "In1.Cu")
		(net "P5E_PEX3_STN4_TX_DN<76>")
	)
	(gr_poly
		(pts
			(arc
				(start 425.25315 -312.999882)
				(mid 424.84675 -312.999882)
				(end 425.25315 -312.999882)
			)
		)
		(stroke
			(width 0)
			(type solid)
		)
		(fill yes)
		(layer "In1.Cu")
		(net "P5E_PEX3_STN4_TX_DP<76>")
	)
	(gr_poly
		(pts
			(arc
				(start 425.25315 -309.199788)
				(mid 424.84675 -309.199788)
				(end 425.25315 -309.199788)
			)
		)
		(stroke
			(width 0)
			(type solid)
		)
		(fill yes)
		(layer "In1.Cu")
		(net "P5E_PEX3_STN4_TX_DP<69>")
	)
	(gr_poly
		(pts
			(arc
				(start 425.25315 -307.299868)
				(mid 424.84675 -307.299868)
				(end 425.25315 -307.299868)
			)
		)
		(stroke
			(width 0)
			(type solid)
		)
		(fill yes)
		(layer "In1.Cu")
		(net "P5E_PEX3_STN4_TX_DP<67>")
	)
	(gr_poly
		(pts
			(arc
				(start 425.25315 -305.399948)
				(mid 424.84675 -305.399948)
				(end 425.25315 -305.399948)
			)
		)
		(stroke
			(width 0)
			(type solid)
		)
		(fill yes)
		(layer "In1.Cu")
		(net "P5E_PEX3_STN4_TX_DP<65>")
	)
	(gr_poly
		(pts
			(arc
				(start 425.25315 -288.299906)
				(mid 424.84675 -288.299906)
				(end 425.25315 -288.299906)
			)
		)
		(stroke
			(width 0)
			(type solid)
		)
		(fill yes)
		(layer "In1.Cu")
		(net "P5E_PEX3_STN0_TX_DP<0>")
	)
	(gr_poly
		(pts
			(arc
				(start 425.25315 -286.399986)
				(mid 424.84675 -286.399986)
				(end 425.25315 -286.399986)
			)
		)
		(stroke
			(width 0)
			(type solid)
		)
		(fill yes)
		(layer "In1.Cu")
		(net "P5E_PEX3_STN0_TX_DP<2>")
	)
	(gr_poly
		(pts
			(arc
				(start 425.25315 -284.499812)
				(mid 424.84675 -284.499812)
				(end 425.25315 -284.499812)
			)
		)
		(stroke
			(width 0)
			(type solid)
		)
		(fill yes)
		(layer "In1.Cu")
		(net "P5E_PEX3_STN0_TX_DP<4>")
	)
	(gr_poly
		(pts
			(arc
				(start 425.25315 -282.599892)
				(mid 424.84675 -282.599892)
				(end 425.25315 -282.599892)
			)
		)
		(stroke
			(width 0)
			(type solid)
		)
		(fill yes)
		(layer "In1.Cu")
		(net "P5E_PEX3_STN0_TX_DP<6>")
	)
	(gr_poly
		(pts
			(arc
				(start 426.202856 -275.949918)
				(mid 425.796456 -275.949918)
				(end 426.202856 -275.949918)
			)
		)
		(stroke
			(width 0)
			(type solid)
		)
		(fill yes)
		(layer "In1.Cu")
		(net "P5E_PEX3_STN0_RX_DP<12>")
	)
	(gr_poly
		(pts
			(arc
				(start 426.202856 -274.999958)
				(mid 425.796456 -274.999958)
				(end 426.202856 -274.999958)
			)
		)
		(stroke
			(width 0)
			(type solid)
		)
		(fill yes)
		(layer "In1.Cu")
		(net "P5E_PEX3_STN0_RX_DN<12>")
	)
	(gr_poly
		(pts
			(arc
				(start 426.20311 -316.799722)
				(mid 425.79671 -316.799722)
				(end 426.20311 -316.799722)
			)
		)
		(stroke
			(width 0)
			(type solid)
		)
		(fill yes)
		(layer "In1.Cu")
		(net "P5E_PEX3_STN4_RX_DN<75>")
	)
	(gr_poly
		(pts
			(arc
				(start 426.20311 -315.849762)
				(mid 425.79671 -315.849762)
				(end 426.20311 -315.849762)
			)
		)
		(stroke
			(width 0)
			(type solid)
		)
		(fill yes)
		(layer "In1.Cu")
		(net "P5E_PEX3_STN4_RX_DP<75>")
	)
	(gr_poly
		(pts
			(arc
				(start 426.20311 -312.049922)
				(mid 425.79671 -312.049922)
				(end 426.20311 -312.049922)
			)
		)
		(stroke
			(width 0)
			(type solid)
		)
		(fill yes)
		(layer "In1.Cu")
		(net "P5E_PEX3_STN4_TX_DN<75>")
	)
	(gr_poly
		(pts
			(arc
				(start 426.20311 -311.099962)
				(mid 425.79671 -311.099962)
				(end 426.20311 -311.099962)
			)
		)
		(stroke
			(width 0)
			(type solid)
		)
		(fill yes)
		(layer "In1.Cu")
		(net "P5E_PEX3_STN4_TX_DP<75>")
	)
	(gr_poly
		(pts
			(arc
				(start 426.20311 -309.199788)
				(mid 425.79671 -309.199788)
				(end 426.20311 -309.199788)
			)
		)
		(stroke
			(width 0)
			(type solid)
		)
		(fill yes)
		(layer "In1.Cu")
		(net "P5E_PEX3_STN4_TX_DN<69>")
	)
	(gr_poly
		(pts
			(arc
				(start 426.20311 -307.299868)
				(mid 425.79671 -307.299868)
				(end 426.20311 -307.299868)
			)
		)
		(stroke
			(width 0)
			(type solid)
		)
		(fill yes)
		(layer "In1.Cu")
		(net "P5E_PEX3_STN4_TX_DN<67>")
	)
	(gr_poly
		(pts
			(arc
				(start 426.20311 -305.399948)
				(mid 425.79671 -305.399948)
				(end 426.20311 -305.399948)
			)
		)
		(stroke
			(width 0)
			(type solid)
		)
		(fill yes)
		(layer "In1.Cu")
		(net "P5E_PEX3_STN4_TX_DN<65>")
	)
	(gr_poly
		(pts
			(arc
				(start 426.20311 -288.299906)
				(mid 425.79671 -288.299906)
				(end 426.20311 -288.299906)
			)
		)
		(stroke
			(width 0)
			(type solid)
		)
		(fill yes)
		(layer "In1.Cu")
		(net "P5E_PEX3_STN0_TX_DN<0>")
	)
	(gr_poly
		(pts
			(arc
				(start 426.20311 -286.399986)
				(mid 425.79671 -286.399986)
				(end 426.20311 -286.399986)
			)
		)
		(stroke
			(width 0)
			(type solid)
		)
		(fill yes)
		(layer "In1.Cu")
		(net "P5E_PEX3_STN0_TX_DN<2>")
	)
	(gr_poly
		(pts
			(arc
				(start 426.20311 -284.499812)
				(mid 425.79671 -284.499812)
				(end 426.20311 -284.499812)
			)
		)
		(stroke
			(width 0)
			(type solid)
		)
		(fill yes)
		(layer "In1.Cu")
		(net "P5E_PEX3_STN0_TX_DN<4>")
	)
	(gr_poly
		(pts
			(arc
				(start 426.20311 -282.599892)
				(mid 425.79671 -282.599892)
				(end 426.20311 -282.599892)
			)
		)
		(stroke
			(width 0)
			(type solid)
		)
		(fill yes)
		(layer "In1.Cu")
		(net "P5E_PEX3_STN0_TX_DN<6>")
	)
	(gr_poly
		(pts
			(arc
				(start 426.20311 -280.699464)
				(mid 425.79671 -280.699464)
				(end 426.20311 -280.699464)
			)
		)
		(stroke
			(width 0)
			(type solid)
		)
		(fill yes)
		(layer "In1.Cu")
		(net "P5E_PEX3_STN0_TX_DN<12>")
	)
	(gr_poly
		(pts
			(arc
				(start 426.20311 -279.749504)
				(mid 425.79671 -279.749504)
				(end 426.20311 -279.749504)
			)
		)
		(stroke
			(width 0)
			(type solid)
		)
		(fill yes)
		(layer "In1.Cu")
		(net "P5E_PEX3_STN0_TX_DP<12>")
	)
	(gr_poly
		(pts
			(arc
				(start 427.152816 -278.799798)
				(mid 426.746416 -278.799798)
				(end 427.152816 -278.799798)
			)
		)
		(stroke
			(width 0)
			(type solid)
		)
		(fill yes)
		(layer "In1.Cu")
		(net "P5E_PEX3_STN0_TX_DP<11>")
	)
	(gr_poly
		(pts
			(arc
				(start 427.152816 -277.849838)
				(mid 426.746416 -277.849838)
				(end 427.152816 -277.849838)
			)
		)
		(stroke
			(width 0)
			(type solid)
		)
		(fill yes)
		(layer "In1.Cu")
		(net "P5E_PEX3_STN0_TX_DN<11>")
	)
	(gr_poly
		(pts
			(arc
				(start 427.152816 -274.049744)
				(mid 426.746416 -274.049744)
				(end 427.152816 -274.049744)
			)
		)
		(stroke
			(width 0)
			(type solid)
		)
		(fill yes)
		(layer "In1.Cu")
		(net "P5E_PEX3_STN0_RX_DP<11>")
	)
	(gr_poly
		(pts
			(arc
				(start 427.152816 -273.099784)
				(mid 426.746416 -273.099784)
				(end 427.152816 -273.099784)
			)
		)
		(stroke
			(width 0)
			(type solid)
		)
		(fill yes)
		(layer "In1.Cu")
		(net "P5E_PEX3_STN0_RX_DN<11>")
	)
	(gr_poly
		(pts
			(arc
				(start 427.15307 -318.699896)
				(mid 426.74667 -318.699896)
				(end 427.15307 -318.699896)
			)
		)
		(stroke
			(width 0)
			(type solid)
		)
		(fill yes)
		(layer "In1.Cu")
		(net "P5E_PEX3_STN4_RX_DN<74>")
	)
	(gr_poly
		(pts
			(arc
				(start 427.15307 -317.749936)
				(mid 426.74667 -317.749936)
				(end 427.15307 -317.749936)
			)
		)
		(stroke
			(width 0)
			(type solid)
		)
		(fill yes)
		(layer "In1.Cu")
		(net "P5E_PEX3_STN4_RX_DP<74>")
	)
	(gr_poly
		(pts
			(arc
				(start 427.15307 -313.949842)
				(mid 426.74667 -313.949842)
				(end 427.15307 -313.949842)
			)
		)
		(stroke
			(width 0)
			(type solid)
		)
		(fill yes)
		(layer "In1.Cu")
		(net "P5E_PEX3_STN4_TX_DN<74>")
	)
	(gr_poly
		(pts
			(arc
				(start 427.15307 -312.999882)
				(mid 426.74667 -312.999882)
				(end 427.15307 -312.999882)
			)
		)
		(stroke
			(width 0)
			(type solid)
		)
		(fill yes)
		(layer "In1.Cu")
		(net "P5E_PEX3_STN4_TX_DP<74>")
	)
	(gr_poly
		(pts
			(arc
				(start 428.102776 -275.949918)
				(mid 427.696376 -275.949918)
				(end 428.102776 -275.949918)
			)
		)
		(stroke
			(width 0)
			(type solid)
		)
		(fill yes)
		(layer "In1.Cu")
		(net "P5E_PEX3_STN0_RX_DP<10>")
	)
	(gr_poly
		(pts
			(arc
				(start 428.102776 -274.999958)
				(mid 427.696376 -274.999958)
				(end 428.102776 -274.999958)
			)
		)
		(stroke
			(width 0)
			(type solid)
		)
		(fill yes)
		(layer "In1.Cu")
		(net "P5E_PEX3_STN0_RX_DN<10>")
	)
	(gr_poly
		(pts
			(arc
				(start 428.10303 -316.799722)
				(mid 427.69663 -316.799722)
				(end 428.10303 -316.799722)
			)
		)
		(stroke
			(width 0)
			(type solid)
		)
		(fill yes)
		(layer "In1.Cu")
		(net "P5E_PEX3_STN4_RX_DN<73>")
	)
	(gr_poly
		(pts
			(arc
				(start 428.10303 -315.849762)
				(mid 427.69663 -315.849762)
				(end 428.10303 -315.849762)
			)
		)
		(stroke
			(width 0)
			(type solid)
		)
		(fill yes)
		(layer "In1.Cu")
		(net "P5E_PEX3_STN4_RX_DP<73>")
	)
	(gr_poly
		(pts
			(arc
				(start 428.10303 -312.049922)
				(mid 427.69663 -312.049922)
				(end 428.10303 -312.049922)
			)
		)
		(stroke
			(width 0)
			(type solid)
		)
		(fill yes)
		(layer "In1.Cu")
		(net "P5E_PEX3_STN4_TX_DN<73>")
	)
	(gr_poly
		(pts
			(arc
				(start 428.10303 -311.099962)
				(mid 427.69663 -311.099962)
				(end 428.10303 -311.099962)
			)
		)
		(stroke
			(width 0)
			(type solid)
		)
		(fill yes)
		(layer "In1.Cu")
		(net "P5E_PEX3_STN4_TX_DP<73>")
	)
	(gr_poly
		(pts
			(arc
				(start 428.10303 -309.199788)
				(mid 427.69663 -309.199788)
				(end 428.10303 -309.199788)
			)
		)
		(stroke
			(width 0)
			(type solid)
		)
		(fill yes)
		(layer "In1.Cu")
		(net "P5E_PEX3_STN4_RX_DP<69>")
	)
	(gr_poly
		(pts
			(arc
				(start 428.10303 -307.299868)
				(mid 427.69663 -307.299868)
				(end 428.10303 -307.299868)
			)
		)
		(stroke
			(width 0)
			(type solid)
		)
		(fill yes)
		(layer "In1.Cu")
		(net "P5E_PEX3_STN4_RX_DP<67>")
	)
	(gr_poly
		(pts
			(arc
				(start 428.10303 -305.399948)
				(mid 427.69663 -305.399948)
				(end 428.10303 -305.399948)
			)
		)
		(stroke
			(width 0)
			(type solid)
		)
		(fill yes)
		(layer "In1.Cu")
		(net "P5E_PEX3_STN4_RX_DP<65>")
	)
	(gr_poly
		(pts
			(arc
				(start 428.10303 -288.299906)
				(mid 427.69663 -288.299906)
				(end 428.10303 -288.299906)
			)
		)
		(stroke
			(width 0)
			(type solid)
		)
		(fill yes)
		(layer "In1.Cu")
		(net "P5E_PEX3_STN0_RX_DP<0>")
	)
	(gr_poly
		(pts
			(arc
				(start 428.10303 -286.399732)
				(mid 427.69663 -286.399732)
				(end 428.10303 -286.399732)
			)
		)
		(stroke
			(width 0)
			(type solid)
		)
		(fill yes)
		(layer "In1.Cu")
		(net "P5E_PEX3_STN0_RX_DP<2>")
	)
	(gr_poly
		(pts
			(arc
				(start 428.10303 -284.499812)
				(mid 427.69663 -284.499812)
				(end 428.10303 -284.499812)
			)
		)
		(stroke
			(width 0)
			(type solid)
		)
		(fill yes)
		(layer "In1.Cu")
		(net "P5E_PEX3_STN0_RX_DP<4>")
	)
	(gr_poly
		(pts
			(arc
				(start 428.10303 -282.599892)
				(mid 427.69663 -282.599892)
				(end 428.10303 -282.599892)
			)
		)
		(stroke
			(width 0)
			(type solid)
		)
		(fill yes)
		(layer "In1.Cu")
		(net "P5E_PEX3_STN0_RX_DP<6>")
	)
	(gr_poly
		(pts
			(arc
				(start 428.10303 -280.699718)
				(mid 427.69663 -280.699718)
				(end 428.10303 -280.699718)
			)
		)
		(stroke
			(width 0)
			(type solid)
		)
		(fill yes)
		(layer "In1.Cu")
		(net "P5E_PEX3_STN0_TX_DP<10>")
	)
	(gr_poly
		(pts
			(arc
				(start 428.10303 -279.749758)
				(mid 427.69663 -279.749758)
				(end 428.10303 -279.749758)
			)
		)
		(stroke
			(width 0)
			(type solid)
		)
		(fill yes)
		(layer "In1.Cu")
		(net "P5E_PEX3_STN0_TX_DN<10>")
	)
	(gr_poly
		(pts
			(arc
				(start 429.052736 -274.049744)
				(mid 428.646336 -274.049744)
				(end 429.052736 -274.049744)
			)
		)
		(stroke
			(width 0)
			(type solid)
		)
		(fill yes)
		(layer "In1.Cu")
		(net "P5E_PEX3_STN0_RX_DP<9>")
	)
	(gr_poly
		(pts
			(arc
				(start 429.052736 -273.099784)
				(mid 428.646336 -273.099784)
				(end 429.052736 -273.099784)
			)
		)
		(stroke
			(width 0)
			(type solid)
		)
		(fill yes)
		(layer "In1.Cu")
		(net "P5E_PEX3_STN0_RX_DN<9>")
	)
	(gr_poly
		(pts
			(arc
				(start 429.05299 -318.699896)
				(mid 428.64659 -318.699896)
				(end 429.05299 -318.699896)
			)
		)
		(stroke
			(width 0)
			(type solid)
		)
		(fill yes)
		(layer "In1.Cu")
		(net "P5E_PEX3_STN4_RX_DN<72>")
	)
	(gr_poly
		(pts
			(arc
				(start 429.05299 -317.749936)
				(mid 428.64659 -317.749936)
				(end 429.05299 -317.749936)
			)
		)
		(stroke
			(width 0)
			(type solid)
		)
		(fill yes)
		(layer "In1.Cu")
		(net "P5E_PEX3_STN4_RX_DP<72>")
	)
	(gr_poly
		(pts
			(arc
				(start 429.05299 -313.949842)
				(mid 428.64659 -313.949842)
				(end 429.05299 -313.949842)
			)
		)
		(stroke
			(width 0)
			(type solid)
		)
		(fill yes)
		(layer "In1.Cu")
		(net "P5E_PEX3_STN4_TX_DN<72>")
	)
	(gr_poly
		(pts
			(arc
				(start 429.05299 -312.999882)
				(mid 428.64659 -312.999882)
				(end 429.05299 -312.999882)
			)
		)
		(stroke
			(width 0)
			(type solid)
		)
		(fill yes)
		(layer "In1.Cu")
		(net "P5E_PEX3_STN4_TX_DP<72>")
	)
	(gr_poly
		(pts
			(arc
				(start 429.05299 -309.199788)
				(mid 428.64659 -309.199788)
				(end 429.05299 -309.199788)
			)
		)
		(stroke
			(width 0)
			(type solid)
		)
		(fill yes)
		(layer "In1.Cu")
		(net "P5E_PEX3_STN4_RX_DN<69>")
	)
	(gr_poly
		(pts
			(arc
				(start 429.05299 -307.299868)
				(mid 428.64659 -307.299868)
				(end 429.05299 -307.299868)
			)
		)
		(stroke
			(width 0)
			(type solid)
		)
		(fill yes)
		(layer "In1.Cu")
		(net "P5E_PEX3_STN4_RX_DN<67>")
	)
	(gr_poly
		(pts
			(arc
				(start 429.05299 -305.399948)
				(mid 428.64659 -305.399948)
				(end 429.05299 -305.399948)
			)
		)
		(stroke
			(width 0)
			(type solid)
		)
		(fill yes)
		(layer "In1.Cu")
		(net "P5E_PEX3_STN4_RX_DN<65>")
	)
	(gr_poly
		(pts
			(arc
				(start 429.05299 -288.299906)
				(mid 428.64659 -288.299906)
				(end 429.05299 -288.299906)
			)
		)
		(stroke
			(width 0)
			(type solid)
		)
		(fill yes)
		(layer "In1.Cu")
		(net "P5E_PEX3_STN0_RX_DN<0>")
	)
	(gr_poly
		(pts
			(arc
				(start 429.05299 -286.399732)
				(mid 428.64659 -286.399732)
				(end 429.05299 -286.399732)
			)
		)
		(stroke
			(width 0)
			(type solid)
		)
		(fill yes)
		(layer "In1.Cu")
		(net "P5E_PEX3_STN0_RX_DN<2>")
	)
	(gr_poly
		(pts
			(arc
				(start 429.05299 -284.499812)
				(mid 428.64659 -284.499812)
				(end 429.05299 -284.499812)
			)
		)
		(stroke
			(width 0)
			(type solid)
		)
		(fill yes)
		(layer "In1.Cu")
		(net "P5E_PEX3_STN0_RX_DN<4>")
	)
	(gr_poly
		(pts
			(arc
				(start 429.05299 -282.599892)
				(mid 428.64659 -282.599892)
				(end 429.05299 -282.599892)
			)
		)
		(stroke
			(width 0)
			(type solid)
		)
		(fill yes)
		(layer "In1.Cu")
		(net "P5E_PEX3_STN0_RX_DN<6>")
	)
	(gr_poly
		(pts
			(arc
				(start 429.05299 -278.799798)
				(mid 428.64659 -278.799798)
				(end 429.05299 -278.799798)
			)
		)
		(stroke
			(width 0)
			(type solid)
		)
		(fill yes)
		(layer "In1.Cu")
		(net "P5E_PEX3_STN0_TX_DP<9>")
	)
	(gr_poly
		(pts
			(arc
				(start 429.05299 -277.849838)
				(mid 428.64659 -277.849838)
				(end 429.05299 -277.849838)
			)
		)
		(stroke
			(width 0)
			(type solid)
		)
		(fill yes)
		(layer "In1.Cu")
		(net "P5E_PEX3_STN0_TX_DN<9>")
	)
	(gr_poly
		(pts
			(arc
				(start 430.003204 -316.799722)
				(mid 429.596804 -316.799722)
				(end 430.003204 -316.799722)
			)
		)
		(stroke
			(width 0)
			(type solid)
		)
		(fill yes)
		(layer "In1.Cu")
		(net "P5E_PEX3_STN4_RX_DP<71>")
	)
	(gr_poly
		(pts
			(arc
				(start 430.003204 -314.899802)
				(mid 429.596804 -314.899802)
				(end 430.003204 -314.899802)
			)
		)
		(stroke
			(width 0)
			(type solid)
		)
		(fill yes)
		(layer "In1.Cu")
		(net "P5E_PEX3_STN4_TX_DP<71>")
	)
	(gr_poly
		(pts
			(arc
				(start 430.003204 -312.049922)
				(mid 429.596804 -312.049922)
				(end 430.003204 -312.049922)
			)
		)
		(stroke
			(width 0)
			(type solid)
		)
		(fill yes)
		(layer "In1.Cu")
		(net "P5E_PEX3_STN4_TX_DP<70>")
	)
	(gr_poly
		(pts
			(arc
				(start 430.003204 -310.149748)
				(mid 429.596804 -310.149748)
				(end 430.003204 -310.149748)
			)
		)
		(stroke
			(width 0)
			(type solid)
		)
		(fill yes)
		(layer "In1.Cu")
		(net "P5E_PEX3_STN4_RX_DP<70>")
	)
	(gr_poly
		(pts
			(arc
				(start 430.003204 -308.249828)
				(mid 429.596804 -308.249828)
				(end 430.003204 -308.249828)
			)
		)
		(stroke
			(width 0)
			(type solid)
		)
		(fill yes)
		(layer "In1.Cu")
		(net "P5E_PEX3_STN4_RX_DP<68>")
	)
	(gr_poly
		(pts
			(arc
				(start 430.003204 -306.349908)
				(mid 429.596804 -306.349908)
				(end 430.003204 -306.349908)
			)
		)
		(stroke
			(width 0)
			(type solid)
		)
		(fill yes)
		(layer "In1.Cu")
		(net "P5E_PEX3_STN4_RX_DP<66>")
	)
	(gr_poly
		(pts
			(arc
				(start 430.003204 -304.449734)
				(mid 429.596804 -304.449734)
				(end 430.003204 -304.449734)
			)
		)
		(stroke
			(width 0)
			(type solid)
		)
		(fill yes)
		(layer "In1.Cu")
		(net "P5E_PEX3_STN4_RX_DP<64>")
	)
	(gr_poly
		(pts
			(arc
				(start 430.003204 -287.349946)
				(mid 429.596804 -287.349946)
				(end 430.003204 -287.349946)
			)
		)
		(stroke
			(width 0)
			(type solid)
		)
		(fill yes)
		(layer "In1.Cu")
		(net "P5E_PEX3_STN0_RX_DP<1>")
	)
	(gr_poly
		(pts
			(arc
				(start 430.003204 -285.449772)
				(mid 429.596804 -285.449772)
				(end 430.003204 -285.449772)
			)
		)
		(stroke
			(width 0)
			(type solid)
		)
		(fill yes)
		(layer "In1.Cu")
		(net "P5E_PEX3_STN0_RX_DP<3>")
	)
	(gr_poly
		(pts
			(arc
				(start 430.003204 -283.549852)
				(mid 429.596804 -283.549852)
				(end 430.003204 -283.549852)
			)
		)
		(stroke
			(width 0)
			(type solid)
		)
		(fill yes)
		(layer "In1.Cu")
		(net "P5E_PEX3_STN0_RX_DP<5>")
	)
	(gr_poly
		(pts
			(arc
				(start 430.003204 -281.649932)
				(mid 429.596804 -281.649932)
				(end 430.003204 -281.649932)
			)
		)
		(stroke
			(width 0)
			(type solid)
		)
		(fill yes)
		(layer "In1.Cu")
		(net "P5E_PEX3_STN0_RX_DP<7>")
	)
	(gr_poly
		(pts
			(arc
				(start 430.003204 -279.749758)
				(mid 429.596804 -279.749758)
				(end 430.003204 -279.749758)
			)
		)
		(stroke
			(width 0)
			(type solid)
		)
		(fill yes)
		(layer "In1.Cu")
		(net "P5E_PEX3_STN0_TX_DP<7>")
	)
	(gr_poly
		(pts
			(arc
				(start 430.003204 -276.899878)
				(mid 429.596804 -276.899878)
				(end 430.003204 -276.899878)
			)
		)
		(stroke
			(width 0)
			(type solid)
		)
		(fill yes)
		(layer "In1.Cu")
		(net "P5E_PEX3_STN0_TX_DP<8>")
	)
	(gr_poly
		(pts
			(arc
				(start 430.003204 -274.999704)
				(mid 429.596804 -274.999704)
				(end 430.003204 -274.999704)
			)
		)
		(stroke
			(width 0)
			(type solid)
		)
		(fill yes)
		(layer "In1.Cu")
		(net "P5E_PEX3_STN0_RX_DP<8>")
	)
	(gr_poly
		(pts
			(arc
				(start 430.953164 -316.799722)
				(mid 430.546764 -316.799722)
				(end 430.953164 -316.799722)
			)
		)
		(stroke
			(width 0)
			(type solid)
		)
		(fill yes)
		(layer "In1.Cu")
		(net "P5E_PEX3_STN4_RX_DN<71>")
	)
	(gr_poly
		(pts
			(arc
				(start 430.953164 -314.899802)
				(mid 430.546764 -314.899802)
				(end 430.953164 -314.899802)
			)
		)
		(stroke
			(width 0)
			(type solid)
		)
		(fill yes)
		(layer "In1.Cu")
		(net "P5E_PEX3_STN4_TX_DN<71>")
	)
	(gr_poly
		(pts
			(arc
				(start 430.953164 -312.049922)
				(mid 430.546764 -312.049922)
				(end 430.953164 -312.049922)
			)
		)
		(stroke
			(width 0)
			(type solid)
		)
		(fill yes)
		(layer "In1.Cu")
		(net "P5E_PEX3_STN4_TX_DN<70>")
	)
	(gr_poly
		(pts
			(arc
				(start 430.953164 -310.149748)
				(mid 430.546764 -310.149748)
				(end 430.953164 -310.149748)
			)
		)
		(stroke
			(width 0)
			(type solid)
		)
		(fill yes)
		(layer "In1.Cu")
		(net "P5E_PEX3_STN4_RX_DN<70>")
	)
	(gr_poly
		(pts
			(arc
				(start 430.953164 -308.249828)
				(mid 430.546764 -308.249828)
				(end 430.953164 -308.249828)
			)
		)
		(stroke
			(width 0)
			(type solid)
		)
		(fill yes)
		(layer "In1.Cu")
		(net "P5E_PEX3_STN4_RX_DN<68>")
	)
	(gr_poly
		(pts
			(arc
				(start 430.953164 -306.349908)
				(mid 430.546764 -306.349908)
				(end 430.953164 -306.349908)
			)
		)
		(stroke
			(width 0)
			(type solid)
		)
		(fill yes)
		(layer "In1.Cu")
		(net "P5E_PEX3_STN4_RX_DN<66>")
	)
	(gr_poly
		(pts
			(arc
				(start 430.953164 -304.449734)
				(mid 430.546764 -304.449734)
				(end 430.953164 -304.449734)
			)
		)
		(stroke
			(width 0)
			(type solid)
		)
		(fill yes)
		(layer "In1.Cu")
		(net "P5E_PEX3_STN4_RX_DN<64>")
	)
	(gr_poly
		(pts
			(arc
				(start 430.953164 -287.349946)
				(mid 430.546764 -287.349946)
				(end 430.953164 -287.349946)
			)
		)
		(stroke
			(width 0)
			(type solid)
		)
		(fill yes)
		(layer "In1.Cu")
		(net "P5E_PEX3_STN0_RX_DN<1>")
	)
	(gr_poly
		(pts
			(arc
				(start 430.953164 -285.449772)
				(mid 430.546764 -285.449772)
				(end 430.953164 -285.449772)
			)
		)
		(stroke
			(width 0)
			(type solid)
		)
		(fill yes)
		(layer "In1.Cu")
		(net "P5E_PEX3_STN0_RX_DN<3>")
	)
	(gr_poly
		(pts
			(arc
				(start 430.953164 -283.549852)
				(mid 430.546764 -283.549852)
				(end 430.953164 -283.549852)
			)
		)
		(stroke
			(width 0)
			(type solid)
		)
		(fill yes)
		(layer "In1.Cu")
		(net "P5E_PEX3_STN0_RX_DN<5>")
	)
	(gr_poly
		(pts
			(arc
				(start 430.953164 -281.649932)
				(mid 430.546764 -281.649932)
				(end 430.953164 -281.649932)
			)
		)
		(stroke
			(width 0)
			(type solid)
		)
		(fill yes)
		(layer "In1.Cu")
		(net "P5E_PEX3_STN0_RX_DN<7>")
	)
	(gr_poly
		(pts
			(arc
				(start 430.953164 -279.749758)
				(mid 430.546764 -279.749758)
				(end 430.953164 -279.749758)
			)
		)
		(stroke
			(width 0)
			(type solid)
		)
		(fill yes)
		(layer "In1.Cu")
		(net "P5E_PEX3_STN0_TX_DN<7>")
	)
	(gr_poly
		(pts
			(arc
				(start 430.953164 -276.899878)
				(mid 430.546764 -276.899878)
				(end 430.953164 -276.899878)
			)
		)
		(stroke
			(width 0)
			(type solid)
		)
		(fill yes)
		(layer "In1.Cu")
		(net "P5E_PEX3_STN0_TX_DN<8>")
	)
	(gr_poly
		(pts
			(arc
				(start 430.953164 -274.999704)
				(mid 430.546764 -274.999704)
				(end 430.953164 -274.999704)
			)
		)
		(stroke
			(width 0)
			(type solid)
		)
		(fill yes)
		(layer "In1.Cu")
		(net "P5E_PEX3_STN0_RX_DN<8>")
	)
	(gr_poly
		(pts
			(arc
				(start 241.741198 -376.399806)
				(mid 241.763367 -376.39459)
				(end 241.781076 -376.380248)
			)
			(arc
				(start 241.781076 -376.380248)
				(mid 241.793461 -376.365378)
				(end 241.80673 -376.351292)
			)
			(xy 242.08994 -376.068082)
			(arc
				(start 242.09502 -376.063002)
				(mid 242.106647 -376.046325)
				(end 242.110768 -376.026426)
			)
			(arc
				(start 242.110768 -368.666268)
				(mid 242.106867 -368.646745)
				(end 242.095782 -368.6302)
			)
			(arc
				(start 241.977672 -368.51209)
				(mid 241.961138 -368.500979)
				(end 241.941604 -368.497104)
			)
			(arc
				(start 236.370368 -368.497104)
				(mid 236.350845 -368.501005)
				(end 236.3343 -368.51209)
			)
			(arc
				(start 236.123734 -368.722656)
				(mid 236.112623 -368.73919)
				(end 236.108748 -368.758724)
			)
			(arc
				(start 236.108748 -376.146314)
				(mid 236.112649 -376.165837)
				(end 236.123734 -376.182382)
			)
			(arc
				(start 236.326172 -376.38482)
				(mid 236.342706 -376.395931)
				(end 236.36224 -376.399806)
			)
		)
		(stroke
			(width 0)
			(type solid)
		)
		(fill yes)
		(layer "In1.Cu")
		(net "P12V_STBY_R1")
	)
	(gr_poly
		(pts
			(arc
				(start 235.60151 -413.087058)
				(mid 235.621033 -413.083157)
				(end 235.637578 -413.072072)
			)
			(arc
				(start 236.756956 -411.952694)
				(mid 236.768067 -411.93616)
				(end 236.771942 -411.916626)
			)
			(arc
				(start 236.771942 -402.84527)
				(mid 236.796095 -402.723754)
				(end 236.864906 -402.620734)
			)
			(arc
				(start 238.766604 -400.719036)
				(mid 238.869636 -400.650255)
				(end 238.99114 -400.626072)
			)
			(arc
				(start 242.910868 -400.626072)
				(mid 242.930391 -400.622171)
				(end 242.946936 -400.611086)
			)
			(arc
				(start 243.79682 -399.761202)
				(mid 243.807931 -399.744668)
				(end 243.811806 -399.725134)
			)
			(arc
				(start 243.811806 -392.09472)
				(mid 243.835959 -391.973204)
				(end 243.90477 -391.870184)
			)
			(arc
				(start 244.93093 -390.844024)
				(mid 245.033962 -390.775243)
				(end 245.155466 -390.75106)
			)
			(arc
				(start 259.056124 -390.75106)
				(mid 259.075647 -390.747159)
				(end 259.092192 -390.736074)
			)
			(arc
				(start 262.00481 -387.823456)
				(mid 262.015921 -387.806922)
				(end 262.019796 -387.787388)
			)
			(arc
				(start 262.019796 -379.197616)
				(mid 262.015895 -379.178093)
				(end 262.00481 -379.161548)
			)
			(arc
				(start 261.967472 -379.12421)
				(mid 261.950938 -379.113099)
				(end 261.931404 -379.109224)
			)
			(arc
				(start 240.584482 -379.109224)
				(mid 240.564959 -379.113125)
				(end 240.548414 -379.12421)
			)
			(arc
				(start 239.998504 -379.67412)
				(mid 239.895472 -379.742901)
				(end 239.773968 -379.767084)
			)
			(arc
				(start 237.129066 -379.767084)
				(mid 237.00755 -379.742931)
				(end 236.90453 -379.67412)
			)
			(arc
				(start 232.953814 -375.723404)
				(mid 232.885033 -375.620372)
				(end 232.86085 -375.498868)
			)
			(arc
				(start 232.86085 -372.11508)
				(mid 232.856949 -372.095557)
				(end 232.845864 -372.079012)
			)
			(arc
				(start 232.203752 -371.4369)
				(mid 232.134971 -371.333868)
				(end 232.110788 -371.212364)
			)
			(arc
				(start 232.110788 -371.075712)
				(mid 232.106887 -371.056189)
				(end 232.095802 -371.039644)
			)
			(arc
				(start 232.035858 -370.9797)
				(mid 231.967077 -370.876668)
				(end 231.942894 -370.755164)
			)
			(arc
				(start 231.942894 -367.397792)
				(mid 231.938993 -367.378269)
				(end 231.927908 -367.361724)
			)
			(arc
				(start 231.89057 -367.324386)
				(mid 231.874036 -367.313275)
				(end 231.854502 -367.3094)
			)
			(arc
				(start 228.741986 -367.3094)
				(mid 228.722463 -367.313301)
				(end 228.705918 -367.324386)
			)
			(arc
				(start 228.66858 -367.361724)
				(mid 228.657469 -367.378258)
				(end 228.653594 -367.397792)
			)
			(arc
				(start 228.653594 -370.74856)
				(mid 228.629441 -370.870076)
				(end 228.56063 -370.973096)
			)
			(arc
				(start 228.481128 -371.052598)
				(mid 228.470017 -371.069132)
				(end 228.466142 -371.088666)
			)
			(arc
				(start 228.466142 -371.354096)
				(mid 228.441989 -371.475612)
				(end 228.373178 -371.578632)
			)
			(arc
				(start 227.178362 -372.773448)
				(mid 227.167251 -372.789982)
				(end 227.163376 -372.809516)
			)
			(arc
				(start 227.163376 -374.166384)
				(mid 227.139223 -374.2879)
				(end 227.070412 -374.39092)
			)
			(arc
				(start 225.794062 -375.66727)
				(mid 225.69103 -375.736051)
				(end 225.569526 -375.760234)
			)
			(arc
				(start 223.648016 -375.760234)
				(mid 223.5265 -375.736081)
				(end 223.42348 -375.66727)
			)
			(arc
				(start 221.55531 -373.7991)
				(mid 221.486529 -373.696068)
				(end 221.462346 -373.574564)
			)
			(arc
				(start 221.462346 -371.091714)
				(mid 221.458445 -371.072191)
				(end 221.44736 -371.055646)
			)
			(arc
				(start 221.361508 -370.969794)
				(mid 221.292727 -370.866762)
				(end 221.268544 -370.745258)
			)
			(arc
				(start 221.268544 -367.391442)
				(mid 221.264643 -367.371919)
				(end 221.253558 -367.355374)
			)
			(arc
				(start 221.225872 -367.327688)
				(mid 221.209338 -367.316577)
				(end 221.189804 -367.312702)
			)
			(arc
				(start 218.110308 -367.312702)
				(mid 218.090785 -367.316603)
				(end 218.07424 -367.327688)
			)
			(arc
				(start 217.967306 -367.434622)
				(mid 217.956195 -367.451156)
				(end 217.95232 -367.47069)
			)
			(arc
				(start 217.95232 -370.719096)
				(mid 217.928167 -370.840612)
				(end 217.859356 -370.943632)
			)
			(arc
				(start 216.82964 -371.973348)
				(mid 216.726608 -372.042129)
				(end 216.605104 -372.066312)
			)
			(arc
				(start 210.424014 -372.066312)
				(mid 210.302498 -372.042159)
				(end 210.199478 -371.973348)
			)
			(arc
				(start 210.067906 -371.841776)
				(mid 209.999125 -371.738744)
				(end 209.974942 -371.61724)
			)
			(arc
				(start 209.974942 -371.309138)
				(mid 209.971041 -371.289615)
				(end 209.959956 -371.27307)
			)
			(arc
				(start 209.949034 -371.262148)
				(mid 209.9325 -371.251037)
				(end 209.912966 -371.247162)
			)
			(arc
				(start 209.559144 -371.247162)
				(mid 209.437628 -371.223009)
				(end 209.334608 -371.154198)
			)
			(arc
				(start 208.669382 -370.488972)
				(mid 208.652848 -370.477861)
				(end 208.633314 -370.473986)
			)
			(arc
				(start 208.394554 -370.473986)
				(mid 208.273038 -370.449833)
				(end 208.170018 -370.381022)
			)
			(arc
				(start 208.11744 -370.328444)
				(mid 208.048659 -370.225412)
				(end 208.024476 -370.103908)
			)
			(arc
				(start 208.024476 -367.401348)
				(mid 208.020575 -367.381825)
				(end 208.00949 -367.36528)
			)
			(arc
				(start 207.981804 -367.337594)
				(mid 207.96527 -367.326483)
				(end 207.945736 -367.322608)
			)
			(arc
				(start 204.823822 -367.322608)
				(mid 204.804299 -367.326509)
				(end 204.787754 -367.337594)
			)
			(arc
				(start 204.740002 -367.385346)
				(mid 204.728891 -367.40188)
				(end 204.725016 -367.421414)
			)
			(arc
				(start 204.725016 -370.796312)
				(mid 204.728917 -370.815835)
				(end 204.740002 -370.83238)
			)
			(arc
				(start 204.77353 -370.865908)
				(mid 204.842311 -370.96894)
				(end 204.866494 -371.090444)
			)
			(arc
				(start 204.866494 -374.47474)
				(mid 204.870058 -374.493432)
				(end 204.88021 -374.509538)
			)
			(arc
				(start 204.88021 -374.509538)
				(mid 204.94326 -374.609679)
				(end 204.9653 -374.725946)
			)
			(arc
				(start 204.9653 -387.02361)
				(mid 204.969201 -387.043133)
				(end 204.980286 -387.059678)
			)
			(arc
				(start 207.47482 -389.554212)
				(mid 207.543601 -389.657244)
				(end 207.567784 -389.778748)
			)
			(arc
				(start 207.567784 -411.696662)
				(mid 207.571685 -411.716185)
				(end 207.58277 -411.73273)
			)
			(arc
				(start 208.922112 -413.072072)
				(mid 208.938646 -413.083183)
				(end 208.95818 -413.087058)
			)
		)
		(stroke
			(width 0)
			(type solid)
		)
		(fill yes)
		(layer "In1.Cu")
		(net "P12V_STBY")
	)
	(gr_poly
		(pts
			(xy 465.600034 -461.99552) (xy 465.655841 -461.994997) (xy 465.767141 -461.986654) (xy 465.877508 -461.970017)
			(xy 465.986322 -461.945179) (xy 466.092976 -461.912278) (xy 466.196873 -461.8715) (xy 466.297432 -461.823072)
			(xy 466.394091 -461.767264) (xy 466.48631 -461.70439) (xy 466.573572 -461.6348) (xy 466.65539 -461.558883)
			(xy 466.731306 -461.477065) (xy 466.800896 -461.389802) (xy 466.86377 -461.297583) (xy 466.919577 -461.200923)
			(xy 466.968004 -461.100364) (xy 467.008782 -460.996466) (xy 467.041681 -460.889812) (xy 467.066519 -460.780998)
			(xy 467.083155 -460.670631) (xy 467.091497 -460.559331) (xy 467.09203 -460.503524) (xy 467.09203 -422.58996)
			(xy 467.091507 -422.534153) (xy 467.083163 -422.422853) (xy 467.066526 -422.312487) (xy 467.041687 -422.203672)
			(xy 467.008787 -422.097019) (xy 466.968009 -421.993121) (xy 466.91958 -421.892562) (xy 466.863773 -421.795903)
			(xy 466.800898 -421.703684) (xy 466.731308 -421.616422) (xy 466.655392 -421.534604) (xy 466.573573 -421.458688)
			(xy 466.486311 -421.389098) (xy 466.394092 -421.326224) (xy 466.297433 -421.270417) (xy 466.196873 -421.221989)
			(xy 466.092976 -421.181211) (xy 465.986322 -421.148311) (xy 465.877508 -421.123473) (xy 465.767141 -421.106836)
			(xy 465.655841 -421.098493) (xy 465.600034 -421.097964) (xy 447.939922 -421.097964) (xy 447.884114 -421.098485)
			(xy 447.77281 -421.106824) (xy 447.66244 -421.123458) (xy 447.553622 -421.148293) (xy 447.446964 -421.181191)
			(xy 447.343062 -421.221967) (xy 447.242499 -421.270394) (xy 447.145835 -421.3262) (xy 447.053613 -421.389074)
			(xy 446.966346 -421.458664) (xy 446.884524 -421.53458) (xy 446.808604 -421.616399) (xy 446.739011 -421.703663)
			(xy 446.676133 -421.795883) (xy 446.620323 -421.892544) (xy 446.571892 -421.993106) (xy 446.531111 -422.097005)
			(xy 446.498209 -422.203662) (xy 446.47337 -422.312479) (xy 446.456731 -422.422848) (xy 446.448387 -422.534152)
			(xy 446.447926 -422.58996) (xy 446.447926 -429.090074) (xy 446.447433 -429.160429) (xy 446.439545 -429.300916)
			(xy 446.423792 -429.440741) (xy 446.400224 -429.579462) (xy 446.368915 -429.716643) (xy 446.329963 -429.851854)
			(xy 446.283491 -429.984667) (xy 446.229646 -430.114666) (xy 446.168596 -430.241441) (xy 446.100533 -430.364593)
			(xy 446.025673 -430.483736) (xy 445.94425 -430.598494) (xy 445.856521 -430.708505) (xy 445.762761 -430.813425)
			(xy 445.663266 -430.912922) (xy 445.558348 -431.006684) (xy 445.448338 -431.094416) (xy 445.333582 -431.175842)
			(xy 445.214442 -431.250705) (xy 445.091291 -431.31877) (xy 444.964517 -431.379823) (xy 444.834519 -431.433671)
			(xy 444.701707 -431.480146) (xy 444.566498 -431.519101) (xy 444.429317 -431.550413) (xy 444.290596 -431.573985)
			(xy 444.150772 -431.589741) (xy 444.010285 -431.597632) (xy 443.93993 -431.59807) (xy 371.24005 -431.59807)
			(xy 371.169695 -431.597587) (xy 371.029207 -431.5897) (xy 370.889383 -431.573948) (xy 370.750661 -431.550381)
			(xy 370.613479 -431.519072) (xy 370.478269 -431.480121) (xy 370.345455 -431.433649) (xy 370.215456 -431.379804)
			(xy 370.088681 -431.318754) (xy 369.965528 -431.250691) (xy 369.846385 -431.175831) (xy 369.731628 -431.094407)
			(xy 369.621616 -431.006677) (xy 369.516697 -430.912917) (xy 369.4172 -430.813421) (xy 369.323438 -430.708502)
			(xy 369.235707 -430.598492) (xy 369.154283 -430.483735) (xy 369.079421 -430.364593) (xy 369.011357 -430.241441)
			(xy 368.950306 -430.114666) (xy 368.896459 -429.984667) (xy 368.849986 -429.851854) (xy 368.811034 -429.716644)
			(xy 368.779724 -429.579463) (xy 368.756155 -429.440741) (xy 368.740402 -429.300917) (xy 368.732514 -429.160429)
			(xy 368.732054 -429.090074) (xy 368.732054 -422.58996) (xy 368.731543 -422.534154) (xy 368.7232 -422.422854)
			(xy 368.706562 -422.31249) (xy 368.681723 -422.203677) (xy 368.648822 -422.097024) (xy 368.608042 -421.993129)
			(xy 368.559613 -421.892571) (xy 368.503804 -421.795914) (xy 368.440929 -421.703697) (xy 368.371337 -421.616438)
			(xy 368.29542 -421.534622) (xy 368.2136 -421.458709) (xy 368.126337 -421.389123) (xy 368.034117 -421.326252)
			(xy 367.937456 -421.270449) (xy 367.836896 -421.222025) (xy 367.732998 -421.181251) (xy 367.626344 -421.148356)
			(xy 367.51753 -421.123523) (xy 367.407164 -421.106891) (xy 367.295864 -421.098554) (xy 367.240058 -421.097964)
			(xy 359.940098 -421.097964) (xy 359.88429 -421.098486) (xy 359.772988 -421.106827) (xy 359.662619 -421.123462)
			(xy 359.553802 -421.148298) (xy 359.447146 -421.181197) (xy 359.343246 -421.221974) (xy 359.242684 -421.270401)
			(xy 359.146022 -421.326208) (xy 359.053801 -421.389082) (xy 358.966536 -421.458672) (xy 358.884716 -421.534589)
			(xy 358.808797 -421.616407) (xy 358.739205 -421.70367) (xy 358.676328 -421.79589) (xy 358.620519 -421.892551)
			(xy 358.572089 -421.993111) (xy 358.53131 -422.09701) (xy 358.498408 -422.203666) (xy 358.473569 -422.312482)
			(xy 358.456931 -422.42285) (xy 358.448587 -422.534152) (xy 358.448102 -422.58996) (xy 358.448102 -429.090074)
			(xy 358.447618 -429.160429) (xy 358.43973 -429.300916) (xy 358.423977 -429.440741) (xy 358.400409 -429.579462)
			(xy 358.369099 -429.716643) (xy 358.330147 -429.851853) (xy 358.283675 -429.984667) (xy 358.229829 -430.114665)
			(xy 358.168779 -430.24144) (xy 358.100716 -430.364593) (xy 358.025856 -430.483735) (xy 357.944432 -430.598492)
			(xy 357.856702 -430.708504) (xy 357.762942 -430.813423) (xy 357.663446 -430.91292) (xy 357.558528 -431.006682)
			(xy 357.448518 -431.094413) (xy 357.333762 -431.175838) (xy 357.21462 -431.2507) (xy 357.091469 -431.318764)
			(xy 356.964695 -431.379816) (xy 356.834697 -431.433664) (xy 356.701884 -431.480138) (xy 356.566674 -431.519091)
			(xy 356.429493 -431.550403) (xy 356.290772 -431.573973) (xy 356.150948 -431.589728) (xy 356.010461 -431.597618)
			(xy 355.940106 -431.59807) (xy 283.239972 -431.59807) (xy 283.169619 -431.597576) (xy 283.029135 -431.589685)
			(xy 282.889313 -431.573929) (xy 282.750596 -431.550359) (xy 282.613418 -431.519047) (xy 282.478212 -431.480093)
			(xy 282.345402 -431.43362) (xy 282.215407 -431.379772) (xy 282.088636 -431.318721) (xy 281.965488 -431.250657)
			(xy 281.84635 -431.175796) (xy 281.731596 -431.094372) (xy 281.621589 -431.006642) (xy 281.516674 -430.912882)
			(xy 281.417181 -430.813387) (xy 281.323423 -430.70847) (xy 281.235695 -430.598461) (xy 281.154274 -430.483705)
			(xy 281.079415 -430.364565) (xy 281.011354 -430.241416) (xy 280.950306 -430.114643) (xy 280.896461 -429.984647)
			(xy 280.84999 -429.851837) (xy 280.811039 -429.71663) (xy 280.779731 -429.579451) (xy 280.756163 -429.440733)
			(xy 280.740411 -429.300912) (xy 280.732523 -429.160427) (xy 280.731976 -429.090074) (xy 280.731976 -422.58996)
			(xy 280.731453 -422.534154) (xy 280.723109 -422.422855) (xy 280.706471 -422.31249) (xy 280.681633 -422.203678)
			(xy 280.648732 -422.097025) (xy 280.607953 -421.99313) (xy 280.559525 -421.892573) (xy 280.503717 -421.795915)
			(xy 280.440842 -421.703699) (xy 280.371251 -421.616439) (xy 280.295334 -421.534623) (xy 280.213516 -421.45871)
			(xy 280.126253 -421.389123) (xy 280.034034 -421.326251) (xy 279.937374 -421.270447) (xy 279.836815 -421.222023)
			(xy 279.732918 -421.181248) (xy 279.626264 -421.148352) (xy 279.517451 -421.123517) (xy 279.407085 -421.106884)
			(xy 279.295786 -421.098545) (xy 279.23998 -421.097964) (xy 276.880066 -421.097964) (xy 276.824259 -421.098487)
			(xy 276.712958 -421.10683) (xy 276.602591 -421.123467) (xy 276.493777 -421.148305) (xy 276.387122 -421.181205)
			(xy 276.283225 -421.221984) (xy 276.182665 -421.270412) (xy 276.086005 -421.326219) (xy 275.993786 -421.389094)
			(xy 275.906523 -421.458684) (xy 275.824704 -421.5346) (xy 275.748787 -421.616418) (xy 275.679197 -421.703681)
			(xy 275.616322 -421.7959) (xy 275.560514 -421.892559) (xy 275.512086 -421.993119) (xy 275.471307 -422.097017)
			(xy 275.438407 -422.203671) (xy 275.413568 -422.312485) (xy 275.396931 -422.422852) (xy 275.388587 -422.534153)
			(xy 275.38807 -422.58996) (xy 275.38807 -430.55794) (xy 275.387576 -430.628293) (xy 275.379684 -430.768777)
			(xy 275.363928 -430.908597) (xy 275.340357 -431.047314) (xy 275.309045 -431.184492) (xy 275.27009 -431.319698)
			(xy 275.223616 -431.452506) (xy 275.169769 -431.582501) (xy 275.108717 -431.709271) (xy 275.040653 -431.832419)
			(xy 274.965792 -431.951557) (xy 274.884368 -432.066309) (xy 274.796638 -432.176316) (xy 274.702878 -432.281231)
			(xy 274.603383 -432.380723) (xy 274.498466 -432.474481) (xy 274.388457 -432.562208) (xy 274.273702 -432.643629)
			(xy 274.154562 -432.718487) (xy 274.031412 -432.786547) (xy 273.90464 -432.847596) (xy 273.774645 -432.90144)
			(xy 273.641835 -432.94791) (xy 273.506628 -432.986861) (xy 273.36945 -433.018169) (xy 273.230732 -433.041737)
			(xy 273.090911 -433.05749) (xy 272.950427 -433.065377) (xy 272.880074 -433.065936) (xy 202.360022 -433.065936)
			(xy 202.289667 -433.065443) (xy 202.14918 -433.057555) (xy 202.009355 -433.041802) (xy 201.870634 -433.018234)
			(xy 201.733452 -432.986924) (xy 201.598242 -432.947972) (xy 201.465429 -432.9015) (xy 201.33543 -432.847655)
			(xy 201.208655 -432.786605) (xy 201.085502 -432.718542) (xy 200.96636 -432.643682) (xy 200.851602 -432.562259)
			(xy 200.74159 -432.47453) (xy 200.63667 -432.38077) (xy 200.537173 -432.281275) (xy 200.44341 -432.176357)
			(xy 200.355678 -432.066348) (xy 200.274252 -431.951592) (xy 200.199389 -431.832451) (xy 200.131324 -431.7093)
			(xy 200.070271 -431.582527) (xy 200.016422 -431.452529) (xy 199.969947 -431.319717) (xy 199.930991 -431.184508)
			(xy 199.899679 -431.047327) (xy 199.876107 -430.908606) (xy 199.86035 -430.768782) (xy 199.852458 -430.628295)
			(xy 199.852026 -430.55794) (xy 199.852026 -422.58996) (xy 199.851503 -422.534154) (xy 199.843159 -422.422853)
			(xy 199.826522 -422.312487) (xy 199.801683 -422.203673) (xy 199.768783 -422.097019) (xy 199.728004 -421.993122)
			(xy 199.679576 -421.892563) (xy 199.623769 -421.795904) (xy 199.560894 -421.703685) (xy 199.491304 -421.616423)
			(xy 199.415387 -421.534606) (xy 199.333569 -421.45869) (xy 199.246306 -421.3891) (xy 199.154088 -421.326226)
			(xy 199.057428 -421.270419) (xy 198.956869 -421.221992) (xy 198.852972 -421.181214) (xy 198.746318 -421.148314)
			(xy 198.637503 -421.123476) (xy 198.527137 -421.10684) (xy 198.415836 -421.098497) (xy 198.36003 -421.097964)
			(xy 188.36005 -421.097964) (xy 188.304244 -421.098488) (xy 188.192943 -421.106832) (xy 188.082578 -421.12347)
			(xy 187.973764 -421.148309) (xy 187.86711 -421.18121) (xy 187.763214 -421.221988) (xy 187.662655 -421.270417)
			(xy 187.565996 -421.326225) (xy 187.473778 -421.389099) (xy 187.386516 -421.458689) (xy 187.304699 -421.534606)
			(xy 187.228783 -421.616424) (xy 187.159193 -421.703686) (xy 187.096319 -421.795905) (xy 187.040512 -421.892564)
			(xy 186.992084 -421.993123) (xy 186.951306 -422.09702) (xy 186.918406 -422.203673) (xy 186.893568 -422.312487)
			(xy 186.876931 -422.422853) (xy 186.868587 -422.534154) (xy 186.868054 -422.58996) (xy 186.868054 -429.090074)
			(xy 186.86757 -429.160428) (xy 186.859682 -429.300915) (xy 186.843929 -429.440738) (xy 186.820361 -429.579458)
			(xy 186.789051 -429.716639) (xy 186.750099 -429.851848) (xy 186.703626 -429.98466) (xy 186.64978 -430.114658)
			(xy 186.58873 -430.241431) (xy 186.520667 -430.364582) (xy 186.445806 -430.483723) (xy 186.364382 -430.598479)
			(xy 186.276652 -430.708489) (xy 186.182891 -430.813407) (xy 186.083395 -430.912902) (xy 185.978477 -431.006662)
			(xy 185.868467 -431.094392) (xy 185.75371 -431.175815) (xy 185.634569 -431.250675) (xy 185.511417 -431.318737)
			(xy 185.384643 -431.379787) (xy 185.254645 -431.433632) (xy 185.121833 -431.480104) (xy 184.986623 -431.519055)
			(xy 184.849443 -431.550364) (xy 184.710722 -431.573931) (xy 184.570899 -431.589684) (xy 184.430412 -431.597571)
			(xy 184.360058 -431.59807) (xy 111.660178 -431.59807) (xy 111.589825 -431.597585) (xy 111.449339 -431.589694)
			(xy 111.309518 -431.573939) (xy 111.170799 -431.550369) (xy 111.033621 -431.519057) (xy 110.898414 -431.480103)
			(xy 110.765603 -431.43363) (xy 110.635608 -431.379782) (xy 110.508836 -431.318731) (xy 110.385687 -431.250667)
			(xy 110.266548 -431.175806) (xy 110.151794 -431.094382) (xy 110.041786 -431.006651) (xy 109.93687 -430.912891)
			(xy 109.837376 -430.813395) (xy 109.743618 -430.708478) (xy 109.65589 -430.598468) (xy 109.574468 -430.483712)
			(xy 109.499608 -430.364572) (xy 109.431547 -430.241421) (xy 109.370498 -430.114648) (xy 109.316653 -429.984652)
			(xy 109.270182 -429.851841) (xy 109.231231 -429.716633) (xy 109.199922 -429.579454) (xy 109.176354 -429.440735)
			(xy 109.160602 -429.300913) (xy 109.152714 -429.160427) (xy 109.152182 -429.090074) (xy 109.152182 -422.58996)
			(xy 109.151659 -422.534154) (xy 109.143315 -422.422855) (xy 109.126678 -422.31249) (xy 109.101839 -422.203677)
			(xy 109.068938 -422.097025) (xy 109.02816 -421.993129) (xy 108.979731 -421.892571) (xy 108.923923 -421.795914)
			(xy 108.861048 -421.703697) (xy 108.791457 -421.616437) (xy 108.715541 -421.534621) (xy 108.633722 -421.458707)
			(xy 108.546459 -421.38912) (xy 108.45424 -421.326248) (xy 108.357581 -421.270444) (xy 108.257021 -421.222019)
			(xy 108.153124 -421.181244) (xy 108.046471 -421.148347) (xy 107.937657 -421.123512) (xy 107.827292 -421.106879)
			(xy 107.715992 -421.098539) (xy 107.660186 -421.097964) (xy 100.359972 -421.097964) (xy 100.304165 -421.098487)
			(xy 100.192864 -421.106829) (xy 100.082497 -421.123466) (xy 99.973681 -421.148304) (xy 99.867027 -421.181204)
			(xy 99.763129 -421.221982) (xy 99.662568 -421.27041) (xy 99.565908 -421.326217) (xy 99.473689 -421.389091)
			(xy 99.386425 -421.458681) (xy 99.304606 -421.534598) (xy 99.228689 -421.616416) (xy 99.159099 -421.703679)
			(xy 99.096223 -421.795898) (xy 99.040415 -421.892558) (xy 98.991987 -421.993118) (xy 98.951208 -422.097015)
			(xy 98.918307 -422.20367) (xy 98.893468 -422.312485) (xy 98.876831 -422.422852) (xy 98.868487 -422.534153)
			(xy 98.867976 -422.58996) (xy 98.867976 -429.090074) (xy 98.867492 -429.160428) (xy 98.859604 -429.300915)
			(xy 98.843851 -429.440739) (xy 98.820283 -429.57946) (xy 98.788973 -429.716641) (xy 98.750021 -429.85185)
			(xy 98.703549 -429.984663) (xy 98.649703 -430.114661) (xy 98.588652 -430.241435) (xy 98.520589 -430.364587)
			(xy 98.445729 -430.483729) (xy 98.364305 -430.598485) (xy 98.276575 -430.708496) (xy 98.182814 -430.813414)
			(xy 98.083319 -430.91291) (xy 97.9784 -431.006671) (xy 97.86839 -431.094401) (xy 97.753634 -431.175825)
			(xy 97.634492 -431.250686) (xy 97.511341 -431.31875) (xy 97.384567 -431.3798) (xy 97.254569 -431.433647)
			(xy 97.121756 -431.480119) (xy 96.986547 -431.519072) (xy 96.849366 -431.550382) (xy 96.710645 -431.57395)
			(xy 96.570821 -431.589704) (xy 96.430334 -431.597592) (xy 96.35998 -431.59807) (xy 23.6601 -431.59807)
			(xy 23.589746 -431.597586) (xy 23.44926 -431.589696) (xy 23.309437 -431.573942) (xy 23.170718 -431.550372)
			(xy 23.033539 -431.519062) (xy 22.89833 -431.480109) (xy 22.765519 -431.433636) (xy 22.635522 -431.379789)
			(xy 22.50875 -431.318738) (xy 22.385599 -431.250675) (xy 22.266459 -431.175813) (xy 22.151704 -431.094389)
			(xy 22.041695 -431.006659) (xy 21.936778 -430.912899) (xy 21.837283 -430.813403) (xy 21.743524 -430.708485)
			(xy 21.655795 -430.598475) (xy 21.574372 -430.483719) (xy 21.499512 -430.364578) (xy 21.43145 -430.241427)
			(xy 21.370401 -430.114654) (xy 21.316555 -429.984657) (xy 21.270083 -429.851845) (xy 21.231132 -429.716636)
			(xy 21.199823 -429.579456) (xy 21.176255 -429.440737) (xy 21.160502 -429.300914) (xy 21.152614 -429.160428)
			(xy 21.152104 -429.090074) (xy 21.152104 -422.58996) (xy 21.151595 -422.534153) (xy 21.143254 -422.42285)
			(xy 21.126618 -422.312481) (xy 21.101782 -422.203665) (xy 21.068883 -422.097009) (xy 21.028105 -421.993109)
			(xy 20.979677 -421.892548) (xy 20.92387 -421.795886) (xy 20.860995 -421.703666) (xy 20.791404 -421.616402)
			(xy 20.715486 -421.534582) (xy 20.633667 -421.458665) (xy 20.546403 -421.389074) (xy 20.454182 -421.326199)
			(xy 20.357521 -421.270392) (xy 20.256959 -421.221964) (xy 20.153059 -421.181187) (xy 20.046403 -421.148288)
			(xy 19.937587 -421.123451) (xy 19.827218 -421.106816) (xy 19.715915 -421.098475) (xy 19.660108 -421.097964)
			(xy 1.999996 -421.097964) (xy 1.944189 -421.098486) (xy 1.832887 -421.106827) (xy 1.72252 -421.123463)
			(xy 1.613705 -421.148299) (xy 1.50705 -421.181198) (xy 1.403151 -421.221976) (xy 1.302591 -421.270403)
			(xy 1.20593 -421.32621) (xy 1.113711 -421.389085) (xy 1.026448 -421.458675) (xy 0.944629 -421.534592)
			(xy 0.868712 -421.616411) (xy 0.799122 -421.703674) (xy 0.736248 -421.795894) (xy 0.680441 -421.892554)
			(xy 0.632014 -421.993115) (xy 0.591237 -422.097013) (xy 0.558338 -422.203669) (xy 0.533502 -422.312484)
			(xy 0.516867 -422.422851) (xy 0.508526 -422.534153) (xy 0.508 -422.58996) (xy 0.508 -457.5681) (xy 2.904225 -457.5681)
			(xy 2.904225 -457.43896) (xy 2.912175 -457.310065) (xy 2.928045 -457.181905) (xy 2.951774 -457.054964)
			(xy 2.983273 -456.929725) (xy 3.022422 -456.806662) (xy 3.069073 -456.686243) (xy 3.123048 -456.568924)
			(xy 3.184143 -456.45515) (xy 3.252126 -456.345353) (xy 3.32674 -456.23995) (xy 3.407701 -456.13934)
			(xy 3.494701 -456.043905) (xy 3.587412 -455.954006) (xy 3.685482 -455.869985) (xy 3.788537 -455.792161)
			(xy 3.896188 -455.720829) (xy 4.008027 -455.656259) (xy 4.123628 -455.598697) (xy 4.242553 -455.54836)
			(xy 4.364352 -455.50544) (xy 4.488562 -455.470099) (xy 4.614711 -455.442472) (xy 4.742323 -455.422663)
			(xy 4.870912 -455.410747) (xy 4.99999 -455.406771) (xy 5.129068 -455.410747) (xy 5.257657 -455.422663)
			(xy 5.385269 -455.442472) (xy 5.511418 -455.470099) (xy 5.635628 -455.50544) (xy 5.757427 -455.54836)
			(xy 5.876352 -455.598697) (xy 5.991953 -455.656259) (xy 6.103792 -455.720829) (xy 6.211443 -455.792161)
			(xy 6.314498 -455.869985) (xy 6.412568 -455.954006) (xy 6.505279 -456.043905) (xy 6.592279 -456.13934)
			(xy 6.67324 -456.23995) (xy 6.747854 -456.345353) (xy 6.815837 -456.45515) (xy 6.876932 -456.568924)
			(xy 6.930907 -456.686243) (xy 6.977558 -456.806662) (xy 7.016707 -456.929725) (xy 7.048206 -457.054964)
			(xy 7.071935 -457.181905) (xy 7.087805 -457.310065) (xy 7.095755 -457.43896) (xy 7.096252 -457.50353)
			(xy 7.095755 -457.5681) (xy 460.504275 -457.5681) (xy 460.504275 -457.43896) (xy 460.512225 -457.310065)
			(xy 460.528095 -457.181905) (xy 460.551824 -457.054964) (xy 460.583323 -456.929725) (xy 460.622472 -456.806662)
			(xy 460.669123 -456.686243) (xy 460.723098 -456.568924) (xy 460.784193 -456.45515) (xy 460.852176 -456.345353)
			(xy 460.92679 -456.23995) (xy 461.007751 -456.13934) (xy 461.094751 -456.043905) (xy 461.187462 -455.954006)
			(xy 461.285532 -455.869985) (xy 461.388587 -455.792161) (xy 461.496238 -455.720829) (xy 461.608077 -455.656259)
			(xy 461.723678 -455.598697) (xy 461.842603 -455.54836) (xy 461.964402 -455.50544) (xy 462.088612 -455.470099)
			(xy 462.214761 -455.442472) (xy 462.342373 -455.422663) (xy 462.470962 -455.410747) (xy 462.60004 -455.406771)
			(xy 462.729118 -455.410747) (xy 462.857707 -455.422663) (xy 462.985319 -455.442472) (xy 463.111468 -455.470099)
			(xy 463.235678 -455.50544) (xy 463.357477 -455.54836) (xy 463.476402 -455.598697) (xy 463.592003 -455.656259)
			(xy 463.703842 -455.720829) (xy 463.811493 -455.792161) (xy 463.914548 -455.869985) (xy 464.012618 -455.954006)
			(xy 464.105329 -456.043905) (xy 464.192329 -456.13934) (xy 464.27329 -456.23995) (xy 464.347904 -456.345353)
			(xy 464.415887 -456.45515) (xy 464.476982 -456.568924) (xy 464.530957 -456.686243) (xy 464.577608 -456.806662)
			(xy 464.616757 -456.929725) (xy 464.648256 -457.054964) (xy 464.671985 -457.181905) (xy 464.687855 -457.310065)
			(xy 464.695805 -457.43896) (xy 464.696302 -457.50353) (xy 464.695805 -457.5681) (xy 464.687855 -457.696995)
			(xy 464.671985 -457.825155) (xy 464.648256 -457.952096) (xy 464.616757 -458.077335) (xy 464.577608 -458.200398)
			(xy 464.530957 -458.320817) (xy 464.476982 -458.438136) (xy 464.415887 -458.55191) (xy 464.347904 -458.661707)
			(xy 464.27329 -458.76711) (xy 464.192329 -458.86772) (xy 464.105329 -458.963155) (xy 464.012618 -459.053054)
			(xy 463.914548 -459.137075) (xy 463.811493 -459.214899) (xy 463.703842 -459.286231) (xy 463.592003 -459.350801)
			(xy 463.476402 -459.408363) (xy 463.357477 -459.4587) (xy 463.235678 -459.50162) (xy 463.111468 -459.536961)
			(xy 462.985319 -459.564588) (xy 462.857707 -459.584397) (xy 462.729118 -459.596313) (xy 462.60004 -459.60029)
			(xy 462.470962 -459.596313) (xy 462.342373 -459.584397) (xy 462.214761 -459.564588) (xy 462.088612 -459.536961)
			(xy 461.964402 -459.50162) (xy 461.842603 -459.4587) (xy 461.723678 -459.408363) (xy 461.608077 -459.350801)
			(xy 461.496238 -459.286231) (xy 461.388587 -459.214899) (xy 461.285532 -459.137075) (xy 461.187462 -459.053054)
			(xy 461.094751 -458.963155) (xy 461.007751 -458.86772) (xy 460.92679 -458.76711) (xy 460.852176 -458.661707)
			(xy 460.784193 -458.55191) (xy 460.723098 -458.438136) (xy 460.669123 -458.320817) (xy 460.622472 -458.200398)
			(xy 460.583323 -458.077335) (xy 460.551824 -457.952096) (xy 460.528095 -457.825155) (xy 460.512225 -457.696995)
			(xy 460.504275 -457.5681) (xy 7.095755 -457.5681) (xy 7.087805 -457.696995) (xy 7.071935 -457.825155)
			(xy 7.048206 -457.952096) (xy 7.016707 -458.077335) (xy 6.977558 -458.200398) (xy 6.930907 -458.320817)
			(xy 6.876932 -458.438136) (xy 6.815837 -458.55191) (xy 6.747854 -458.661707) (xy 6.67324 -458.76711)
			(xy 6.592279 -458.86772) (xy 6.505279 -458.963155) (xy 6.412568 -459.053054) (xy 6.314498 -459.137075)
			(xy 6.211443 -459.214899) (xy 6.103792 -459.286231) (xy 5.991953 -459.350801) (xy 5.876352 -459.408363)
			(xy 5.757427 -459.4587) (xy 5.635628 -459.50162) (xy 5.511418 -459.536961) (xy 5.385269 -459.564588)
			(xy 5.257657 -459.584397) (xy 5.129068 -459.596313) (xy 4.99999 -459.60029) (xy 4.870912 -459.596313)
			(xy 4.742323 -459.584397) (xy 4.614711 -459.564588) (xy 4.488562 -459.536961) (xy 4.364352 -459.50162)
			(xy 4.242553 -459.4587) (xy 4.123628 -459.408363) (xy 4.008027 -459.350801) (xy 3.896188 -459.286231)
			(xy 3.788537 -459.214899) (xy 3.685482 -459.137075) (xy 3.587412 -459.053054) (xy 3.494701 -458.963155)
			(xy 3.407701 -458.86772) (xy 3.32674 -458.76711) (xy 3.252126 -458.661707) (xy 3.184143 -458.55191)
			(xy 3.123048 -458.438136) (xy 3.069073 -458.320817) (xy 3.022422 -458.200398) (xy 2.983273 -458.077335)
			(xy 2.951774 -457.952096) (xy 2.928045 -457.825155) (xy 2.912175 -457.696995) (xy 2.904225 -457.5681)
			(xy 0.508 -457.5681) (xy 0.508 -460.503524) (xy 0.508522 -460.559331) (xy 0.516863 -460.670633) (xy 0.533498 -460.781)
			(xy 0.558335 -460.889816) (xy 0.591234 -460.996471) (xy 0.632011 -461.10037) (xy 0.680438 -461.20093)
			(xy 0.736246 -461.297591) (xy 0.79912 -461.389811) (xy 0.86871 -461.477074) (xy 0.944627 -461.558893)
			(xy 1.026446 -461.63481) (xy 1.113709 -461.7044) (xy 1.205929 -461.767274) (xy 1.30259 -461.823082)
			(xy 1.40315 -461.871509) (xy 1.507049 -461.912286) (xy 1.613704 -461.945185) (xy 1.72252 -461.970022)
			(xy 1.832887 -461.986657) (xy 1.944189 -461.994998) (xy 1.999996 -461.99552)
		)
		(stroke
			(width 0)
			(type solid)
		)
		(fill yes)
		(layer "In1.Cu")
		(net "COUPON_GND1")
	)
	(gr_poly
		(pts
			(xy 13.96492 -10.342118) (xy 14.020727 -10.341596) (xy 14.132028 -10.333253) (xy 14.242395 -10.316617)
			(xy 14.35121 -10.29178) (xy 14.457865 -10.25888) (xy 14.561763 -10.218102) (xy 14.662323 -10.169674)
			(xy 14.758983 -10.113867) (xy 14.851203 -10.050993) (xy 14.938466 -9.981402) (xy 15.020284 -9.905486)
			(xy 15.096201 -9.823667) (xy 15.165791 -9.736404) (xy 15.228666 -9.644185) (xy 15.284473 -9.547525)
			(xy 15.332901 -9.446965) (xy 15.373679 -9.343067) (xy 15.406579 -9.236412) (xy 15.431417 -9.127597)
			(xy 15.448053 -9.01723) (xy 15.456395 -8.905929) (xy 15.456916 -8.850122) (xy 15.456916 0) (xy 15.4574 0.070354)
			(xy 15.46529 0.21084) (xy 15.481044 0.350663) (xy 15.504614 0.489383) (xy 15.535924 0.626563) (xy 15.574877 0.761771)
			(xy 15.62135 0.894583) (xy 15.675197 1.02458) (xy 15.736248 1.151353) (xy 15.804311 1.274504) (xy 15.879172 1.393644)
			(xy 15.960596 1.5084) (xy 16.048326 1.618409) (xy 16.142086 1.723327) (xy 16.241582 1.822822) (xy 16.3465 1.916582)
			(xy 16.45651 2.004311) (xy 16.571266 2.085734) (xy 16.690407 2.160595) (xy 16.813558 2.228658) (xy 16.940331 2.289708)
			(xy 17.070328 2.343554) (xy 17.20314 2.390026) (xy 17.338349 2.428979) (xy 17.475529 2.460289) (xy 17.614249 2.483858)
			(xy 17.754072 2.499611) (xy 17.894558 2.5075) (xy 17.964912 2.507996) (xy 33.96488 2.507996) (xy 34.035234 2.507512)
			(xy 34.175722 2.499624) (xy 34.315546 2.48387) (xy 34.454267 2.460302) (xy 34.591448 2.428992) (xy 34.726657 2.39004)
			(xy 34.85947 2.343568) (xy 34.989468 2.289721) (xy 35.116243 2.228671) (xy 35.239395 2.160608) (xy 35.358537 2.085747)
			(xy 35.473294 2.004324) (xy 35.583304 1.916594) (xy 35.688223 1.822833) (xy 35.78772 1.723338) (xy 35.881481 1.61842)
			(xy 35.969212 1.50841) (xy 36.050636 1.393653) (xy 36.125498 1.274512) (xy 36.193562 1.151361) (xy 36.254613 1.024587)
			(xy 36.30846 0.894589) (xy 36.354934 0.761776) (xy 36.393887 0.626567) (xy 36.425198 0.489386) (xy 36.448768 0.350666)
			(xy 36.464522 0.210842) (xy 36.472412 0.070354) (xy 36.472876 0) (xy 36.472876 -8.850122) (xy 36.473399 -8.905929)
			(xy 36.481741 -9.01723) (xy 36.498377 -9.127597) (xy 36.523215 -9.236413) (xy 36.556114 -9.343067)
			(xy 36.596892 -9.446965) (xy 36.64532 -9.547526) (xy 36.701127 -9.644186) (xy 36.764002 -9.736405)
			(xy 36.833592 -9.823668) (xy 36.909508 -9.905487) (xy 36.991327 -9.981404) (xy 37.07859 -10.050995)
			(xy 37.170809 -10.113869) (xy 37.267469 -10.169677) (xy 37.368029 -10.218105) (xy 37.471927 -10.258884)
			(xy 37.578582 -10.291784) (xy 37.687397 -10.316622) (xy 37.797764 -10.333258) (xy 37.909065 -10.341601)
			(xy 37.964872 -10.342118) (xy 39.965122 -10.342118) (xy 40.020929 -10.341595) (xy 40.13223 -10.333253)
			(xy 40.242597 -10.316617) (xy 40.351412 -10.291779) (xy 40.458067 -10.258879) (xy 40.561964 -10.218102)
			(xy 40.662525 -10.169674) (xy 40.759184 -10.113866) (xy 40.851404 -10.050992) (xy 40.938667 -9.981402)
			(xy 41.020485 -9.905485) (xy 41.096402 -9.823667) (xy 41.165992 -9.736404) (xy 41.228866 -9.644184)
			(xy 41.284674 -9.547525) (xy 41.333102 -9.446964) (xy 41.373879 -9.343067) (xy 41.406779 -9.236412)
			(xy 41.431617 -9.127597) (xy 41.448253 -9.01723) (xy 41.456595 -8.905929) (xy 41.457118 -8.850122)
			(xy 41.457118 0) (xy 41.457602 0.070354) (xy 41.465492 0.21084) (xy 41.481246 0.350663) (xy 41.504816 0.489383)
			(xy 41.536126 0.626563) (xy 41.575079 0.761771) (xy 41.621552 0.894583) (xy 41.675399 1.02458) (xy 41.73645 1.151353)
			(xy 41.804513 1.274503) (xy 41.879374 1.393644) (xy 41.960798 1.508399) (xy 42.048528 1.618409) (xy 42.142288 1.723326)
			(xy 42.241784 1.822821) (xy 42.346702 1.916581) (xy 42.456712 2.00431) (xy 42.571468 2.085733) (xy 42.690609 2.160594)
			(xy 42.81376 2.228657) (xy 42.940533 2.289707) (xy 43.07053 2.343553) (xy 43.203342 2.390025) (xy 43.338551 2.428977)
			(xy 43.475731 2.460287) (xy 43.614451 2.483856) (xy 43.754274 2.499609) (xy 43.89476 2.507498) (xy 43.965114 2.507996)
			(xy 59.965082 2.507996) (xy 60.035436 2.507512) (xy 60.175924 2.499624) (xy 60.315748 2.48387) (xy 60.454468 2.460301)
			(xy 60.591649 2.428992) (xy 60.726859 2.390039) (xy 60.859672 2.343567) (xy 60.98967 2.289721) (xy 61.116444 2.22867)
			(xy 61.239596 2.160607) (xy 61.358738 2.085747) (xy 61.473495 2.004323) (xy 61.583505 1.916593) (xy 61.688424 1.822833)
			(xy 61.78792 1.723337) (xy 61.881681 1.618419) (xy 61.969412 1.508409) (xy 62.050837 1.393653) (xy 62.125698 1.274512)
			(xy 62.193762 1.15136) (xy 62.254813 1.024586) (xy 62.308661 0.894588) (xy 62.355134 0.761776) (xy 62.394087 0.626567)
			(xy 62.425398 0.489386) (xy 62.448968 0.350665) (xy 62.464722 0.210842) (xy 62.472612 0.070354) (xy 62.473078 0)
			(xy 62.473078 -8.850122) (xy 62.473601 -8.905929) (xy 62.481943 -9.01723) (xy 62.498579 -9.127597)
			(xy 62.523417 -9.236412) (xy 62.556316 -9.343067) (xy 62.597094 -9.446965) (xy 62.645522 -9.547525)
			(xy 62.701329 -9.644185) (xy 62.764204 -9.736405) (xy 62.833794 -9.823668) (xy 62.909711 -9.905487)
			(xy 62.991529 -9.981403) (xy 63.078792 -10.050994) (xy 63.171011 -10.113868) (xy 63.267671 -10.169676)
			(xy 63.368231 -10.218104) (xy 63.472129 -10.258882) (xy 63.578784 -10.291782) (xy 63.687599 -10.31662)
			(xy 63.797966 -10.333257) (xy 63.909267 -10.341599) (xy 63.965074 -10.342118) (xy 65.96507 -10.342118)
			(xy 66.020879 -10.34161) (xy 66.132184 -10.333271) (xy 66.242554 -10.316637) (xy 66.351373 -10.291802)
			(xy 66.458032 -10.258905) (xy 66.561934 -10.218128) (xy 66.662499 -10.169702) (xy 66.759163 -10.113895)
			(xy 66.851386 -10.05102) (xy 66.938653 -9.98143) (xy 67.020476 -9.905512) (xy 67.096396 -9.823693)
			(xy 67.165989 -9.736428) (xy 67.228867 -9.644207) (xy 67.284677 -9.547545) (xy 67.333108 -9.446982)
			(xy 67.373888 -9.343081) (xy 67.406789 -9.236424) (xy 67.431628 -9.127605) (xy 67.448265 -9.017235)
			(xy 67.456608 -8.905931) (xy 67.457066 -8.850122) (xy 67.457066 0) (xy 67.457559 0.070354) (xy 67.465449 0.210841)
			(xy 67.481203 0.350665) (xy 67.504772 0.489385) (xy 67.536082 0.626565) (xy 67.575035 0.761774) (xy 67.621508 0.894587)
			(xy 67.675354 1.024584) (xy 67.736404 1.151358) (xy 67.804467 1.27451) (xy 67.879328 1.393651) (xy 67.960751 1.508408)
			(xy 68.04848 1.618419) (xy 68.14224 1.723337) (xy 68.241735 1.822834) (xy 68.346652 1.916595) (xy 68.456662 2.004326)
			(xy 68.571417 2.085751) (xy 68.690557 2.160614) (xy 68.813708 2.228678) (xy 68.940481 2.289731) (xy 69.070478 2.343579)
			(xy 69.203289 2.390053) (xy 69.338498 2.429008) (xy 69.475678 2.46032) (xy 69.614398 2.483892) (xy 69.754221 2.499648)
			(xy 69.894708 2.50754) (xy 69.965062 2.507996) (xy 85.96503 2.507996) (xy 86.035383 2.507502) (xy 86.175868 2.499611)
			(xy 86.31569 2.483855) (xy 86.454408 2.460284) (xy 86.591586 2.428973) (xy 86.726793 2.390019) (xy 86.859603 2.343545)
			(xy 86.989598 2.289698) (xy 87.11637 2.228647) (xy 87.239519 2.160584) (xy 87.358658 2.085722) (xy 87.473412 2.004299)
			(xy 87.58342 1.916569) (xy 87.688336 1.822809) (xy 87.78783 1.723314) (xy 87.881588 1.618397) (xy 87.969317 1.508388)
			(xy 88.050739 1.393633) (xy 88.125599 1.274493) (xy 88.193661 1.151343) (xy 88.254711 1.024571) (xy 88.308556 0.894575)
			(xy 88.355028 0.761764) (xy 88.39398 0.626557) (xy 88.42529 0.489378) (xy 88.448859 0.35066) (xy 88.464613 0.210838)
			(xy 88.472503 0.070353) (xy 88.473026 0) (xy 88.473026 -8.850122) (xy 88.473549 -8.905928) (xy 88.481891 -9.017228)
			(xy 88.498528 -9.127594) (xy 88.523365 -9.236408) (xy 88.556265 -9.343061) (xy 88.597043 -9.446957)
			(xy 88.645472 -9.547516) (xy 88.701279 -9.644174) (xy 88.764154 -9.736392) (xy 88.833745 -9.823653)
			(xy 88.909662 -9.90547) (xy 88.99148 -9.981384) (xy 89.078743 -10.050972) (xy 89.170963 -10.113844)
			(xy 89.267623 -10.169649) (xy 89.368183 -10.218074) (xy 89.472081 -10.258849) (xy 89.578735 -10.291746)
			(xy 89.687549 -10.316581) (xy 89.797915 -10.333214) (xy 89.909216 -10.341553) (xy 89.965022 -10.342118)
			(xy 91.965018 -10.342118) (xy 92.020825 -10.341596) (xy 92.132127 -10.333254) (xy 92.242494 -10.316617)
			(xy 92.351309 -10.29178) (xy 92.457964 -10.258881) (xy 92.561862 -10.218103) (xy 92.662422 -10.169675)
			(xy 92.759082 -10.113868) (xy 92.851302 -10.050993) (xy 92.938565 -9.981403) (xy 93.020384 -9.905487)
			(xy 93.096301 -9.823668) (xy 93.165891 -9.736405) (xy 93.228766 -9.644186) (xy 93.284573 -9.547526)
			(xy 93.333001 -9.446965) (xy 93.373779 -9.343067) (xy 93.406679 -9.236413) (xy 93.431517 -9.127597)
			(xy 93.448153 -9.01723) (xy 93.456495 -8.905929) (xy 93.457014 -8.850122) (xy 93.457014 0) (xy 93.457498 0.070354)
			(xy 93.465388 0.21084) (xy 93.481142 0.350663) (xy 93.504712 0.489383) (xy 93.536022 0.626563) (xy 93.574975 0.761771)
			(xy 93.621448 0.894583) (xy 93.675295 1.02458) (xy 93.736346 1.151353) (xy 93.804409 1.274504) (xy 93.87927 1.393645)
			(xy 93.960694 1.5084) (xy 94.048424 1.61841) (xy 94.142184 1.723327) (xy 94.24168 1.822823) (xy 94.346598 1.916583)
			(xy 94.456608 2.004312) (xy 94.571364 2.085735) (xy 94.690505 2.160596) (xy 94.813655 2.228659) (xy 94.940429 2.289709)
			(xy 95.070426 2.343555) (xy 95.203238 2.390028) (xy 95.338447 2.42898) (xy 95.475627 2.46029) (xy 95.614347 2.483859)
			(xy 95.75417 2.499613) (xy 95.894656 2.507502) (xy 95.96501 2.507996) (xy 124.06503 2.507996) (xy 124.135383 2.507502)
			(xy 124.275868 2.499611) (xy 124.41569 2.483855) (xy 124.554408 2.460284) (xy 124.691586 2.428973)
			(xy 124.826793 2.390019) (xy 124.959603 2.343545) (xy 125.089598 2.289698) (xy 125.21637 2.228647)
			(xy 125.339519 2.160584) (xy 125.458658 2.085722) (xy 125.573412 2.004299) (xy 125.68342 1.916569)
			(xy 125.788336 1.822809) (xy 125.88783 1.723314) (xy 125.981588 1.618397) (xy 126.069317 1.508388)
			(xy 126.150739 1.393633) (xy 126.225599 1.274493) (xy 126.293661 1.151343) (xy 126.354711 1.024571)
			(xy 126.408556 0.894575) (xy 126.455028 0.761764) (xy 126.49398 0.626557) (xy 126.52529 0.489378)
			(xy 126.548859 0.35066) (xy 126.564613 0.210838) (xy 126.572503 0.070353) (xy 126.573026 0) (xy 126.573026 -8.850122)
			(xy 126.573549 -8.905928) (xy 126.581891 -9.017228) (xy 126.598528 -9.127594) (xy 126.623365 -9.236408)
			(xy 126.656265 -9.343061) (xy 126.697043 -9.446957) (xy 126.745472 -9.547516) (xy 126.801279 -9.644174)
			(xy 126.864154 -9.736392) (xy 126.933745 -9.823653) (xy 127.009662 -9.90547) (xy 127.09148 -9.981384)
			(xy 127.178743 -10.050972) (xy 127.270963 -10.113844) (xy 127.367623 -10.169649) (xy 127.468183 -10.218074)
			(xy 127.572081 -10.258849) (xy 127.678735 -10.291746) (xy 127.787549 -10.316581) (xy 127.897915 -10.333214)
			(xy 128.009216 -10.341553) (xy 128.065022 -10.342118) (xy 130.065018 -10.342118) (xy 130.120825 -10.341596)
			(xy 130.232127 -10.333254) (xy 130.342494 -10.316617) (xy 130.451309 -10.29178) (xy 130.557964 -10.258881)
			(xy 130.661862 -10.218103) (xy 130.762422 -10.169675) (xy 130.859082 -10.113868) (xy 130.951302 -10.050993)
			(xy 131.038565 -9.981403) (xy 131.120384 -9.905487) (xy 131.196301 -9.823668) (xy 131.265891 -9.736405)
			(xy 131.328766 -9.644186) (xy 131.384573 -9.547526) (xy 131.433001 -9.446965) (xy 131.473779 -9.343067)
			(xy 131.506679 -9.236413) (xy 131.531517 -9.127597) (xy 131.548153 -9.01723) (xy 131.556495 -8.905929)
			(xy 131.557014 -8.850122) (xy 131.557014 0) (xy 131.557498 0.070354) (xy 131.565388 0.21084) (xy 131.581142 0.350663)
			(xy 131.604712 0.489383) (xy 131.636022 0.626563) (xy 131.674975 0.761771) (xy 131.721448 0.894583)
			(xy 131.775295 1.02458) (xy 131.836346 1.151353) (xy 131.904409 1.274504) (xy 131.97927 1.393645)
			(xy 132.060694 1.5084) (xy 132.148424 1.61841) (xy 132.242184 1.723327) (xy 132.34168 1.822823) (xy 132.446598 1.916583)
			(xy 132.556608 2.004312) (xy 132.671364 2.085735) (xy 132.790505 2.160596) (xy 132.913655 2.228659)
			(xy 133.040429 2.289709) (xy 133.170426 2.343555) (xy 133.303238 2.390028) (xy 133.438447 2.42898)
			(xy 133.575627 2.46029) (xy 133.714347 2.483859) (xy 133.85417 2.499613) (xy 133.994656 2.507502)
			(xy 134.06501 2.507996) (xy 150.064978 2.507996) (xy 150.135332 2.507512) (xy 150.27582 2.499624)
			(xy 150.415644 2.483871) (xy 150.554365 2.460302) (xy 150.691546 2.428993) (xy 150.826756 2.39004)
			(xy 150.959569 2.343568) (xy 151.089567 2.289722) (xy 151.216342 2.228672) (xy 151.339494 2.160609)
			(xy 151.458636 2.085748) (xy 151.573393 2.004324) (xy 151.683404 1.916594) (xy 151.788322 1.822834)
			(xy 151.887819 1.723338) (xy 151.98158 1.61842) (xy 152.069311 1.50841) (xy 152.150736 1.393654)
			(xy 152.225598 1.274513) (xy 152.293661 1.151361) (xy 152.354713 1.024587) (xy 152.40856 0.894589)
			(xy 152.455034 0.761777) (xy 152.493987 0.626567) (xy 152.525298 0.489386) (xy 152.548868 0.350666)
			(xy 152.564622 0.210842) (xy 152.572512 0.070354) (xy 152.572974 0) (xy 152.572974 -8.850122) (xy 152.573497 -8.905929)
			(xy 152.581839 -9.017231) (xy 152.598475 -9.127598) (xy 152.623313 -9.236413) (xy 152.656212 -9.343068)
			(xy 152.69699 -9.446966) (xy 152.745418 -9.547526) (xy 152.801225 -9.644186) (xy 152.8641 -9.736406)
			(xy 152.93369 -9.823669) (xy 153.009606 -9.905488) (xy 153.091425 -9.981405) (xy 153.178688 -10.050995)
			(xy 153.270907 -10.11387) (xy 153.367567 -10.169678) (xy 153.468127 -10.218107) (xy 153.572025 -10.258885)
			(xy 153.67868 -10.291785) (xy 153.787495 -10.316623) (xy 153.897862 -10.33326) (xy 154.009163 -10.341603)
			(xy 154.06497 -10.342118) (xy 156.064966 -10.342118) (xy 156.120775 -10.34161) (xy 156.23208 -10.333271)
			(xy 156.342451 -10.316638) (xy 156.45127 -10.291803) (xy 156.557929 -10.258906) (xy 156.661832 -10.21813)
			(xy 156.762396 -10.169703) (xy 156.859061 -10.113896) (xy 156.951284 -10.051022) (xy 157.038552 -9.981431)
			(xy 157.120374 -9.905514) (xy 157.196295 -9.823694) (xy 157.265888 -9.736429) (xy 157.328766 -9.644208)
			(xy 157.384577 -9.547546) (xy 157.433007 -9.446983) (xy 157.473787 -9.343082) (xy 157.506689 -9.236424)
			(xy 157.531528 -9.127606) (xy 157.548165 -9.017236) (xy 157.556508 -8.905931) (xy 157.556962 -8.850122)
			(xy 157.556962 0) (xy 157.557455 0.070354) (xy 157.565345 0.210841) (xy 157.581099 0.350665) (xy 157.604668 0.489385)
			(xy 157.635978 0.626566) (xy 157.674931 0.761775) (xy 157.721404 0.894587) (xy 157.77525 1.024585)
			(xy 157.8363 1.151359) (xy 157.904363 1.274511) (xy 157.979224 1.393652) (xy 158.060647 1.508409)
			(xy 158.148376 1.61842) (xy 158.242136 1.723339) (xy 158.341631 1.822835) (xy 158.446548 1.916597)
			(xy 158.556557 2.004328) (xy 158.671313 2.085753) (xy 158.790453 2.160616) (xy 158.913604 2.22868)
			(xy 159.040377 2.289733) (xy 159.170374 2.343581) (xy 159.303185 2.390056) (xy 159.438394 2.429011)
			(xy 159.575574 2.460324) (xy 159.714294 2.483895) (xy 159.854117 2.499652) (xy 159.994604 2.507544)
			(xy 160.064958 2.507996) (xy 176.064926 2.507996) (xy 176.135279 2.507502) (xy 176.275764 2.499611)
			(xy 176.415586 2.483856) (xy 176.554304 2.460285) (xy 176.691483 2.428974) (xy 176.82669 2.39002)
			(xy 176.9595 2.343547) (xy 177.089496 2.289699) (xy 177.216267 2.228648) (xy 177.339416 2.160585)
			(xy 177.458556 2.085724) (xy 177.57331 2.0043) (xy 177.683318 1.91657) (xy 177.788234 1.822811) (xy 177.887728 1.723315)
			(xy 177.981487 1.618398) (xy 178.069216 1.508389) (xy 178.150638 1.393634) (xy 178.225498 1.274494)
			(xy 178.29356 1.151344) (xy 178.35461 1.024572) (xy 178.408456 0.894576) (xy 178.454928 0.761765)
			(xy 178.49388 0.626558) (xy 178.52519 0.489379) (xy 178.548759 0.35066) (xy 178.564513 0.210838)
			(xy 178.572403 0.070353) (xy 178.572922 0) (xy 178.572922 -8.850122) (xy 178.573445 -8.905928) (xy 178.581787 -9.017229)
			(xy 178.598424 -9.127594) (xy 178.623261 -9.236408) (xy 178.656161 -9.343061) (xy 178.696939 -9.446958)
			(xy 178.745367 -9.547517) (xy 178.801175 -9.644175) (xy 178.86405 -9.736393) (xy 178.93364 -9.823654)
			(xy 179.009557 -9.905471) (xy 179.091376 -9.981386) (xy 179.178639 -10.050974) (xy 179.270859 -10.113846)
			(xy 179.367519 -10.169651) (xy 179.468079 -10.218077) (xy 179.571976 -10.258852) (xy 179.678631 -10.291749)
			(xy 179.787445 -10.316584) (xy 179.897811 -10.333218) (xy 180.009112 -10.341557) (xy 180.064918 -10.342118)
			(xy 182.064914 -10.342118) (xy 182.120721 -10.341596) (xy 182.232023 -10.333254) (xy 182.34239 -10.316618)
			(xy 182.451206 -10.291781) (xy 182.557861 -10.258882) (xy 182.661759 -10.218104) (xy 182.76232 -10.169676)
			(xy 182.85898 -10.113869) (xy 182.9512 -10.050995) (xy 183.038463 -9.981405) (xy 183.120282 -9.905488)
			(xy 183.196199 -9.823669) (xy 183.26579 -9.736406) (xy 183.328665 -9.644187) (xy 183.384473 -9.547527)
			(xy 183.432901 -9.446966) (xy 183.473679 -9.343068) (xy 183.506579 -9.236413) (xy 183.531416 -9.127598)
			(xy 183.548053 -9.017231) (xy 183.556395 -8.905929) (xy 183.55691 -8.850122) (xy 183.55691 0) (xy 183.557394 0.070354)
			(xy 183.565284 0.21084) (xy 183.581038 0.350664) (xy 183.604608 0.489383) (xy 183.635918 0.626563)
			(xy 183.674871 0.761772) (xy 183.721344 0.894584) (xy 183.775191 1.024581) (xy 183.836242 1.151354)
			(xy 183.904305 1.274505) (xy 183.979166 1.393646) (xy 184.06059 1.508401) (xy 184.14832 1.618411)
			(xy 184.24208 1.723329) (xy 184.341576 1.822824) (xy 184.446493 1.916584) (xy 184.556503 2.004314)
			(xy 184.671259 2.085737) (xy 184.7904 2.160598) (xy 184.913551 2.228661) (xy 185.040325 2.289712)
			(xy 185.170322 2.343558) (xy 185.303134 2.390031) (xy 185.438342 2.428983) (xy 185.575523 2.460294)
			(xy 185.714242 2.483863) (xy 185.854066 2.499617) (xy 185.994552 2.507506) (xy 186.064906 2.507996)
			(xy 202.064874 2.507996) (xy 202.135228 2.507512) (xy 202.275716 2.499624) (xy 202.41554 2.483871)
			(xy 202.554261 2.460303) (xy 202.691443 2.428993) (xy 202.826653 2.390041) (xy 202.959466 2.343569)
			(xy 203.089464 2.289723) (xy 203.216239 2.228673) (xy 203.339391 2.16061) (xy 203.458534 2.085749)
			(xy 203.573291 2.004326) (xy 203.683302 1.916596) (xy 203.788221 1.822836) (xy 203.887718 1.72334)
			(xy 203.981479 1.618422) (xy 204.06921 1.508412) (xy 204.150635 1.393655) (xy 204.225497 1.274514)
			(xy 204.293561 1.151362) (xy 204.354613 1.024588) (xy 204.40846 0.89459) (xy 204.454933 0.761778)
			(xy 204.493887 0.626568) (xy 204.525198 0.489387) (xy 204.548768 0.350666) (xy 204.564522 0.210842)
			(xy 204.572412 0.070354) (xy 204.57287 0) (xy 204.57287 -8.850122) (xy 204.573393 -8.905929) (xy 204.581735 -9.017231)
			(xy 204.598371 -9.127598) (xy 204.623209 -9.236413) (xy 204.656108 -9.343068) (xy 204.696886 -9.446966)
			(xy 204.745314 -9.547527) (xy 204.801121 -9.644187) (xy 204.863996 -9.736407) (xy 204.933586 -9.82367)
			(xy 205.009502 -9.905489) (xy 205.091321 -9.981407) (xy 205.178583 -10.050997) (xy 205.270803 -10.113872)
			(xy 205.367463 -10.16968) (xy 205.468023 -10.218109) (xy 205.571921 -10.258888) (xy 205.678575 -10.291788)
			(xy 205.78739 -10.316626) (xy 205.897757 -10.333264) (xy 206.009059 -10.341607) (xy 206.064866 -10.342118)
			(xy 208.065116 -10.342118) (xy 208.120923 -10.341596) (xy 208.232225 -10.333254) (xy 208.342592 -10.316618)
			(xy 208.451407 -10.29178) (xy 208.558062 -10.258881) (xy 208.66196 -10.218103) (xy 208.762521 -10.169676)
			(xy 208.859181 -10.113868) (xy 208.951401 -10.050994) (xy 209.038664 -9.981404) (xy 209.120483 -9.905487)
			(xy 209.1964 -9.823669) (xy 209.26599 -9.736406) (xy 209.328865 -9.644186) (xy 209.384673 -9.547526)
			(xy 209.433101 -9.446966) (xy 209.473879 -9.343068) (xy 209.506779 -9.236413) (xy 209.531617 -9.127598)
			(xy 209.548253 -9.017231) (xy 209.556595 -8.905929) (xy 209.557112 -8.850122) (xy 209.557112 0) (xy 209.557596 0.070354)
			(xy 209.565486 0.21084) (xy 209.58124 0.350663) (xy 209.60481 0.489383) (xy 209.63612 0.626563) (xy 209.675073 0.761772)
			(xy 209.721546 0.894583) (xy 209.775393 1.02458) (xy 209.836444 1.151354) (xy 209.904507 1.274505)
			(xy 209.979368 1.393645) (xy 210.060792 1.508401) (xy 210.148522 1.618411) (xy 210.242282 1.723328)
			(xy 210.341778 1.822823) (xy 210.446696 1.916583) (xy 210.556706 2.004313) (xy 210.671462 2.085736)
			(xy 210.790602 2.160597) (xy 210.913753 2.22866) (xy 211.040527 2.289711) (xy 211.170524 2.343557)
			(xy 211.303336 2.390029) (xy 211.438545 2.428982) (xy 211.575725 2.460292) (xy 211.714444 2.483861)
			(xy 211.854268 2.499615) (xy 211.994754 2.507504) (xy 212.065108 2.507996) (xy 240.164874 2.507996)
			(xy 240.235228 2.507512) (xy 240.375716 2.499624) (xy 240.51554 2.483871) (xy 240.654261 2.460303)
			(xy 240.791443 2.428993) (xy 240.926653 2.390041) (xy 241.059466 2.343569) (xy 241.189464 2.289723)
			(xy 241.316239 2.228673) (xy 241.439391 2.16061) (xy 241.558534 2.085749) (xy 241.673291 2.004326)
			(xy 241.783302 1.916596) (xy 241.888221 1.822836) (xy 241.987718 1.72334) (xy 242.081479 1.618422)
			(xy 242.16921 1.508412) (xy 242.250635 1.393655) (xy 242.325497 1.274514) (xy 242.393561 1.151362)
			(xy 242.454613 1.024588) (xy 242.50846 0.89459) (xy 242.554933 0.761778) (xy 242.593887 0.626568)
			(xy 242.625198 0.489387) (xy 242.648768 0.350666) (xy 242.664522 0.210842) (xy 242.672412 0.070354)
			(xy 242.67287 0) (xy 242.67287 -8.850122) (xy 242.673393 -8.905929) (xy 242.681735 -9.017231) (xy 242.698371 -9.127598)
			(xy 242.723209 -9.236413) (xy 242.756108 -9.343068) (xy 242.796886 -9.446966) (xy 242.845314 -9.547527)
			(xy 242.901121 -9.644187) (xy 242.963996 -9.736407) (xy 243.033586 -9.82367) (xy 243.109502 -9.905489)
			(xy 243.191321 -9.981407) (xy 243.278583 -10.050997) (xy 243.370803 -10.113872) (xy 243.467463 -10.16968)
			(xy 243.568023 -10.218109) (xy 243.671921 -10.258888) (xy 243.778575 -10.291788) (xy 243.88739 -10.316626)
			(xy 243.997757 -10.333264) (xy 244.109059 -10.341607) (xy 244.164866 -10.342118) (xy 246.165116 -10.342118)
			(xy 246.220923 -10.341596) (xy 246.332225 -10.333254) (xy 246.442592 -10.316618) (xy 246.551407 -10.29178)
			(xy 246.658062 -10.258881) (xy 246.76196 -10.218103) (xy 246.862521 -10.169676) (xy 246.959181 -10.113868)
			(xy 247.051401 -10.050994) (xy 247.138664 -9.981404) (xy 247.220483 -9.905487) (xy 247.2964 -9.823669)
			(xy 247.36599 -9.736406) (xy 247.428865 -9.644186) (xy 247.484673 -9.547526) (xy 247.533101 -9.446966)
			(xy 247.573879 -9.343068) (xy 247.606779 -9.236413) (xy 247.631617 -9.127598) (xy 247.648253 -9.017231)
			(xy 247.656595 -8.905929) (xy 247.657112 -8.850122) (xy 247.657112 0) (xy 247.657596 0.070354) (xy 247.665486 0.21084)
			(xy 247.68124 0.350663) (xy 247.70481 0.489383) (xy 247.73612 0.626563) (xy 247.775073 0.761772)
			(xy 247.821546 0.894583) (xy 247.875393 1.02458) (xy 247.936444 1.151354) (xy 248.004507 1.274505)
			(xy 248.079368 1.393645) (xy 248.160792 1.508401) (xy 248.248522 1.618411) (xy 248.342282 1.723328)
			(xy 248.441778 1.822823) (xy 248.546696 1.916583) (xy 248.656706 2.004313) (xy 248.771462 2.085736)
			(xy 248.890602 2.160597) (xy 249.013753 2.22866) (xy 249.140527 2.289711) (xy 249.270524 2.343557)
			(xy 249.403336 2.390029) (xy 249.538545 2.428982) (xy 249.675725 2.460292) (xy 249.814444 2.483861)
			(xy 249.954268 2.499615) (xy 250.094754 2.507504) (xy 250.165108 2.507996) (xy 266.165076 2.507996)
			(xy 266.23543 2.507512) (xy 266.375918 2.499624) (xy 266.515742 2.483871) (xy 266.654463 2.460303)
			(xy 266.791644 2.428993) (xy 266.926854 2.390041) (xy 267.059667 2.343569) (xy 267.189666 2.289723)
			(xy 267.31644 2.228672) (xy 267.439593 2.160609) (xy 267.558735 2.085749) (xy 267.673492 2.004325)
			(xy 267.783503 1.916595) (xy 267.888422 1.822835) (xy 267.987918 1.723339) (xy 268.08168 1.618421)
			(xy 268.169411 1.508411) (xy 268.250835 1.393655) (xy 268.325697 1.274513) (xy 268.393761 1.151362)
			(xy 268.454813 1.024588) (xy 268.50866 0.89459) (xy 268.555134 0.761777) (xy 268.594087 0.626568)
			(xy 268.625398 0.489387) (xy 268.648968 0.350666) (xy 268.664722 0.210842) (xy 268.672612 0.070354)
			(xy 268.673072 0) (xy 268.673072 -8.850122) (xy 268.673595 -8.905929) (xy 268.681937 -9.017231) (xy 268.698573 -9.127598)
			(xy 268.723411 -9.236413) (xy 268.75631 -9.343068) (xy 268.797088 -9.446966) (xy 268.845516 -9.547526)
			(xy 268.901323 -9.644187) (xy 268.964198 -9.736406) (xy 269.033788 -9.82367) (xy 269.109704 -9.905489)
			(xy 269.191523 -9.981406) (xy 269.278786 -10.050996) (xy 269.371005 -10.113871) (xy 269.467665 -10.169679)
			(xy 269.568225 -10.218108) (xy 269.672123 -10.258886) (xy 269.778777 -10.291787) (xy 269.887592 -10.316625)
			(xy 269.997959 -10.333262) (xy 270.109261 -10.341605) (xy 270.165068 -10.342118) (xy 272.165064 -10.342118)
			(xy 272.220873 -10.34161) (xy 272.332178 -10.333272) (xy 272.442549 -10.316638) (xy 272.551368 -10.291804)
			(xy 272.658028 -10.258906) (xy 272.76193 -10.21813) (xy 272.862495 -10.169703) (xy 272.95916 -10.113897)
			(xy 273.051383 -10.051022) (xy 273.138651 -9.981432) (xy 273.220473 -9.905515) (xy 273.296394 -9.823695)
			(xy 273.365988 -9.73643) (xy 273.428866 -9.644209) (xy 273.484676 -9.547546) (xy 273.533107 -9.446983)
			(xy 273.573887 -9.343082) (xy 273.606789 -9.236425) (xy 273.631628 -9.127606) (xy 273.648265 -9.017236)
			(xy 273.656608 -8.905931) (xy 273.65706 -8.850122) (xy 273.65706 0) (xy 273.657553 0.070354) (xy 273.665443 0.210841)
			(xy 273.681197 0.350665) (xy 273.704766 0.489385) (xy 273.736076 0.626566) (xy 273.775029 0.761775)
			(xy 273.821502 0.894588) (xy 273.875348 1.024585) (xy 273.936398 1.15136) (xy 274.004461 1.274511)
			(xy 274.079321 1.393653) (xy 274.160745 1.50841) (xy 274.248474 1.618421) (xy 274.342234 1.723339)
			(xy 274.441729 1.822836) (xy 274.546646 1.916598) (xy 274.656655 2.004329) (xy 274.771411 2.085754)
			(xy 274.890551 2.160617) (xy 275.013701 2.228682) (xy 275.140474 2.289734) (xy 275.270471 2.343583)
			(xy 275.403283 2.390058) (xy 275.538492 2.429013) (xy 275.675672 2.460325) (xy 275.814392 2.483897)
			(xy 275.954215 2.499654) (xy 276.094702 2.507545) (xy 276.165056 2.507996) (xy 292.165024 2.507996)
			(xy 292.235377 2.507502) (xy 292.375862 2.499611) (xy 292.515684 2.483856) (xy 292.654403 2.460285)
			(xy 292.791581 2.428974) (xy 292.926788 2.390021) (xy 293.059599 2.343547) (xy 293.189594 2.2897)
			(xy 293.316366 2.228649) (xy 293.439515 2.160586) (xy 293.558655 2.085724) (xy 293.673409 2.004301)
			(xy 293.783417 1.916571) (xy 293.888334 1.822811) (xy 293.987828 1.723316) (xy 294.081587 1.618399)
			(xy 294.169315 1.50839) (xy 294.250738 1.393635) (xy 294.325598 1.274495) (xy 294.39366 1.151345)
			(xy 294.45471 1.024572) (xy 294.508556 0.894576) (xy 294.555028 0.761765) (xy 294.59398 0.626558)
			(xy 294.62529 0.489379) (xy 294.648859 0.35066) (xy 294.664613 0.210839) (xy 294.672503 0.070353)
			(xy 294.67302 0) (xy 294.67302 -8.850122) (xy 294.673543 -8.905928) (xy 294.681885 -9.017229) (xy 294.698522 -9.127594)
			(xy 294.723359 -9.236408) (xy 294.756259 -9.343062) (xy 294.797037 -9.446958) (xy 294.845465 -9.547517)
			(xy 294.901273 -9.644176) (xy 294.964148 -9.736394) (xy 295.033738 -9.823655) (xy 295.109655 -9.905472)
			(xy 295.191474 -9.981387) (xy 295.278737 -10.050975) (xy 295.370956 -10.113847) (xy 295.467616 -10.169652)
			(xy 295.568176 -10.218078) (xy 295.672074 -10.258853) (xy 295.778728 -10.291751) (xy 295.887543 -10.316586)
			(xy 295.997909 -10.333219) (xy 296.10921 -10.341559) (xy 296.165016 -10.342118) (xy 298.165012 -10.342118)
			(xy 298.220819 -10.341596) (xy 298.332121 -10.333254) (xy 298.442488 -10.316618) (xy 298.551304 -10.291781)
			(xy 298.657959 -10.258882) (xy 298.761858 -10.218105) (xy 298.862418 -10.169677) (xy 298.959079 -10.11387)
			(xy 299.051299 -10.050995) (xy 299.138562 -9.981405) (xy 299.220382 -9.905489) (xy 299.296299 -9.82367)
			(xy 299.365889 -9.736407) (xy 299.428764 -9.644188) (xy 299.484572 -9.547527) (xy 299.533001 -9.446967)
			(xy 299.573779 -9.343069) (xy 299.606679 -9.236414) (xy 299.631516 -9.127598) (xy 299.648153 -9.017231)
			(xy 299.656495 -8.905929) (xy 299.657008 -8.850122) (xy 299.657008 0) (xy 299.657492 0.070354) (xy 299.665382 0.21084)
			(xy 299.681136 0.350664) (xy 299.704706 0.489383) (xy 299.736016 0.626564) (xy 299.774969 0.761772)
			(xy 299.821442 0.894584) (xy 299.875289 1.024581) (xy 299.93634 1.151355) (xy 300.004403 1.274505)
			(xy 300.079264 1.393646) (xy 300.160688 1.508402) (xy 300.248418 1.618412) (xy 300.342178 1.723329)
			(xy 300.441673 1.822825) (xy 300.546591 1.916585) (xy 300.656601 2.004315) (xy 300.771357 2.085738)
			(xy 300.890498 2.160599) (xy 301.013649 2.228662) (xy 301.140423 2.289713) (xy 301.27042 2.343559)
			(xy 301.403232 2.390032) (xy 301.53844 2.428985) (xy 301.67562 2.460295) (xy 301.81434 2.483864)
			(xy 301.954163 2.499618) (xy 302.09465 2.507508) (xy 302.165004 2.507996) (xy 318.164972 2.507996)
			(xy 318.235326 2.507512) (xy 318.375814 2.499624) (xy 318.515639 2.483871) (xy 318.65436 2.460303)
			(xy 318.791541 2.428994) (xy 318.926751 2.390042) (xy 319.059564 2.34357) (xy 319.189563 2.289724)
			(xy 319.316338 2.228673) (xy 319.43949 2.160611) (xy 319.558633 2.08575) (xy 319.67339 2.004327)
			(xy 319.783401 1.916597) (xy 319.88832 1.822836) (xy 319.987817 1.723341) (xy 320.081579 1.618423)
			(xy 320.16931 1.508412) (xy 320.250734 1.393656) (xy 320.325597 1.274514) (xy 320.393661 1.151363)
			(xy 320.454712 1.024589) (xy 320.50856 0.894591) (xy 320.555033 0.761778) (xy 320.593987 0.626568)
			(xy 320.625298 0.489387) (xy 320.648868 0.350666) (xy 320.664622 0.210842) (xy 320.672512 0.070354)
			(xy 320.672968 0) (xy 320.672968 -8.850122) (xy 320.673491 -8.905929) (xy 320.681833 -9.017231) (xy 320.698469 -9.127598)
			(xy 320.723307 -9.236413) (xy 320.756206 -9.343068) (xy 320.796984 -9.446967) (xy 320.845412 -9.547527)
			(xy 320.901219 -9.644188) (xy 320.964093 -9.736408) (xy 321.033684 -9.823671) (xy 321.1096 -9.90549)
			(xy 321.191418 -9.981407) (xy 321.278681 -10.050998) (xy 321.3709 -10.113873) (xy 321.46756 -10.169682)
			(xy 321.56812 -10.21811) (xy 321.672018 -10.258889) (xy 321.778673 -10.29179) (xy 321.887488 -10.316628)
			(xy 321.997855 -10.333266) (xy 322.109157 -10.341609) (xy 322.164964 -10.342118) (xy 324.16496 -10.342118)
			(xy 324.220769 -10.34161) (xy 324.332074 -10.333272) (xy 324.442446 -10.316639) (xy 324.551265 -10.291805)
			(xy 324.657925 -10.258907) (xy 324.761827 -10.218131) (xy 324.862393 -10.169705) (xy 324.959057 -10.113898)
			(xy 325.051281 -10.051024) (xy 325.138549 -9.981433) (xy 325.220372 -9.905516) (xy 325.296293 -9.823696)
			(xy 325.365887 -9.736431) (xy 325.428765 -9.64421) (xy 325.484576 -9.547547) (xy 325.533007 -9.446984)
			(xy 325.573787 -9.343083) (xy 325.606689 -9.236425) (xy 325.631528 -9.127607) (xy 325.648165 -9.017236)
			(xy 325.656508 -8.905931) (xy 325.656956 -8.850122) (xy 325.656956 0) (xy 325.657449 0.070354) (xy 325.665339 0.210841)
			(xy 325.681093 0.350665) (xy 325.704662 0.489386) (xy 325.735972 0.626566) (xy 325.774925 0.761776)
			(xy 325.821398 0.894588) (xy 325.875244 1.024586) (xy 325.936294 1.15136) (xy 326.004357 1.274512)
			(xy 326.079217 1.393654) (xy 326.16064 1.508411) (xy 326.24837 1.618422) (xy 326.342129 1.723341)
			(xy 326.441624 1.822838) (xy 326.546542 1.916599) (xy 326.656551 2.004331) (xy 326.771306 2.085756)
			(xy 326.890447 2.160619) (xy 327.013597 2.228684) (xy 327.14037 2.289737) (xy 327.270367 2.343585)
			(xy 327.403179 2.39006) (xy 327.538387 2.429016) (xy 327.675567 2.460328) (xy 327.814287 2.4839)
			(xy 327.954111 2.499657) (xy 328.094598 2.507549) (xy 328.164952 2.507996) (xy 356.264972 2.507996)
			(xy 356.335326 2.507512) (xy 356.475814 2.499624) (xy 356.615639 2.483871) (xy 356.75436 2.460303)
			(xy 356.891541 2.428994) (xy 357.026751 2.390042) (xy 357.159564 2.34357) (xy 357.289563 2.289724)
			(xy 357.416338 2.228673) (xy 357.53949 2.160611) (xy 357.658633 2.08575) (xy 357.77339 2.004327)
			(xy 357.883401 1.916597) (xy 357.98832 1.822836) (xy 358.087817 1.723341) (xy 358.181579 1.618423)
			(xy 358.26931 1.508412) (xy 358.350734 1.393656) (xy 358.425597 1.274514) (xy 358.493661 1.151363)
			(xy 358.554712 1.024589) (xy 358.60856 0.894591) (xy 358.655033 0.761778) (xy 358.693987 0.626568)
			(xy 358.725298 0.489387) (xy 358.748868 0.350666) (xy 358.764622 0.210842) (xy 358.772512 0.070354)
			(xy 358.772968 0) (xy 358.772968 -8.850122) (xy 358.773491 -8.905929) (xy 358.781833 -9.017231) (xy 358.798469 -9.127598)
			(xy 358.823307 -9.236413) (xy 358.856206 -9.343068) (xy 358.896984 -9.446967) (xy 358.945412 -9.547527)
			(xy 359.001219 -9.644188) (xy 359.064093 -9.736408) (xy 359.133684 -9.823671) (xy 359.2096 -9.90549)
			(xy 359.291418 -9.981407) (xy 359.378681 -10.050998) (xy 359.4709 -10.113873) (xy 359.56756 -10.169682)
			(xy 359.66812 -10.21811) (xy 359.772018 -10.258889) (xy 359.878673 -10.29179) (xy 359.987488 -10.316628)
			(xy 360.097855 -10.333266) (xy 360.209157 -10.341609) (xy 360.264964 -10.342118) (xy 362.26496 -10.342118)
			(xy 362.320769 -10.34161) (xy 362.432074 -10.333272) (xy 362.542446 -10.316639) (xy 362.651265 -10.291805)
			(xy 362.757925 -10.258907) (xy 362.861827 -10.218131) (xy 362.962393 -10.169705) (xy 363.059057 -10.113898)
			(xy 363.151281 -10.051024) (xy 363.238549 -9.981433) (xy 363.320372 -9.905516) (xy 363.396293 -9.823696)
			(xy 363.465887 -9.736431) (xy 363.528765 -9.64421) (xy 363.584576 -9.547547) (xy 363.633007 -9.446984)
			(xy 363.673787 -9.343083) (xy 363.706689 -9.236425) (xy 363.731528 -9.127607) (xy 363.748165 -9.017236)
			(xy 363.756508 -8.905931) (xy 363.756956 -8.850122) (xy 363.756956 0) (xy 363.757449 0.070354) (xy 363.765339 0.210841)
			(xy 363.781093 0.350665) (xy 363.804662 0.489386) (xy 363.835972 0.626566) (xy 363.874925 0.761776)
			(xy 363.921398 0.894588) (xy 363.975244 1.024586) (xy 364.036294 1.15136) (xy 364.104357 1.274512)
			(xy 364.179217 1.393654) (xy 364.26064 1.508411) (xy 364.34837 1.618422) (xy 364.442129 1.723341)
			(xy 364.541624 1.822838) (xy 364.646542 1.916599) (xy 364.756551 2.004331) (xy 364.871306 2.085756)
			(xy 364.990447 2.160619) (xy 365.113597 2.228684) (xy 365.24037 2.289737) (xy 365.370367 2.343585)
			(xy 365.503179 2.39006) (xy 365.638387 2.429016) (xy 365.775567 2.460328) (xy 365.914287 2.4839)
			(xy 366.054111 2.499657) (xy 366.194598 2.507549) (xy 366.264952 2.507996) (xy 382.26492 2.507996)
			(xy 382.335273 2.507502) (xy 382.475759 2.499612) (xy 382.615581 2.483856) (xy 382.754299 2.460286)
			(xy 382.891478 2.428975) (xy 383.026685 2.390022) (xy 383.159496 2.343548) (xy 383.289491 2.289701)
			(xy 383.416264 2.22865) (xy 383.539413 2.160587) (xy 383.658552 2.085726) (xy 383.773307 2.004302)
			(xy 383.883316 1.916573) (xy 383.988232 1.822813) (xy 384.087726 1.723318) (xy 384.181485 1.6184)
			(xy 384.269214 1.508391) (xy 384.350637 1.393636) (xy 384.425497 1.274496) (xy 384.493559 1.151346)
			(xy 384.554609 1.024573) (xy 384.608455 0.894577) (xy 384.654928 0.761766) (xy 384.69388 0.626559)
			(xy 384.72519 0.48938) (xy 384.748759 0.350661) (xy 384.764513 0.210839) (xy 384.772403 0.070353)
			(xy 384.772916 0) (xy 384.772916 -8.850122) (xy 384.773439 -8.905928) (xy 384.781781 -9.017229) (xy 384.798418 -9.127595)
			(xy 384.823255 -9.236409) (xy 384.856155 -9.343062) (xy 384.896933 -9.446959) (xy 384.945361 -9.547518)
			(xy 385.001169 -9.644177) (xy 385.064044 -9.736395) (xy 385.133634 -9.823656) (xy 385.209551 -9.905473)
			(xy 385.29137 -9.981388) (xy 385.378633 -10.050977) (xy 385.470852 -10.113849) (xy 385.567512 -10.169655)
			(xy 385.668072 -10.218081) (xy 385.77197 -10.258856) (xy 385.878624 -10.291754) (xy 385.987439 -10.316589)
			(xy 386.097805 -10.333223) (xy 386.209106 -10.341563) (xy 386.264912 -10.342118) (xy 388.264908 -10.342118)
			(xy 388.320715 -10.341596) (xy 388.432017 -10.333255) (xy 388.542385 -10.316619) (xy 388.651201 -10.291782)
			(xy 388.757856 -10.258883) (xy 388.861755 -10.218106) (xy 388.962316 -10.169678) (xy 389.058977 -10.113871)
			(xy 389.151197 -10.050997) (xy 389.238461 -9.981407) (xy 389.32028 -9.90549) (xy 389.396198 -9.823671)
			(xy 389.465789 -9.736408) (xy 389.528664 -9.644189) (xy 389.584472 -9.547528) (xy 389.6329 -9.446968)
			(xy 389.673678 -9.343069) (xy 389.706579 -9.236414) (xy 389.731416 -9.127599) (xy 389.748053 -9.017231)
			(xy 389.756395 -8.905929) (xy 389.756904 -8.850122) (xy 389.756904 0) (xy 389.757397 0.070354) (xy 389.765287 0.21084)
			(xy 389.781041 0.350663) (xy 389.80461 0.489382) (xy 389.835921 0.626562) (xy 389.874874 0.76177)
			(xy 389.921346 0.894581) (xy 389.975193 1.024578) (xy 390.036243 1.151351) (xy 390.104306 1.274502)
			(xy 390.179167 1.393642) (xy 390.260591 1.508398) (xy 390.34832 1.618407) (xy 390.44208 1.723325)
			(xy 390.541575 1.82282) (xy 390.646493 1.91658) (xy 390.756502 2.004309) (xy 390.871258 2.085733)
			(xy 390.990398 2.160594) (xy 391.113549 2.228657) (xy 391.240322 2.289707) (xy 391.370319 2.343554)
			(xy 391.50313 2.390026) (xy 391.638338 2.428979) (xy 391.775518 2.46029) (xy 391.914237 2.483859)
			(xy 392.05406 2.499613) (xy 392.194546 2.507503) (xy 392.2649 2.507996) (xy 408.265122 2.507996)
			(xy 408.335475 2.507502) (xy 408.475961 2.499611) (xy 408.615782 2.483856) (xy 408.754501 2.460286)
			(xy 408.89168 2.428975) (xy 409.026887 2.390021) (xy 409.159697 2.343548) (xy 409.289693 2.289701)
			(xy 409.416465 2.22865) (xy 409.539614 2.160586) (xy 409.658754 2.085725) (xy 409.773508 2.004302)
			(xy 409.883516 1.916572) (xy 409.988433 1.822812) (xy 410.087927 1.723317) (xy 410.181686 1.6184)
			(xy 410.269415 1.50839) (xy 410.350837 1.393635) (xy 410.425697 1.274495) (xy 410.49376 1.151345)
			(xy 410.55481 1.024573) (xy 410.608655 0.894577) (xy 410.655128 0.761766) (xy 410.69408 0.626558)
			(xy 410.72539 0.489379) (xy 410.748959 0.350661) (xy 410.764713 0.210839) (xy 410.772603 0.070353)
			(xy 410.773118 0) (xy 410.773118 -8.850122) (xy 410.773641 -8.905928) (xy 410.781983 -9.017229) (xy 410.79862 -9.127595)
			(xy 410.823457 -9.236408) (xy 410.856357 -9.343062) (xy 410.897135 -9.446959) (xy 410.945563 -9.547518)
			(xy 411.001371 -9.644176) (xy 411.064246 -9.736394) (xy 411.133836 -9.823656) (xy 411.209753 -9.905472)
			(xy 411.291572 -9.981387) (xy 411.378835 -10.050976) (xy 411.471054 -10.113848) (xy 411.567714 -10.169653)
			(xy 411.668274 -10.218079) (xy 411.772172 -10.258855) (xy 411.878826 -10.291752) (xy 411.987641 -10.316587)
			(xy 412.098007 -10.333221) (xy 412.209308 -10.341561) (xy 412.265114 -10.342118) (xy 414.26511 -10.342118)
			(xy 414.320917 -10.341596) (xy 414.432219 -10.333254) (xy 414.542587 -10.316619) (xy 414.651402 -10.291782)
			(xy 414.758058 -10.258883) (xy 414.861956 -10.218105) (xy 414.962517 -10.169678) (xy 415.059178 -10.11387)
			(xy 415.151398 -10.050996) (xy 415.238662 -9.981406) (xy 415.320481 -9.905489) (xy 415.396398 -9.823671)
			(xy 415.465989 -9.736408) (xy 415.528864 -9.644188) (xy 415.584672 -9.547528) (xy 415.6331 -9.446967)
			(xy 415.673879 -9.343069) (xy 415.706779 -9.236414) (xy 415.731616 -9.127598) (xy 415.748253 -9.017231)
			(xy 415.756595 -8.905929) (xy 415.757106 -8.850122) (xy 415.757106 0) (xy 415.75759 0.070354) (xy 415.76548 0.210841)
			(xy 415.781234 0.350664) (xy 415.804804 0.489384) (xy 415.836114 0.626564) (xy 415.875067 0.761772)
			(xy 415.92154 0.894584) (xy 415.975387 1.024581) (xy 416.036438 1.151355) (xy 416.104501 1.274506)
			(xy 416.179362 1.393647) (xy 416.260785 1.508402) (xy 416.348515 1.618412) (xy 416.442276 1.72333)
			(xy 416.541771 1.822826) (xy 416.646689 1.916586) (xy 416.756699 2.004316) (xy 416.871455 2.085739)
			(xy 416.990596 2.1606) (xy 417.113747 2.228663) (xy 417.24052 2.289714) (xy 417.370518 2.343561)
			(xy 417.503329 2.390034) (xy 417.638538 2.428986) (xy 417.775718 2.460297) (xy 417.914438 2.483866)
			(xy 418.054261 2.49962) (xy 418.194748 2.50751) (xy 418.265102 2.507996) (xy 434.26507 2.507996)
			(xy 434.335425 2.507513) (xy 434.475912 2.499625) (xy 434.615737 2.483872) (xy 434.754458 2.460304)
			(xy 434.89164 2.428994) (xy 435.02685 2.390042) (xy 435.159663 2.34357) (xy 435.289662 2.289724)
			(xy 435.416437 2.228674) (xy 435.539589 2.160612) (xy 435.658732 2.085751) (xy 435.773489 2.004327)
			(xy 435.8835 1.916597) (xy 435.988419 1.822837) (xy 436.087916 1.723341) (xy 436.181678 1.618423)
			(xy 436.269409 1.508413) (xy 436.350834 1.393656) (xy 436.425696 1.274515) (xy 436.49376 1.151363)
			(xy 436.554812 1.024589) (xy 436.60866 0.894591) (xy 436.655133 0.761778) (xy 436.694087 0.626569)
			(xy 436.725398 0.489387) (xy 436.748967 0.350667) (xy 436.764722 0.210842) (xy 436.772612 0.070355)
			(xy 436.773066 0) (xy 436.773066 -8.850122) (xy 436.773589 -8.905929) (xy 436.781931 -9.017231) (xy 436.798567 -9.127598)
			(xy 436.823405 -9.236414) (xy 436.856304 -9.343069) (xy 436.897082 -9.446967) (xy 436.94551 -9.547528)
			(xy 437.001317 -9.644188) (xy 437.064191 -9.736408) (xy 437.133781 -9.823672) (xy 437.209698 -9.905491)
			(xy 437.291516 -9.981408) (xy 437.378779 -10.050999) (xy 437.470998 -10.113874) (xy 437.567658 -10.169683)
			(xy 437.668218 -10.218112) (xy 437.772116 -10.25889) (xy 437.878771 -10.291791) (xy 437.987586 -10.31663)
			(xy 438.097953 -10.333267) (xy 438.209255 -10.341611) (xy 438.265062 -10.342118) (xy 440.265058 -10.342118)
			(xy 440.320867 -10.34161) (xy 440.432173 -10.333272) (xy 440.542544 -10.316639) (xy 440.651364 -10.291805)
			(xy 440.758023 -10.258908) (xy 440.861926 -10.218132) (xy 440.962491 -10.169705) (xy 441.059156 -10.113899)
			(xy 441.151381 -10.051025) (xy 441.238648 -9.981434) (xy 441.320471 -9.905517) (xy 441.396392 -9.823697)
			(xy 441.465987 -9.736432) (xy 441.528865 -9.64421) (xy 441.584675 -9.547548) (xy 441.633106 -9.446985)
			(xy 441.673887 -9.343084) (xy 441.706788 -9.236425) (xy 441.731628 -9.127607) (xy 441.748265 -9.017236)
			(xy 441.756608 -8.905931) (xy 441.757054 -8.850122) (xy 441.757054 0) (xy 441.757538 0.070353) (xy 441.765428 0.210839)
			(xy 441.781182 0.350661) (xy 441.804752 0.48938) (xy 441.836062 0.626559) (xy 441.875016 0.761767)
			(xy 441.921489 0.894578) (xy 441.975336 1.024574) (xy 442.036387 1.151346) (xy 442.10445 1.274495)
			(xy 442.179312 1.393635) (xy 442.260736 1.508389) (xy 442.348466 1.618398) (xy 442.442227 1.723314)
			(xy 442.541722 1.822808) (xy 442.64664 1.916566) (xy 442.756651 2.004294) (xy 442.871407 2.085716)
			(xy 442.990548 2.160575) (xy 443.113699 2.228636) (xy 443.240472 2.289685) (xy 443.370469 2.343529)
			(xy 443.503281 2.39) (xy 443.638489 2.42895) (xy 443.775669 2.460258) (xy 443.914388 2.483825) (xy 444.054211 2.499576)
			(xy 444.194697 2.507463) (xy 444.26505 2.507996) (xy 465.600034 2.507996) (xy 465.65584 2.508519)
			(xy 465.767141 2.516862) (xy 465.877506 2.533499) (xy 465.98632 2.558338) (xy 466.092974 2.591238)
			(xy 466.19687 2.632016) (xy 466.297429 2.680445) (xy 466.394088 2.736252) (xy 466.486306 2.799127)
			(xy 466.573567 2.868717) (xy 466.655384 2.944634) (xy 466.7313 3.026452) (xy 466.800888 3.113715)
			(xy 466.863762 3.205934) (xy 466.919568 3.302594) (xy 466.967994 3.403154) (xy 467.008771 3.507051)
			(xy 467.041669 3.613705) (xy 467.066505 3.722519) (xy 467.083141 3.832885) (xy 467.091482 3.944186)
			(xy 467.09203 3.999992) (xy 467.09203 24.157686) (xy 467.091509 24.213494) (xy 467.083169 24.324797)
			(xy 467.066535 24.435167) (xy 467.041699 24.543984) (xy 467.008801 24.650641) (xy 466.968025 24.754542)
			(xy 466.919598 24.855105) (xy 466.863791 24.951768) (xy 466.800917 25.04399) (xy 466.731327 25.131255)
			(xy 466.655411 25.213077) (xy 466.573592 25.288996) (xy 466.486328 25.358589) (xy 466.394108 25.421466)
			(xy 466.297447 25.477275) (xy 466.196886 25.525705) (xy 466.092987 25.566485) (xy 465.986331 25.599387)
			(xy 465.877514 25.624226) (xy 465.767145 25.640863) (xy 465.655842 25.649207) (xy 465.600034 25.649682)
			(xy 160.11398 25.649682) (xy 160.058174 25.64916) (xy 159.946873 25.640817) (xy 159.836507 25.624181)
			(xy 159.727693 25.599343) (xy 159.62104 25.566443) (xy 159.517143 25.525665) (xy 159.416584 25.477237)
			(xy 159.319925 25.42143) (xy 159.227707 25.358555) (xy 159.140445 25.288965) (xy 159.058628 25.213048)
			(xy 158.982713 25.131229) (xy 158.913125 25.043966) (xy 158.850252 24.951746) (xy 158.794447 24.855086)
			(xy 158.746021 24.754526) (xy 158.705245 24.650628) (xy 158.672348 24.543974) (xy 158.647513 24.435159)
			(xy 158.630879 24.324793) (xy 158.622539 24.213492) (xy 158.621984 24.157686) (xy 158.621984 21.802649)
			(xy 269.304757 21.802649) (xy 269.304757 21.888399) (xy 269.312669 21.973782) (xy 269.328425 22.058072)
			(xy 269.351892 22.140548) (xy 269.382868 22.220507) (xy 269.42109 22.297267) (xy 269.466231 22.370173)
			(xy 269.517907 22.438602) (xy 269.575676 22.501972) (xy 269.639046 22.559741) (xy 269.707475 22.611417)
			(xy 269.780381 22.656558) (xy 269.857141 22.69478) (xy 269.9371 22.725756) (xy 270.019576 22.749223)
			(xy 270.103866 22.764979) (xy 270.189249 22.772891) (xy 270.274999 22.772891) (xy 270.360382 22.764979)
			(xy 270.444672 22.749223) (xy 270.527148 22.725756) (xy 270.607107 22.69478) (xy 270.683867 22.656558)
			(xy 270.756773 22.611417) (xy 270.825202 22.559741) (xy 270.888572 22.501972) (xy 270.946341 22.438602)
			(xy 270.998017 22.370173) (xy 271.043158 22.297267) (xy 271.08138 22.220507) (xy 271.112356 22.140548)
			(xy 271.135823 22.058072) (xy 271.151579 21.973782) (xy 271.159491 21.888399) (xy 271.159986 21.845524)
			(xy 271.159491 21.802649) (xy 275.654757 21.802649) (xy 275.654757 21.888399) (xy 275.662669 21.973782)
			(xy 275.678425 22.058072) (xy 275.701892 22.140548) (xy 275.732868 22.220507) (xy 275.77109 22.297267)
			(xy 275.816231 22.370173) (xy 275.867907 22.438602) (xy 275.925676 22.501972) (xy 275.989046 22.559741)
			(xy 276.057475 22.611417) (xy 276.130381 22.656558) (xy 276.207141 22.69478) (xy 276.2871 22.725756)
			(xy 276.369576 22.749223) (xy 276.453866 22.764979) (xy 276.539249 22.772891) (xy 276.624999 22.772891)
			(xy 276.710382 22.764979) (xy 276.794672 22.749223) (xy 276.877148 22.725756) (xy 276.957107 22.69478)
			(xy 277.033867 22.656558) (xy 277.106773 22.611417) (xy 277.175202 22.559741) (xy 277.238572 22.501972)
			(xy 277.296341 22.438602) (xy 277.348017 22.370173) (xy 277.393158 22.297267) (xy 277.43138 22.220507)
			(xy 277.462356 22.140548) (xy 277.485823 22.058072) (xy 277.501579 21.973782) (xy 277.509491 21.888399)
			(xy 277.509986 21.845524) (xy 277.509491 21.802649) (xy 277.508832 21.795537) (xy 308.364877 21.795537)
			(xy 308.364877 21.881287) (xy 308.372789 21.96667) (xy 308.388545 22.05096) (xy 308.412012 22.133436)
			(xy 308.442988 22.213395) (xy 308.48121 22.290155) (xy 308.526351 22.363061) (xy 308.578027 22.43149)
			(xy 308.635796 22.49486) (xy 308.699166 22.552629) (xy 308.767595 22.604305) (xy 308.840501 22.649446)
			(xy 308.917261 22.687668) (xy 308.99722 22.718644) (xy 309.079696 22.742111) (xy 309.163986 22.757867)
			(xy 309.249369 22.765779) (xy 309.335119 22.765779) (xy 309.420502 22.757867) (xy 309.504792 22.742111)
			(xy 309.587268 22.718644) (xy 309.667227 22.687668) (xy 309.743987 22.649446) (xy 309.816893 22.604305)
			(xy 309.885322 22.552629) (xy 309.948692 22.49486) (xy 310.006461 22.43149) (xy 310.058137 22.363061)
			(xy 310.103278 22.290155) (xy 310.1415 22.213395) (xy 310.172476 22.133436) (xy 310.195943 22.05096)
			(xy 310.211699 21.96667) (xy 310.219611 21.881287) (xy 310.220106 21.838412) (xy 310.219611 21.795537)
			(xy 314.714877 21.795537) (xy 314.714877 21.881287) (xy 314.722789 21.96667) (xy 314.738545 22.05096)
			(xy 314.762012 22.133436) (xy 314.792988 22.213395) (xy 314.83121 22.290155) (xy 314.876351 22.363061)
			(xy 314.928027 22.43149) (xy 314.985796 22.49486) (xy 315.049166 22.552629) (xy 315.117595 22.604305)
			(xy 315.190501 22.649446) (xy 315.267261 22.687668) (xy 315.34722 22.718644) (xy 315.429696 22.742111)
			(xy 315.513986 22.757867) (xy 315.599369 22.765779) (xy 315.685119 22.765779) (xy 315.770502 22.757867)
			(xy 315.854792 22.742111) (xy 315.937268 22.718644) (xy 316.017227 22.687668) (xy 316.093987 22.649446)
			(xy 316.166893 22.604305) (xy 316.235322 22.552629) (xy 316.298692 22.49486) (xy 316.356461 22.43149)
			(xy 316.408137 22.363061) (xy 316.453278 22.290155) (xy 316.4915 22.213395) (xy 316.522476 22.133436)
			(xy 316.545943 22.05096) (xy 316.561699 21.96667) (xy 316.569611 21.881287) (xy 316.570106 21.838412)
			(xy 316.569693 21.802649) (xy 334.455757 21.802649) (xy 334.455757 21.888399) (xy 334.463669 21.973782)
			(xy 334.479425 22.058072) (xy 334.502892 22.140548) (xy 334.533868 22.220507) (xy 334.57209 22.297267)
			(xy 334.617231 22.370173) (xy 334.668907 22.438602) (xy 334.726676 22.501972) (xy 334.790046 22.559741)
			(xy 334.858475 22.611417) (xy 334.931381 22.656558) (xy 335.008141 22.69478) (xy 335.0881 22.725756)
			(xy 335.170576 22.749223) (xy 335.254866 22.764979) (xy 335.340249 22.772891) (xy 335.425999 22.772891)
			(xy 335.511382 22.764979) (xy 335.595672 22.749223) (xy 335.678148 22.725756) (xy 335.758107 22.69478)
			(xy 335.834867 22.656558) (xy 335.907773 22.611417) (xy 335.976202 22.559741) (xy 336.039572 22.501972)
			(xy 336.097341 22.438602) (xy 336.149017 22.370173) (xy 336.194158 22.297267) (xy 336.23238 22.220507)
			(xy 336.263356 22.140548) (xy 336.286823 22.058072) (xy 336.302579 21.973782) (xy 336.310491 21.888399)
			(xy 336.310986 21.845524) (xy 336.310491 21.802649) (xy 340.805757 21.802649) (xy 340.805757 21.888399)
			(xy 340.813669 21.973782) (xy 340.829425 22.058072) (xy 340.852892 22.140548) (xy 340.883868 22.220507)
			(xy 340.92209 22.297267) (xy 340.967231 22.370173) (xy 341.018907 22.438602) (xy 341.076676 22.501972)
			(xy 341.140046 22.559741) (xy 341.208475 22.611417) (xy 341.281381 22.656558) (xy 341.358141 22.69478)
			(xy 341.4381 22.725756) (xy 341.520576 22.749223) (xy 341.604866 22.764979) (xy 341.690249 22.772891)
			(xy 341.775999 22.772891) (xy 341.861382 22.764979) (xy 341.945672 22.749223) (xy 342.028148 22.725756)
			(xy 342.108107 22.69478) (xy 342.184867 22.656558) (xy 342.257773 22.611417) (xy 342.326202 22.559741)
			(xy 342.389572 22.501972) (xy 342.447341 22.438602) (xy 342.499017 22.370173) (xy 342.544158 22.297267)
			(xy 342.58238 22.220507) (xy 342.613356 22.140548) (xy 342.636823 22.058072) (xy 342.652579 21.973782)
			(xy 342.660491 21.888399) (xy 342.660986 21.845524) (xy 342.660491 21.802649) (xy 342.659832 21.795537)
			(xy 373.515877 21.795537) (xy 373.515877 21.881287) (xy 373.523789 21.96667) (xy 373.539545 22.05096)
			(xy 373.563012 22.133436) (xy 373.593988 22.213395) (xy 373.63221 22.290155) (xy 373.677351 22.363061)
			(xy 373.729027 22.43149) (xy 373.786796 22.49486) (xy 373.850166 22.552629) (xy 373.918595 22.604305)
			(xy 373.991501 22.649446) (xy 374.068261 22.687668) (xy 374.14822 22.718644) (xy 374.230696 22.742111)
			(xy 374.314986 22.757867) (xy 374.400369 22.765779) (xy 374.486119 22.765779) (xy 374.571502 22.757867)
			(xy 374.655792 22.742111) (xy 374.738268 22.718644) (xy 374.818227 22.687668) (xy 374.894987 22.649446)
			(xy 374.967893 22.604305) (xy 375.036322 22.552629) (xy 375.099692 22.49486) (xy 375.157461 22.43149)
			(xy 375.209137 22.363061) (xy 375.254278 22.290155) (xy 375.2925 22.213395) (xy 375.323476 22.133436)
			(xy 375.346943 22.05096) (xy 375.362699 21.96667) (xy 375.370611 21.881287) (xy 375.371106 21.838412)
			(xy 375.370611 21.795537) (xy 379.865877 21.795537) (xy 379.865877 21.881287) (xy 379.873789 21.96667)
			(xy 379.889545 22.05096) (xy 379.913012 22.133436) (xy 379.943988 22.213395) (xy 379.98221 22.290155)
			(xy 380.027351 22.363061) (xy 380.079027 22.43149) (xy 380.136796 22.49486) (xy 380.200166 22.552629)
			(xy 380.268595 22.604305) (xy 380.341501 22.649446) (xy 380.418261 22.687668) (xy 380.49822 22.718644)
			(xy 380.580696 22.742111) (xy 380.664986 22.757867) (xy 380.750369 22.765779) (xy 380.836119 22.765779)
			(xy 380.921502 22.757867) (xy 381.005792 22.742111) (xy 381.088268 22.718644) (xy 381.168227 22.687668)
			(xy 381.244987 22.649446) (xy 381.317893 22.604305) (xy 381.386322 22.552629) (xy 381.449692 22.49486)
			(xy 381.507461 22.43149) (xy 381.559137 22.363061) (xy 381.604278 22.290155) (xy 381.6425 22.213395)
			(xy 381.673476 22.133436) (xy 381.696943 22.05096) (xy 381.712699 21.96667) (xy 381.720611 21.881287)
			(xy 381.721106 21.838412) (xy 381.720693 21.802649) (xy 399.098757 21.802649) (xy 399.098757 21.888399)
			(xy 399.106669 21.973782) (xy 399.122425 22.058072) (xy 399.145892 22.140548) (xy 399.176868 22.220507)
			(xy 399.21509 22.297267) (xy 399.260231 22.370173) (xy 399.311907 22.438602) (xy 399.369676 22.501972)
			(xy 399.433046 22.559741) (xy 399.501475 22.611417) (xy 399.574381 22.656558) (xy 399.651141 22.69478)
			(xy 399.7311 22.725756) (xy 399.813576 22.749223) (xy 399.897866 22.764979) (xy 399.983249 22.772891)
			(xy 400.068999 22.772891) (xy 400.154382 22.764979) (xy 400.238672 22.749223) (xy 400.321148 22.725756)
			(xy 400.401107 22.69478) (xy 400.477867 22.656558) (xy 400.550773 22.611417) (xy 400.619202 22.559741)
			(xy 400.682572 22.501972) (xy 400.740341 22.438602) (xy 400.792017 22.370173) (xy 400.837158 22.297267)
			(xy 400.87538 22.220507) (xy 400.906356 22.140548) (xy 400.929823 22.058072) (xy 400.945579 21.973782)
			(xy 400.953491 21.888399) (xy 400.953986 21.845524) (xy 400.953491 21.802649) (xy 405.448757 21.802649)
			(xy 405.448757 21.888399) (xy 405.456669 21.973782) (xy 405.472425 22.058072) (xy 405.495892 22.140548)
			(xy 405.526868 22.220507) (xy 405.56509 22.297267) (xy 405.610231 22.370173) (xy 405.661907 22.438602)
			(xy 405.719676 22.501972) (xy 405.783046 22.559741) (xy 405.851475 22.611417) (xy 405.924381 22.656558)
			(xy 406.001141 22.69478) (xy 406.0811 22.725756) (xy 406.163576 22.749223) (xy 406.247866 22.764979)
			(xy 406.333249 22.772891) (xy 406.418999 22.772891) (xy 406.504382 22.764979) (xy 406.588672 22.749223)
			(xy 406.671148 22.725756) (xy 406.751107 22.69478) (xy 406.827867 22.656558) (xy 406.900773 22.611417)
			(xy 406.969202 22.559741) (xy 407.032572 22.501972) (xy 407.090341 22.438602) (xy 407.142017 22.370173)
			(xy 407.187158 22.297267) (xy 407.22538 22.220507) (xy 407.256356 22.140548) (xy 407.279823 22.058072)
			(xy 407.295579 21.973782) (xy 407.303491 21.888399) (xy 407.303986 21.845524) (xy 407.303491 21.802649)
			(xy 407.302832 21.795537) (xy 438.158877 21.795537) (xy 438.158877 21.881287) (xy 438.166789 21.96667)
			(xy 438.182545 22.05096) (xy 438.206012 22.133436) (xy 438.236988 22.213395) (xy 438.27521 22.290155)
			(xy 438.320351 22.363061) (xy 438.372027 22.43149) (xy 438.429796 22.49486) (xy 438.493166 22.552629)
			(xy 438.561595 22.604305) (xy 438.634501 22.649446) (xy 438.711261 22.687668) (xy 438.79122 22.718644)
			(xy 438.873696 22.742111) (xy 438.957986 22.757867) (xy 439.043369 22.765779) (xy 439.129119 22.765779)
			(xy 439.214502 22.757867) (xy 439.298792 22.742111) (xy 439.381268 22.718644) (xy 439.461227 22.687668)
			(xy 439.537987 22.649446) (xy 439.610893 22.604305) (xy 439.679322 22.552629) (xy 439.742692 22.49486)
			(xy 439.800461 22.43149) (xy 439.852137 22.363061) (xy 439.897278 22.290155) (xy 439.9355 22.213395)
			(xy 439.966476 22.133436) (xy 439.989943 22.05096) (xy 440.005699 21.96667) (xy 440.013611 21.881287)
			(xy 440.014106 21.838412) (xy 440.013611 21.795537) (xy 444.508877 21.795537) (xy 444.508877 21.881287)
			(xy 444.516789 21.96667) (xy 444.532545 22.05096) (xy 444.556012 22.133436) (xy 444.586988 22.213395)
			(xy 444.62521 22.290155) (xy 444.670351 22.363061) (xy 444.722027 22.43149) (xy 444.779796 22.49486)
			(xy 444.843166 22.552629) (xy 444.911595 22.604305) (xy 444.984501 22.649446) (xy 445.061261 22.687668)
			(xy 445.14122 22.718644) (xy 445.223696 22.742111) (xy 445.307986 22.757867) (xy 445.393369 22.765779)
			(xy 445.479119 22.765779) (xy 445.564502 22.757867) (xy 445.648792 22.742111) (xy 445.731268 22.718644)
			(xy 445.811227 22.687668) (xy 445.887987 22.649446) (xy 445.960893 22.604305) (xy 446.029322 22.552629)
			(xy 446.092692 22.49486) (xy 446.150461 22.43149) (xy 446.202137 22.363061) (xy 446.247278 22.290155)
			(xy 446.2855 22.213395) (xy 446.316476 22.133436) (xy 446.339943 22.05096) (xy 446.355699 21.96667)
			(xy 446.363611 21.881287) (xy 446.364106 21.838412) (xy 446.363611 21.795537) (xy 446.355699 21.710154)
			(xy 446.339943 21.625864) (xy 446.316476 21.543388) (xy 446.2855 21.463429) (xy 446.247278 21.386669)
			(xy 446.202137 21.313763) (xy 446.150461 21.245334) (xy 446.092692 21.181964) (xy 446.029322 21.124195)
			(xy 445.988175 21.093122) (xy 460.504275 21.093122) (xy 460.504275 21.222262) (xy 460.512225 21.351157)
			(xy 460.528095 21.479317) (xy 460.551824 21.606258) (xy 460.583323 21.731497) (xy 460.622472 21.85456)
			(xy 460.669123 21.974979) (xy 460.723098 22.092298) (xy 460.784193 22.206072) (xy 460.852176 22.315869)
			(xy 460.92679 22.421272) (xy 461.007751 22.521882) (xy 461.094751 22.617317) (xy 461.187462 22.707216)
			(xy 461.285532 22.791237) (xy 461.388587 22.869061) (xy 461.496238 22.940393) (xy 461.608077 23.004963)
			(xy 461.723678 23.062525) (xy 461.842603 23.112862) (xy 461.964402 23.155782) (xy 462.088612 23.191123)
			(xy 462.214761 23.21875) (xy 462.342373 23.238559) (xy 462.470962 23.250475) (xy 462.60004 23.254452)
			(xy 462.729118 23.250475) (xy 462.857707 23.238559) (xy 462.985319 23.21875) (xy 463.111468 23.191123)
			(xy 463.235678 23.155782) (xy 463.357477 23.112862) (xy 463.476402 23.062525) (xy 463.592003 23.004963)
			(xy 463.703842 22.940393) (xy 463.811493 22.869061) (xy 463.914548 22.791237) (xy 464.012618 22.707216)
			(xy 464.105329 22.617317) (xy 464.192329 22.521882) (xy 464.27329 22.421272) (xy 464.347904 22.315869)
			(xy 464.415887 22.206072) (xy 464.476982 22.092298) (xy 464.530957 21.974979) (xy 464.577608 21.85456)
			(xy 464.616757 21.731497) (xy 464.648256 21.606258) (xy 464.671985 21.479317) (xy 464.687855 21.351157)
			(xy 464.695805 21.222262) (xy 464.696302 21.157692) (xy 464.695805 21.093122) (xy 464.687855 20.964227)
			(xy 464.671985 20.836067) (xy 464.648256 20.709126) (xy 464.616757 20.583887) (xy 464.577608 20.460824)
			(xy 464.530957 20.340405) (xy 464.476982 20.223086) (xy 464.415887 20.109312) (xy 464.347904 19.999515)
			(xy 464.27329 19.894112) (xy 464.192329 19.793502) (xy 464.105329 19.698067) (xy 464.012618 19.608168)
			(xy 463.914548 19.524147) (xy 463.811493 19.446323) (xy 463.703842 19.374991) (xy 463.592003 19.310421)
			(xy 463.476402 19.252859) (xy 463.357477 19.202522) (xy 463.235678 19.159602) (xy 463.111468 19.124261)
			(xy 462.985319 19.096634) (xy 462.857707 19.076825) (xy 462.729118 19.064909) (xy 462.60004 19.060933)
			(xy 462.470962 19.064909) (xy 462.342373 19.076825) (xy 462.214761 19.096634) (xy 462.088612 19.124261)
			(xy 461.964402 19.159602) (xy 461.842603 19.202522) (xy 461.723678 19.252859) (xy 461.608077 19.310421)
			(xy 461.496238 19.374991) (xy 461.388587 19.446323) (xy 461.285532 19.524147) (xy 461.187462 19.608168)
			(xy 461.094751 19.698067) (xy 461.007751 19.793502) (xy 460.92679 19.894112) (xy 460.852176 19.999515)
			(xy 460.784193 20.109312) (xy 460.723098 20.223086) (xy 460.669123 20.340405) (xy 460.622472 20.460824)
			(xy 460.583323 20.583887) (xy 460.551824 20.709126) (xy 460.528095 20.836067) (xy 460.512225 20.964227)
			(xy 460.504275 21.093122) (xy 445.988175 21.093122) (xy 445.960893 21.072519) (xy 445.887987 21.027378)
			(xy 445.811227 20.989156) (xy 445.731268 20.95818) (xy 445.648792 20.934713) (xy 445.564502 20.918957)
			(xy 445.479119 20.911045) (xy 445.393369 20.911045) (xy 445.307986 20.918957) (xy 445.223696 20.934713)
			(xy 445.14122 20.95818) (xy 445.061261 20.989156) (xy 444.984501 21.027378) (xy 444.911595 21.072519)
			(xy 444.843166 21.124195) (xy 444.779796 21.181964) (xy 444.722027 21.245334) (xy 444.670351 21.313763)
			(xy 444.62521 21.386669) (xy 444.586988 21.463429) (xy 444.556012 21.543388) (xy 444.532545 21.625864)
			(xy 444.516789 21.710154) (xy 444.508877 21.795537) (xy 440.013611 21.795537) (xy 440.005699 21.710154)
			(xy 439.989943 21.625864) (xy 439.966476 21.543388) (xy 439.9355 21.463429) (xy 439.897278 21.386669)
			(xy 439.852137 21.313763) (xy 439.800461 21.245334) (xy 439.742692 21.181964) (xy 439.679322 21.124195)
			(xy 439.610893 21.072519) (xy 439.537987 21.027378) (xy 439.461227 20.989156) (xy 439.381268 20.95818)
			(xy 439.298792 20.934713) (xy 439.214502 20.918957) (xy 439.129119 20.911045) (xy 439.043369 20.911045)
			(xy 438.957986 20.918957) (xy 438.873696 20.934713) (xy 438.79122 20.95818) (xy 438.711261 20.989156)
			(xy 438.634501 21.027378) (xy 438.561595 21.072519) (xy 438.493166 21.124195) (xy 438.429796 21.181964)
			(xy 438.372027 21.245334) (xy 438.320351 21.313763) (xy 438.27521 21.386669) (xy 438.236988 21.463429)
			(xy 438.206012 21.543388) (xy 438.182545 21.625864) (xy 438.166789 21.710154) (xy 438.158877 21.795537)
			(xy 407.302832 21.795537) (xy 407.295579 21.717266) (xy 407.279823 21.632976) (xy 407.256356 21.5505)
			(xy 407.22538 21.470541) (xy 407.187158 21.393781) (xy 407.142017 21.320875) (xy 407.090341 21.252446)
			(xy 407.032572 21.189076) (xy 406.969202 21.131307) (xy 406.900773 21.079631) (xy 406.827867 21.03449)
			(xy 406.751107 20.996268) (xy 406.671148 20.965292) (xy 406.588672 20.941825) (xy 406.504382 20.926069)
			(xy 406.418999 20.918157) (xy 406.333249 20.918157) (xy 406.247866 20.926069) (xy 406.163576 20.941825)
			(xy 406.0811 20.965292) (xy 406.001141 20.996268) (xy 405.924381 21.03449) (xy 405.851475 21.079631)
			(xy 405.783046 21.131307) (xy 405.719676 21.189076) (xy 405.661907 21.252446) (xy 405.610231 21.320875)
			(xy 405.56509 21.393781) (xy 405.526868 21.470541) (xy 405.495892 21.5505) (xy 405.472425 21.632976)
			(xy 405.456669 21.717266) (xy 405.448757 21.802649) (xy 400.953491 21.802649) (xy 400.945579 21.717266)
			(xy 400.929823 21.632976) (xy 400.906356 21.5505) (xy 400.87538 21.470541) (xy 400.837158 21.393781)
			(xy 400.792017 21.320875) (xy 400.740341 21.252446) (xy 400.682572 21.189076) (xy 400.619202 21.131307)
			(xy 400.550773 21.079631) (xy 400.477867 21.03449) (xy 400.401107 20.996268) (xy 400.321148 20.965292)
			(xy 400.238672 20.941825) (xy 400.154382 20.926069) (xy 400.068999 20.918157) (xy 399.983249 20.918157)
			(xy 399.897866 20.926069) (xy 399.813576 20.941825) (xy 399.7311 20.965292) (xy 399.651141 20.996268)
			(xy 399.574381 21.03449) (xy 399.501475 21.079631) (xy 399.433046 21.131307) (xy 399.369676 21.189076)
			(xy 399.311907 21.252446) (xy 399.260231 21.320875) (xy 399.21509 21.393781) (xy 399.176868 21.470541)
			(xy 399.145892 21.5505) (xy 399.122425 21.632976) (xy 399.106669 21.717266) (xy 399.098757 21.802649)
			(xy 381.720693 21.802649) (xy 381.720611 21.795537) (xy 381.712699 21.710154) (xy 381.696943 21.625864)
			(xy 381.673476 21.543388) (xy 381.6425 21.463429) (xy 381.604278 21.386669) (xy 381.559137 21.313763)
			(xy 381.507461 21.245334) (xy 381.449692 21.181964) (xy 381.386322 21.124195) (xy 381.317893 21.072519)
			(xy 381.244987 21.027378) (xy 381.168227 20.989156) (xy 381.088268 20.95818) (xy 381.005792 20.934713)
			(xy 380.921502 20.918957) (xy 380.836119 20.911045) (xy 380.750369 20.911045) (xy 380.664986 20.918957)
			(xy 380.580696 20.934713) (xy 380.49822 20.95818) (xy 380.418261 20.989156) (xy 380.341501 21.027378)
			(xy 380.268595 21.072519) (xy 380.200166 21.124195) (xy 380.136796 21.181964) (xy 380.079027 21.245334)
			(xy 380.027351 21.313763) (xy 379.98221 21.386669) (xy 379.943988 21.463429) (xy 379.913012 21.543388)
			(xy 379.889545 21.625864) (xy 379.873789 21.710154) (xy 379.865877 21.795537) (xy 375.370611 21.795537)
			(xy 375.362699 21.710154) (xy 375.346943 21.625864) (xy 375.323476 21.543388) (xy 375.2925 21.463429)
			(xy 375.254278 21.386669) (xy 375.209137 21.313763) (xy 375.157461 21.245334) (xy 375.099692 21.181964)
			(xy 375.036322 21.124195) (xy 374.967893 21.072519) (xy 374.894987 21.027378) (xy 374.818227 20.989156)
			(xy 374.738268 20.95818) (xy 374.655792 20.934713) (xy 374.571502 20.918957) (xy 374.486119 20.911045)
			(xy 374.400369 20.911045) (xy 374.314986 20.918957) (xy 374.230696 20.934713) (xy 374.14822 20.95818)
			(xy 374.068261 20.989156) (xy 373.991501 21.027378) (xy 373.918595 21.072519) (xy 373.850166 21.124195)
			(xy 373.786796 21.181964) (xy 373.729027 21.245334) (xy 373.677351 21.313763) (xy 373.63221 21.386669)
			(xy 373.593988 21.463429) (xy 373.563012 21.543388) (xy 373.539545 21.625864) (xy 373.523789 21.710154)
			(xy 373.515877 21.795537) (xy 342.659832 21.795537) (xy 342.652579 21.717266) (xy 342.636823 21.632976)
			(xy 342.613356 21.5505) (xy 342.58238 21.470541) (xy 342.544158 21.393781) (xy 342.499017 21.320875)
			(xy 342.447341 21.252446) (xy 342.389572 21.189076) (xy 342.326202 21.131307) (xy 342.257773 21.079631)
			(xy 342.184867 21.03449) (xy 342.108107 20.996268) (xy 342.028148 20.965292) (xy 341.945672 20.941825)
			(xy 341.861382 20.926069) (xy 341.775999 20.918157) (xy 341.690249 20.918157) (xy 341.604866 20.926069)
			(xy 341.520576 20.941825) (xy 341.4381 20.965292) (xy 341.358141 20.996268) (xy 341.281381 21.03449)
			(xy 341.208475 21.079631) (xy 341.140046 21.131307) (xy 341.076676 21.189076) (xy 341.018907 21.252446)
			(xy 340.967231 21.320875) (xy 340.92209 21.393781) (xy 340.883868 21.470541) (xy 340.852892 21.5505)
			(xy 340.829425 21.632976) (xy 340.813669 21.717266) (xy 340.805757 21.802649) (xy 336.310491 21.802649)
			(xy 336.302579 21.717266) (xy 336.286823 21.632976) (xy 336.263356 21.5505) (xy 336.23238 21.470541)
			(xy 336.194158 21.393781) (xy 336.149017 21.320875) (xy 336.097341 21.252446) (xy 336.039572 21.189076)
			(xy 335.976202 21.131307) (xy 335.907773 21.079631) (xy 335.834867 21.03449) (xy 335.758107 20.996268)
			(xy 335.678148 20.965292) (xy 335.595672 20.941825) (xy 335.511382 20.926069) (xy 335.425999 20.918157)
			(xy 335.340249 20.918157) (xy 335.254866 20.926069) (xy 335.170576 20.941825) (xy 335.0881 20.965292)
			(xy 335.008141 20.996268) (xy 334.931381 21.03449) (xy 334.858475 21.079631) (xy 334.790046 21.131307)
			(xy 334.726676 21.189076) (xy 334.668907 21.252446) (xy 334.617231 21.320875) (xy 334.57209 21.393781)
			(xy 334.533868 21.470541) (xy 334.502892 21.5505) (xy 334.479425 21.632976) (xy 334.463669 21.717266)
			(xy 334.455757 21.802649) (xy 316.569693 21.802649) (xy 316.569611 21.795537) (xy 316.561699 21.710154)
			(xy 316.545943 21.625864) (xy 316.522476 21.543388) (xy 316.4915 21.463429) (xy 316.453278 21.386669)
			(xy 316.408137 21.313763) (xy 316.356461 21.245334) (xy 316.298692 21.181964) (xy 316.235322 21.124195)
			(xy 316.166893 21.072519) (xy 316.093987 21.027378) (xy 316.017227 20.989156) (xy 315.937268 20.95818)
			(xy 315.854792 20.934713) (xy 315.770502 20.918957) (xy 315.685119 20.911045) (xy 315.599369 20.911045)
			(xy 315.513986 20.918957) (xy 315.429696 20.934713) (xy 315.34722 20.95818) (xy 315.267261 20.989156)
			(xy 315.190501 21.027378) (xy 315.117595 21.072519) (xy 315.049166 21.124195) (xy 314.985796 21.181964)
			(xy 314.928027 21.245334) (xy 314.876351 21.313763) (xy 314.83121 21.386669) (xy 314.792988 21.463429)
			(xy 314.762012 21.543388) (xy 314.738545 21.625864) (xy 314.722789 21.710154) (xy 314.714877 21.795537)
			(xy 310.219611 21.795537) (xy 310.211699 21.710154) (xy 310.195943 21.625864) (xy 310.172476 21.543388)
			(xy 310.1415 21.463429) (xy 310.103278 21.386669) (xy 310.058137 21.313763) (xy 310.006461 21.245334)
			(xy 309.948692 21.181964) (xy 309.885322 21.124195) (xy 309.816893 21.072519) (xy 309.743987 21.027378)
			(xy 309.667227 20.989156) (xy 309.587268 20.95818) (xy 309.504792 20.934713) (xy 309.420502 20.918957)
			(xy 309.335119 20.911045) (xy 309.249369 20.911045) (xy 309.163986 20.918957) (xy 309.079696 20.934713)
			(xy 308.99722 20.95818) (xy 308.917261 20.989156) (xy 308.840501 21.027378) (xy 308.767595 21.072519)
			(xy 308.699166 21.124195) (xy 308.635796 21.181964) (xy 308.578027 21.245334) (xy 308.526351 21.313763)
			(xy 308.48121 21.386669) (xy 308.442988 21.463429) (xy 308.412012 21.543388) (xy 308.388545 21.625864)
			(xy 308.372789 21.710154) (xy 308.364877 21.795537) (xy 277.508832 21.795537) (xy 277.501579 21.717266)
			(xy 277.485823 21.632976) (xy 277.462356 21.5505) (xy 277.43138 21.470541) (xy 277.393158 21.393781)
			(xy 277.348017 21.320875) (xy 277.296341 21.252446) (xy 277.238572 21.189076) (xy 277.175202 21.131307)
			(xy 277.106773 21.079631) (xy 277.033867 21.03449) (xy 276.957107 20.996268) (xy 276.877148 20.965292)
			(xy 276.794672 20.941825) (xy 276.710382 20.926069) (xy 276.624999 20.918157) (xy 276.539249 20.918157)
			(xy 276.453866 20.926069) (xy 276.369576 20.941825) (xy 276.2871 20.965292) (xy 276.207141 20.996268)
			(xy 276.130381 21.03449) (xy 276.057475 21.079631) (xy 275.989046 21.131307) (xy 275.925676 21.189076)
			(xy 275.867907 21.252446) (xy 275.816231 21.320875) (xy 275.77109 21.393781) (xy 275.732868 21.470541)
			(xy 275.701892 21.5505) (xy 275.678425 21.632976) (xy 275.662669 21.717266) (xy 275.654757 21.802649)
			(xy 271.159491 21.802649) (xy 271.151579 21.717266) (xy 271.135823 21.632976) (xy 271.112356 21.5505)
			(xy 271.08138 21.470541) (xy 271.043158 21.393781) (xy 270.998017 21.320875) (xy 270.946341 21.252446)
			(xy 270.888572 21.189076) (xy 270.825202 21.131307) (xy 270.756773 21.079631) (xy 270.683867 21.03449)
			(xy 270.607107 20.996268) (xy 270.527148 20.965292) (xy 270.444672 20.941825) (xy 270.360382 20.926069)
			(xy 270.274999 20.918157) (xy 270.189249 20.918157) (xy 270.103866 20.926069) (xy 270.019576 20.941825)
			(xy 269.9371 20.965292) (xy 269.857141 20.996268) (xy 269.780381 21.03449) (xy 269.707475 21.079631)
			(xy 269.639046 21.131307) (xy 269.575676 21.189076) (xy 269.517907 21.252446) (xy 269.466231 21.320875)
			(xy 269.42109 21.393781) (xy 269.382868 21.470541) (xy 269.351892 21.5505) (xy 269.328425 21.632976)
			(xy 269.312669 21.717266) (xy 269.304757 21.802649) (xy 158.621984 21.802649) (xy 158.621984 19.262649)
			(xy 209.995757 19.262649) (xy 209.995757 19.348399) (xy 210.003669 19.433782) (xy 210.019425 19.518072)
			(xy 210.042892 19.600548) (xy 210.073868 19.680507) (xy 210.11209 19.757267) (xy 210.157231 19.830173)
			(xy 210.208907 19.898602) (xy 210.266676 19.961972) (xy 210.330046 20.019741) (xy 210.398475 20.071417)
			(xy 210.471381 20.116558) (xy 210.548141 20.15478) (xy 210.6281 20.185756) (xy 210.710576 20.209223)
			(xy 210.794866 20.224979) (xy 210.880249 20.232891) (xy 210.965999 20.232891) (xy 211.051382 20.224979)
			(xy 211.135672 20.209223) (xy 211.218148 20.185756) (xy 211.298107 20.15478) (xy 211.374867 20.116558)
			(xy 211.447773 20.071417) (xy 211.516202 20.019741) (xy 211.579572 19.961972) (xy 211.637341 19.898602)
			(xy 211.689017 19.830173) (xy 211.734158 19.757267) (xy 211.77238 19.680507) (xy 211.803356 19.600548)
			(xy 211.826823 19.518072) (xy 211.842579 19.433782) (xy 211.850491 19.348399) (xy 211.850986 19.305524)
			(xy 211.850491 19.262649) (xy 216.345757 19.262649) (xy 216.345757 19.348399) (xy 216.353669 19.433782)
			(xy 216.369425 19.518072) (xy 216.392892 19.600548) (xy 216.423868 19.680507) (xy 216.46209 19.757267)
			(xy 216.507231 19.830173) (xy 216.558907 19.898602) (xy 216.616676 19.961972) (xy 216.680046 20.019741)
			(xy 216.748475 20.071417) (xy 216.821381 20.116558) (xy 216.898141 20.15478) (xy 216.9781 20.185756)
			(xy 217.060576 20.209223) (xy 217.144866 20.224979) (xy 217.230249 20.232891) (xy 217.315999 20.232891)
			(xy 217.401382 20.224979) (xy 217.485672 20.209223) (xy 217.568148 20.185756) (xy 217.648107 20.15478)
			(xy 217.724867 20.116558) (xy 217.797773 20.071417) (xy 217.866202 20.019741) (xy 217.929572 19.961972)
			(xy 217.987341 19.898602) (xy 218.039017 19.830173) (xy 218.084158 19.757267) (xy 218.12238 19.680507)
			(xy 218.153356 19.600548) (xy 218.176823 19.518072) (xy 218.192579 19.433782) (xy 218.200491 19.348399)
			(xy 218.200986 19.305524) (xy 218.200491 19.262649) (xy 218.199832 19.255537) (xy 244.026677 19.255537)
			(xy 244.026677 19.341287) (xy 244.034589 19.42667) (xy 244.050345 19.51096) (xy 244.073812 19.593436)
			(xy 244.104788 19.673395) (xy 244.14301 19.750155) (xy 244.188151 19.823061) (xy 244.239827 19.89149)
			(xy 244.297596 19.95486) (xy 244.360966 20.012629) (xy 244.429395 20.064305) (xy 244.502301 20.109446)
			(xy 244.579061 20.147668) (xy 244.65902 20.178644) (xy 244.741496 20.202111) (xy 244.825786 20.217867)
			(xy 244.911169 20.225779) (xy 244.996919 20.225779) (xy 245.082302 20.217867) (xy 245.166592 20.202111)
			(xy 245.249068 20.178644) (xy 245.329027 20.147668) (xy 245.405787 20.109446) (xy 245.478693 20.064305)
			(xy 245.547122 20.012629) (xy 245.610492 19.95486) (xy 245.668261 19.89149) (xy 245.719937 19.823061)
			(xy 245.765078 19.750155) (xy 245.8033 19.673395) (xy 245.834276 19.593436) (xy 245.857743 19.51096)
			(xy 245.873499 19.42667) (xy 245.881411 19.341287) (xy 245.881906 19.298412) (xy 245.881411 19.255537)
			(xy 250.376677 19.255537) (xy 250.376677 19.341287) (xy 250.384589 19.42667) (xy 250.400345 19.51096)
			(xy 250.423812 19.593436) (xy 250.454788 19.673395) (xy 250.49301 19.750155) (xy 250.538151 19.823061)
			(xy 250.589827 19.89149) (xy 250.647596 19.95486) (xy 250.710966 20.012629) (xy 250.779395 20.064305)
			(xy 250.852301 20.109446) (xy 250.929061 20.147668) (xy 251.00902 20.178644) (xy 251.091496 20.202111)
			(xy 251.175786 20.217867) (xy 251.261169 20.225779) (xy 251.346919 20.225779) (xy 251.432302 20.217867)
			(xy 251.516592 20.202111) (xy 251.599068 20.178644) (xy 251.679027 20.147668) (xy 251.755787 20.109446)
			(xy 251.828693 20.064305) (xy 251.897122 20.012629) (xy 251.960492 19.95486) (xy 252.018261 19.89149)
			(xy 252.069937 19.823061) (xy 252.115078 19.750155) (xy 252.1533 19.673395) (xy 252.184276 19.593436)
			(xy 252.207743 19.51096) (xy 252.223499 19.42667) (xy 252.231411 19.341287) (xy 252.231906 19.298412)
			(xy 252.231493 19.262649) (xy 269.304757 19.262649) (xy 269.304757 19.348399) (xy 269.312669 19.433782)
			(xy 269.328425 19.518072) (xy 269.351892 19.600548) (xy 269.382868 19.680507) (xy 269.42109 19.757267)
			(xy 269.466231 19.830173) (xy 269.517907 19.898602) (xy 269.575676 19.961972) (xy 269.639046 20.019741)
			(xy 269.707475 20.071417) (xy 269.780381 20.116558) (xy 269.857141 20.15478) (xy 269.9371 20.185756)
			(xy 270.019576 20.209223) (xy 270.103866 20.224979) (xy 270.189249 20.232891) (xy 270.274999 20.232891)
			(xy 270.360382 20.224979) (xy 270.444672 20.209223) (xy 270.527148 20.185756) (xy 270.607107 20.15478)
			(xy 270.62931 20.143724) (xy 274.239736 20.143724) (xy 274.239736 21.007324) (xy 274.240222 21.034593)
			(xy 274.247984 21.088577) (xy 274.263349 21.140907) (xy 274.286006 21.190517) (xy 274.315492 21.236398)
			(xy 274.351207 21.277615) (xy 274.392424 21.31333) (xy 274.438305 21.342816) (xy 274.487915 21.365473)
			(xy 274.540245 21.380838) (xy 274.594229 21.3886) (xy 274.648767 21.3886) (xy 274.702751 21.380838)
			(xy 274.755081 21.365473) (xy 274.804691 21.342816) (xy 274.850572 21.31333) (xy 274.891789 21.277615)
			(xy 274.927504 21.236398) (xy 274.95699 21.190517) (xy 274.979647 21.140907) (xy 274.995012 21.088577)
			(xy 275.002774 21.034593) (xy 275.00326 21.007324) (xy 275.00326 20.143724) (xy 275.002774 20.116455)
			(xy 274.995012 20.062471) (xy 274.979647 20.010141) (xy 274.95699 19.960531) (xy 274.927504 19.91465)
			(xy 274.891789 19.873433) (xy 274.850572 19.837718) (xy 274.804691 19.808232) (xy 274.755081 19.785575)
			(xy 274.702751 19.77021) (xy 274.648767 19.762448) (xy 274.594229 19.762448) (xy 274.540245 19.77021)
			(xy 274.487915 19.785575) (xy 274.438305 19.808232) (xy 274.392424 19.837718) (xy 274.351207 19.873433)
			(xy 274.315492 19.91465) (xy 274.286006 19.960531) (xy 274.263349 20.010141) (xy 274.247984 20.062471)
			(xy 274.240222 20.116455) (xy 274.239736 20.143724) (xy 270.62931 20.143724) (xy 270.683867 20.116558)
			(xy 270.756773 20.071417) (xy 270.825202 20.019741) (xy 270.888572 19.961972) (xy 270.946341 19.898602)
			(xy 270.998017 19.830173) (xy 271.043158 19.757267) (xy 271.08138 19.680507) (xy 271.112356 19.600548)
			(xy 271.135823 19.518072) (xy 271.151579 19.433782) (xy 271.159491 19.348399) (xy 271.159986 19.305524)
			(xy 271.159491 19.262649) (xy 275.654757 19.262649) (xy 275.654757 19.348399) (xy 275.662669 19.433782)
			(xy 275.678425 19.518072) (xy 275.701892 19.600548) (xy 275.732868 19.680507) (xy 275.77109 19.757267)
			(xy 275.816231 19.830173) (xy 275.867907 19.898602) (xy 275.925676 19.961972) (xy 275.989046 20.019741)
			(xy 276.057475 20.071417) (xy 276.130381 20.116558) (xy 276.207141 20.15478) (xy 276.2871 20.185756)
			(xy 276.369576 20.209223) (xy 276.453866 20.224979) (xy 276.539249 20.232891) (xy 276.624999 20.232891)
			(xy 276.710382 20.224979) (xy 276.794672 20.209223) (xy 276.877148 20.185756) (xy 276.957107 20.15478)
			(xy 277.033867 20.116558) (xy 277.106773 20.071417) (xy 277.175202 20.019741) (xy 277.238572 19.961972)
			(xy 277.296341 19.898602) (xy 277.348017 19.830173) (xy 277.393158 19.757267) (xy 277.43138 19.680507)
			(xy 277.462356 19.600548) (xy 277.485823 19.518072) (xy 277.501579 19.433782) (xy 277.509491 19.348399)
			(xy 277.509986 19.305524) (xy 277.509491 19.262649) (xy 277.508832 19.255537) (xy 308.364877 19.255537)
			(xy 308.364877 19.341287) (xy 308.372789 19.42667) (xy 308.388545 19.51096) (xy 308.412012 19.593436)
			(xy 308.442988 19.673395) (xy 308.48121 19.750155) (xy 308.526351 19.823061) (xy 308.578027 19.89149)
			(xy 308.635796 19.95486) (xy 308.699166 20.012629) (xy 308.767595 20.064305) (xy 308.840501 20.109446)
			(xy 308.917261 20.147668) (xy 308.99722 20.178644) (xy 309.079696 20.202111) (xy 309.163986 20.217867)
			(xy 309.249369 20.225779) (xy 309.335119 20.225779) (xy 309.420502 20.217867) (xy 309.504792 20.202111)
			(xy 309.587268 20.178644) (xy 309.667227 20.147668) (xy 309.68943 20.136612) (xy 310.871108 20.136612)
			(xy 310.871108 21.000212) (xy 310.871594 21.027481) (xy 310.879356 21.081465) (xy 310.894721 21.133795)
			(xy 310.917378 21.183405) (xy 310.946864 21.229286) (xy 310.982579 21.270503) (xy 311.023796 21.306218)
			(xy 311.069677 21.335704) (xy 311.119287 21.358361) (xy 311.171617 21.373726) (xy 311.225601 21.381488)
			(xy 311.280139 21.381488) (xy 311.334123 21.373726) (xy 311.386453 21.358361) (xy 311.436063 21.335704)
			(xy 311.481944 21.306218) (xy 311.523161 21.270503) (xy 311.558876 21.229286) (xy 311.588362 21.183405)
			(xy 311.611019 21.133795) (xy 311.626384 21.081465) (xy 311.634146 21.027481) (xy 311.634632 21.000212)
			(xy 311.634632 20.136612) (xy 311.634146 20.109343) (xy 311.626384 20.055359) (xy 311.611019 20.003029)
			(xy 311.588362 19.953419) (xy 311.558876 19.907538) (xy 311.523161 19.866321) (xy 311.481944 19.830606)
			(xy 311.436063 19.80112) (xy 311.386453 19.778463) (xy 311.334123 19.763098) (xy 311.280139 19.755336)
			(xy 311.225601 19.755336) (xy 311.171617 19.763098) (xy 311.119287 19.778463) (xy 311.069677 19.80112)
			(xy 311.023796 19.830606) (xy 310.982579 19.866321) (xy 310.946864 19.907538) (xy 310.917378 19.953419)
			(xy 310.894721 20.003029) (xy 310.879356 20.055359) (xy 310.871594 20.109343) (xy 310.871108 20.136612)
			(xy 309.68943 20.136612) (xy 309.743987 20.109446) (xy 309.816893 20.064305) (xy 309.885322 20.012629)
			(xy 309.948692 19.95486) (xy 310.006461 19.89149) (xy 310.058137 19.823061) (xy 310.103278 19.750155)
			(xy 310.1415 19.673395) (xy 310.172476 19.593436) (xy 310.195943 19.51096) (xy 310.211699 19.42667)
			(xy 310.219611 19.341287) (xy 310.220106 19.298412) (xy 310.219611 19.255537) (xy 314.714877 19.255537)
			(xy 314.714877 19.341287) (xy 314.722789 19.42667) (xy 314.738545 19.51096) (xy 314.762012 19.593436)
			(xy 314.792988 19.673395) (xy 314.83121 19.750155) (xy 314.876351 19.823061) (xy 314.928027 19.89149)
			(xy 314.985796 19.95486) (xy 315.049166 20.012629) (xy 315.117595 20.064305) (xy 315.190501 20.109446)
			(xy 315.267261 20.147668) (xy 315.34722 20.178644) (xy 315.429696 20.202111) (xy 315.513986 20.217867)
			(xy 315.599369 20.225779) (xy 315.685119 20.225779) (xy 315.770502 20.217867) (xy 315.854792 20.202111)
			(xy 315.937268 20.178644) (xy 316.017227 20.147668) (xy 316.093987 20.109446) (xy 316.166893 20.064305)
			(xy 316.235322 20.012629) (xy 316.298692 19.95486) (xy 316.356461 19.89149) (xy 316.408137 19.823061)
			(xy 316.453278 19.750155) (xy 316.4915 19.673395) (xy 316.522476 19.593436) (xy 316.545943 19.51096)
			(xy 316.561699 19.42667) (xy 316.569611 19.341287) (xy 316.570106 19.298412) (xy 316.569693 19.262649)
			(xy 334.455757 19.262649) (xy 334.455757 19.348399) (xy 334.463669 19.433782) (xy 334.479425 19.518072)
			(xy 334.502892 19.600548) (xy 334.533868 19.680507) (xy 334.57209 19.757267) (xy 334.617231 19.830173)
			(xy 334.668907 19.898602) (xy 334.726676 19.961972) (xy 334.790046 20.019741) (xy 334.858475 20.071417)
			(xy 334.931381 20.116558) (xy 335.008141 20.15478) (xy 335.0881 20.185756) (xy 335.170576 20.209223)
			(xy 335.254866 20.224979) (xy 335.340249 20.232891) (xy 335.425999 20.232891) (xy 335.511382 20.224979)
			(xy 335.595672 20.209223) (xy 335.678148 20.185756) (xy 335.758107 20.15478) (xy 335.78031 20.143724)
			(xy 339.390736 20.143724) (xy 339.390736 21.007324) (xy 339.391222 21.034593) (xy 339.398984 21.088577)
			(xy 339.414349 21.140907) (xy 339.437006 21.190517) (xy 339.466492 21.236398) (xy 339.502207 21.277615)
			(xy 339.543424 21.31333) (xy 339.589305 21.342816) (xy 339.638915 21.365473) (xy 339.691245 21.380838)
			(xy 339.745229 21.3886) (xy 339.799767 21.3886) (xy 339.853751 21.380838) (xy 339.906081 21.365473)
			(xy 339.955691 21.342816) (xy 340.001572 21.31333) (xy 340.042789 21.277615) (xy 340.078504 21.236398)
			(xy 340.10799 21.190517) (xy 340.130647 21.140907) (xy 340.146012 21.088577) (xy 340.153774 21.034593)
			(xy 340.15426 21.007324) (xy 340.15426 20.143724) (xy 340.153774 20.116455) (xy 340.146012 20.062471)
			(xy 340.130647 20.010141) (xy 340.10799 19.960531) (xy 340.078504 19.91465) (xy 340.042789 19.873433)
			(xy 340.001572 19.837718) (xy 339.955691 19.808232) (xy 339.906081 19.785575) (xy 339.853751 19.77021)
			(xy 339.799767 19.762448) (xy 339.745229 19.762448) (xy 339.691245 19.77021) (xy 339.638915 19.785575)
			(xy 339.589305 19.808232) (xy 339.543424 19.837718) (xy 339.502207 19.873433) (xy 339.466492 19.91465)
			(xy 339.437006 19.960531) (xy 339.414349 20.010141) (xy 339.398984 20.062471) (xy 339.391222 20.116455)
			(xy 339.390736 20.143724) (xy 335.78031 20.143724) (xy 335.834867 20.116558) (xy 335.907773 20.071417)
			(xy 335.976202 20.019741) (xy 336.039572 19.961972) (xy 336.097341 19.898602) (xy 336.149017 19.830173)
			(xy 336.194158 19.757267) (xy 336.23238 19.680507) (xy 336.263356 19.600548) (xy 336.286823 19.518072)
			(xy 336.302579 19.433782) (xy 336.310491 19.348399) (xy 336.310986 19.305524) (xy 336.310491 19.262649)
			(xy 340.805757 19.262649) (xy 340.805757 19.348399) (xy 340.813669 19.433782) (xy 340.829425 19.518072)
			(xy 340.852892 19.600548) (xy 340.883868 19.680507) (xy 340.92209 19.757267) (xy 340.967231 19.830173)
			(xy 341.018907 19.898602) (xy 341.076676 19.961972) (xy 341.140046 20.019741) (xy 341.208475 20.071417)
			(xy 341.281381 20.116558) (xy 341.358141 20.15478) (xy 341.4381 20.185756) (xy 341.520576 20.209223)
			(xy 341.604866 20.224979) (xy 341.690249 20.232891) (xy 341.775999 20.232891) (xy 341.861382 20.224979)
			(xy 341.945672 20.209223) (xy 342.028148 20.185756) (xy 342.108107 20.15478) (xy 342.184867 20.116558)
			(xy 342.257773 20.071417) (xy 342.326202 20.019741) (xy 342.389572 19.961972) (xy 342.447341 19.898602)
			(xy 342.499017 19.830173) (xy 342.544158 19.757267) (xy 342.58238 19.680507) (xy 342.613356 19.600548)
			(xy 342.636823 19.518072) (xy 342.652579 19.433782) (xy 342.660491 19.348399) (xy 342.660986 19.305524)
			(xy 342.660491 19.262649) (xy 342.659832 19.255537) (xy 373.515877 19.255537) (xy 373.515877 19.341287)
			(xy 373.523789 19.42667) (xy 373.539545 19.51096) (xy 373.563012 19.593436) (xy 373.593988 19.673395)
			(xy 373.63221 19.750155) (xy 373.677351 19.823061) (xy 373.729027 19.89149) (xy 373.786796 19.95486)
			(xy 373.850166 20.012629) (xy 373.918595 20.064305) (xy 373.991501 20.109446) (xy 374.068261 20.147668)
			(xy 374.14822 20.178644) (xy 374.230696 20.202111) (xy 374.314986 20.217867) (xy 374.400369 20.225779)
			(xy 374.486119 20.225779) (xy 374.571502 20.217867) (xy 374.655792 20.202111) (xy 374.738268 20.178644)
			(xy 374.818227 20.147668) (xy 374.84043 20.136612) (xy 376.022108 20.136612) (xy 376.022108 21.000212)
			(xy 376.022594 21.027481) (xy 376.030356 21.081465) (xy 376.045721 21.133795) (xy 376.068378 21.183405)
			(xy 376.097864 21.229286) (xy 376.133579 21.270503) (xy 376.174796 21.306218) (xy 376.220677 21.335704)
			(xy 376.270287 21.358361) (xy 376.322617 21.373726) (xy 376.376601 21.381488) (xy 376.431139 21.381488)
			(xy 376.485123 21.373726) (xy 376.537453 21.358361) (xy 376.587063 21.335704) (xy 376.632944 21.306218)
			(xy 376.674161 21.270503) (xy 376.709876 21.229286) (xy 376.739362 21.183405) (xy 376.762019 21.133795)
			(xy 376.777384 21.081465) (xy 376.785146 21.027481) (xy 376.785632 21.000212) (xy 376.785632 20.136612)
			(xy 376.785146 20.109343) (xy 376.777384 20.055359) (xy 376.762019 20.003029) (xy 376.739362 19.953419)
			(xy 376.709876 19.907538) (xy 376.674161 19.866321) (xy 376.632944 19.830606) (xy 376.587063 19.80112)
			(xy 376.537453 19.778463) (xy 376.485123 19.763098) (xy 376.431139 19.755336) (xy 376.376601 19.755336)
			(xy 376.322617 19.763098) (xy 376.270287 19.778463) (xy 376.220677 19.80112) (xy 376.174796 19.830606)
			(xy 376.133579 19.866321) (xy 376.097864 19.907538) (xy 376.068378 19.953419) (xy 376.045721 20.003029)
			(xy 376.030356 20.055359) (xy 376.022594 20.109343) (xy 376.022108 20.136612) (xy 374.84043 20.136612)
			(xy 374.894987 20.109446) (xy 374.967893 20.064305) (xy 375.036322 20.012629) (xy 375.099692 19.95486)
			(xy 375.157461 19.89149) (xy 375.209137 19.823061) (xy 375.254278 19.750155) (xy 375.2925 19.673395)
			(xy 375.323476 19.593436) (xy 375.346943 19.51096) (xy 375.362699 19.42667) (xy 375.370611 19.341287)
			(xy 375.371106 19.298412) (xy 375.370611 19.255537) (xy 379.865877 19.255537) (xy 379.865877 19.341287)
			(xy 379.873789 19.42667) (xy 379.889545 19.51096) (xy 379.913012 19.593436) (xy 379.943988 19.673395)
			(xy 379.98221 19.750155) (xy 380.027351 19.823061) (xy 380.079027 19.89149) (xy 380.136796 19.95486)
			(xy 380.200166 20.012629) (xy 380.268595 20.064305) (xy 380.341501 20.109446) (xy 380.418261 20.147668)
			(xy 380.49822 20.178644) (xy 380.580696 20.202111) (xy 380.664986 20.217867) (xy 380.750369 20.225779)
			(xy 380.836119 20.225779) (xy 380.921502 20.217867) (xy 381.005792 20.202111) (xy 381.088268 20.178644)
			(xy 381.168227 20.147668) (xy 381.244987 20.109446) (xy 381.317893 20.064305) (xy 381.386322 20.012629)
			(xy 381.449692 19.95486) (xy 381.507461 19.89149) (xy 381.559137 19.823061) (xy 381.604278 19.750155)
			(xy 381.6425 19.673395) (xy 381.673476 19.593436) (xy 381.696943 19.51096) (xy 381.712699 19.42667)
			(xy 381.720611 19.341287) (xy 381.721106 19.298412) (xy 381.720693 19.262649) (xy 399.098757 19.262649)
			(xy 399.098757 19.348399) (xy 399.106669 19.433782) (xy 399.122425 19.518072) (xy 399.145892 19.600548)
			(xy 399.176868 19.680507) (xy 399.21509 19.757267) (xy 399.260231 19.830173) (xy 399.311907 19.898602)
			(xy 399.369676 19.961972) (xy 399.433046 20.019741) (xy 399.501475 20.071417) (xy 399.574381 20.116558)
			(xy 399.651141 20.15478) (xy 399.7311 20.185756) (xy 399.813576 20.209223) (xy 399.897866 20.224979)
			(xy 399.983249 20.232891) (xy 400.068999 20.232891) (xy 400.154382 20.224979) (xy 400.238672 20.209223)
			(xy 400.321148 20.185756) (xy 400.401107 20.15478) (xy 400.42331 20.143724) (xy 404.033736 20.143724)
			(xy 404.033736 21.007324) (xy 404.034222 21.034593) (xy 404.041984 21.088577) (xy 404.057349 21.140907)
			(xy 404.080006 21.190517) (xy 404.109492 21.236398) (xy 404.145207 21.277615) (xy 404.186424 21.31333)
			(xy 404.232305 21.342816) (xy 404.281915 21.365473) (xy 404.334245 21.380838) (xy 404.388229 21.3886)
			(xy 404.442767 21.3886) (xy 404.496751 21.380838) (xy 404.549081 21.365473) (xy 404.598691 21.342816)
			(xy 404.644572 21.31333) (xy 404.685789 21.277615) (xy 404.721504 21.236398) (xy 404.75099 21.190517)
			(xy 404.773647 21.140907) (xy 404.789012 21.088577) (xy 404.796774 21.034593) (xy 404.79726 21.007324)
			(xy 404.79726 20.143724) (xy 404.796774 20.116455) (xy 404.789012 20.062471) (xy 404.773647 20.010141)
			(xy 404.75099 19.960531) (xy 404.721504 19.91465) (xy 404.685789 19.873433) (xy 404.644572 19.837718)
			(xy 404.598691 19.808232) (xy 404.549081 19.785575) (xy 404.496751 19.77021) (xy 404.442767 19.762448)
			(xy 404.388229 19.762448) (xy 404.334245 19.77021) (xy 404.281915 19.785575) (xy 404.232305 19.808232)
			(xy 404.186424 19.837718) (xy 404.145207 19.873433) (xy 404.109492 19.91465) (xy 404.080006 19.960531)
			(xy 404.057349 20.010141) (xy 404.041984 20.062471) (xy 404.034222 20.116455) (xy 404.033736 20.143724)
			(xy 400.42331 20.143724) (xy 400.477867 20.116558) (xy 400.550773 20.071417) (xy 400.619202 20.019741)
			(xy 400.682572 19.961972) (xy 400.740341 19.898602) (xy 400.792017 19.830173) (xy 400.837158 19.757267)
			(xy 400.87538 19.680507) (xy 400.906356 19.600548) (xy 400.929823 19.518072) (xy 400.945579 19.433782)
			(xy 400.953491 19.348399) (xy 400.953986 19.305524) (xy 400.953491 19.262649) (xy 405.448757 19.262649)
			(xy 405.448757 19.348399) (xy 405.456669 19.433782) (xy 405.472425 19.518072) (xy 405.495892 19.600548)
			(xy 405.526868 19.680507) (xy 405.56509 19.757267) (xy 405.610231 19.830173) (xy 405.661907 19.898602)
			(xy 405.719676 19.961972) (xy 405.783046 20.019741) (xy 405.851475 20.071417) (xy 405.924381 20.116558)
			(xy 406.001141 20.15478) (xy 406.0811 20.185756) (xy 406.163576 20.209223) (xy 406.247866 20.224979)
			(xy 406.333249 20.232891) (xy 406.418999 20.232891) (xy 406.504382 20.224979) (xy 406.588672 20.209223)
			(xy 406.671148 20.185756) (xy 406.751107 20.15478) (xy 406.827867 20.116558) (xy 406.900773 20.071417)
			(xy 406.969202 20.019741) (xy 407.032572 19.961972) (xy 407.090341 19.898602) (xy 407.142017 19.830173)
			(xy 407.187158 19.757267) (xy 407.22538 19.680507) (xy 407.256356 19.600548) (xy 407.279823 19.518072)
			(xy 407.295579 19.433782) (xy 407.303491 19.348399) (xy 407.303986 19.305524) (xy 407.303491 19.262649)
			(xy 407.302832 19.255537) (xy 438.158877 19.255537) (xy 438.158877 19.341287) (xy 438.166789 19.42667)
			(xy 438.182545 19.51096) (xy 438.206012 19.593436) (xy 438.236988 19.673395) (xy 438.27521 19.750155)
			(xy 438.320351 19.823061) (xy 438.372027 19.89149) (xy 438.429796 19.95486) (xy 438.493166 20.012629)
			(xy 438.561595 20.064305) (xy 438.634501 20.109446) (xy 438.711261 20.147668) (xy 438.79122 20.178644)
			(xy 438.873696 20.202111) (xy 438.957986 20.217867) (xy 439.043369 20.225779) (xy 439.129119 20.225779)
			(xy 439.214502 20.217867) (xy 439.298792 20.202111) (xy 439.381268 20.178644) (xy 439.461227 20.147668)
			(xy 439.48343 20.136612) (xy 440.665108 20.136612) (xy 440.665108 21.000212) (xy 440.665594 21.027481)
			(xy 440.673356 21.081465) (xy 440.688721 21.133795) (xy 440.711378 21.183405) (xy 440.740864 21.229286)
			(xy 440.776579 21.270503) (xy 440.817796 21.306218) (xy 440.863677 21.335704) (xy 440.913287 21.358361)
			(xy 440.965617 21.373726) (xy 441.019601 21.381488) (xy 441.074139 21.381488) (xy 441.128123 21.373726)
			(xy 441.180453 21.358361) (xy 441.230063 21.335704) (xy 441.275944 21.306218) (xy 441.317161 21.270503)
			(xy 441.352876 21.229286) (xy 441.382362 21.183405) (xy 441.405019 21.133795) (xy 441.420384 21.081465)
			(xy 441.428146 21.027481) (xy 441.428632 21.000212) (xy 441.428632 20.136612) (xy 441.428146 20.109343)
			(xy 441.420384 20.055359) (xy 441.405019 20.003029) (xy 441.382362 19.953419) (xy 441.352876 19.907538)
			(xy 441.317161 19.866321) (xy 441.275944 19.830606) (xy 441.230063 19.80112) (xy 441.180453 19.778463)
			(xy 441.128123 19.763098) (xy 441.074139 19.755336) (xy 441.019601 19.755336) (xy 440.965617 19.763098)
			(xy 440.913287 19.778463) (xy 440.863677 19.80112) (xy 440.817796 19.830606) (xy 440.776579 19.866321)
			(xy 440.740864 19.907538) (xy 440.711378 19.953419) (xy 440.688721 20.003029) (xy 440.673356 20.055359)
			(xy 440.665594 20.109343) (xy 440.665108 20.136612) (xy 439.48343 20.136612) (xy 439.537987 20.109446)
			(xy 439.610893 20.064305) (xy 439.679322 20.012629) (xy 439.742692 19.95486) (xy 439.800461 19.89149)
			(xy 439.852137 19.823061) (xy 439.897278 19.750155) (xy 439.9355 19.673395) (xy 439.966476 19.593436)
			(xy 439.989943 19.51096) (xy 440.005699 19.42667) (xy 440.013611 19.341287) (xy 440.014106 19.298412)
			(xy 440.013611 19.255537) (xy 444.508877 19.255537) (xy 444.508877 19.341287) (xy 444.516789 19.42667)
			(xy 444.532545 19.51096) (xy 444.556012 19.593436) (xy 444.586988 19.673395) (xy 444.62521 19.750155)
			(xy 444.670351 19.823061) (xy 444.722027 19.89149) (xy 444.779796 19.95486) (xy 444.843166 20.012629)
			(xy 444.911595 20.064305) (xy 444.984501 20.109446) (xy 445.061261 20.147668) (xy 445.14122 20.178644)
			(xy 445.223696 20.202111) (xy 445.307986 20.217867) (xy 445.393369 20.225779) (xy 445.479119 20.225779)
			(xy 445.564502 20.217867) (xy 445.648792 20.202111) (xy 445.731268 20.178644) (xy 445.811227 20.147668)
			(xy 445.887987 20.109446) (xy 445.960893 20.064305) (xy 446.029322 20.012629) (xy 446.092692 19.95486)
			(xy 446.150461 19.89149) (xy 446.202137 19.823061) (xy 446.247278 19.750155) (xy 446.2855 19.673395)
			(xy 446.316476 19.593436) (xy 446.339943 19.51096) (xy 446.355699 19.42667) (xy 446.363611 19.341287)
			(xy 446.364106 19.298412) (xy 446.363611 19.255537) (xy 446.355699 19.170154) (xy 446.339943 19.085864)
			(xy 446.316476 19.003388) (xy 446.2855 18.923429) (xy 446.247278 18.846669) (xy 446.202137 18.773763)
			(xy 446.150461 18.705334) (xy 446.092692 18.641964) (xy 446.029322 18.584195) (xy 445.960893 18.532519)
			(xy 445.887987 18.487378) (xy 445.811227 18.449156) (xy 445.731268 18.41818) (xy 445.648792 18.394713)
			(xy 445.564502 18.378957) (xy 445.479119 18.371045) (xy 445.393369 18.371045) (xy 445.307986 18.378957)
			(xy 445.223696 18.394713) (xy 445.14122 18.41818) (xy 445.061261 18.449156) (xy 444.984501 18.487378)
			(xy 444.911595 18.532519) (xy 444.843166 18.584195) (xy 444.779796 18.641964) (xy 444.722027 18.705334)
			(xy 444.670351 18.773763) (xy 444.62521 18.846669) (xy 444.586988 18.923429) (xy 444.556012 19.003388)
			(xy 444.532545 19.085864) (xy 444.516789 19.170154) (xy 444.508877 19.255537) (xy 440.013611 19.255537)
			(xy 440.005699 19.170154) (xy 439.989943 19.085864) (xy 439.966476 19.003388) (xy 439.9355 18.923429)
			(xy 439.897278 18.846669) (xy 439.852137 18.773763) (xy 439.800461 18.705334) (xy 439.742692 18.641964)
			(xy 439.679322 18.584195) (xy 439.610893 18.532519) (xy 439.537987 18.487378) (xy 439.461227 18.449156)
			(xy 439.381268 18.41818) (xy 439.298792 18.394713) (xy 439.214502 18.378957) (xy 439.129119 18.371045)
			(xy 439.043369 18.371045) (xy 438.957986 18.378957) (xy 438.873696 18.394713) (xy 438.79122 18.41818)
			(xy 438.711261 18.449156) (xy 438.634501 18.487378) (xy 438.561595 18.532519) (xy 438.493166 18.584195)
			(xy 438.429796 18.641964) (xy 438.372027 18.705334) (xy 438.320351 18.773763) (xy 438.27521 18.846669)
			(xy 438.236988 18.923429) (xy 438.206012 19.003388) (xy 438.182545 19.085864) (xy 438.166789 19.170154)
			(xy 438.158877 19.255537) (xy 407.302832 19.255537) (xy 407.295579 19.177266) (xy 407.279823 19.092976)
			(xy 407.256356 19.0105) (xy 407.22538 18.930541) (xy 407.187158 18.853781) (xy 407.142017 18.780875)
			(xy 407.090341 18.712446) (xy 407.032572 18.649076) (xy 406.969202 18.591307) (xy 406.900773 18.539631)
			(xy 406.827867 18.49449) (xy 406.751107 18.456268) (xy 406.671148 18.425292) (xy 406.588672 18.401825)
			(xy 406.504382 18.386069) (xy 406.418999 18.378157) (xy 406.333249 18.378157) (xy 406.247866 18.386069)
			(xy 406.163576 18.401825) (xy 406.0811 18.425292) (xy 406.001141 18.456268) (xy 405.924381 18.49449)
			(xy 405.851475 18.539631) (xy 405.783046 18.591307) (xy 405.719676 18.649076) (xy 405.661907 18.712446)
			(xy 405.610231 18.780875) (xy 405.56509 18.853781) (xy 405.526868 18.930541) (xy 405.495892 19.0105)
			(xy 405.472425 19.092976) (xy 405.456669 19.177266) (xy 405.448757 19.262649) (xy 400.953491 19.262649)
			(xy 400.945579 19.177266) (xy 400.929823 19.092976) (xy 400.906356 19.0105) (xy 400.87538 18.930541)
			(xy 400.837158 18.853781) (xy 400.792017 18.780875) (xy 400.740341 18.712446) (xy 400.682572 18.649076)
			(xy 400.619202 18.591307) (xy 400.550773 18.539631) (xy 400.477867 18.49449) (xy 400.401107 18.456268)
			(xy 400.321148 18.425292) (xy 400.238672 18.401825) (xy 400.154382 18.386069) (xy 400.068999 18.378157)
			(xy 399.983249 18.378157) (xy 399.897866 18.386069) (xy 399.813576 18.401825) (xy 399.7311 18.425292)
			(xy 399.651141 18.456268) (xy 399.574381 18.49449) (xy 399.501475 18.539631) (xy 399.433046 18.591307)
			(xy 399.369676 18.649076) (xy 399.311907 18.712446) (xy 399.260231 18.780875) (xy 399.21509 18.853781)
			(xy 399.176868 18.930541) (xy 399.145892 19.0105) (xy 399.122425 19.092976) (xy 399.106669 19.177266)
			(xy 399.098757 19.262649) (xy 381.720693 19.262649) (xy 381.720611 19.255537) (xy 381.712699 19.170154)
			(xy 381.696943 19.085864) (xy 381.673476 19.003388) (xy 381.6425 18.923429) (xy 381.604278 18.846669)
			(xy 381.559137 18.773763) (xy 381.507461 18.705334) (xy 381.449692 18.641964) (xy 381.386322 18.584195)
			(xy 381.317893 18.532519) (xy 381.244987 18.487378) (xy 381.168227 18.449156) (xy 381.088268 18.41818)
			(xy 381.005792 18.394713) (xy 380.921502 18.378957) (xy 380.836119 18.371045) (xy 380.750369 18.371045)
			(xy 380.664986 18.378957) (xy 380.580696 18.394713) (xy 380.49822 18.41818) (xy 380.418261 18.449156)
			(xy 380.341501 18.487378) (xy 380.268595 18.532519) (xy 380.200166 18.584195) (xy 380.136796 18.641964)
			(xy 380.079027 18.705334) (xy 380.027351 18.773763) (xy 379.98221 18.846669) (xy 379.943988 18.923429)
			(xy 379.913012 19.003388) (xy 379.889545 19.085864) (xy 379.873789 19.170154) (xy 379.865877 19.255537)
			(xy 375.370611 19.255537) (xy 375.362699 19.170154) (xy 375.346943 19.085864) (xy 375.323476 19.003388)
			(xy 375.2925 18.923429) (xy 375.254278 18.846669) (xy 375.209137 18.773763) (xy 375.157461 18.705334)
			(xy 375.099692 18.641964) (xy 375.036322 18.584195) (xy 374.967893 18.532519) (xy 374.894987 18.487378)
			(xy 374.818227 18.449156) (xy 374.738268 18.41818) (xy 374.655792 18.394713) (xy 374.571502 18.378957)
			(xy 374.486119 18.371045) (xy 374.400369 18.371045) (xy 374.314986 18.378957) (xy 374.230696 18.394713)
			(xy 374.14822 18.41818) (xy 374.068261 18.449156) (xy 373.991501 18.487378) (xy 373.918595 18.532519)
			(xy 373.850166 18.584195) (xy 373.786796 18.641964) (xy 373.729027 18.705334) (xy 373.677351 18.773763)
			(xy 373.63221 18.846669) (xy 373.593988 18.923429) (xy 373.563012 19.003388) (xy 373.539545 19.085864)
			(xy 373.523789 19.170154) (xy 373.515877 19.255537) (xy 342.659832 19.255537) (xy 342.652579 19.177266)
			(xy 342.636823 19.092976) (xy 342.613356 19.0105) (xy 342.58238 18.930541) (xy 342.544158 18.853781)
			(xy 342.499017 18.780875) (xy 342.447341 18.712446) (xy 342.389572 18.649076) (xy 342.326202 18.591307)
			(xy 342.257773 18.539631) (xy 342.184867 18.49449) (xy 342.108107 18.456268) (xy 342.028148 18.425292)
			(xy 341.945672 18.401825) (xy 341.861382 18.386069) (xy 341.775999 18.378157) (xy 341.690249 18.378157)
			(xy 341.604866 18.386069) (xy 341.520576 18.401825) (xy 341.4381 18.425292) (xy 341.358141 18.456268)
			(xy 341.281381 18.49449) (xy 341.208475 18.539631) (xy 341.140046 18.591307) (xy 341.076676 18.649076)
			(xy 341.018907 18.712446) (xy 340.967231 18.780875) (xy 340.92209 18.853781) (xy 340.883868 18.930541)
			(xy 340.852892 19.0105) (xy 340.829425 19.092976) (xy 340.813669 19.177266) (xy 340.805757 19.262649)
			(xy 336.310491 19.262649) (xy 336.302579 19.177266) (xy 336.286823 19.092976) (xy 336.263356 19.0105)
			(xy 336.23238 18.930541) (xy 336.194158 18.853781) (xy 336.149017 18.780875) (xy 336.097341 18.712446)
			(xy 336.039572 18.649076) (xy 335.976202 18.591307) (xy 335.907773 18.539631) (xy 335.834867 18.49449)
			(xy 335.758107 18.456268) (xy 335.678148 18.425292) (xy 335.595672 18.401825) (xy 335.511382 18.386069)
			(xy 335.425999 18.378157) (xy 335.340249 18.378157) (xy 335.254866 18.386069) (xy 335.170576 18.401825)
			(xy 335.0881 18.425292) (xy 335.008141 18.456268) (xy 334.931381 18.49449) (xy 334.858475 18.539631)
			(xy 334.790046 18.591307) (xy 334.726676 18.649076) (xy 334.668907 18.712446) (xy 334.617231 18.780875)
			(xy 334.57209 18.853781) (xy 334.533868 18.930541) (xy 334.502892 19.0105) (xy 334.479425 19.092976)
			(xy 334.463669 19.177266) (xy 334.455757 19.262649) (xy 316.569693 19.262649) (xy 316.569611 19.255537)
			(xy 316.561699 19.170154) (xy 316.545943 19.085864) (xy 316.522476 19.003388) (xy 316.4915 18.923429)
			(xy 316.453278 18.846669) (xy 316.408137 18.773763) (xy 316.356461 18.705334) (xy 316.298692 18.641964)
			(xy 316.235322 18.584195) (xy 316.166893 18.532519) (xy 316.093987 18.487378) (xy 316.017227 18.449156)
			(xy 315.937268 18.41818) (xy 315.854792 18.394713) (xy 315.770502 18.378957) (xy 315.685119 18.371045)
			(xy 315.599369 18.371045) (xy 315.513986 18.378957) (xy 315.429696 18.394713) (xy 315.34722 18.41818)
			(xy 315.267261 18.449156) (xy 315.190501 18.487378) (xy 315.117595 18.532519) (xy 315.049166 18.584195)
			(xy 314.985796 18.641964) (xy 314.928027 18.705334) (xy 314.876351 18.773763) (xy 314.83121 18.846669)
			(xy 314.792988 18.923429) (xy 314.762012 19.003388) (xy 314.738545 19.085864) (xy 314.722789 19.170154)
			(xy 314.714877 19.255537) (xy 310.219611 19.255537) (xy 310.211699 19.170154) (xy 310.195943 19.085864)
			(xy 310.172476 19.003388) (xy 310.1415 18.923429) (xy 310.103278 18.846669) (xy 310.058137 18.773763)
			(xy 310.006461 18.705334) (xy 309.948692 18.641964) (xy 309.885322 18.584195) (xy 309.816893 18.532519)
			(xy 309.743987 18.487378) (xy 309.667227 18.449156) (xy 309.587268 18.41818) (xy 309.504792 18.394713)
			(xy 309.420502 18.378957) (xy 309.335119 18.371045) (xy 309.249369 18.371045) (xy 309.163986 18.378957)
			(xy 309.079696 18.394713) (xy 308.99722 18.41818) (xy 308.917261 18.449156) (xy 308.840501 18.487378)
			(xy 308.767595 18.532519) (xy 308.699166 18.584195) (xy 308.635796 18.641964) (xy 308.578027 18.705334)
			(xy 308.526351 18.773763) (xy 308.48121 18.846669) (xy 308.442988 18.923429) (xy 308.412012 19.003388)
			(xy 308.388545 19.085864) (xy 308.372789 19.170154) (xy 308.364877 19.255537) (xy 277.508832 19.255537)
			(xy 277.501579 19.177266) (xy 277.485823 19.092976) (xy 277.462356 19.0105) (xy 277.43138 18.930541)
			(xy 277.393158 18.853781) (xy 277.348017 18.780875) (xy 277.296341 18.712446) (xy 277.238572 18.649076)
			(xy 277.175202 18.591307) (xy 277.106773 18.539631) (xy 277.033867 18.49449) (xy 276.957107 18.456268)
			(xy 276.877148 18.425292) (xy 276.794672 18.401825) (xy 276.710382 18.386069) (xy 276.624999 18.378157)
			(xy 276.539249 18.378157) (xy 276.453866 18.386069) (xy 276.369576 18.401825) (xy 276.2871 18.425292)
			(xy 276.207141 18.456268) (xy 276.130381 18.49449) (xy 276.057475 18.539631) (xy 275.989046 18.591307)
			(xy 275.925676 18.649076) (xy 275.867907 18.712446) (xy 275.816231 18.780875) (xy 275.77109 18.853781)
			(xy 275.732868 18.930541) (xy 275.701892 19.0105) (xy 275.678425 19.092976) (xy 275.662669 19.177266)
			(xy 275.654757 19.262649) (xy 271.159491 19.262649) (xy 271.151579 19.177266) (xy 271.135823 19.092976)
			(xy 271.112356 19.0105) (xy 271.08138 18.930541) (xy 271.043158 18.853781) (xy 270.998017 18.780875)
			(xy 270.946341 18.712446) (xy 270.888572 18.649076) (xy 270.825202 18.591307) (xy 270.756773 18.539631)
			(xy 270.683867 18.49449) (xy 270.607107 18.456268) (xy 270.527148 18.425292) (xy 270.444672 18.401825)
			(xy 270.360382 18.386069) (xy 270.274999 18.378157) (xy 270.189249 18.378157) (xy 270.103866 18.386069)
			(xy 270.019576 18.401825) (xy 269.9371 18.425292) (xy 269.857141 18.456268) (xy 269.780381 18.49449)
			(xy 269.707475 18.539631) (xy 269.639046 18.591307) (xy 269.575676 18.649076) (xy 269.517907 18.712446)
			(xy 269.466231 18.780875) (xy 269.42109 18.853781) (xy 269.382868 18.930541) (xy 269.351892 19.0105)
			(xy 269.328425 19.092976) (xy 269.312669 19.177266) (xy 269.304757 19.262649) (xy 252.231493 19.262649)
			(xy 252.231411 19.255537) (xy 252.223499 19.170154) (xy 252.207743 19.085864) (xy 252.184276 19.003388)
			(xy 252.1533 18.923429) (xy 252.115078 18.846669) (xy 252.069937 18.773763) (xy 252.018261 18.705334)
			(xy 251.960492 18.641964) (xy 251.897122 18.584195) (xy 251.828693 18.532519) (xy 251.755787 18.487378)
			(xy 251.679027 18.449156) (xy 251.599068 18.41818) (xy 251.516592 18.394713) (xy 251.432302 18.378957)
			(xy 251.346919 18.371045) (xy 251.261169 18.371045) (xy 251.175786 18.378957) (xy 251.091496 18.394713)
			(xy 251.00902 18.41818) (xy 250.929061 18.449156) (xy 250.852301 18.487378) (xy 250.779395 18.532519)
			(xy 250.710966 18.584195) (xy 250.647596 18.641964) (xy 250.589827 18.705334) (xy 250.538151 18.773763)
			(xy 250.49301 18.846669) (xy 250.454788 18.923429) (xy 250.423812 19.003388) (xy 250.400345 19.085864)
			(xy 250.384589 19.170154) (xy 250.376677 19.255537) (xy 245.881411 19.255537) (xy 245.873499 19.170154)
			(xy 245.857743 19.085864) (xy 245.834276 19.003388) (xy 245.8033 18.923429) (xy 245.765078 18.846669)
			(xy 245.719937 18.773763) (xy 245.668261 18.705334) (xy 245.610492 18.641964) (xy 245.547122 18.584195)
			(xy 245.478693 18.532519) (xy 245.405787 18.487378) (xy 245.329027 18.449156) (xy 245.249068 18.41818)
			(xy 245.166592 18.394713) (xy 245.082302 18.378957) (xy 244.996919 18.371045) (xy 244.911169 18.371045)
			(xy 244.825786 18.378957) (xy 244.741496 18.394713) (xy 244.65902 18.41818) (xy 244.579061 18.449156)
			(xy 244.502301 18.487378) (xy 244.429395 18.532519) (xy 244.360966 18.584195) (xy 244.297596 18.641964)
			(xy 244.239827 18.705334) (xy 244.188151 18.773763) (xy 244.14301 18.846669) (xy 244.104788 18.923429)
			(xy 244.073812 19.003388) (xy 244.050345 19.085864) (xy 244.034589 19.170154) (xy 244.026677 19.255537)
			(xy 218.199832 19.255537) (xy 218.192579 19.177266) (xy 218.176823 19.092976) (xy 218.153356 19.0105)
			(xy 218.12238 18.930541) (xy 218.084158 18.853781) (xy 218.039017 18.780875) (xy 217.987341 18.712446)
			(xy 217.929572 18.649076) (xy 217.866202 18.591307) (xy 217.797773 18.539631) (xy 217.724867 18.49449)
			(xy 217.648107 18.456268) (xy 217.568148 18.425292) (xy 217.485672 18.401825) (xy 217.401382 18.386069)
			(xy 217.315999 18.378157) (xy 217.230249 18.378157) (xy 217.144866 18.386069) (xy 217.060576 18.401825)
			(xy 216.9781 18.425292) (xy 216.898141 18.456268) (xy 216.821381 18.49449) (xy 216.748475 18.539631)
			(xy 216.680046 18.591307) (xy 216.616676 18.649076) (xy 216.558907 18.712446) (xy 216.507231 18.780875)
			(xy 216.46209 18.853781) (xy 216.423868 18.930541) (xy 216.392892 19.0105) (xy 216.369425 19.092976)
			(xy 216.353669 19.177266) (xy 216.345757 19.262649) (xy 211.850491 19.262649) (xy 211.842579 19.177266)
			(xy 211.826823 19.092976) (xy 211.803356 19.0105) (xy 211.77238 18.930541) (xy 211.734158 18.853781)
			(xy 211.689017 18.780875) (xy 211.637341 18.712446) (xy 211.579572 18.649076) (xy 211.516202 18.591307)
			(xy 211.447773 18.539631) (xy 211.374867 18.49449) (xy 211.298107 18.456268) (xy 211.218148 18.425292)
			(xy 211.135672 18.401825) (xy 211.051382 18.386069) (xy 210.965999 18.378157) (xy 210.880249 18.378157)
			(xy 210.794866 18.386069) (xy 210.710576 18.401825) (xy 210.6281 18.425292) (xy 210.548141 18.456268)
			(xy 210.471381 18.49449) (xy 210.398475 18.539631) (xy 210.330046 18.591307) (xy 210.266676 18.649076)
			(xy 210.208907 18.712446) (xy 210.157231 18.780875) (xy 210.11209 18.853781) (xy 210.073868 18.930541)
			(xy 210.042892 19.0105) (xy 210.019425 19.092976) (xy 210.003669 19.177266) (xy 209.995757 19.262649)
			(xy 158.621984 19.262649) (xy 158.621984 16.722649) (xy 209.995757 16.722649) (xy 209.995757 16.808399)
			(xy 210.003669 16.893782) (xy 210.019425 16.978072) (xy 210.042892 17.060548) (xy 210.073868 17.140507)
			(xy 210.11209 17.217267) (xy 210.157231 17.290173) (xy 210.208907 17.358602) (xy 210.266676 17.421972)
			(xy 210.330046 17.479741) (xy 210.398475 17.531417) (xy 210.471381 17.576558) (xy 210.548141 17.61478)
			(xy 210.6281 17.645756) (xy 210.710576 17.669223) (xy 210.794866 17.684979) (xy 210.880249 17.692891)
			(xy 210.965999 17.692891) (xy 211.051382 17.684979) (xy 211.135672 17.669223) (xy 211.218148 17.645756)
			(xy 211.298107 17.61478) (xy 211.374867 17.576558) (xy 211.447773 17.531417) (xy 211.506743 17.486884)
			(xy 214.154512 17.486884) (xy 214.154512 18.584164) (xy 214.154944 18.596247) (xy 214.162404 18.619232)
			(xy 214.176604 18.638784) (xy 214.196154 18.652989) (xy 214.219137 18.660454) (xy 214.23122 18.660872)
			(xy 214.84336 18.660872) (xy 214.855444 18.660453) (xy 214.878432 18.652992) (xy 214.897986 18.638789)
			(xy 214.91219 18.619235) (xy 214.919652 18.596248) (xy 214.920068 18.584164) (xy 214.920068 17.486884)
			(xy 214.9197 17.474796) (xy 214.912224 17.451806) (xy 214.898007 17.432253) (xy 214.878443 17.418051)
			(xy 214.855448 17.410591) (xy 214.84336 17.410176) (xy 214.23122 17.410176) (xy 214.21914 17.41063)
			(xy 214.196161 17.41809) (xy 214.176611 17.432286) (xy 214.162406 17.451828) (xy 214.154935 17.474804)
			(xy 214.154512 17.486884) (xy 211.506743 17.486884) (xy 211.516202 17.479741) (xy 211.579572 17.421972)
			(xy 211.637341 17.358602) (xy 211.689017 17.290173) (xy 211.734158 17.217267) (xy 211.77238 17.140507)
			(xy 211.803356 17.060548) (xy 211.826823 16.978072) (xy 211.842579 16.893782) (xy 211.850491 16.808399)
			(xy 211.850986 16.765524) (xy 211.850491 16.722649) (xy 216.345757 16.722649) (xy 216.345757 16.808399)
			(xy 216.353669 16.893782) (xy 216.369425 16.978072) (xy 216.392892 17.060548) (xy 216.423868 17.140507)
			(xy 216.46209 17.217267) (xy 216.507231 17.290173) (xy 216.558907 17.358602) (xy 216.616676 17.421972)
			(xy 216.680046 17.479741) (xy 216.748475 17.531417) (xy 216.821381 17.576558) (xy 216.898141 17.61478)
			(xy 216.9781 17.645756) (xy 217.060576 17.669223) (xy 217.144866 17.684979) (xy 217.230249 17.692891)
			(xy 217.315999 17.692891) (xy 217.401382 17.684979) (xy 217.485672 17.669223) (xy 217.568148 17.645756)
			(xy 217.648107 17.61478) (xy 217.724867 17.576558) (xy 217.797773 17.531417) (xy 217.866202 17.479741)
			(xy 217.929572 17.421972) (xy 217.987341 17.358602) (xy 218.039017 17.290173) (xy 218.084158 17.217267)
			(xy 218.12238 17.140507) (xy 218.153356 17.060548) (xy 218.176823 16.978072) (xy 218.192579 16.893782)
			(xy 218.200491 16.808399) (xy 218.200986 16.765524) (xy 218.200491 16.722649) (xy 218.199832 16.715537)
			(xy 244.026677 16.715537) (xy 244.026677 16.801287) (xy 244.034589 16.88667) (xy 244.050345 16.97096)
			(xy 244.073812 17.053436) (xy 244.104788 17.133395) (xy 244.14301 17.210155) (xy 244.188151 17.283061)
			(xy 244.239827 17.35149) (xy 244.297596 17.41486) (xy 244.360966 17.472629) (xy 244.429395 17.524305)
			(xy 244.502301 17.569446) (xy 244.579061 17.607668) (xy 244.65902 17.638644) (xy 244.741496 17.662111)
			(xy 244.825786 17.677867) (xy 244.911169 17.685779) (xy 244.996919 17.685779) (xy 245.082302 17.677867)
			(xy 245.166592 17.662111) (xy 245.249068 17.638644) (xy 245.329027 17.607668) (xy 245.405787 17.569446)
			(xy 245.478693 17.524305) (xy 245.537663 17.479772) (xy 247.3071 17.479772) (xy 247.3071 18.577052)
			(xy 247.307554 18.589133) (xy 247.315009 18.612116) (xy 247.329204 18.631667) (xy 247.348749 18.645873)
			(xy 247.371727 18.65334) (xy 247.383808 18.65376) (xy 247.995948 18.65376) (xy 248.00803 18.653376)
			(xy 248.031007 18.645894) (xy 248.050547 18.631679) (xy 248.064738 18.612121) (xy 248.072191 18.589134)
			(xy 248.072656 18.577052) (xy 248.072656 17.479772) (xy 248.072161 17.467701) (xy 248.064696 17.444741)
			(xy 248.050506 17.425208) (xy 248.030977 17.411013) (xy 248.008019 17.403542) (xy 247.995948 17.403064)
			(xy 247.383808 17.403064) (xy 247.371737 17.403571) (xy 247.348774 17.411028) (xy 247.32924 17.425214)
			(xy 247.315044 17.444742) (xy 247.307576 17.467701) (xy 247.3071 17.479772) (xy 245.537663 17.479772)
			(xy 245.547122 17.472629) (xy 245.610492 17.41486) (xy 245.668261 17.35149) (xy 245.719937 17.283061)
			(xy 245.765078 17.210155) (xy 245.8033 17.133395) (xy 245.834276 17.053436) (xy 245.857743 16.97096)
			(xy 245.873499 16.88667) (xy 245.881411 16.801287) (xy 245.881906 16.758412) (xy 245.881411 16.715537)
			(xy 250.376677 16.715537) (xy 250.376677 16.801287) (xy 250.384589 16.88667) (xy 250.400345 16.97096)
			(xy 250.423812 17.053436) (xy 250.454788 17.133395) (xy 250.49301 17.210155) (xy 250.538151 17.283061)
			(xy 250.589827 17.35149) (xy 250.647596 17.41486) (xy 250.710966 17.472629) (xy 250.779395 17.524305)
			(xy 250.852301 17.569446) (xy 250.929061 17.607668) (xy 251.00902 17.638644) (xy 251.091496 17.662111)
			(xy 251.175786 17.677867) (xy 251.261169 17.685779) (xy 251.346919 17.685779) (xy 251.432302 17.677867)
			(xy 251.516592 17.662111) (xy 251.599068 17.638644) (xy 251.679027 17.607668) (xy 251.755787 17.569446)
			(xy 251.828693 17.524305) (xy 251.897122 17.472629) (xy 251.960492 17.41486) (xy 252.018261 17.35149)
			(xy 252.069937 17.283061) (xy 252.115078 17.210155) (xy 252.1533 17.133395) (xy 252.184276 17.053436)
			(xy 252.207743 16.97096) (xy 252.223499 16.88667) (xy 252.231411 16.801287) (xy 252.231906 16.758412)
			(xy 252.231493 16.722649) (xy 269.304757 16.722649) (xy 269.304757 16.808399) (xy 269.312669 16.893782)
			(xy 269.328425 16.978072) (xy 269.351892 17.060548) (xy 269.382868 17.140507) (xy 269.42109 17.217267)
			(xy 269.466231 17.290173) (xy 269.517907 17.358602) (xy 269.575676 17.421972) (xy 269.639046 17.479741)
			(xy 269.707475 17.531417) (xy 269.780381 17.576558) (xy 269.857141 17.61478) (xy 269.9371 17.645756)
			(xy 270.019576 17.669223) (xy 270.103866 17.684979) (xy 270.189249 17.692891) (xy 270.274999 17.692891)
			(xy 270.360382 17.684979) (xy 270.444672 17.669223) (xy 270.527148 17.645756) (xy 270.607107 17.61478)
			(xy 270.683867 17.576558) (xy 270.756773 17.531417) (xy 270.815743 17.486884) (xy 273.463512 17.486884)
			(xy 273.463512 18.584164) (xy 273.463944 18.596247) (xy 273.471404 18.619232) (xy 273.485604 18.638784)
			(xy 273.505154 18.652989) (xy 273.528137 18.660454) (xy 273.54022 18.660872) (xy 274.15236 18.660872)
			(xy 274.160617 18.660709) (xy 274.17676 18.657239) (xy 274.184364 18.654014) (xy 274.192492 18.650204)
			(xy 274.210272 18.64868) (xy 274.290282 18.67027) (xy 274.30476 18.68043) (xy 274.30984 18.687542)
			(xy 274.325255 18.708552) (xy 274.360854 18.746606) (xy 274.401298 18.779463) (xy 274.445835 18.806514)
			(xy 274.493639 18.827255) (xy 274.543819 18.8413) (xy 274.595444 18.848389) (xy 274.621498 18.848832)
			(xy 274.648757 18.848375) (xy 274.702721 18.840619) (xy 274.755033 18.825265) (xy 274.804628 18.802626)
			(xy 274.850498 18.773161) (xy 274.89171 18.73747) (xy 274.927425 18.696279) (xy 274.956917 18.650427)
			(xy 274.979586 18.600845) (xy 274.994971 18.548542) (xy 275.002758 18.494583) (xy 275.00326 18.467324)
			(xy 275.00326 17.603724) (xy 275.002821 17.576458) (xy 274.99506 17.522481) (xy 274.979692 17.47016)
			(xy 274.95703 17.42056) (xy 274.927536 17.374692) (xy 274.891812 17.333491) (xy 274.850585 17.297797)
			(xy 274.804696 17.268337) (xy 274.755079 17.245711) (xy 274.702747 17.230381) (xy 274.648764 17.222659)
			(xy 274.621498 17.222216) (xy 274.595444 17.222672) (xy 274.54382 17.229759) (xy 274.49364 17.243803)
			(xy 274.445836 17.264541) (xy 274.401297 17.291588) (xy 274.360851 17.324443) (xy 274.325249 17.362493)
			(xy 274.30984 17.383506) (xy 274.30476 17.390618) (xy 274.290282 17.400778) (xy 274.210272 17.422368)
			(xy 274.192492 17.420844) (xy 274.184364 17.417034) (xy 274.176759 17.413818) (xy 274.160615 17.410365)
			(xy 274.15236 17.410176) (xy 273.54022 17.410176) (xy 273.52814 17.41063) (xy 273.505161 17.41809)
			(xy 273.485611 17.432286) (xy 273.471406 17.451828) (xy 273.463935 17.474804) (xy 273.463512 17.486884)
			(xy 270.815743 17.486884) (xy 270.825202 17.479741) (xy 270.888572 17.421972) (xy 270.946341 17.358602)
			(xy 270.998017 17.290173) (xy 271.043158 17.217267) (xy 271.08138 17.140507) (xy 271.112356 17.060548)
			(xy 271.135823 16.978072) (xy 271.151579 16.893782) (xy 271.159491 16.808399) (xy 271.159986 16.765524)
			(xy 271.159491 16.722649) (xy 275.654757 16.722649) (xy 275.654757 16.808399) (xy 275.662669 16.893782)
			(xy 275.678425 16.978072) (xy 275.701892 17.060548) (xy 275.732868 17.140507) (xy 275.77109 17.217267)
			(xy 275.816231 17.290173) (xy 275.867907 17.358602) (xy 275.925676 17.421972) (xy 275.989046 17.479741)
			(xy 276.057475 17.531417) (xy 276.130381 17.576558) (xy 276.207141 17.61478) (xy 276.2871 17.645756)
			(xy 276.369576 17.669223) (xy 276.453866 17.684979) (xy 276.539249 17.692891) (xy 276.624999 17.692891)
			(xy 276.710382 17.684979) (xy 276.794672 17.669223) (xy 276.877148 17.645756) (xy 276.957107 17.61478)
			(xy 277.033867 17.576558) (xy 277.106773 17.531417) (xy 277.175202 17.479741) (xy 277.238572 17.421972)
			(xy 277.296341 17.358602) (xy 277.348017 17.290173) (xy 277.393158 17.217267) (xy 277.43138 17.140507)
			(xy 277.462356 17.060548) (xy 277.485823 16.978072) (xy 277.501579 16.893782) (xy 277.509491 16.808399)
			(xy 277.509986 16.765524) (xy 277.509491 16.722649) (xy 277.508832 16.715537) (xy 308.364877 16.715537)
			(xy 308.364877 16.801287) (xy 308.372789 16.88667) (xy 308.388545 16.97096) (xy 308.412012 17.053436)
			(xy 308.442988 17.133395) (xy 308.48121 17.210155) (xy 308.526351 17.283061) (xy 308.578027 17.35149)
			(xy 308.635796 17.41486) (xy 308.699166 17.472629) (xy 308.767595 17.524305) (xy 308.840501 17.569446)
			(xy 308.917261 17.607668) (xy 308.99722 17.638644) (xy 309.079696 17.662111) (xy 309.163986 17.677867)
			(xy 309.249369 17.685779) (xy 309.335119 17.685779) (xy 309.420502 17.677867) (xy 309.504792 17.662111)
			(xy 309.587268 17.638644) (xy 309.667227 17.607668) (xy 309.68943 17.596612) (xy 310.871108 17.596612)
			(xy 310.871108 18.460212) (xy 310.871544 18.487477) (xy 310.87931 18.541453) (xy 310.894681 18.593772)
			(xy 310.917345 18.64337) (xy 310.946839 18.689237) (xy 310.982563 18.730436) (xy 311.023789 18.76613)
			(xy 311.069677 18.79559) (xy 311.119292 18.818217) (xy 311.171623 18.83355) (xy 311.225604 18.841276)
			(xy 311.25287 18.84172) (xy 311.278923 18.841225) (xy 311.330544 18.834143) (xy 311.380723 18.820105)
			(xy 311.428526 18.799373) (xy 311.473065 18.772331) (xy 311.513513 18.739484) (xy 311.549117 18.70144)
			(xy 311.564528 18.68043) (xy 311.569608 18.673318) (xy 311.584086 18.663158) (xy 311.664096 18.641568)
			(xy 311.681876 18.643092) (xy 311.690004 18.646902) (xy 311.697614 18.650105) (xy 311.713754 18.653567)
			(xy 311.722008 18.65376) (xy 312.334148 18.65376) (xy 312.34623 18.653376) (xy 312.369207 18.645894)
			(xy 312.388747 18.631679) (xy 312.402938 18.612121) (xy 312.410391 18.589134) (xy 312.410856 18.577052)
			(xy 312.410856 17.479772) (xy 312.410361 17.467701) (xy 312.402896 17.444741) (xy 312.388706 17.425208)
			(xy 312.369177 17.411013) (xy 312.346219 17.403542) (xy 312.334148 17.403064) (xy 311.722008 17.403064)
			(xy 311.713753 17.403253) (xy 311.697609 17.406706) (xy 311.690004 17.409922) (xy 311.681876 17.413732)
			(xy 311.664096 17.415256) (xy 311.584086 17.393666) (xy 311.569608 17.383506) (xy 311.564528 17.376394)
			(xy 311.549122 17.355377) (xy 311.513523 17.317322) (xy 311.473078 17.284463) (xy 311.428539 17.257413)
			(xy 311.380734 17.236674) (xy 311.330551 17.222631) (xy 311.278925 17.215545) (xy 311.25287 17.215104)
			(xy 311.225613 17.215596) (xy 311.171654 17.223354) (xy 311.119347 17.238708) (xy 311.069755 17.261347)
			(xy 311.023889 17.290809) (xy 310.982679 17.326496) (xy 310.946964 17.367682) (xy 310.917471 17.413529)
			(xy 310.894799 17.463105) (xy 310.879409 17.515401) (xy 310.871614 17.569355) (xy 310.871108 17.596612)
			(xy 309.68943 17.596612) (xy 309.743987 17.569446) (xy 309.816893 17.524305) (xy 309.885322 17.472629)
			(xy 309.948692 17.41486) (xy 310.006461 17.35149) (xy 310.058137 17.283061) (xy 310.103278 17.210155)
			(xy 310.1415 17.133395) (xy 310.172476 17.053436) (xy 310.195943 16.97096) (xy 310.211699 16.88667)
			(xy 310.219611 16.801287) (xy 310.220106 16.758412) (xy 310.219611 16.715537) (xy 314.714877 16.715537)
			(xy 314.714877 16.801287) (xy 314.722789 16.88667) (xy 314.738545 16.97096) (xy 314.762012 17.053436)
			(xy 314.792988 17.133395) (xy 314.83121 17.210155) (xy 314.876351 17.283061) (xy 314.928027 17.35149)
			(xy 314.985796 17.41486) (xy 315.049166 17.472629) (xy 315.117595 17.524305) (xy 315.190501 17.569446)
			(xy 315.267261 17.607668) (xy 315.34722 17.638644) (xy 315.429696 17.662111) (xy 315.513986 17.677867)
			(xy 315.599369 17.685779) (xy 315.685119 17.685779) (xy 315.770502 17.677867) (xy 315.854792 17.662111)
			(xy 315.937268 17.638644) (xy 316.017227 17.607668) (xy 316.093987 17.569446) (xy 316.166893 17.524305)
			(xy 316.235322 17.472629) (xy 316.298692 17.41486) (xy 316.356461 17.35149) (xy 316.408137 17.283061)
			(xy 316.453278 17.210155) (xy 316.4915 17.133395) (xy 316.522476 17.053436) (xy 316.545943 16.97096)
			(xy 316.561699 16.88667) (xy 316.569611 16.801287) (xy 316.570106 16.758412) (xy 316.569693 16.722649)
			(xy 334.455757 16.722649) (xy 334.455757 16.808399) (xy 334.463669 16.893782) (xy 334.479425 16.978072)
			(xy 334.502892 17.060548) (xy 334.533868 17.140507) (xy 334.57209 17.217267) (xy 334.617231 17.290173)
			(xy 334.668907 17.358602) (xy 334.726676 17.421972) (xy 334.790046 17.479741) (xy 334.858475 17.531417)
			(xy 334.931381 17.576558) (xy 335.008141 17.61478) (xy 335.0881 17.645756) (xy 335.170576 17.669223)
			(xy 335.254866 17.684979) (xy 335.340249 17.692891) (xy 335.425999 17.692891) (xy 335.511382 17.684979)
			(xy 335.595672 17.669223) (xy 335.678148 17.645756) (xy 335.758107 17.61478) (xy 335.834867 17.576558)
			(xy 335.907773 17.531417) (xy 335.966743 17.486884) (xy 338.614512 17.486884) (xy 338.614512 18.584164)
			(xy 338.614944 18.596247) (xy 338.622404 18.619232) (xy 338.636604 18.638784) (xy 338.656154 18.652989)
			(xy 338.679137 18.660454) (xy 338.69122 18.660872) (xy 339.30336 18.660872) (xy 339.311617 18.660709)
			(xy 339.32776 18.657239) (xy 339.335364 18.654014) (xy 339.343492 18.650204) (xy 339.361272 18.64868)
			(xy 339.441282 18.67027) (xy 339.45576 18.68043) (xy 339.46084 18.687542) (xy 339.476255 18.708552)
			(xy 339.511854 18.746606) (xy 339.552298 18.779463) (xy 339.596835 18.806514) (xy 339.644639 18.827255)
			(xy 339.694819 18.8413) (xy 339.746444 18.848389) (xy 339.772498 18.848832) (xy 339.799757 18.848375)
			(xy 339.853721 18.840619) (xy 339.906033 18.825265) (xy 339.955628 18.802626) (xy 340.001498 18.773161)
			(xy 340.04271 18.73747) (xy 340.078425 18.696279) (xy 340.107917 18.650427) (xy 340.130586 18.600845)
			(xy 340.145971 18.548542) (xy 340.153758 18.494583) (xy 340.15426 18.467324) (xy 340.15426 17.603724)
			(xy 340.153821 17.576458) (xy 340.14606 17.522481) (xy 340.130692 17.47016) (xy 340.10803 17.42056)
			(xy 340.078536 17.374692) (xy 340.042812 17.333491) (xy 340.001585 17.297797) (xy 339.955696 17.268337)
			(xy 339.906079 17.245711) (xy 339.853747 17.230381) (xy 339.799764 17.222659) (xy 339.772498 17.222216)
			(xy 339.746444 17.222672) (xy 339.69482 17.229759) (xy 339.64464 17.243803) (xy 339.596836 17.264541)
			(xy 339.552297 17.291588) (xy 339.511851 17.324443) (xy 339.476249 17.362493) (xy 339.46084 17.383506)
			(xy 339.45576 17.390618) (xy 339.441282 17.400778) (xy 339.361272 17.422368) (xy 339.343492 17.420844)
			(xy 339.335364 17.417034) (xy 339.327759 17.413818) (xy 339.311615 17.410365) (xy 339.30336 17.410176)
			(xy 338.69122 17.410176) (xy 338.67914 17.41063) (xy 338.656161 17.41809) (xy 338.636611 17.432286)
			(xy 338.622406 17.451828) (xy 338.614935 17.474804) (xy 338.614512 17.486884) (xy 335.966743 17.486884)
			(xy 335.976202 17.479741) (xy 336.039572 17.421972) (xy 336.097341 17.358602) (xy 336.149017 17.290173)
			(xy 336.194158 17.217267) (xy 336.23238 17.140507) (xy 336.263356 17.060548) (xy 336.286823 16.978072)
			(xy 336.302579 16.893782) (xy 336.310491 16.808399) (xy 336.310986 16.765524) (xy 336.310491 16.722649)
			(xy 340.805757 16.722649) (xy 340.805757 16.808399) (xy 340.813669 16.893782) (xy 340.829425 16.978072)
			(xy 340.852892 17.060548) (xy 340.883868 17.140507) (xy 340.92209 17.217267) (xy 340.967231 17.290173)
			(xy 341.018907 17.358602) (xy 341.076676 17.421972) (xy 341.140046 17.479741) (xy 341.208475 17.531417)
			(xy 341.281381 17.576558) (xy 341.358141 17.61478) (xy 341.4381 17.645756) (xy 341.520576 17.669223)
			(xy 341.604866 17.684979) (xy 341.690249 17.692891) (xy 341.775999 17.692891) (xy 341.861382 17.684979)
			(xy 341.945672 17.669223) (xy 342.028148 17.645756) (xy 342.108107 17.61478) (xy 342.184867 17.576558)
			(xy 342.257773 17.531417) (xy 342.326202 17.479741) (xy 342.389572 17.421972) (xy 342.447341 17.358602)
			(xy 342.499017 17.290173) (xy 342.544158 17.217267) (xy 342.58238 17.140507) (xy 342.613356 17.060548)
			(xy 342.636823 16.978072) (xy 342.652579 16.893782) (xy 342.660491 16.808399) (xy 342.660986 16.765524)
			(xy 342.660491 16.722649) (xy 342.659832 16.715537) (xy 373.515877 16.715537) (xy 373.515877 16.801287)
			(xy 373.523789 16.88667) (xy 373.539545 16.97096) (xy 373.563012 17.053436) (xy 373.593988 17.133395)
			(xy 373.63221 17.210155) (xy 373.677351 17.283061) (xy 373.729027 17.35149) (xy 373.786796 17.41486)
			(xy 373.850166 17.472629) (xy 373.918595 17.524305) (xy 373.991501 17.569446) (xy 374.068261 17.607668)
			(xy 374.14822 17.638644) (xy 374.230696 17.662111) (xy 374.314986 17.677867) (xy 374.400369 17.685779)
			(xy 374.486119 17.685779) (xy 374.571502 17.677867) (xy 374.655792 17.662111) (xy 374.738268 17.638644)
			(xy 374.818227 17.607668) (xy 374.84043 17.596612) (xy 376.022108 17.596612) (xy 376.022108 18.460212)
			(xy 376.022544 18.487477) (xy 376.03031 18.541453) (xy 376.045681 18.593772) (xy 376.068345 18.64337)
			(xy 376.097839 18.689237) (xy 376.133563 18.730436) (xy 376.174789 18.76613) (xy 376.220677 18.79559)
			(xy 376.270292 18.818217) (xy 376.322623 18.83355) (xy 376.376604 18.841276) (xy 376.40387 18.84172)
			(xy 376.429923 18.841225) (xy 376.481544 18.834143) (xy 376.531723 18.820105) (xy 376.579526 18.799373)
			(xy 376.624065 18.772331) (xy 376.664513 18.739484) (xy 376.700117 18.70144) (xy 376.715528 18.68043)
			(xy 376.720608 18.673318) (xy 376.735086 18.663158) (xy 376.815096 18.641568) (xy 376.832876 18.643092)
			(xy 376.841004 18.646902) (xy 376.848614 18.650105) (xy 376.864754 18.653567) (xy 376.873008 18.65376)
			(xy 377.485148 18.65376) (xy 377.49723 18.653376) (xy 377.520207 18.645894) (xy 377.539747 18.631679)
			(xy 377.553938 18.612121) (xy 377.561391 18.589134) (xy 377.561856 18.577052) (xy 377.561856 17.479772)
			(xy 377.561361 17.467701) (xy 377.553896 17.444741) (xy 377.539706 17.425208) (xy 377.520177 17.411013)
			(xy 377.497219 17.403542) (xy 377.485148 17.403064) (xy 376.873008 17.403064) (xy 376.864753 17.403253)
			(xy 376.848609 17.406706) (xy 376.841004 17.409922) (xy 376.832876 17.413732) (xy 376.815096 17.415256)
			(xy 376.735086 17.393666) (xy 376.720608 17.383506) (xy 376.715528 17.376394) (xy 376.700122 17.355377)
			(xy 376.664523 17.317322) (xy 376.624078 17.284463) (xy 376.579539 17.257413) (xy 376.531734 17.236674)
			(xy 376.481551 17.222631) (xy 376.429925 17.215545) (xy 376.40387 17.215104) (xy 376.376613 17.215596)
			(xy 376.322654 17.223354) (xy 376.270347 17.238708) (xy 376.220755 17.261347) (xy 376.174889 17.290809)
			(xy 376.133679 17.326496) (xy 376.097964 17.367682) (xy 376.068471 17.413529) (xy 376.045799 17.463105)
			(xy 376.030409 17.515401) (xy 376.022614 17.569355) (xy 376.022108 17.596612) (xy 374.84043 17.596612)
			(xy 374.894987 17.569446) (xy 374.967893 17.524305) (xy 375.036322 17.472629) (xy 375.099692 17.41486)
			(xy 375.157461 17.35149) (xy 375.209137 17.283061) (xy 375.254278 17.210155) (xy 375.2925 17.133395)
			(xy 375.323476 17.053436) (xy 375.346943 16.97096) (xy 375.362699 16.88667) (xy 375.370611 16.801287)
			(xy 375.371106 16.758412) (xy 375.370611 16.715537) (xy 379.865877 16.715537) (xy 379.865877 16.801287)
			(xy 379.873789 16.88667) (xy 379.889545 16.97096) (xy 379.913012 17.053436) (xy 379.943988 17.133395)
			(xy 379.98221 17.210155) (xy 380.027351 17.283061) (xy 380.079027 17.35149) (xy 380.136796 17.41486)
			(xy 380.200166 17.472629) (xy 380.268595 17.524305) (xy 380.341501 17.569446) (xy 380.418261 17.607668)
			(xy 380.49822 17.638644) (xy 380.580696 17.662111) (xy 380.664986 17.677867) (xy 380.750369 17.685779)
			(xy 380.836119 17.685779) (xy 380.921502 17.677867) (xy 381.005792 17.662111) (xy 381.088268 17.638644)
			(xy 381.168227 17.607668) (xy 381.244987 17.569446) (xy 381.317893 17.524305) (xy 381.386322 17.472629)
			(xy 381.449692 17.41486) (xy 381.507461 17.35149) (xy 381.559137 17.283061) (xy 381.604278 17.210155)
			(xy 381.6425 17.133395) (xy 381.673476 17.053436) (xy 381.696943 16.97096) (xy 381.712699 16.88667)
			(xy 381.720611 16.801287) (xy 381.721106 16.758412) (xy 381.720693 16.722649) (xy 399.098757 16.722649)
			(xy 399.098757 16.808399) (xy 399.106669 16.893782) (xy 399.122425 16.978072) (xy 399.145892 17.060548)
			(xy 399.176868 17.140507) (xy 399.21509 17.217267) (xy 399.260231 17.290173) (xy 399.311907 17.358602)
			(xy 399.369676 17.421972) (xy 399.433046 17.479741) (xy 399.501475 17.531417) (xy 399.574381 17.576558)
			(xy 399.651141 17.61478) (xy 399.7311 17.645756) (xy 399.813576 17.669223) (xy 399.897866 17.684979)
			(xy 399.983249 17.692891) (xy 400.068999 17.692891) (xy 400.154382 17.684979) (xy 400.238672 17.669223)
			(xy 400.321148 17.645756) (xy 400.401107 17.61478) (xy 400.477867 17.576558) (xy 400.550773 17.531417)
			(xy 400.609743 17.486884) (xy 403.257512 17.486884) (xy 403.257512 18.584164) (xy 403.257944 18.596247)
			(xy 403.265404 18.619232) (xy 403.279604 18.638784) (xy 403.299154 18.652989) (xy 403.322137 18.660454)
			(xy 403.33422 18.660872) (xy 403.94636 18.660872) (xy 403.954617 18.660709) (xy 403.97076 18.657239)
			(xy 403.978364 18.654014) (xy 403.986492 18.650204) (xy 404.004272 18.64868) (xy 404.084282 18.67027)
			(xy 404.09876 18.68043) (xy 404.10384 18.687542) (xy 404.119255 18.708552) (xy 404.154854 18.746606)
			(xy 404.195298 18.779463) (xy 404.239835 18.806514) (xy 404.287639 18.827255) (xy 404.337819 18.8413)
			(xy 404.389444 18.848389) (xy 404.415498 18.848832) (xy 404.442757 18.848375) (xy 404.496721 18.840619)
			(xy 404.549033 18.825265) (xy 404.598628 18.802626) (xy 404.644498 18.773161) (xy 404.68571 18.73747)
			(xy 404.721425 18.696279) (xy 404.750917 18.650427) (xy 404.773586 18.600845) (xy 404.788971 18.548542)
			(xy 404.796758 18.494583) (xy 404.79726 18.467324) (xy 404.79726 17.603724) (xy 404.796821 17.576458)
			(xy 404.78906 17.522481) (xy 404.773692 17.47016) (xy 404.75103 17.42056) (xy 404.721536 17.374692)
			(xy 404.685812 17.333491) (xy 404.644585 17.297797) (xy 404.598696 17.268337) (xy 404.549079 17.245711)
			(xy 404.496747 17.230381) (xy 404.442764 17.222659) (xy 404.415498 17.222216) (xy 404.389444 17.222672)
			(xy 404.33782 17.229759) (xy 404.28764 17.243803) (xy 404.239836 17.264541) (xy 404.195297 17.291588)
			(xy 404.154851 17.324443) (xy 404.119249 17.362493) (xy 404.10384 17.383506) (xy 404.09876 17.390618)
			(xy 404.084282 17.400778) (xy 404.004272 17.422368) (xy 403.986492 17.420844) (xy 403.978364 17.417034)
			(xy 403.970759 17.413818) (xy 403.954615 17.410365) (xy 403.94636 17.410176) (xy 403.33422 17.410176)
			(xy 403.32214 17.41063) (xy 403.299161 17.41809) (xy 403.279611 17.432286) (xy 403.265406 17.451828)
			(xy 403.257935 17.474804) (xy 403.257512 17.486884) (xy 400.609743 17.486884) (xy 400.619202 17.479741)
			(xy 400.682572 17.421972) (xy 400.740341 17.358602) (xy 400.792017 17.290173) (xy 400.837158 17.217267)
			(xy 400.87538 17.140507) (xy 400.906356 17.060548) (xy 400.929823 16.978072) (xy 400.945579 16.893782)
			(xy 400.953491 16.808399) (xy 400.953986 16.765524) (xy 400.953491 16.722649) (xy 405.448757 16.722649)
			(xy 405.448757 16.808399) (xy 405.456669 16.893782) (xy 405.472425 16.978072) (xy 405.495892 17.060548)
			(xy 405.526868 17.140507) (xy 405.56509 17.217267) (xy 405.610231 17.290173) (xy 405.661907 17.358602)
			(xy 405.719676 17.421972) (xy 405.783046 17.479741) (xy 405.851475 17.531417) (xy 405.924381 17.576558)
			(xy 406.001141 17.61478) (xy 406.0811 17.645756) (xy 406.163576 17.669223) (xy 406.247866 17.684979)
			(xy 406.333249 17.692891) (xy 406.418999 17.692891) (xy 406.504382 17.684979) (xy 406.588672 17.669223)
			(xy 406.671148 17.645756) (xy 406.751107 17.61478) (xy 406.827867 17.576558) (xy 406.900773 17.531417)
			(xy 406.969202 17.479741) (xy 407.032572 17.421972) (xy 407.090341 17.358602) (xy 407.142017 17.290173)
			(xy 407.187158 17.217267) (xy 407.22538 17.140507) (xy 407.256356 17.060548) (xy 407.279823 16.978072)
			(xy 407.295579 16.893782) (xy 407.303491 16.808399) (xy 407.303986 16.765524) (xy 407.303491 16.722649)
			(xy 407.302832 16.715537) (xy 438.158877 16.715537) (xy 438.158877 16.801287) (xy 438.166789 16.88667)
			(xy 438.182545 16.97096) (xy 438.206012 17.053436) (xy 438.236988 17.133395) (xy 438.27521 17.210155)
			(xy 438.320351 17.283061) (xy 438.372027 17.35149) (xy 438.429796 17.41486) (xy 438.493166 17.472629)
			(xy 438.561595 17.524305) (xy 438.634501 17.569446) (xy 438.711261 17.607668) (xy 438.79122 17.638644)
			(xy 438.873696 17.662111) (xy 438.957986 17.677867) (xy 439.043369 17.685779) (xy 439.129119 17.685779)
			(xy 439.214502 17.677867) (xy 439.298792 17.662111) (xy 439.381268 17.638644) (xy 439.461227 17.607668)
			(xy 439.48343 17.596612) (xy 440.665108 17.596612) (xy 440.665108 18.460212) (xy 440.665544 18.487477)
			(xy 440.67331 18.541453) (xy 440.688681 18.593772) (xy 440.711345 18.64337) (xy 440.740839 18.689237)
			(xy 440.776563 18.730436) (xy 440.817789 18.76613) (xy 440.863677 18.79559) (xy 440.913292 18.818217)
			(xy 440.965623 18.83355) (xy 441.019604 18.841276) (xy 441.04687 18.84172) (xy 441.072923 18.841225)
			(xy 441.124544 18.834143) (xy 441.174723 18.820105) (xy 441.222526 18.799373) (xy 441.267065 18.772331)
			(xy 441.307513 18.739484) (xy 441.343117 18.70144) (xy 441.358528 18.68043) (xy 441.363608 18.673318)
			(xy 441.378086 18.663158) (xy 441.458096 18.641568) (xy 441.475876 18.643092) (xy 441.484004 18.646902)
			(xy 441.491614 18.650105) (xy 441.507754 18.653567) (xy 441.516008 18.65376) (xy 442.128148 18.65376)
			(xy 442.14023 18.653376) (xy 442.163207 18.645894) (xy 442.182747 18.631679) (xy 442.196938 18.612121)
			(xy 442.204391 18.589134) (xy 442.204856 18.577052) (xy 442.204856 17.479772) (xy 442.204361 17.467701)
			(xy 442.196896 17.444741) (xy 442.182706 17.425208) (xy 442.163177 17.411013) (xy 442.140219 17.403542)
			(xy 442.128148 17.403064) (xy 441.516008 17.403064) (xy 441.507753 17.403253) (xy 441.491609 17.406706)
			(xy 441.484004 17.409922) (xy 441.475876 17.413732) (xy 441.458096 17.415256) (xy 441.378086 17.393666)
			(xy 441.363608 17.383506) (xy 441.358528 17.376394) (xy 441.343122 17.355377) (xy 441.307523 17.317322)
			(xy 441.267078 17.284463) (xy 441.222539 17.257413) (xy 441.174734 17.236674) (xy 441.124551 17.222631)
			(xy 441.072925 17.215545) (xy 441.04687 17.215104) (xy 441.019613 17.215596) (xy 440.965654 17.223354)
			(xy 440.913347 17.238708) (xy 440.863755 17.261347) (xy 440.817889 17.290809) (xy 440.776679 17.326496)
			(xy 440.740964 17.367682) (xy 440.711471 17.413529) (xy 440.688799 17.463105) (xy 440.673409 17.515401)
			(xy 440.665614 17.569355) (xy 440.665108 17.596612) (xy 439.48343 17.596612) (xy 439.537987 17.569446)
			(xy 439.610893 17.524305) (xy 439.679322 17.472629) (xy 439.742692 17.41486) (xy 439.800461 17.35149)
			(xy 439.852137 17.283061) (xy 439.897278 17.210155) (xy 439.9355 17.133395) (xy 439.966476 17.053436)
			(xy 439.989943 16.97096) (xy 440.005699 16.88667) (xy 440.013611 16.801287) (xy 440.014106 16.758412)
			(xy 440.013611 16.715537) (xy 444.508877 16.715537) (xy 444.508877 16.801287) (xy 444.516789 16.88667)
			(xy 444.532545 16.97096) (xy 444.556012 17.053436) (xy 444.586988 17.133395) (xy 444.62521 17.210155)
			(xy 444.670351 17.283061) (xy 444.722027 17.35149) (xy 444.779796 17.41486) (xy 444.843166 17.472629)
			(xy 444.911595 17.524305) (xy 444.984501 17.569446) (xy 445.061261 17.607668) (xy 445.14122 17.638644)
			(xy 445.223696 17.662111) (xy 445.307986 17.677867) (xy 445.393369 17.685779) (xy 445.479119 17.685779)
			(xy 445.564502 17.677867) (xy 445.648792 17.662111) (xy 445.731268 17.638644) (xy 445.811227 17.607668)
			(xy 445.887987 17.569446) (xy 445.960893 17.524305) (xy 446.029322 17.472629) (xy 446.092692 17.41486)
			(xy 446.150461 17.35149) (xy 446.202137 17.283061) (xy 446.247278 17.210155) (xy 446.2855 17.133395)
			(xy 446.316476 17.053436) (xy 446.339943 16.97096) (xy 446.355699 16.88667) (xy 446.363611 16.801287)
			(xy 446.364106 16.758412) (xy 446.363611 16.715537) (xy 446.355699 16.630154) (xy 446.339943 16.545864)
			(xy 446.316476 16.463388) (xy 446.2855 16.383429) (xy 446.247278 16.306669) (xy 446.202137 16.233763)
			(xy 446.150461 16.165334) (xy 446.092692 16.101964) (xy 446.029322 16.044195) (xy 445.960893 15.992519)
			(xy 445.887987 15.947378) (xy 445.811227 15.909156) (xy 445.731268 15.87818) (xy 445.648792 15.854713)
			(xy 445.564502 15.838957) (xy 445.479119 15.831045) (xy 445.393369 15.831045) (xy 445.307986 15.838957)
			(xy 445.223696 15.854713) (xy 445.14122 15.87818) (xy 445.061261 15.909156) (xy 444.984501 15.947378)
			(xy 444.911595 15.992519) (xy 444.843166 16.044195) (xy 444.779796 16.101964) (xy 444.722027 16.165334)
			(xy 444.670351 16.233763) (xy 444.62521 16.306669) (xy 444.586988 16.383429) (xy 444.556012 16.463388)
			(xy 444.532545 16.545864) (xy 444.516789 16.630154) (xy 444.508877 16.715537) (xy 440.013611 16.715537)
			(xy 440.005699 16.630154) (xy 439.989943 16.545864) (xy 439.966476 16.463388) (xy 439.9355 16.383429)
			(xy 439.897278 16.306669) (xy 439.852137 16.233763) (xy 439.800461 16.165334) (xy 439.742692 16.101964)
			(xy 439.679322 16.044195) (xy 439.610893 15.992519) (xy 439.537987 15.947378) (xy 439.461227 15.909156)
			(xy 439.381268 15.87818) (xy 439.298792 15.854713) (xy 439.214502 15.838957) (xy 439.129119 15.831045)
			(xy 439.043369 15.831045) (xy 438.957986 15.838957) (xy 438.873696 15.854713) (xy 438.79122 15.87818)
			(xy 438.711261 15.909156) (xy 438.634501 15.947378) (xy 438.561595 15.992519) (xy 438.493166 16.044195)
			(xy 438.429796 16.101964) (xy 438.372027 16.165334) (xy 438.320351 16.233763) (xy 438.27521 16.306669)
			(xy 438.236988 16.383429) (xy 438.206012 16.463388) (xy 438.182545 16.545864) (xy 438.166789 16.630154)
			(xy 438.158877 16.715537) (xy 407.302832 16.715537) (xy 407.295579 16.637266) (xy 407.279823 16.552976)
			(xy 407.256356 16.4705) (xy 407.22538 16.390541) (xy 407.187158 16.313781) (xy 407.142017 16.240875)
			(xy 407.090341 16.172446) (xy 407.032572 16.109076) (xy 406.969202 16.051307) (xy 406.900773 15.999631)
			(xy 406.827867 15.95449) (xy 406.751107 15.916268) (xy 406.671148 15.885292) (xy 406.588672 15.861825)
			(xy 406.504382 15.846069) (xy 406.418999 15.838157) (xy 406.333249 15.838157) (xy 406.247866 15.846069)
			(xy 406.163576 15.861825) (xy 406.0811 15.885292) (xy 406.001141 15.916268) (xy 405.924381 15.95449)
			(xy 405.851475 15.999631) (xy 405.783046 16.051307) (xy 405.719676 16.109076) (xy 405.661907 16.172446)
			(xy 405.610231 16.240875) (xy 405.56509 16.313781) (xy 405.526868 16.390541) (xy 405.495892 16.4705)
			(xy 405.472425 16.552976) (xy 405.456669 16.637266) (xy 405.448757 16.722649) (xy 400.953491 16.722649)
			(xy 400.945579 16.637266) (xy 400.929823 16.552976) (xy 400.906356 16.4705) (xy 400.87538 16.390541)
			(xy 400.837158 16.313781) (xy 400.792017 16.240875) (xy 400.740341 16.172446) (xy 400.682572 16.109076)
			(xy 400.619202 16.051307) (xy 400.550773 15.999631) (xy 400.477867 15.95449) (xy 400.401107 15.916268)
			(xy 400.321148 15.885292) (xy 400.238672 15.861825) (xy 400.154382 15.846069) (xy 400.068999 15.838157)
			(xy 399.983249 15.838157) (xy 399.897866 15.846069) (xy 399.813576 15.861825) (xy 399.7311 15.885292)
			(xy 399.651141 15.916268) (xy 399.574381 15.95449) (xy 399.501475 15.999631) (xy 399.433046 16.051307)
			(xy 399.369676 16.109076) (xy 399.311907 16.172446) (xy 399.260231 16.240875) (xy 399.21509 16.313781)
			(xy 399.176868 16.390541) (xy 399.145892 16.4705) (xy 399.122425 16.552976) (xy 399.106669 16.637266)
			(xy 399.098757 16.722649) (xy 381.720693 16.722649) (xy 381.720611 16.715537) (xy 381.712699 16.630154)
			(xy 381.696943 16.545864) (xy 381.673476 16.463388) (xy 381.6425 16.383429) (xy 381.604278 16.306669)
			(xy 381.559137 16.233763) (xy 381.507461 16.165334) (xy 381.449692 16.101964) (xy 381.386322 16.044195)
			(xy 381.317893 15.992519) (xy 381.244987 15.947378) (xy 381.168227 15.909156) (xy 381.088268 15.87818)
			(xy 381.005792 15.854713) (xy 380.921502 15.838957) (xy 380.836119 15.831045) (xy 380.750369 15.831045)
			(xy 380.664986 15.838957) (xy 380.580696 15.854713) (xy 380.49822 15.87818) (xy 380.418261 15.909156)
			(xy 380.341501 15.947378) (xy 380.268595 15.992519) (xy 380.200166 16.044195) (xy 380.136796 16.101964)
			(xy 380.079027 16.165334) (xy 380.027351 16.233763) (xy 379.98221 16.306669) (xy 379.943988 16.383429)
			(xy 379.913012 16.463388) (xy 379.889545 16.545864) (xy 379.873789 16.630154) (xy 379.865877 16.715537)
			(xy 375.370611 16.715537) (xy 375.362699 16.630154) (xy 375.346943 16.545864) (xy 375.323476 16.463388)
			(xy 375.2925 16.383429) (xy 375.254278 16.306669) (xy 375.209137 16.233763) (xy 375.157461 16.165334)
			(xy 375.099692 16.101964) (xy 375.036322 16.044195) (xy 374.967893 15.992519) (xy 374.894987 15.947378)
			(xy 374.818227 15.909156) (xy 374.738268 15.87818) (xy 374.655792 15.854713) (xy 374.571502 15.838957)
			(xy 374.486119 15.831045) (xy 374.400369 15.831045) (xy 374.314986 15.838957) (xy 374.230696 15.854713)
			(xy 374.14822 15.87818) (xy 374.068261 15.909156) (xy 373.991501 15.947378) (xy 373.918595 15.992519)
			(xy 373.850166 16.044195) (xy 373.786796 16.101964) (xy 373.729027 16.165334) (xy 373.677351 16.233763)
			(xy 373.63221 16.306669) (xy 373.593988 16.383429) (xy 373.563012 16.463388) (xy 373.539545 16.545864)
			(xy 373.523789 16.630154) (xy 373.515877 16.715537) (xy 342.659832 16.715537) (xy 342.652579 16.637266)
			(xy 342.636823 16.552976) (xy 342.613356 16.4705) (xy 342.58238 16.390541) (xy 342.544158 16.313781)
			(xy 342.499017 16.240875) (xy 342.447341 16.172446) (xy 342.389572 16.109076) (xy 342.326202 16.051307)
			(xy 342.257773 15.999631) (xy 342.184867 15.95449) (xy 342.108107 15.916268) (xy 342.028148 15.885292)
			(xy 341.945672 15.861825) (xy 341.861382 15.846069) (xy 341.775999 15.838157) (xy 341.690249 15.838157)
			(xy 341.604866 15.846069) (xy 341.520576 15.861825) (xy 341.4381 15.885292) (xy 341.358141 15.916268)
			(xy 341.281381 15.95449) (xy 341.208475 15.999631) (xy 341.140046 16.051307) (xy 341.076676 16.109076)
			(xy 341.018907 16.172446) (xy 340.967231 16.240875) (xy 340.92209 16.313781) (xy 340.883868 16.390541)
			(xy 340.852892 16.4705) (xy 340.829425 16.552976) (xy 340.813669 16.637266) (xy 340.805757 16.722649)
			(xy 336.310491 16.722649) (xy 336.302579 16.637266) (xy 336.286823 16.552976) (xy 336.263356 16.4705)
			(xy 336.23238 16.390541) (xy 336.194158 16.313781) (xy 336.149017 16.240875) (xy 336.097341 16.172446)
			(xy 336.039572 16.109076) (xy 335.976202 16.051307) (xy 335.907773 15.999631) (xy 335.834867 15.95449)
			(xy 335.758107 15.916268) (xy 335.678148 15.885292) (xy 335.595672 15.861825) (xy 335.511382 15.846069)
			(xy 335.425999 15.838157) (xy 335.340249 15.838157) (xy 335.254866 15.846069) (xy 335.170576 15.861825)
			(xy 335.0881 15.885292) (xy 335.008141 15.916268) (xy 334.931381 15.95449) (xy 334.858475 15.999631)
			(xy 334.790046 16.051307) (xy 334.726676 16.109076) (xy 334.668907 16.172446) (xy 334.617231 16.240875)
			(xy 334.57209 16.313781) (xy 334.533868 16.390541) (xy 334.502892 16.4705) (xy 334.479425 16.552976)
			(xy 334.463669 16.637266) (xy 334.455757 16.722649) (xy 316.569693 16.722649) (xy 316.569611 16.715537)
			(xy 316.561699 16.630154) (xy 316.545943 16.545864) (xy 316.522476 16.463388) (xy 316.4915 16.383429)
			(xy 316.453278 16.306669) (xy 316.408137 16.233763) (xy 316.356461 16.165334) (xy 316.298692 16.101964)
			(xy 316.235322 16.044195) (xy 316.166893 15.992519) (xy 316.093987 15.947378) (xy 316.017227 15.909156)
			(xy 315.937268 15.87818) (xy 315.854792 15.854713) (xy 315.770502 15.838957) (xy 315.685119 15.831045)
			(xy 315.599369 15.831045) (xy 315.513986 15.838957) (xy 315.429696 15.854713) (xy 315.34722 15.87818)
			(xy 315.267261 15.909156) (xy 315.190501 15.947378) (xy 315.117595 15.992519) (xy 315.049166 16.044195)
			(xy 314.985796 16.101964) (xy 314.928027 16.165334) (xy 314.876351 16.233763) (xy 314.83121 16.306669)
			(xy 314.792988 16.383429) (xy 314.762012 16.463388) (xy 314.738545 16.545864) (xy 314.722789 16.630154)
			(xy 314.714877 16.715537) (xy 310.219611 16.715537) (xy 310.211699 16.630154) (xy 310.195943 16.545864)
			(xy 310.172476 16.463388) (xy 310.1415 16.383429) (xy 310.103278 16.306669) (xy 310.058137 16.233763)
			(xy 310.006461 16.165334) (xy 309.948692 16.101964) (xy 309.885322 16.044195) (xy 309.816893 15.992519)
			(xy 309.743987 15.947378) (xy 309.667227 15.909156) (xy 309.587268 15.87818) (xy 309.504792 15.854713)
			(xy 309.420502 15.838957) (xy 309.335119 15.831045) (xy 309.249369 15.831045) (xy 309.163986 15.838957)
			(xy 309.079696 15.854713) (xy 308.99722 15.87818) (xy 308.917261 15.909156) (xy 308.840501 15.947378)
			(xy 308.767595 15.992519) (xy 308.699166 16.044195) (xy 308.635796 16.101964) (xy 308.578027 16.165334)
			(xy 308.526351 16.233763) (xy 308.48121 16.306669) (xy 308.442988 16.383429) (xy 308.412012 16.463388)
			(xy 308.388545 16.545864) (xy 308.372789 16.630154) (xy 308.364877 16.715537) (xy 277.508832 16.715537)
			(xy 277.501579 16.637266) (xy 277.485823 16.552976) (xy 277.462356 16.4705) (xy 277.43138 16.390541)
			(xy 277.393158 16.313781) (xy 277.348017 16.240875) (xy 277.296341 16.172446) (xy 277.238572 16.109076)
			(xy 277.175202 16.051307) (xy 277.106773 15.999631) (xy 277.033867 15.95449) (xy 276.957107 15.916268)
			(xy 276.877148 15.885292) (xy 276.794672 15.861825) (xy 276.710382 15.846069) (xy 276.624999 15.838157)
			(xy 276.539249 15.838157) (xy 276.453866 15.846069) (xy 276.369576 15.861825) (xy 276.2871 15.885292)
			(xy 276.207141 15.916268) (xy 276.130381 15.95449) (xy 276.057475 15.999631) (xy 275.989046 16.051307)
			(xy 275.925676 16.109076) (xy 275.867907 16.172446) (xy 275.816231 16.240875) (xy 275.77109 16.313781)
			(xy 275.732868 16.390541) (xy 275.701892 16.4705) (xy 275.678425 16.552976) (xy 275.662669 16.637266)
			(xy 275.654757 16.722649) (xy 271.159491 16.722649) (xy 271.151579 16.637266) (xy 271.135823 16.552976)
			(xy 271.112356 16.4705) (xy 271.08138 16.390541) (xy 271.043158 16.313781) (xy 270.998017 16.240875)
			(xy 270.946341 16.172446) (xy 270.888572 16.109076) (xy 270.825202 16.051307) (xy 270.756773 15.999631)
			(xy 270.683867 15.95449) (xy 270.607107 15.916268) (xy 270.527148 15.885292) (xy 270.444672 15.861825)
			(xy 270.360382 15.846069) (xy 270.274999 15.838157) (xy 270.189249 15.838157) (xy 270.103866 15.846069)
			(xy 270.019576 15.861825) (xy 269.9371 15.885292) (xy 269.857141 15.916268) (xy 269.780381 15.95449)
			(xy 269.707475 15.999631) (xy 269.639046 16.051307) (xy 269.575676 16.109076) (xy 269.517907 16.172446)
			(xy 269.466231 16.240875) (xy 269.42109 16.313781) (xy 269.382868 16.390541) (xy 269.351892 16.4705)
			(xy 269.328425 16.552976) (xy 269.312669 16.637266) (xy 269.304757 16.722649) (xy 252.231493 16.722649)
			(xy 252.231411 16.715537) (xy 252.223499 16.630154) (xy 252.207743 16.545864) (xy 252.184276 16.463388)
			(xy 252.1533 16.383429) (xy 252.115078 16.306669) (xy 252.069937 16.233763) (xy 252.018261 16.165334)
			(xy 251.960492 16.101964) (xy 251.897122 16.044195) (xy 251.828693 15.992519) (xy 251.755787 15.947378)
			(xy 251.679027 15.909156) (xy 251.599068 15.87818) (xy 251.516592 15.854713) (xy 251.432302 15.838957)
			(xy 251.346919 15.831045) (xy 251.261169 15.831045) (xy 251.175786 15.838957) (xy 251.091496 15.854713)
			(xy 251.00902 15.87818) (xy 250.929061 15.909156) (xy 250.852301 15.947378) (xy 250.779395 15.992519)
			(xy 250.710966 16.044195) (xy 250.647596 16.101964) (xy 250.589827 16.165334) (xy 250.538151 16.233763)
			(xy 250.49301 16.306669) (xy 250.454788 16.383429) (xy 250.423812 16.463388) (xy 250.400345 16.545864)
			(xy 250.384589 16.630154) (xy 250.376677 16.715537) (xy 245.881411 16.715537) (xy 245.873499 16.630154)
			(xy 245.857743 16.545864) (xy 245.834276 16.463388) (xy 245.8033 16.383429) (xy 245.765078 16.306669)
			(xy 245.719937 16.233763) (xy 245.668261 16.165334) (xy 245.610492 16.101964) (xy 245.547122 16.044195)
			(xy 245.478693 15.992519) (xy 245.405787 15.947378) (xy 245.329027 15.909156) (xy 245.249068 15.87818)
			(xy 245.166592 15.854713) (xy 245.082302 15.838957) (xy 244.996919 15.831045) (xy 244.911169 15.831045)
			(xy 244.825786 15.838957) (xy 244.741496 15.854713) (xy 244.65902 15.87818) (xy 244.579061 15.909156)
			(xy 244.502301 15.947378) (xy 244.429395 15.992519) (xy 244.360966 16.044195) (xy 244.297596 16.101964)
			(xy 244.239827 16.165334) (xy 244.188151 16.233763) (xy 244.14301 16.306669) (xy 244.104788 16.383429)
			(xy 244.073812 16.463388) (xy 244.050345 16.545864) (xy 244.034589 16.630154) (xy 244.026677 16.715537)
			(xy 218.199832 16.715537) (xy 218.192579 16.637266) (xy 218.176823 16.552976) (xy 218.153356 16.4705)
			(xy 218.12238 16.390541) (xy 218.084158 16.313781) (xy 218.039017 16.240875) (xy 217.987341 16.172446)
			(xy 217.929572 16.109076) (xy 217.866202 16.051307) (xy 217.797773 15.999631) (xy 217.724867 15.95449)
			(xy 217.648107 15.916268) (xy 217.568148 15.885292) (xy 217.485672 15.861825) (xy 217.401382 15.846069)
			(xy 217.315999 15.838157) (xy 217.230249 15.838157) (xy 217.144866 15.846069) (xy 217.060576 15.861825)
			(xy 216.9781 15.885292) (xy 216.898141 15.916268) (xy 216.821381 15.95449) (xy 216.748475 15.999631)
			(xy 216.680046 16.051307) (xy 216.616676 16.109076) (xy 216.558907 16.172446) (xy 216.507231 16.240875)
			(xy 216.46209 16.313781) (xy 216.423868 16.390541) (xy 216.392892 16.4705) (xy 216.369425 16.552976)
			(xy 216.353669 16.637266) (xy 216.345757 16.722649) (xy 211.850491 16.722649) (xy 211.842579 16.637266)
			(xy 211.826823 16.552976) (xy 211.803356 16.4705) (xy 211.77238 16.390541) (xy 211.734158 16.313781)
			(xy 211.689017 16.240875) (xy 211.637341 16.172446) (xy 211.579572 16.109076) (xy 211.516202 16.051307)
			(xy 211.447773 15.999631) (xy 211.374867 15.95449) (xy 211.298107 15.916268) (xy 211.218148 15.885292)
			(xy 211.135672 15.861825) (xy 211.051382 15.846069) (xy 210.965999 15.838157) (xy 210.880249 15.838157)
			(xy 210.794866 15.846069) (xy 210.710576 15.861825) (xy 210.6281 15.885292) (xy 210.548141 15.916268)
			(xy 210.471381 15.95449) (xy 210.398475 15.999631) (xy 210.330046 16.051307) (xy 210.266676 16.109076)
			(xy 210.208907 16.172446) (xy 210.157231 16.240875) (xy 210.11209 16.313781) (xy 210.073868 16.390541)
			(xy 210.042892 16.4705) (xy 210.019425 16.552976) (xy 210.003669 16.637266) (xy 209.995757 16.722649)
			(xy 158.621984 16.722649) (xy 158.621984 11.850929) (xy 251.524757 11.850929) (xy 251.524757 11.936679)
			(xy 251.532669 12.022062) (xy 251.548425 12.106352) (xy 251.571892 12.188828) (xy 251.602868 12.268787)
			(xy 251.64109 12.345547) (xy 251.686231 12.418453) (xy 251.737907 12.486882) (xy 251.795676 12.550252)
			(xy 251.859046 12.608021) (xy 251.927475 12.659697) (xy 252.000381 12.704838) (xy 252.077141 12.74306)
			(xy 252.1571 12.774036) (xy 252.239576 12.797503) (xy 252.323866 12.813259) (xy 252.409249 12.821171)
			(xy 252.494999 12.821171) (xy 252.580382 12.813259) (xy 252.664672 12.797503) (xy 252.747148 12.774036)
			(xy 252.827107 12.74306) (xy 252.903867 12.704838) (xy 252.976773 12.659697) (xy 253.045202 12.608021)
			(xy 253.108572 12.550252) (xy 253.166341 12.486882) (xy 253.218017 12.418453) (xy 253.263158 12.345547)
			(xy 253.30138 12.268787) (xy 253.332356 12.188828) (xy 253.355823 12.106352) (xy 253.371579 12.022062)
			(xy 253.379491 11.936679) (xy 253.379986 11.893804) (xy 253.379491 11.850929) (xy 257.874757 11.850929)
			(xy 257.874757 11.936679) (xy 257.882669 12.022062) (xy 257.898425 12.106352) (xy 257.921892 12.188828)
			(xy 257.952868 12.268787) (xy 257.99109 12.345547) (xy 258.036231 12.418453) (xy 258.087907 12.486882)
			(xy 258.145676 12.550252) (xy 258.209046 12.608021) (xy 258.277475 12.659697) (xy 258.350381 12.704838)
			(xy 258.427141 12.74306) (xy 258.5071 12.774036) (xy 258.589576 12.797503) (xy 258.673866 12.813259)
			(xy 258.759249 12.821171) (xy 258.844999 12.821171) (xy 258.930382 12.813259) (xy 259.014672 12.797503)
			(xy 259.097148 12.774036) (xy 259.177107 12.74306) (xy 259.253867 12.704838) (xy 259.326773 12.659697)
			(xy 259.395202 12.608021) (xy 259.458572 12.550252) (xy 259.516341 12.486882) (xy 259.568017 12.418453)
			(xy 259.613158 12.345547) (xy 259.65138 12.268787) (xy 259.682356 12.188828) (xy 259.705823 12.106352)
			(xy 259.721579 12.022062) (xy 259.729491 11.936679) (xy 259.729986 11.893804) (xy 259.72979 11.876837)
			(xy 309.725301 11.876837) (xy 309.725301 11.962587) (xy 309.733213 12.04797) (xy 309.748969 12.13226)
			(xy 309.772436 12.214736) (xy 309.803412 12.294695) (xy 309.841634 12.371455) (xy 309.886775 12.444361)
			(xy 309.938451 12.51279) (xy 309.99622 12.57616) (xy 310.05959 12.633929) (xy 310.128019 12.685605)
			(xy 310.200925 12.730746) (xy 310.277685 12.768968) (xy 310.357644 12.799944) (xy 310.44012 12.823411)
			(xy 310.52441 12.839167) (xy 310.609793 12.847079) (xy 310.695543 12.847079) (xy 310.780926 12.839167)
			(xy 310.865216 12.823411) (xy 310.947692 12.799944) (xy 311.027651 12.768968) (xy 311.104411 12.730746)
			(xy 311.177317 12.685605) (xy 311.245746 12.633929) (xy 311.309116 12.57616) (xy 311.366885 12.51279)
			(xy 311.418561 12.444361) (xy 311.463702 12.371455) (xy 311.501924 12.294695) (xy 311.5329 12.214736)
			(xy 311.556367 12.13226) (xy 311.572123 12.04797) (xy 311.580035 11.962587) (xy 311.58053 11.919712)
			(xy 311.580035 11.876837) (xy 316.075301 11.876837) (xy 316.075301 11.962587) (xy 316.083213 12.04797)
			(xy 316.098969 12.13226) (xy 316.122436 12.214736) (xy 316.153412 12.294695) (xy 316.191634 12.371455)
			(xy 316.236775 12.444361) (xy 316.288451 12.51279) (xy 316.34622 12.57616) (xy 316.40959 12.633929)
			(xy 316.478019 12.685605) (xy 316.550925 12.730746) (xy 316.627685 12.768968) (xy 316.707644 12.799944)
			(xy 316.79012 12.823411) (xy 316.87441 12.839167) (xy 316.959793 12.847079) (xy 317.045543 12.847079)
			(xy 317.130926 12.839167) (xy 317.215216 12.823411) (xy 317.297692 12.799944) (xy 317.377651 12.768968)
			(xy 317.454411 12.730746) (xy 317.527317 12.685605) (xy 317.595746 12.633929) (xy 317.659116 12.57616)
			(xy 317.716885 12.51279) (xy 317.768561 12.444361) (xy 317.813702 12.371455) (xy 317.851924 12.294695)
			(xy 317.8829 12.214736) (xy 317.906367 12.13226) (xy 317.922123 12.04797) (xy 317.930035 11.962587)
			(xy 317.93053 11.919712) (xy 317.930117 11.883949) (xy 324.295757 11.883949) (xy 324.295757 11.969699)
			(xy 324.303669 12.055082) (xy 324.319425 12.139372) (xy 324.342892 12.221848) (xy 324.373868 12.301807)
			(xy 324.41209 12.378567) (xy 324.457231 12.451473) (xy 324.508907 12.519902) (xy 324.566676 12.583272)
			(xy 324.630046 12.641041) (xy 324.698475 12.692717) (xy 324.771381 12.737858) (xy 324.848141 12.77608)
			(xy 324.9281 12.807056) (xy 325.010576 12.830523) (xy 325.094866 12.846279) (xy 325.180249 12.854191)
			(xy 325.265999 12.854191) (xy 325.351382 12.846279) (xy 325.435672 12.830523) (xy 325.518148 12.807056)
			(xy 325.598107 12.77608) (xy 325.674867 12.737858) (xy 325.747773 12.692717) (xy 325.816202 12.641041)
			(xy 325.879572 12.583272) (xy 325.937341 12.519902) (xy 325.989017 12.451473) (xy 326.034158 12.378567)
			(xy 326.07238 12.301807) (xy 326.103356 12.221848) (xy 326.126823 12.139372) (xy 326.142579 12.055082)
			(xy 326.150491 11.969699) (xy 326.150986 11.926824) (xy 326.150491 11.883949) (xy 330.645757 11.883949)
			(xy 330.645757 11.969699) (xy 330.653669 12.055082) (xy 330.669425 12.139372) (xy 330.692892 12.221848)
			(xy 330.723868 12.301807) (xy 330.76209 12.378567) (xy 330.807231 12.451473) (xy 330.858907 12.519902)
			(xy 330.916676 12.583272) (xy 330.980046 12.641041) (xy 331.048475 12.692717) (xy 331.121381 12.737858)
			(xy 331.198141 12.77608) (xy 331.2781 12.807056) (xy 331.360576 12.830523) (xy 331.444866 12.846279)
			(xy 331.530249 12.854191) (xy 331.615999 12.854191) (xy 331.701382 12.846279) (xy 331.785672 12.830523)
			(xy 331.868148 12.807056) (xy 331.948107 12.77608) (xy 332.024867 12.737858) (xy 332.097773 12.692717)
			(xy 332.166202 12.641041) (xy 332.229572 12.583272) (xy 332.287341 12.519902) (xy 332.339017 12.451473)
			(xy 332.384158 12.378567) (xy 332.42238 12.301807) (xy 332.453356 12.221848) (xy 332.476823 12.139372)
			(xy 332.492579 12.055082) (xy 332.500491 11.969699) (xy 332.500986 11.926824) (xy 332.50079 11.909857)
			(xy 382.496301 11.909857) (xy 382.496301 11.995607) (xy 382.504213 12.08099) (xy 382.519969 12.16528)
			(xy 382.543436 12.247756) (xy 382.574412 12.327715) (xy 382.612634 12.404475) (xy 382.657775 12.477381)
			(xy 382.709451 12.54581) (xy 382.76722 12.60918) (xy 382.83059 12.666949) (xy 382.899019 12.718625)
			(xy 382.971925 12.763766) (xy 383.048685 12.801988) (xy 383.128644 12.832964) (xy 383.21112 12.856431)
			(xy 383.29541 12.872187) (xy 383.380793 12.880099) (xy 383.466543 12.880099) (xy 383.551926 12.872187)
			(xy 383.636216 12.856431) (xy 383.718692 12.832964) (xy 383.798651 12.801988) (xy 383.875411 12.763766)
			(xy 383.948317 12.718625) (xy 384.016746 12.666949) (xy 384.080116 12.60918) (xy 384.137885 12.54581)
			(xy 384.189561 12.477381) (xy 384.234702 12.404475) (xy 384.272924 12.327715) (xy 384.3039 12.247756)
			(xy 384.327367 12.16528) (xy 384.343123 12.08099) (xy 384.351035 11.995607) (xy 384.35153 11.952732)
			(xy 384.351035 11.909857) (xy 388.846301 11.909857) (xy 388.846301 11.995607) (xy 388.854213 12.08099)
			(xy 388.869969 12.16528) (xy 388.893436 12.247756) (xy 388.924412 12.327715) (xy 388.962634 12.404475)
			(xy 389.007775 12.477381) (xy 389.059451 12.54581) (xy 389.11722 12.60918) (xy 389.18059 12.666949)
			(xy 389.249019 12.718625) (xy 389.321925 12.763766) (xy 389.398685 12.801988) (xy 389.478644 12.832964)
			(xy 389.56112 12.856431) (xy 389.64541 12.872187) (xy 389.730793 12.880099) (xy 389.816543 12.880099)
			(xy 389.901926 12.872187) (xy 389.986216 12.856431) (xy 390.068692 12.832964) (xy 390.148651 12.801988)
			(xy 390.225411 12.763766) (xy 390.298317 12.718625) (xy 390.366746 12.666949) (xy 390.430116 12.60918)
			(xy 390.487885 12.54581) (xy 390.539561 12.477381) (xy 390.584702 12.404475) (xy 390.622924 12.327715)
			(xy 390.6539 12.247756) (xy 390.677367 12.16528) (xy 390.693123 12.08099) (xy 390.701035 11.995607)
			(xy 390.70153 11.952732) (xy 390.701117 11.916969) (xy 396.558757 11.916969) (xy 396.558757 12.002719)
			(xy 396.566669 12.088102) (xy 396.582425 12.172392) (xy 396.605892 12.254868) (xy 396.636868 12.334827)
			(xy 396.67509 12.411587) (xy 396.720231 12.484493) (xy 396.771907 12.552922) (xy 396.829676 12.616292)
			(xy 396.893046 12.674061) (xy 396.961475 12.725737) (xy 397.034381 12.770878) (xy 397.111141 12.8091)
			(xy 397.1911 12.840076) (xy 397.273576 12.863543) (xy 397.357866 12.879299) (xy 397.443249 12.887211)
			(xy 397.528999 12.887211) (xy 397.614382 12.879299) (xy 397.698672 12.863543) (xy 397.781148 12.840076)
			(xy 397.861107 12.8091) (xy 397.937867 12.770878) (xy 398.010773 12.725737) (xy 398.079202 12.674061)
			(xy 398.142572 12.616292) (xy 398.200341 12.552922) (xy 398.252017 12.484493) (xy 398.297158 12.411587)
			(xy 398.33538 12.334827) (xy 398.366356 12.254868) (xy 398.389823 12.172392) (xy 398.405579 12.088102)
			(xy 398.413491 12.002719) (xy 398.413986 11.959844) (xy 398.413491 11.916969) (xy 402.908757 11.916969)
			(xy 402.908757 12.002719) (xy 402.916669 12.088102) (xy 402.932425 12.172392) (xy 402.955892 12.254868)
			(xy 402.986868 12.334827) (xy 403.02509 12.411587) (xy 403.070231 12.484493) (xy 403.121907 12.552922)
			(xy 403.179676 12.616292) (xy 403.243046 12.674061) (xy 403.311475 12.725737) (xy 403.384381 12.770878)
			(xy 403.461141 12.8091) (xy 403.5411 12.840076) (xy 403.623576 12.863543) (xy 403.707866 12.879299)
			(xy 403.793249 12.887211) (xy 403.878999 12.887211) (xy 403.964382 12.879299) (xy 404.048672 12.863543)
			(xy 404.131148 12.840076) (xy 404.211107 12.8091) (xy 404.287867 12.770878) (xy 404.360773 12.725737)
			(xy 404.429202 12.674061) (xy 404.492572 12.616292) (xy 404.550341 12.552922) (xy 404.602017 12.484493)
			(xy 404.647158 12.411587) (xy 404.68538 12.334827) (xy 404.716356 12.254868) (xy 404.739823 12.172392)
			(xy 404.755579 12.088102) (xy 404.763491 12.002719) (xy 404.763986 11.959844) (xy 404.76379 11.942877)
			(xy 454.759301 11.942877) (xy 454.759301 12.028627) (xy 454.767213 12.11401) (xy 454.782969 12.1983)
			(xy 454.806436 12.280776) (xy 454.837412 12.360735) (xy 454.875634 12.437495) (xy 454.920775 12.510401)
			(xy 454.972451 12.57883) (xy 455.03022 12.6422) (xy 455.09359 12.699969) (xy 455.162019 12.751645)
			(xy 455.234925 12.796786) (xy 455.311685 12.835008) (xy 455.391644 12.865984) (xy 455.47412 12.889451)
			(xy 455.55841 12.905207) (xy 455.643793 12.913119) (xy 455.729543 12.913119) (xy 455.814926 12.905207)
			(xy 455.899216 12.889451) (xy 455.981692 12.865984) (xy 456.061651 12.835008) (xy 456.138411 12.796786)
			(xy 456.211317 12.751645) (xy 456.279746 12.699969) (xy 456.343116 12.6422) (xy 456.400885 12.57883)
			(xy 456.452561 12.510401) (xy 456.497702 12.437495) (xy 456.535924 12.360735) (xy 456.5669 12.280776)
			(xy 456.590367 12.1983) (xy 456.606123 12.11401) (xy 456.614035 12.028627) (xy 456.61453 11.985752)
			(xy 456.614035 11.942877) (xy 461.109301 11.942877) (xy 461.109301 12.028627) (xy 461.117213 12.11401)
			(xy 461.132969 12.1983) (xy 461.156436 12.280776) (xy 461.187412 12.360735) (xy 461.225634 12.437495)
			(xy 461.270775 12.510401) (xy 461.322451 12.57883) (xy 461.38022 12.6422) (xy 461.44359 12.699969)
			(xy 461.512019 12.751645) (xy 461.584925 12.796786) (xy 461.661685 12.835008) (xy 461.741644 12.865984)
			(xy 461.82412 12.889451) (xy 461.90841 12.905207) (xy 461.993793 12.913119) (xy 462.079543 12.913119)
			(xy 462.164926 12.905207) (xy 462.249216 12.889451) (xy 462.331692 12.865984) (xy 462.411651 12.835008)
			(xy 462.488411 12.796786) (xy 462.561317 12.751645) (xy 462.629746 12.699969) (xy 462.693116 12.6422)
			(xy 462.750885 12.57883) (xy 462.802561 12.510401) (xy 462.847702 12.437495) (xy 462.885924 12.360735)
			(xy 462.9169 12.280776) (xy 462.940367 12.1983) (xy 462.956123 12.11401) (xy 462.964035 12.028627)
			(xy 462.96453 11.985752) (xy 462.964035 11.942877) (xy 462.956123 11.857494) (xy 462.940367 11.773204)
			(xy 462.9169 11.690728) (xy 462.885924 11.610769) (xy 462.847702 11.534009) (xy 462.802561 11.461103)
			(xy 462.750885 11.392674) (xy 462.693116 11.329304) (xy 462.629746 11.271535) (xy 462.561317 11.219859)
			(xy 462.488411 11.174718) (xy 462.411651 11.136496) (xy 462.331692 11.10552) (xy 462.249216 11.082053)
			(xy 462.164926 11.066297) (xy 462.079543 11.058385) (xy 461.993793 11.058385) (xy 461.90841 11.066297)
			(xy 461.82412 11.082053) (xy 461.741644 11.10552) (xy 461.661685 11.136496) (xy 461.584925 11.174718)
			(xy 461.512019 11.219859) (xy 461.44359 11.271535) (xy 461.38022 11.329304) (xy 461.322451 11.392674)
			(xy 461.270775 11.461103) (xy 461.225634 11.534009) (xy 461.187412 11.610769) (xy 461.156436 11.690728)
			(xy 461.132969 11.773204) (xy 461.117213 11.857494) (xy 461.109301 11.942877) (xy 456.614035 11.942877)
			(xy 456.606123 11.857494) (xy 456.590367 11.773204) (xy 456.5669 11.690728) (xy 456.535924 11.610769)
			(xy 456.497702 11.534009) (xy 456.452561 11.461103) (xy 456.400885 11.392674) (xy 456.343116 11.329304)
			(xy 456.279746 11.271535) (xy 456.211317 11.219859) (xy 456.138411 11.174718) (xy 456.061651 11.136496)
			(xy 455.981692 11.10552) (xy 455.899216 11.082053) (xy 455.814926 11.066297) (xy 455.729543 11.058385)
			(xy 455.643793 11.058385) (xy 455.55841 11.066297) (xy 455.47412 11.082053) (xy 455.391644 11.10552)
			(xy 455.311685 11.136496) (xy 455.234925 11.174718) (xy 455.162019 11.219859) (xy 455.09359 11.271535)
			(xy 455.03022 11.329304) (xy 454.972451 11.392674) (xy 454.920775 11.461103) (xy 454.875634 11.534009)
			(xy 454.837412 11.610769) (xy 454.806436 11.690728) (xy 454.782969 11.773204) (xy 454.767213 11.857494)
			(xy 454.759301 11.942877) (xy 404.76379 11.942877) (xy 404.763491 11.916969) (xy 404.755579 11.831586)
			(xy 404.739823 11.747296) (xy 404.716356 11.66482) (xy 404.68538 11.584861) (xy 404.647158 11.508101)
			(xy 404.602017 11.435195) (xy 404.550341 11.366766) (xy 404.492572 11.303396) (xy 404.429202 11.245627)
			(xy 404.360773 11.193951) (xy 404.287867 11.14881) (xy 404.211107 11.110588) (xy 404.131148 11.079612)
			(xy 404.048672 11.056145) (xy 403.964382 11.040389) (xy 403.878999 11.032477) (xy 403.793249 11.032477)
			(xy 403.707866 11.040389) (xy 403.623576 11.056145) (xy 403.5411 11.079612) (xy 403.461141 11.110588)
			(xy 403.384381 11.14881) (xy 403.311475 11.193951) (xy 403.243046 11.245627) (xy 403.179676 11.303396)
			(xy 403.121907 11.366766) (xy 403.070231 11.435195) (xy 403.02509 11.508101) (xy 402.986868 11.584861)
			(xy 402.955892 11.66482) (xy 402.932425 11.747296) (xy 402.916669 11.831586) (xy 402.908757 11.916969)
			(xy 398.413491 11.916969) (xy 398.405579 11.831586) (xy 398.389823 11.747296) (xy 398.366356 11.66482)
			(xy 398.33538 11.584861) (xy 398.297158 11.508101) (xy 398.252017 11.435195) (xy 398.200341 11.366766)
			(xy 398.142572 11.303396) (xy 398.079202 11.245627) (xy 398.010773 11.193951) (xy 397.937867 11.14881)
			(xy 397.861107 11.110588) (xy 397.781148 11.079612) (xy 397.698672 11.056145) (xy 397.614382 11.040389)
			(xy 397.528999 11.032477) (xy 397.443249 11.032477) (xy 397.357866 11.040389) (xy 397.273576 11.056145)
			(xy 397.1911 11.079612) (xy 397.111141 11.110588) (xy 397.034381 11.14881) (xy 396.961475 11.193951)
			(xy 396.893046 11.245627) (xy 396.829676 11.303396) (xy 396.771907 11.366766) (xy 396.720231 11.435195)
			(xy 396.67509 11.508101) (xy 396.636868 11.584861) (xy 396.605892 11.66482) (xy 396.582425 11.747296)
			(xy 396.566669 11.831586) (xy 396.558757 11.916969) (xy 390.701117 11.916969) (xy 390.701035 11.909857)
			(xy 390.693123 11.824474) (xy 390.677367 11.740184) (xy 390.6539 11.657708) (xy 390.622924 11.577749)
			(xy 390.584702 11.500989) (xy 390.539561 11.428083) (xy 390.487885 11.359654) (xy 390.430116 11.296284)
			(xy 390.366746 11.238515) (xy 390.298317 11.186839) (xy 390.225411 11.141698) (xy 390.148651 11.103476)
			(xy 390.068692 11.0725) (xy 389.986216 11.049033) (xy 389.901926 11.033277) (xy 389.816543 11.025365)
			(xy 389.730793 11.025365) (xy 389.64541 11.033277) (xy 389.56112 11.049033) (xy 389.478644 11.0725)
			(xy 389.398685 11.103476) (xy 389.321925 11.141698) (xy 389.249019 11.186839) (xy 389.18059 11.238515)
			(xy 389.11722 11.296284) (xy 389.059451 11.359654) (xy 389.007775 11.428083) (xy 388.962634 11.500989)
			(xy 388.924412 11.577749) (xy 388.893436 11.657708) (xy 388.869969 11.740184) (xy 388.854213 11.824474)
			(xy 388.846301 11.909857) (xy 384.351035 11.909857) (xy 384.343123 11.824474) (xy 384.327367 11.740184)
			(xy 384.3039 11.657708) (xy 384.272924 11.577749) (xy 384.234702 11.500989) (xy 384.189561 11.428083)
			(xy 384.137885 11.359654) (xy 384.080116 11.296284) (xy 384.016746 11.238515) (xy 383.948317 11.186839)
			(xy 383.875411 11.141698) (xy 383.798651 11.103476) (xy 383.718692 11.0725) (xy 383.636216 11.049033)
			(xy 383.551926 11.033277) (xy 383.466543 11.025365) (xy 383.380793 11.025365) (xy 383.29541 11.033277)
			(xy 383.21112 11.049033) (xy 383.128644 11.0725) (xy 383.048685 11.103476) (xy 382.971925 11.141698)
			(xy 382.899019 11.186839) (xy 382.83059 11.238515) (xy 382.76722 11.296284) (xy 382.709451 11.359654)
			(xy 382.657775 11.428083) (xy 382.612634 11.500989) (xy 382.574412 11.577749) (xy 382.543436 11.657708)
			(xy 382.519969 11.740184) (xy 382.504213 11.824474) (xy 382.496301 11.909857) (xy 332.50079 11.909857)
			(xy 332.500491 11.883949) (xy 332.492579 11.798566) (xy 332.476823 11.714276) (xy 332.453356 11.6318)
			(xy 332.42238 11.551841) (xy 332.384158 11.475081) (xy 332.339017 11.402175) (xy 332.287341 11.333746)
			(xy 332.229572 11.270376) (xy 332.166202 11.212607) (xy 332.097773 11.160931) (xy 332.024867 11.11579)
			(xy 331.948107 11.077568) (xy 331.868148 11.046592) (xy 331.785672 11.023125) (xy 331.701382 11.007369)
			(xy 331.615999 10.999457) (xy 331.530249 10.999457) (xy 331.444866 11.007369) (xy 331.360576 11.023125)
			(xy 331.2781 11.046592) (xy 331.198141 11.077568) (xy 331.121381 11.11579) (xy 331.048475 11.160931)
			(xy 330.980046 11.212607) (xy 330.916676 11.270376) (xy 330.858907 11.333746) (xy 330.807231 11.402175)
			(xy 330.76209 11.475081) (xy 330.723868 11.551841) (xy 330.692892 11.6318) (xy 330.669425 11.714276)
			(xy 330.653669 11.798566) (xy 330.645757 11.883949) (xy 326.150491 11.883949) (xy 326.142579 11.798566)
			(xy 326.126823 11.714276) (xy 326.103356 11.6318) (xy 326.07238 11.551841) (xy 326.034158 11.475081)
			(xy 325.989017 11.402175) (xy 325.937341 11.333746) (xy 325.879572 11.270376) (xy 325.816202 11.212607)
			(xy 325.747773 11.160931) (xy 325.674867 11.11579) (xy 325.598107 11.077568) (xy 325.518148 11.046592)
			(xy 325.435672 11.023125) (xy 325.351382 11.007369) (xy 325.265999 10.999457) (xy 325.180249 10.999457)
			(xy 325.094866 11.007369) (xy 325.010576 11.023125) (xy 324.9281 11.046592) (xy 324.848141 11.077568)
			(xy 324.771381 11.11579) (xy 324.698475 11.160931) (xy 324.630046 11.212607) (xy 324.566676 11.270376)
			(xy 324.508907 11.333746) (xy 324.457231 11.402175) (xy 324.41209 11.475081) (xy 324.373868 11.551841)
			(xy 324.342892 11.6318) (xy 324.319425 11.714276) (xy 324.303669 11.798566) (xy 324.295757 11.883949)
			(xy 317.930117 11.883949) (xy 317.930035 11.876837) (xy 317.922123 11.791454) (xy 317.906367 11.707164)
			(xy 317.8829 11.624688) (xy 317.851924 11.544729) (xy 317.813702 11.467969) (xy 317.768561 11.395063)
			(xy 317.716885 11.326634) (xy 317.659116 11.263264) (xy 317.595746 11.205495) (xy 317.527317 11.153819)
			(xy 317.454411 11.108678) (xy 317.377651 11.070456) (xy 317.297692 11.03948) (xy 317.215216 11.016013)
			(xy 317.130926 11.000257) (xy 317.045543 10.992345) (xy 316.959793 10.992345) (xy 316.87441 11.000257)
			(xy 316.79012 11.016013) (xy 316.707644 11.03948) (xy 316.627685 11.070456) (xy 316.550925 11.108678)
			(xy 316.478019 11.153819) (xy 316.40959 11.205495) (xy 316.34622 11.263264) (xy 316.288451 11.326634)
			(xy 316.236775 11.395063) (xy 316.191634 11.467969) (xy 316.153412 11.544729) (xy 316.122436 11.624688)
			(xy 316.098969 11.707164) (xy 316.083213 11.791454) (xy 316.075301 11.876837) (xy 311.580035 11.876837)
			(xy 311.572123 11.791454) (xy 311.556367 11.707164) (xy 311.5329 11.624688) (xy 311.501924 11.544729)
			(xy 311.463702 11.467969) (xy 311.418561 11.395063) (xy 311.366885 11.326634) (xy 311.309116 11.263264)
			(xy 311.245746 11.205495) (xy 311.177317 11.153819) (xy 311.104411 11.108678) (xy 311.027651 11.070456)
			(xy 310.947692 11.03948) (xy 310.865216 11.016013) (xy 310.780926 11.000257) (xy 310.695543 10.992345)
			(xy 310.609793 10.992345) (xy 310.52441 11.000257) (xy 310.44012 11.016013) (xy 310.357644 11.03948)
			(xy 310.277685 11.070456) (xy 310.200925 11.108678) (xy 310.128019 11.153819) (xy 310.05959 11.205495)
			(xy 309.99622 11.263264) (xy 309.938451 11.326634) (xy 309.886775 11.395063) (xy 309.841634 11.467969)
			(xy 309.803412 11.544729) (xy 309.772436 11.624688) (xy 309.748969 11.707164) (xy 309.733213 11.791454)
			(xy 309.725301 11.876837) (xy 259.72979 11.876837) (xy 259.729491 11.850929) (xy 259.721579 11.765546)
			(xy 259.705823 11.681256) (xy 259.682356 11.59878) (xy 259.65138 11.518821) (xy 259.613158 11.442061)
			(xy 259.568017 11.369155) (xy 259.516341 11.300726) (xy 259.458572 11.237356) (xy 259.395202 11.179587)
			(xy 259.326773 11.127911) (xy 259.253867 11.08277) (xy 259.177107 11.044548) (xy 259.097148 11.013572)
			(xy 259.014672 10.990105) (xy 258.930382 10.974349) (xy 258.844999 10.966437) (xy 258.759249 10.966437)
			(xy 258.673866 10.974349) (xy 258.589576 10.990105) (xy 258.5071 11.013572) (xy 258.427141 11.044548)
			(xy 258.350381 11.08277) (xy 258.277475 11.127911) (xy 258.209046 11.179587) (xy 258.145676 11.237356)
			(xy 258.087907 11.300726) (xy 258.036231 11.369155) (xy 257.99109 11.442061) (xy 257.952868 11.518821)
			(xy 257.921892 11.59878) (xy 257.898425 11.681256) (xy 257.882669 11.765546) (xy 257.874757 11.850929)
			(xy 253.379491 11.850929) (xy 253.371579 11.765546) (xy 253.355823 11.681256) (xy 253.332356 11.59878)
			(xy 253.30138 11.518821) (xy 253.263158 11.442061) (xy 253.218017 11.369155) (xy 253.166341 11.300726)
			(xy 253.108572 11.237356) (xy 253.045202 11.179587) (xy 252.976773 11.127911) (xy 252.903867 11.08277)
			(xy 252.827107 11.044548) (xy 252.747148 11.013572) (xy 252.664672 10.990105) (xy 252.580382 10.974349)
			(xy 252.494999 10.966437) (xy 252.409249 10.966437) (xy 252.323866 10.974349) (xy 252.239576 10.990105)
			(xy 252.1571 11.013572) (xy 252.077141 11.044548) (xy 252.000381 11.08277) (xy 251.927475 11.127911)
			(xy 251.859046 11.179587) (xy 251.795676 11.237356) (xy 251.737907 11.300726) (xy 251.686231 11.369155)
			(xy 251.64109 11.442061) (xy 251.602868 11.518821) (xy 251.571892 11.59878) (xy 251.548425 11.681256)
			(xy 251.532669 11.765546) (xy 251.524757 11.850929) (xy 158.621984 11.850929) (xy 158.621984 9.310929)
			(xy 179.515757 9.310929) (xy 179.515757 9.396679) (xy 179.523669 9.482062) (xy 179.539425 9.566352)
			(xy 179.562892 9.648828) (xy 179.593868 9.728787) (xy 179.63209 9.805547) (xy 179.677231 9.878453)
			(xy 179.728907 9.946882) (xy 179.786676 10.010252) (xy 179.850046 10.068021) (xy 179.918475 10.119697)
			(xy 179.991381 10.164838) (xy 180.068141 10.20306) (xy 180.1481 10.234036) (xy 180.230576 10.257503)
			(xy 180.314866 10.273259) (xy 180.400249 10.281171) (xy 180.485999 10.281171) (xy 180.571382 10.273259)
			(xy 180.655672 10.257503) (xy 180.738148 10.234036) (xy 180.818107 10.20306) (xy 180.894867 10.164838)
			(xy 180.967773 10.119697) (xy 181.036202 10.068021) (xy 181.099572 10.010252) (xy 181.157341 9.946882)
			(xy 181.209017 9.878453) (xy 181.254158 9.805547) (xy 181.29238 9.728787) (xy 181.323356 9.648828)
			(xy 181.346823 9.566352) (xy 181.362579 9.482062) (xy 181.370491 9.396679) (xy 181.370986 9.353804)
			(xy 181.370491 9.310929) (xy 185.865757 9.310929) (xy 185.865757 9.396679) (xy 185.873669 9.482062)
			(xy 185.889425 9.566352) (xy 185.912892 9.648828) (xy 185.943868 9.728787) (xy 185.98209 9.805547)
			(xy 186.027231 9.878453) (xy 186.078907 9.946882) (xy 186.136676 10.010252) (xy 186.200046 10.068021)
			(xy 186.268475 10.119697) (xy 186.341381 10.164838) (xy 186.418141 10.20306) (xy 186.4981 10.234036)
			(xy 186.580576 10.257503) (xy 186.664866 10.273259) (xy 186.750249 10.281171) (xy 186.835999 10.281171)
			(xy 186.921382 10.273259) (xy 187.005672 10.257503) (xy 187.088148 10.234036) (xy 187.168107 10.20306)
			(xy 187.244867 10.164838) (xy 187.317773 10.119697) (xy 187.386202 10.068021) (xy 187.449572 10.010252)
			(xy 187.507341 9.946882) (xy 187.559017 9.878453) (xy 187.604158 9.805547) (xy 187.64238 9.728787)
			(xy 187.673356 9.648828) (xy 187.696823 9.566352) (xy 187.712579 9.482062) (xy 187.720491 9.396679)
			(xy 187.720986 9.353804) (xy 187.720491 9.310929) (xy 187.719832 9.303817) (xy 237.716301 9.303817)
			(xy 237.716301 9.389567) (xy 237.724213 9.47495) (xy 237.739969 9.55924) (xy 237.763436 9.641716)
			(xy 237.794412 9.721675) (xy 237.832634 9.798435) (xy 237.877775 9.871341) (xy 237.929451 9.93977)
			(xy 237.98722 10.00314) (xy 238.05059 10.060909) (xy 238.119019 10.112585) (xy 238.191925 10.157726)
			(xy 238.268685 10.195948) (xy 238.348644 10.226924) (xy 238.43112 10.250391) (xy 238.51541 10.266147)
			(xy 238.600793 10.274059) (xy 238.686543 10.274059) (xy 238.771926 10.266147) (xy 238.856216 10.250391)
			(xy 238.938692 10.226924) (xy 239.018651 10.195948) (xy 239.095411 10.157726) (xy 239.168317 10.112585)
			(xy 239.236746 10.060909) (xy 239.300116 10.00314) (xy 239.357885 9.93977) (xy 239.409561 9.871341)
			(xy 239.454702 9.798435) (xy 239.492924 9.721675) (xy 239.5239 9.641716) (xy 239.547367 9.55924)
			(xy 239.563123 9.47495) (xy 239.571035 9.389567) (xy 239.57153 9.346692) (xy 239.571035 9.303817)
			(xy 244.066301 9.303817) (xy 244.066301 9.389567) (xy 244.074213 9.47495) (xy 244.089969 9.55924)
			(xy 244.113436 9.641716) (xy 244.144412 9.721675) (xy 244.182634 9.798435) (xy 244.227775 9.871341)
			(xy 244.279451 9.93977) (xy 244.33722 10.00314) (xy 244.40059 10.060909) (xy 244.469019 10.112585)
			(xy 244.541925 10.157726) (xy 244.618685 10.195948) (xy 244.698644 10.226924) (xy 244.78112 10.250391)
			(xy 244.86541 10.266147) (xy 244.950793 10.274059) (xy 245.036543 10.274059) (xy 245.121926 10.266147)
			(xy 245.206216 10.250391) (xy 245.288692 10.226924) (xy 245.368651 10.195948) (xy 245.445411 10.157726)
			(xy 245.518317 10.112585) (xy 245.586746 10.060909) (xy 245.650116 10.00314) (xy 245.707885 9.93977)
			(xy 245.759561 9.871341) (xy 245.804702 9.798435) (xy 245.842924 9.721675) (xy 245.8739 9.641716)
			(xy 245.897367 9.55924) (xy 245.913123 9.47495) (xy 245.921035 9.389567) (xy 245.92153 9.346692)
			(xy 245.921117 9.310929) (xy 251.524757 9.310929) (xy 251.524757 9.396679) (xy 251.532669 9.482062)
			(xy 251.548425 9.566352) (xy 251.571892 9.648828) (xy 251.602868 9.728787) (xy 251.64109 9.805547)
			(xy 251.686231 9.878453) (xy 251.737907 9.946882) (xy 251.795676 10.010252) (xy 251.859046 10.068021)
			(xy 251.927475 10.119697) (xy 252.000381 10.164838) (xy 252.077141 10.20306) (xy 252.1571 10.234036)
			(xy 252.239576 10.257503) (xy 252.323866 10.273259) (xy 252.409249 10.281171) (xy 252.494999 10.281171)
			(xy 252.580382 10.273259) (xy 252.664672 10.257503) (xy 252.747148 10.234036) (xy 252.827107 10.20306)
			(xy 252.84931 10.192004) (xy 256.459736 10.192004) (xy 256.459736 11.055604) (xy 256.460222 11.082873)
			(xy 256.467984 11.136857) (xy 256.483349 11.189187) (xy 256.506006 11.238797) (xy 256.535492 11.284678)
			(xy 256.571207 11.325895) (xy 256.612424 11.36161) (xy 256.658305 11.391096) (xy 256.707915 11.413753)
			(xy 256.760245 11.429118) (xy 256.814229 11.43688) (xy 256.868767 11.43688) (xy 256.922751 11.429118)
			(xy 256.975081 11.413753) (xy 257.024691 11.391096) (xy 257.070572 11.36161) (xy 257.111789 11.325895)
			(xy 257.147504 11.284678) (xy 257.17699 11.238797) (xy 257.199647 11.189187) (xy 257.215012 11.136857)
			(xy 257.222774 11.082873) (xy 257.22326 11.055604) (xy 257.22326 10.192004) (xy 257.222774 10.164735)
			(xy 257.215012 10.110751) (xy 257.199647 10.058421) (xy 257.17699 10.008811) (xy 257.147504 9.96293)
			(xy 257.111789 9.921713) (xy 257.070572 9.885998) (xy 257.024691 9.856512) (xy 256.975081 9.833855)
			(xy 256.922751 9.81849) (xy 256.868767 9.810728) (xy 256.814229 9.810728) (xy 256.760245 9.81849)
			(xy 256.707915 9.833855) (xy 256.658305 9.856512) (xy 256.612424 9.885998) (xy 256.571207 9.921713)
			(xy 256.535492 9.96293) (xy 256.506006 10.008811) (xy 256.483349 10.058421) (xy 256.467984 10.110751)
			(xy 256.460222 10.164735) (xy 256.459736 10.192004) (xy 252.84931 10.192004) (xy 252.903867 10.164838)
			(xy 252.976773 10.119697) (xy 253.045202 10.068021) (xy 253.108572 10.010252) (xy 253.166341 9.946882)
			(xy 253.218017 9.878453) (xy 253.263158 9.805547) (xy 253.30138 9.728787) (xy 253.332356 9.648828)
			(xy 253.355823 9.566352) (xy 253.371579 9.482062) (xy 253.379491 9.396679) (xy 253.379986 9.353804)
			(xy 253.379491 9.310929) (xy 257.874757 9.310929) (xy 257.874757 9.396679) (xy 257.882669 9.482062)
			(xy 257.898425 9.566352) (xy 257.921892 9.648828) (xy 257.952868 9.728787) (xy 257.99109 9.805547)
			(xy 258.036231 9.878453) (xy 258.087907 9.946882) (xy 258.145676 10.010252) (xy 258.209046 10.068021)
			(xy 258.277475 10.119697) (xy 258.350381 10.164838) (xy 258.427141 10.20306) (xy 258.5071 10.234036)
			(xy 258.589576 10.257503) (xy 258.673866 10.273259) (xy 258.759249 10.281171) (xy 258.844999 10.281171)
			(xy 258.930382 10.273259) (xy 259.014672 10.257503) (xy 259.097148 10.234036) (xy 259.177107 10.20306)
			(xy 259.253867 10.164838) (xy 259.326773 10.119697) (xy 259.395202 10.068021) (xy 259.458572 10.010252)
			(xy 259.516341 9.946882) (xy 259.568017 9.878453) (xy 259.613158 9.805547) (xy 259.65138 9.728787)
			(xy 259.682356 9.648828) (xy 259.705823 9.566352) (xy 259.721579 9.482062) (xy 259.729491 9.396679)
			(xy 259.729986 9.353804) (xy 259.72979 9.336837) (xy 309.725301 9.336837) (xy 309.725301 9.422587)
			(xy 309.733213 9.50797) (xy 309.748969 9.59226) (xy 309.772436 9.674736) (xy 309.803412 9.754695)
			(xy 309.841634 9.831455) (xy 309.886775 9.904361) (xy 309.938451 9.97279) (xy 309.99622 10.03616)
			(xy 310.05959 10.093929) (xy 310.128019 10.145605) (xy 310.200925 10.190746) (xy 310.277685 10.228968)
			(xy 310.357644 10.259944) (xy 310.44012 10.283411) (xy 310.52441 10.299167) (xy 310.609793 10.307079)
			(xy 310.695543 10.307079) (xy 310.780926 10.299167) (xy 310.865216 10.283411) (xy 310.947692 10.259944)
			(xy 311.027651 10.228968) (xy 311.049854 10.217912) (xy 312.231532 10.217912) (xy 312.231532 11.081512)
			(xy 312.232018 11.108781) (xy 312.23978 11.162765) (xy 312.255145 11.215095) (xy 312.277802 11.264705)
			(xy 312.307288 11.310586) (xy 312.343003 11.351803) (xy 312.38422 11.387518) (xy 312.430101 11.417004)
			(xy 312.479711 11.439661) (xy 312.532041 11.455026) (xy 312.586025 11.462788) (xy 312.640563 11.462788)
			(xy 312.694547 11.455026) (xy 312.746877 11.439661) (xy 312.796487 11.417004) (xy 312.842368 11.387518)
			(xy 312.883585 11.351803) (xy 312.9193 11.310586) (xy 312.948786 11.264705) (xy 312.971443 11.215095)
			(xy 312.986808 11.162765) (xy 312.99457 11.108781) (xy 312.995056 11.081512) (xy 312.995056 10.217912)
			(xy 312.99457 10.190643) (xy 312.986808 10.136659) (xy 312.971443 10.084329) (xy 312.948786 10.034719)
			(xy 312.9193 9.988838) (xy 312.883585 9.947621) (xy 312.842368 9.911906) (xy 312.796487 9.88242)
			(xy 312.746877 9.859763) (xy 312.694547 9.844398) (xy 312.640563 9.836636) (xy 312.586025 9.836636)
			(xy 312.532041 9.844398) (xy 312.479711 9.859763) (xy 312.430101 9.88242) (xy 312.38422 9.911906)
			(xy 312.343003 9.947621) (xy 312.307288 9.988838) (xy 312.277802 10.034719) (xy 312.255145 10.084329)
			(xy 312.23978 10.136659) (xy 312.232018 10.190643) (xy 312.231532 10.217912) (xy 311.049854 10.217912)
			(xy 311.104411 10.190746) (xy 311.177317 10.145605) (xy 311.245746 10.093929) (xy 311.309116 10.03616)
			(xy 311.366885 9.97279) (xy 311.418561 9.904361) (xy 311.463702 9.831455) (xy 311.501924 9.754695)
			(xy 311.5329 9.674736) (xy 311.556367 9.59226) (xy 311.572123 9.50797) (xy 311.580035 9.422587) (xy 311.58053 9.379712)
			(xy 311.580035 9.336837) (xy 316.075301 9.336837) (xy 316.075301 9.422587) (xy 316.083213 9.50797)
			(xy 316.098969 9.59226) (xy 316.122436 9.674736) (xy 316.153412 9.754695) (xy 316.191634 9.831455)
			(xy 316.236775 9.904361) (xy 316.288451 9.97279) (xy 316.34622 10.03616) (xy 316.40959 10.093929)
			(xy 316.478019 10.145605) (xy 316.550925 10.190746) (xy 316.627685 10.228968) (xy 316.707644 10.259944)
			(xy 316.79012 10.283411) (xy 316.87441 10.299167) (xy 316.959793 10.307079) (xy 317.045543 10.307079)
			(xy 317.130926 10.299167) (xy 317.215216 10.283411) (xy 317.297692 10.259944) (xy 317.377651 10.228968)
			(xy 317.454411 10.190746) (xy 317.527317 10.145605) (xy 317.595746 10.093929) (xy 317.659116 10.03616)
			(xy 317.716885 9.97279) (xy 317.768561 9.904361) (xy 317.813702 9.831455) (xy 317.851924 9.754695)
			(xy 317.8829 9.674736) (xy 317.906367 9.59226) (xy 317.922123 9.50797) (xy 317.930035 9.422587) (xy 317.93053 9.379712)
			(xy 317.930117 9.343949) (xy 324.295757 9.343949) (xy 324.295757 9.429699) (xy 324.303669 9.515082)
			(xy 324.319425 9.599372) (xy 324.342892 9.681848) (xy 324.373868 9.761807) (xy 324.41209 9.838567)
			(xy 324.457231 9.911473) (xy 324.508907 9.979902) (xy 324.566676 10.043272) (xy 324.630046 10.101041)
			(xy 324.698475 10.152717) (xy 324.771381 10.197858) (xy 324.848141 10.23608) (xy 324.9281 10.267056)
			(xy 325.010576 10.290523) (xy 325.094866 10.306279) (xy 325.180249 10.314191) (xy 325.265999 10.314191)
			(xy 325.351382 10.306279) (xy 325.435672 10.290523) (xy 325.518148 10.267056) (xy 325.598107 10.23608)
			(xy 325.62031 10.225024) (xy 329.230736 10.225024) (xy 329.230736 11.088624) (xy 329.231222 11.115893)
			(xy 329.238984 11.169877) (xy 329.254349 11.222207) (xy 329.277006 11.271817) (xy 329.306492 11.317698)
			(xy 329.342207 11.358915) (xy 329.383424 11.39463) (xy 329.429305 11.424116) (xy 329.478915 11.446773)
			(xy 329.531245 11.462138) (xy 329.585229 11.4699) (xy 329.639767 11.4699) (xy 329.693751 11.462138)
			(xy 329.746081 11.446773) (xy 329.795691 11.424116) (xy 329.841572 11.39463) (xy 329.882789 11.358915)
			(xy 329.918504 11.317698) (xy 329.94799 11.271817) (xy 329.970647 11.222207) (xy 329.986012 11.169877)
			(xy 329.993774 11.115893) (xy 329.99426 11.088624) (xy 329.99426 10.225024) (xy 329.993774 10.197755)
			(xy 329.986012 10.143771) (xy 329.970647 10.091441) (xy 329.94799 10.041831) (xy 329.918504 9.99595)
			(xy 329.882789 9.954733) (xy 329.841572 9.919018) (xy 329.795691 9.889532) (xy 329.746081 9.866875)
			(xy 329.693751 9.85151) (xy 329.639767 9.843748) (xy 329.585229 9.843748) (xy 329.531245 9.85151)
			(xy 329.478915 9.866875) (xy 329.429305 9.889532) (xy 329.383424 9.919018) (xy 329.342207 9.954733)
			(xy 329.306492 9.99595) (xy 329.277006 10.041831) (xy 329.254349 10.091441) (xy 329.238984 10.143771)
			(xy 329.231222 10.197755) (xy 329.230736 10.225024) (xy 325.62031 10.225024) (xy 325.674867 10.197858)
			(xy 325.747773 10.152717) (xy 325.816202 10.101041) (xy 325.879572 10.043272) (xy 325.937341 9.979902)
			(xy 325.989017 9.911473) (xy 326.034158 9.838567) (xy 326.07238 9.761807) (xy 326.103356 9.681848)
			(xy 326.126823 9.599372) (xy 326.142579 9.515082) (xy 326.150491 9.429699) (xy 326.150986 9.386824)
			(xy 326.150491 9.343949) (xy 330.645757 9.343949) (xy 330.645757 9.429699) (xy 330.653669 9.515082)
			(xy 330.669425 9.599372) (xy 330.692892 9.681848) (xy 330.723868 9.761807) (xy 330.76209 9.838567)
			(xy 330.807231 9.911473) (xy 330.858907 9.979902) (xy 330.916676 10.043272) (xy 330.980046 10.101041)
			(xy 331.048475 10.152717) (xy 331.121381 10.197858) (xy 331.198141 10.23608) (xy 331.2781 10.267056)
			(xy 331.360576 10.290523) (xy 331.444866 10.306279) (xy 331.530249 10.314191) (xy 331.615999 10.314191)
			(xy 331.701382 10.306279) (xy 331.785672 10.290523) (xy 331.868148 10.267056) (xy 331.948107 10.23608)
			(xy 332.024867 10.197858) (xy 332.097773 10.152717) (xy 332.166202 10.101041) (xy 332.229572 10.043272)
			(xy 332.287341 9.979902) (xy 332.339017 9.911473) (xy 332.384158 9.838567) (xy 332.42238 9.761807)
			(xy 332.453356 9.681848) (xy 332.476823 9.599372) (xy 332.492579 9.515082) (xy 332.500491 9.429699)
			(xy 332.500986 9.386824) (xy 332.50079 9.369857) (xy 382.496301 9.369857) (xy 382.496301 9.455607)
			(xy 382.504213 9.54099) (xy 382.519969 9.62528) (xy 382.543436 9.707756) (xy 382.574412 9.787715)
			(xy 382.612634 9.864475) (xy 382.657775 9.937381) (xy 382.709451 10.00581) (xy 382.76722 10.06918)
			(xy 382.83059 10.126949) (xy 382.899019 10.178625) (xy 382.971925 10.223766) (xy 383.048685 10.261988)
			(xy 383.128644 10.292964) (xy 383.21112 10.316431) (xy 383.29541 10.332187) (xy 383.380793 10.340099)
			(xy 383.466543 10.340099) (xy 383.551926 10.332187) (xy 383.636216 10.316431) (xy 383.718692 10.292964)
			(xy 383.798651 10.261988) (xy 383.820854 10.250932) (xy 385.002532 10.250932) (xy 385.002532 11.114532)
			(xy 385.003018 11.141801) (xy 385.01078 11.195785) (xy 385.026145 11.248115) (xy 385.048802 11.297725)
			(xy 385.078288 11.343606) (xy 385.114003 11.384823) (xy 385.15522 11.420538) (xy 385.201101 11.450024)
			(xy 385.250711 11.472681) (xy 385.303041 11.488046) (xy 385.357025 11.495808) (xy 385.411563 11.495808)
			(xy 385.465547 11.488046) (xy 385.517877 11.472681) (xy 385.567487 11.450024) (xy 385.613368 11.420538)
			(xy 385.654585 11.384823) (xy 385.6903 11.343606) (xy 385.719786 11.297725) (xy 385.742443 11.248115)
			(xy 385.757808 11.195785) (xy 385.76557 11.141801) (xy 385.766056 11.114532) (xy 385.766056 10.250932)
			(xy 385.76557 10.223663) (xy 385.757808 10.169679) (xy 385.742443 10.117349) (xy 385.719786 10.067739)
			(xy 385.6903 10.021858) (xy 385.654585 9.980641) (xy 385.613368 9.944926) (xy 385.567487 9.91544)
			(xy 385.517877 9.892783) (xy 385.465547 9.877418) (xy 385.411563 9.869656) (xy 385.357025 9.869656)
			(xy 385.303041 9.877418) (xy 385.250711 9.892783) (xy 385.201101 9.91544) (xy 385.15522 9.944926)
			(xy 385.114003 9.980641) (xy 385.078288 10.021858) (xy 385.048802 10.067739) (xy 385.026145 10.117349)
			(xy 385.01078 10.169679) (xy 385.003018 10.223663) (xy 385.002532 10.250932) (xy 383.820854 10.250932)
			(xy 383.875411 10.223766) (xy 383.948317 10.178625) (xy 384.016746 10.126949) (xy 384.080116 10.06918)
			(xy 384.137885 10.00581) (xy 384.189561 9.937381) (xy 384.234702 9.864475) (xy 384.272924 9.787715)
			(xy 384.3039 9.707756) (xy 384.327367 9.62528) (xy 384.343123 9.54099) (xy 384.351035 9.455607) (xy 384.35153 9.412732)
			(xy 384.351035 9.369857) (xy 388.846301 9.369857) (xy 388.846301 9.455607) (xy 388.854213 9.54099)
			(xy 388.869969 9.62528) (xy 388.893436 9.707756) (xy 388.924412 9.787715) (xy 388.962634 9.864475)
			(xy 389.007775 9.937381) (xy 389.059451 10.00581) (xy 389.11722 10.06918) (xy 389.18059 10.126949)
			(xy 389.249019 10.178625) (xy 389.321925 10.223766) (xy 389.398685 10.261988) (xy 389.478644 10.292964)
			(xy 389.56112 10.316431) (xy 389.64541 10.332187) (xy 389.730793 10.340099) (xy 389.816543 10.340099)
			(xy 389.901926 10.332187) (xy 389.986216 10.316431) (xy 390.068692 10.292964) (xy 390.148651 10.261988)
			(xy 390.225411 10.223766) (xy 390.298317 10.178625) (xy 390.366746 10.126949) (xy 390.430116 10.06918)
			(xy 390.487885 10.00581) (xy 390.539561 9.937381) (xy 390.584702 9.864475) (xy 390.622924 9.787715)
			(xy 390.6539 9.707756) (xy 390.677367 9.62528) (xy 390.693123 9.54099) (xy 390.701035 9.455607) (xy 390.70153 9.412732)
			(xy 390.701117 9.376969) (xy 396.558757 9.376969) (xy 396.558757 9.462719) (xy 396.566669 9.548102)
			(xy 396.582425 9.632392) (xy 396.605892 9.714868) (xy 396.636868 9.794827) (xy 396.67509 9.871587)
			(xy 396.720231 9.944493) (xy 396.771907 10.012922) (xy 396.829676 10.076292) (xy 396.893046 10.134061)
			(xy 396.961475 10.185737) (xy 397.034381 10.230878) (xy 397.111141 10.2691) (xy 397.1911 10.300076)
			(xy 397.273576 10.323543) (xy 397.357866 10.339299) (xy 397.443249 10.347211) (xy 397.528999 10.347211)
			(xy 397.614382 10.339299) (xy 397.698672 10.323543) (xy 397.781148 10.300076) (xy 397.861107 10.2691)
			(xy 397.88331 10.258044) (xy 401.493736 10.258044) (xy 401.493736 11.121644) (xy 401.494222 11.148913)
			(xy 401.501984 11.202897) (xy 401.517349 11.255227) (xy 401.540006 11.304837) (xy 401.569492 11.350718)
			(xy 401.605207 11.391935) (xy 401.646424 11.42765) (xy 401.692305 11.457136) (xy 401.741915 11.479793)
			(xy 401.794245 11.495158) (xy 401.848229 11.50292) (xy 401.902767 11.50292) (xy 401.956751 11.495158)
			(xy 402.009081 11.479793) (xy 402.058691 11.457136) (xy 402.104572 11.42765) (xy 402.145789 11.391935)
			(xy 402.181504 11.350718) (xy 402.21099 11.304837) (xy 402.233647 11.255227) (xy 402.249012 11.202897)
			(xy 402.256774 11.148913) (xy 402.25726 11.121644) (xy 402.25726 10.258044) (xy 402.256774 10.230775)
			(xy 402.249012 10.176791) (xy 402.233647 10.124461) (xy 402.21099 10.074851) (xy 402.181504 10.02897)
			(xy 402.145789 9.987753) (xy 402.104572 9.952038) (xy 402.058691 9.922552) (xy 402.009081 9.899895)
			(xy 401.956751 9.88453) (xy 401.902767 9.876768) (xy 401.848229 9.876768) (xy 401.794245 9.88453)
			(xy 401.741915 9.899895) (xy 401.692305 9.922552) (xy 401.646424 9.952038) (xy 401.605207 9.987753)
			(xy 401.569492 10.02897) (xy 401.540006 10.074851) (xy 401.517349 10.124461) (xy 401.501984 10.176791)
			(xy 401.494222 10.230775) (xy 401.493736 10.258044) (xy 397.88331 10.258044) (xy 397.937867 10.230878)
			(xy 398.010773 10.185737) (xy 398.079202 10.134061) (xy 398.142572 10.076292) (xy 398.200341 10.012922)
			(xy 398.252017 9.944493) (xy 398.297158 9.871587) (xy 398.33538 9.794827) (xy 398.366356 9.714868)
			(xy 398.389823 9.632392) (xy 398.405579 9.548102) (xy 398.413491 9.462719) (xy 398.413986 9.419844)
			(xy 398.413491 9.376969) (xy 402.908757 9.376969) (xy 402.908757 9.462719) (xy 402.916669 9.548102)
			(xy 402.932425 9.632392) (xy 402.955892 9.714868) (xy 402.986868 9.794827) (xy 403.02509 9.871587)
			(xy 403.070231 9.944493) (xy 403.121907 10.012922) (xy 403.179676 10.076292) (xy 403.243046 10.134061)
			(xy 403.311475 10.185737) (xy 403.384381 10.230878) (xy 403.461141 10.2691) (xy 403.5411 10.300076)
			(xy 403.623576 10.323543) (xy 403.707866 10.339299) (xy 403.793249 10.347211) (xy 403.878999 10.347211)
			(xy 403.964382 10.339299) (xy 404.048672 10.323543) (xy 404.131148 10.300076) (xy 404.211107 10.2691)
			(xy 404.287867 10.230878) (xy 404.360773 10.185737) (xy 404.429202 10.134061) (xy 404.492572 10.076292)
			(xy 404.550341 10.012922) (xy 404.602017 9.944493) (xy 404.647158 9.871587) (xy 404.68538 9.794827)
			(xy 404.716356 9.714868) (xy 404.739823 9.632392) (xy 404.755579 9.548102) (xy 404.763491 9.462719)
			(xy 404.763986 9.419844) (xy 404.76379 9.402877) (xy 454.759301 9.402877) (xy 454.759301 9.488627)
			(xy 454.767213 9.57401) (xy 454.782969 9.6583) (xy 454.806436 9.740776) (xy 454.837412 9.820735)
			(xy 454.875634 9.897495) (xy 454.920775 9.970401) (xy 454.972451 10.03883) (xy 455.03022 10.1022)
			(xy 455.09359 10.159969) (xy 455.162019 10.211645) (xy 455.234925 10.256786) (xy 455.311685 10.295008)
			(xy 455.391644 10.325984) (xy 455.47412 10.349451) (xy 455.55841 10.365207) (xy 455.643793 10.373119)
			(xy 455.729543 10.373119) (xy 455.814926 10.365207) (xy 455.899216 10.349451) (xy 455.981692 10.325984)
			(xy 456.061651 10.295008) (xy 456.083854 10.283952) (xy 457.265532 10.283952) (xy 457.265532 11.147552)
			(xy 457.266018 11.174821) (xy 457.27378 11.228805) (xy 457.289145 11.281135) (xy 457.311802 11.330745)
			(xy 457.341288 11.376626) (xy 457.377003 11.417843) (xy 457.41822 11.453558) (xy 457.464101 11.483044)
			(xy 457.513711 11.505701) (xy 457.566041 11.521066) (xy 457.620025 11.528828) (xy 457.674563 11.528828)
			(xy 457.728547 11.521066) (xy 457.780877 11.505701) (xy 457.830487 11.483044) (xy 457.876368 11.453558)
			(xy 457.917585 11.417843) (xy 457.9533 11.376626) (xy 457.982786 11.330745) (xy 458.005443 11.281135)
			(xy 458.020808 11.228805) (xy 458.02857 11.174821) (xy 458.029056 11.147552) (xy 458.029056 10.283952)
			(xy 458.02857 10.256683) (xy 458.020808 10.202699) (xy 458.005443 10.150369) (xy 457.982786 10.100759)
			(xy 457.9533 10.054878) (xy 457.917585 10.013661) (xy 457.876368 9.977946) (xy 457.830487 9.94846)
			(xy 457.780877 9.925803) (xy 457.728547 9.910438) (xy 457.674563 9.902676) (xy 457.620025 9.902676)
			(xy 457.566041 9.910438) (xy 457.513711 9.925803) (xy 457.464101 9.94846) (xy 457.41822 9.977946)
			(xy 457.377003 10.013661) (xy 457.341288 10.054878) (xy 457.311802 10.100759) (xy 457.289145 10.150369)
			(xy 457.27378 10.202699) (xy 457.266018 10.256683) (xy 457.265532 10.283952) (xy 456.083854 10.283952)
			(xy 456.138411 10.256786) (xy 456.211317 10.211645) (xy 456.279746 10.159969) (xy 456.343116 10.1022)
			(xy 456.400885 10.03883) (xy 456.452561 9.970401) (xy 456.497702 9.897495) (xy 456.535924 9.820735)
			(xy 456.5669 9.740776) (xy 456.590367 9.6583) (xy 456.606123 9.57401) (xy 456.614035 9.488627) (xy 456.61453 9.445752)
			(xy 456.614035 9.402877) (xy 461.109301 9.402877) (xy 461.109301 9.488627) (xy 461.117213 9.57401)
			(xy 461.132969 9.6583) (xy 461.156436 9.740776) (xy 461.187412 9.820735) (xy 461.225634 9.897495)
			(xy 461.270775 9.970401) (xy 461.322451 10.03883) (xy 461.38022 10.1022) (xy 461.44359 10.159969)
			(xy 461.512019 10.211645) (xy 461.584925 10.256786) (xy 461.661685 10.295008) (xy 461.741644 10.325984)
			(xy 461.82412 10.349451) (xy 461.90841 10.365207) (xy 461.993793 10.373119) (xy 462.079543 10.373119)
			(xy 462.164926 10.365207) (xy 462.249216 10.349451) (xy 462.331692 10.325984) (xy 462.411651 10.295008)
			(xy 462.488411 10.256786) (xy 462.561317 10.211645) (xy 462.629746 10.159969) (xy 462.693116 10.1022)
			(xy 462.750885 10.03883) (xy 462.802561 9.970401) (xy 462.847702 9.897495) (xy 462.885924 9.820735)
			(xy 462.9169 9.740776) (xy 462.940367 9.6583) (xy 462.956123 9.57401) (xy 462.964035 9.488627) (xy 462.96453 9.445752)
			(xy 462.964035 9.402877) (xy 462.956123 9.317494) (xy 462.940367 9.233204) (xy 462.9169 9.150728)
			(xy 462.885924 9.070769) (xy 462.847702 8.994009) (xy 462.802561 8.921103) (xy 462.750885 8.852674)
			(xy 462.693116 8.789304) (xy 462.629746 8.731535) (xy 462.561317 8.679859) (xy 462.488411 8.634718)
			(xy 462.411651 8.596496) (xy 462.331692 8.56552) (xy 462.249216 8.542053) (xy 462.164926 8.526297)
			(xy 462.079543 8.518385) (xy 461.993793 8.518385) (xy 461.90841 8.526297) (xy 461.82412 8.542053)
			(xy 461.741644 8.56552) (xy 461.661685 8.596496) (xy 461.584925 8.634718) (xy 461.512019 8.679859)
			(xy 461.44359 8.731535) (xy 461.38022 8.789304) (xy 461.322451 8.852674) (xy 461.270775 8.921103)
			(xy 461.225634 8.994009) (xy 461.187412 9.070769) (xy 461.156436 9.150728) (xy 461.132969 9.233204)
			(xy 461.117213 9.317494) (xy 461.109301 9.402877) (xy 456.614035 9.402877) (xy 456.606123 9.317494)
			(xy 456.590367 9.233204) (xy 456.5669 9.150728) (xy 456.535924 9.070769) (xy 456.497702 8.994009)
			(xy 456.452561 8.921103) (xy 456.400885 8.852674) (xy 456.343116 8.789304) (xy 456.279746 8.731535)
			(xy 456.211317 8.679859) (xy 456.138411 8.634718) (xy 456.061651 8.596496) (xy 455.981692 8.56552)
			(xy 455.899216 8.542053) (xy 455.814926 8.526297) (xy 455.729543 8.518385) (xy 455.643793 8.518385)
			(xy 455.55841 8.526297) (xy 455.47412 8.542053) (xy 455.391644 8.56552) (xy 455.311685 8.596496)
			(xy 455.234925 8.634718) (xy 455.162019 8.679859) (xy 455.09359 8.731535) (xy 455.03022 8.789304)
			(xy 454.972451 8.852674) (xy 454.920775 8.921103) (xy 454.875634 8.994009) (xy 454.837412 9.070769)
			(xy 454.806436 9.150728) (xy 454.782969 9.233204) (xy 454.767213 9.317494) (xy 454.759301 9.402877)
			(xy 404.76379 9.402877) (xy 404.763491 9.376969) (xy 404.755579 9.291586) (xy 404.739823 9.207296)
			(xy 404.716356 9.12482) (xy 404.68538 9.044861) (xy 404.647158 8.968101) (xy 404.602017 8.895195)
			(xy 404.550341 8.826766) (xy 404.492572 8.763396) (xy 404.429202 8.705627) (xy 404.360773 8.653951)
			(xy 404.287867 8.60881) (xy 404.211107 8.570588) (xy 404.131148 8.539612) (xy 404.048672 8.516145)
			(xy 403.964382 8.500389) (xy 403.878999 8.492477) (xy 403.793249 8.492477) (xy 403.707866 8.500389)
			(xy 403.623576 8.516145) (xy 403.5411 8.539612) (xy 403.461141 8.570588) (xy 403.384381 8.60881)
			(xy 403.311475 8.653951) (xy 403.243046 8.705627) (xy 403.179676 8.763396) (xy 403.121907 8.826766)
			(xy 403.070231 8.895195) (xy 403.02509 8.968101) (xy 402.986868 9.044861) (xy 402.955892 9.12482)
			(xy 402.932425 9.207296) (xy 402.916669 9.291586) (xy 402.908757 9.376969) (xy 398.413491 9.376969)
			(xy 398.405579 9.291586) (xy 398.389823 9.207296) (xy 398.366356 9.12482) (xy 398.33538 9.044861)
			(xy 398.297158 8.968101) (xy 398.252017 8.895195) (xy 398.200341 8.826766) (xy 398.142572 8.763396)
			(xy 398.079202 8.705627) (xy 398.010773 8.653951) (xy 397.937867 8.60881) (xy 397.861107 8.570588)
			(xy 397.781148 8.539612) (xy 397.698672 8.516145) (xy 397.614382 8.500389) (xy 397.528999 8.492477)
			(xy 397.443249 8.492477) (xy 397.357866 8.500389) (xy 397.273576 8.516145) (xy 397.1911 8.539612)
			(xy 397.111141 8.570588) (xy 397.034381 8.60881) (xy 396.961475 8.653951) (xy 396.893046 8.705627)
			(xy 396.829676 8.763396) (xy 396.771907 8.826766) (xy 396.720231 8.895195) (xy 396.67509 8.968101)
			(xy 396.636868 9.044861) (xy 396.605892 9.12482) (xy 396.582425 9.207296) (xy 396.566669 9.291586)
			(xy 396.558757 9.376969) (xy 390.701117 9.376969) (xy 390.701035 9.369857) (xy 390.693123 9.284474)
			(xy 390.677367 9.200184) (xy 390.6539 9.117708) (xy 390.622924 9.037749) (xy 390.584702 8.960989)
			(xy 390.539561 8.888083) (xy 390.487885 8.819654) (xy 390.430116 8.756284) (xy 390.366746 8.698515)
			(xy 390.298317 8.646839) (xy 390.225411 8.601698) (xy 390.148651 8.563476) (xy 390.068692 8.5325)
			(xy 389.986216 8.509033) (xy 389.901926 8.493277) (xy 389.816543 8.485365) (xy 389.730793 8.485365)
			(xy 389.64541 8.493277) (xy 389.56112 8.509033) (xy 389.478644 8.5325) (xy 389.398685 8.563476) (xy 389.321925 8.601698)
			(xy 389.249019 8.646839) (xy 389.18059 8.698515) (xy 389.11722 8.756284) (xy 389.059451 8.819654)
			(xy 389.007775 8.888083) (xy 388.962634 8.960989) (xy 388.924412 9.037749) (xy 388.893436 9.117708)
			(xy 388.869969 9.200184) (xy 388.854213 9.284474) (xy 388.846301 9.369857) (xy 384.351035 9.369857)
			(xy 384.343123 9.284474) (xy 384.327367 9.200184) (xy 384.3039 9.117708) (xy 384.272924 9.037749)
			(xy 384.234702 8.960989) (xy 384.189561 8.888083) (xy 384.137885 8.819654) (xy 384.080116 8.756284)
			(xy 384.016746 8.698515) (xy 383.948317 8.646839) (xy 383.875411 8.601698) (xy 383.798651 8.563476)
			(xy 383.718692 8.5325) (xy 383.636216 8.509033) (xy 383.551926 8.493277) (xy 383.466543 8.485365)
			(xy 383.380793 8.485365) (xy 383.29541 8.493277) (xy 383.21112 8.509033) (xy 383.128644 8.5325) (xy 383.048685 8.563476)
			(xy 382.971925 8.601698) (xy 382.899019 8.646839) (xy 382.83059 8.698515) (xy 382.76722 8.756284)
			(xy 382.709451 8.819654) (xy 382.657775 8.888083) (xy 382.612634 8.960989) (xy 382.574412 9.037749)
			(xy 382.543436 9.117708) (xy 382.519969 9.200184) (xy 382.504213 9.284474) (xy 382.496301 9.369857)
			(xy 332.50079 9.369857) (xy 332.500491 9.343949) (xy 332.492579 9.258566) (xy 332.476823 9.174276)
			(xy 332.453356 9.0918) (xy 332.42238 9.011841) (xy 332.384158 8.935081) (xy 332.339017 8.862175)
			(xy 332.287341 8.793746) (xy 332.229572 8.730376) (xy 332.166202 8.672607) (xy 332.097773 8.620931)
			(xy 332.024867 8.57579) (xy 331.948107 8.537568) (xy 331.868148 8.506592) (xy 331.785672 8.483125)
			(xy 331.701382 8.467369) (xy 331.615999 8.459457) (xy 331.530249 8.459457) (xy 331.444866 8.467369)
			(xy 331.360576 8.483125) (xy 331.2781 8.506592) (xy 331.198141 8.537568) (xy 331.121381 8.57579)
			(xy 331.048475 8.620931) (xy 330.980046 8.672607) (xy 330.916676 8.730376) (xy 330.858907 8.793746)
			(xy 330.807231 8.862175) (xy 330.76209 8.935081) (xy 330.723868 9.011841) (xy 330.692892 9.0918)
			(xy 330.669425 9.174276) (xy 330.653669 9.258566) (xy 330.645757 9.343949) (xy 326.150491 9.343949)
			(xy 326.142579 9.258566) (xy 326.126823 9.174276) (xy 326.103356 9.0918) (xy 326.07238 9.011841)
			(xy 326.034158 8.935081) (xy 325.989017 8.862175) (xy 325.937341 8.793746) (xy 325.879572 8.730376)
			(xy 325.816202 8.672607) (xy 325.747773 8.620931) (xy 325.674867 8.57579) (xy 325.598107 8.537568)
			(xy 325.518148 8.506592) (xy 325.435672 8.483125) (xy 325.351382 8.467369) (xy 325.265999 8.459457)
			(xy 325.180249 8.459457) (xy 325.094866 8.467369) (xy 325.010576 8.483125) (xy 324.9281 8.506592)
			(xy 324.848141 8.537568) (xy 324.771381 8.57579) (xy 324.698475 8.620931) (xy 324.630046 8.672607)
			(xy 324.566676 8.730376) (xy 324.508907 8.793746) (xy 324.457231 8.862175) (xy 324.41209 8.935081)
			(xy 324.373868 9.011841) (xy 324.342892 9.0918) (xy 324.319425 9.174276) (xy 324.303669 9.258566)
			(xy 324.295757 9.343949) (xy 317.930117 9.343949) (xy 317.930035 9.336837) (xy 317.922123 9.251454)
			(xy 317.906367 9.167164) (xy 317.8829 9.084688) (xy 317.851924 9.004729) (xy 317.813702 8.927969)
			(xy 317.768561 8.855063) (xy 317.716885 8.786634) (xy 317.659116 8.723264) (xy 317.595746 8.665495)
			(xy 317.527317 8.613819) (xy 317.454411 8.568678) (xy 317.377651 8.530456) (xy 317.297692 8.49948)
			(xy 317.215216 8.476013) (xy 317.130926 8.460257) (xy 317.045543 8.452345) (xy 316.959793 8.452345)
			(xy 316.87441 8.460257) (xy 316.79012 8.476013) (xy 316.707644 8.49948) (xy 316.627685 8.530456)
			(xy 316.550925 8.568678) (xy 316.478019 8.613819) (xy 316.40959 8.665495) (xy 316.34622 8.723264)
			(xy 316.288451 8.786634) (xy 316.236775 8.855063) (xy 316.191634 8.927969) (xy 316.153412 9.004729)
			(xy 316.122436 9.084688) (xy 316.098969 9.167164) (xy 316.083213 9.251454) (xy 316.075301 9.336837)
			(xy 311.580035 9.336837) (xy 311.572123 9.251454) (xy 311.556367 9.167164) (xy 311.5329 9.084688)
			(xy 311.501924 9.004729) (xy 311.463702 8.927969) (xy 311.418561 8.855063) (xy 311.366885 8.786634)
			(xy 311.309116 8.723264) (xy 311.245746 8.665495) (xy 311.177317 8.613819) (xy 311.104411 8.568678)
			(xy 311.027651 8.530456) (xy 310.947692 8.49948) (xy 310.865216 8.476013) (xy 310.780926 8.460257)
			(xy 310.695543 8.452345) (xy 310.609793 8.452345) (xy 310.52441 8.460257) (xy 310.44012 8.476013)
			(xy 310.357644 8.49948) (xy 310.277685 8.530456) (xy 310.200925 8.568678) (xy 310.128019 8.613819)
			(xy 310.05959 8.665495) (xy 309.99622 8.723264) (xy 309.938451 8.786634) (xy 309.886775 8.855063)
			(xy 309.841634 8.927969) (xy 309.803412 9.004729) (xy 309.772436 9.084688) (xy 309.748969 9.167164)
			(xy 309.733213 9.251454) (xy 309.725301 9.336837) (xy 259.72979 9.336837) (xy 259.729491 9.310929)
			(xy 259.721579 9.225546) (xy 259.705823 9.141256) (xy 259.682356 9.05878) (xy 259.65138 8.978821)
			(xy 259.613158 8.902061) (xy 259.568017 8.829155) (xy 259.516341 8.760726) (xy 259.458572 8.697356)
			(xy 259.395202 8.639587) (xy 259.326773 8.587911) (xy 259.253867 8.54277) (xy 259.177107 8.504548)
			(xy 259.097148 8.473572) (xy 259.014672 8.450105) (xy 258.930382 8.434349) (xy 258.844999 8.426437)
			(xy 258.759249 8.426437) (xy 258.673866 8.434349) (xy 258.589576 8.450105) (xy 258.5071 8.473572)
			(xy 258.427141 8.504548) (xy 258.350381 8.54277) (xy 258.277475 8.587911) (xy 258.209046 8.639587)
			(xy 258.145676 8.697356) (xy 258.087907 8.760726) (xy 258.036231 8.829155) (xy 257.99109 8.902061)
			(xy 257.952868 8.978821) (xy 257.921892 9.05878) (xy 257.898425 9.141256) (xy 257.882669 9.225546)
			(xy 257.874757 9.310929) (xy 253.379491 9.310929) (xy 253.371579 9.225546) (xy 253.355823 9.141256)
			(xy 253.332356 9.05878) (xy 253.30138 8.978821) (xy 253.263158 8.902061) (xy 253.218017 8.829155)
			(xy 253.166341 8.760726) (xy 253.108572 8.697356) (xy 253.045202 8.639587) (xy 252.976773 8.587911)
			(xy 252.903867 8.54277) (xy 252.827107 8.504548) (xy 252.747148 8.473572) (xy 252.664672 8.450105)
			(xy 252.580382 8.434349) (xy 252.494999 8.426437) (xy 252.409249 8.426437) (xy 252.323866 8.434349)
			(xy 252.239576 8.450105) (xy 252.1571 8.473572) (xy 252.077141 8.504548) (xy 252.000381 8.54277)
			(xy 251.927475 8.587911) (xy 251.859046 8.639587) (xy 251.795676 8.697356) (xy 251.737907 8.760726)
			(xy 251.686231 8.829155) (xy 251.64109 8.902061) (xy 251.602868 8.978821) (xy 251.571892 9.05878)
			(xy 251.548425 9.141256) (xy 251.532669 9.225546) (xy 251.524757 9.310929) (xy 245.921117 9.310929)
			(xy 245.921035 9.303817) (xy 245.913123 9.218434) (xy 245.897367 9.134144) (xy 245.8739 9.051668)
			(xy 245.842924 8.971709) (xy 245.804702 8.894949) (xy 245.759561 8.822043) (xy 245.707885 8.753614)
			(xy 245.650116 8.690244) (xy 245.586746 8.632475) (xy 245.518317 8.580799) (xy 245.445411 8.535658)
			(xy 245.368651 8.497436) (xy 245.288692 8.46646) (xy 245.206216 8.442993) (xy 245.121926 8.427237)
			(xy 245.036543 8.419325) (xy 244.950793 8.419325) (xy 244.86541 8.427237) (xy 244.78112 8.442993)
			(xy 244.698644 8.46646) (xy 244.618685 8.497436) (xy 244.541925 8.535658) (xy 244.469019 8.580799)
			(xy 244.40059 8.632475) (xy 244.33722 8.690244) (xy 244.279451 8.753614) (xy 244.227775 8.822043)
			(xy 244.182634 8.894949) (xy 244.144412 8.971709) (xy 244.113436 9.051668) (xy 244.089969 9.134144)
			(xy 244.074213 9.218434) (xy 244.066301 9.303817) (xy 239.571035 9.303817) (xy 239.563123 9.218434)
			(xy 239.547367 9.134144) (xy 239.5239 9.051668) (xy 239.492924 8.971709) (xy 239.454702 8.894949)
			(xy 239.409561 8.822043) (xy 239.357885 8.753614) (xy 239.300116 8.690244) (xy 239.236746 8.632475)
			(xy 239.168317 8.580799) (xy 239.095411 8.535658) (xy 239.018651 8.497436) (xy 238.938692 8.46646)
			(xy 238.856216 8.442993) (xy 238.771926 8.427237) (xy 238.686543 8.419325) (xy 238.600793 8.419325)
			(xy 238.51541 8.427237) (xy 238.43112 8.442993) (xy 238.348644 8.46646) (xy 238.268685 8.497436)
			(xy 238.191925 8.535658) (xy 238.119019 8.580799) (xy 238.05059 8.632475) (xy 237.98722 8.690244)
			(xy 237.929451 8.753614) (xy 237.877775 8.822043) (xy 237.832634 8.894949) (xy 237.794412 8.971709)
			(xy 237.763436 9.051668) (xy 237.739969 9.134144) (xy 237.724213 9.218434) (xy 237.716301 9.303817)
			(xy 187.719832 9.303817) (xy 187.712579 9.225546) (xy 187.696823 9.141256) (xy 187.673356 9.05878)
			(xy 187.64238 8.978821) (xy 187.604158 8.902061) (xy 187.559017 8.829155) (xy 187.507341 8.760726)
			(xy 187.449572 8.697356) (xy 187.386202 8.639587) (xy 187.317773 8.587911) (xy 187.244867 8.54277)
			(xy 187.168107 8.504548) (xy 187.088148 8.473572) (xy 187.005672 8.450105) (xy 186.921382 8.434349)
			(xy 186.835999 8.426437) (xy 186.750249 8.426437) (xy 186.664866 8.434349) (xy 186.580576 8.450105)
			(xy 186.4981 8.473572) (xy 186.418141 8.504548) (xy 186.341381 8.54277) (xy 186.268475 8.587911)
			(xy 186.200046 8.639587) (xy 186.136676 8.697356) (xy 186.078907 8.760726) (xy 186.027231 8.829155)
			(xy 185.98209 8.902061) (xy 185.943868 8.978821) (xy 185.912892 9.05878) (xy 185.889425 9.141256)
			(xy 185.873669 9.225546) (xy 185.865757 9.310929) (xy 181.370491 9.310929) (xy 181.362579 9.225546)
			(xy 181.346823 9.141256) (xy 181.323356 9.05878) (xy 181.29238 8.978821) (xy 181.254158 8.902061)
			(xy 181.209017 8.829155) (xy 181.157341 8.760726) (xy 181.099572 8.697356) (xy 181.036202 8.639587)
			(xy 180.967773 8.587911) (xy 180.894867 8.54277) (xy 180.818107 8.504548) (xy 180.738148 8.473572)
			(xy 180.655672 8.450105) (xy 180.571382 8.434349) (xy 180.485999 8.426437) (xy 180.400249 8.426437)
			(xy 180.314866 8.434349) (xy 180.230576 8.450105) (xy 180.1481 8.473572) (xy 180.068141 8.504548)
			(xy 179.991381 8.54277) (xy 179.918475 8.587911) (xy 179.850046 8.639587) (xy 179.786676 8.697356)
			(xy 179.728907 8.760726) (xy 179.677231 8.829155) (xy 179.63209 8.902061) (xy 179.593868 8.978821)
			(xy 179.562892 9.05878) (xy 179.539425 9.141256) (xy 179.523669 9.225546) (xy 179.515757 9.310929)
			(xy 158.621984 9.310929) (xy 158.621984 8.377682) (xy 158.62149 8.307329) (xy 158.6136 8.166844)
			(xy 158.597845 8.027022) (xy 158.574274 7.888303) (xy 158.542963 7.751125) (xy 158.50401 7.615918)
			(xy 158.457537 7.483107) (xy 158.40369 7.353112) (xy 158.342638 7.22634) (xy 158.274575 7.103191)
			(xy 158.199714 6.984051) (xy 158.11829 6.869297) (xy 158.039844 6.770929) (xy 179.515757 6.770929)
			(xy 179.515757 6.856679) (xy 179.523669 6.942062) (xy 179.539425 7.026352) (xy 179.562892 7.108828)
			(xy 179.593868 7.188787) (xy 179.63209 7.265547) (xy 179.677231 7.338453) (xy 179.728907 7.406882)
			(xy 179.786676 7.470252) (xy 179.850046 7.528021) (xy 179.918475 7.579697) (xy 179.991381 7.624838)
			(xy 180.068141 7.66306) (xy 180.1481 7.694036) (xy 180.230576 7.717503) (xy 180.314866 7.733259)
			(xy 180.400249 7.741171) (xy 180.485999 7.741171) (xy 180.571382 7.733259) (xy 180.655672 7.717503)
			(xy 180.738148 7.694036) (xy 180.818107 7.66306) (xy 180.894867 7.624838) (xy 180.967773 7.579697)
			(xy 181.026743 7.535164) (xy 183.674512 7.535164) (xy 183.674512 8.632444) (xy 183.674927 8.644523)
			(xy 183.682404 8.667495) (xy 183.696613 8.687033) (xy 183.716162 8.701225) (xy 183.739141 8.708683)
			(xy 183.75122 8.709152) (xy 184.36336 8.709152) (xy 184.375428 8.708603) (xy 184.398387 8.701156)
			(xy 184.417921 8.68698) (xy 184.432118 8.667462) (xy 184.439589 8.644512) (xy 184.440068 8.632444)
			(xy 184.440068 7.535164) (xy 184.439717 7.523075) (xy 184.432235 7.500085) (xy 184.418014 7.480532)
			(xy 184.398447 7.46633) (xy 184.375449 7.458871) (xy 184.36336 7.458456) (xy 183.75122 7.458456)
			(xy 183.73915 7.458981) (xy 183.71619 7.466433) (xy 183.696655 7.480615) (xy 183.682459 7.500139)
			(xy 183.674989 7.523094) (xy 183.674512 7.535164) (xy 181.026743 7.535164) (xy 181.036202 7.528021)
			(xy 181.099572 7.470252) (xy 181.157341 7.406882) (xy 181.209017 7.338453) (xy 181.254158 7.265547)
			(xy 181.29238 7.188787) (xy 181.323356 7.108828) (xy 181.346823 7.026352) (xy 181.362579 6.942062)
			(xy 181.370491 6.856679) (xy 181.370986 6.813804) (xy 181.370491 6.770929) (xy 185.865757 6.770929)
			(xy 185.865757 6.856679) (xy 185.873669 6.942062) (xy 185.889425 7.026352) (xy 185.912892 7.108828)
			(xy 185.943868 7.188787) (xy 185.98209 7.265547) (xy 186.027231 7.338453) (xy 186.078907 7.406882)
			(xy 186.136676 7.470252) (xy 186.200046 7.528021) (xy 186.268475 7.579697) (xy 186.341381 7.624838)
			(xy 186.418141 7.66306) (xy 186.4981 7.694036) (xy 186.580576 7.717503) (xy 186.664866 7.733259)
			(xy 186.750249 7.741171) (xy 186.835999 7.741171) (xy 186.921382 7.733259) (xy 187.005672 7.717503)
			(xy 187.088148 7.694036) (xy 187.168107 7.66306) (xy 187.244867 7.624838) (xy 187.317773 7.579697)
			(xy 187.386202 7.528021) (xy 187.449572 7.470252) (xy 187.507341 7.406882) (xy 187.559017 7.338453)
			(xy 187.604158 7.265547) (xy 187.64238 7.188787) (xy 187.673356 7.108828) (xy 187.696823 7.026352)
			(xy 187.712579 6.942062) (xy 187.720491 6.856679) (xy 187.720986 6.813804) (xy 187.720491 6.770929)
			(xy 187.719832 6.763817) (xy 237.716301 6.763817) (xy 237.716301 6.849567) (xy 237.724213 6.93495)
			(xy 237.739969 7.01924) (xy 237.763436 7.101716) (xy 237.794412 7.181675) (xy 237.832634 7.258435)
			(xy 237.877775 7.331341) (xy 237.929451 7.39977) (xy 237.98722 7.46314) (xy 238.05059 7.520909) (xy 238.119019 7.572585)
			(xy 238.191925 7.617726) (xy 238.268685 7.655948) (xy 238.348644 7.686924) (xy 238.43112 7.710391)
			(xy 238.51541 7.726147) (xy 238.600793 7.734059) (xy 238.686543 7.734059) (xy 238.771926 7.726147)
			(xy 238.856216 7.710391) (xy 238.938692 7.686924) (xy 239.018651 7.655948) (xy 239.095411 7.617726)
			(xy 239.168317 7.572585) (xy 239.227287 7.528052) (xy 240.996724 7.528052) (xy 240.996724 8.625332)
			(xy 240.997137 8.637411) (xy 241.004612 8.660385) (xy 241.018821 8.679925) (xy 241.038372 8.694117)
			(xy 241.061352 8.701573) (xy 241.073432 8.70204) (xy 241.685572 8.70204) (xy 241.697642 8.701513)
			(xy 241.720603 8.694062) (xy 241.740138 8.67988) (xy 241.754334 8.660357) (xy 241.761803 8.637402)
			(xy 241.76228 8.625332) (xy 241.76228 7.528052) (xy 241.761876 7.515972) (xy 241.754397 7.492999)
			(xy 241.740186 7.47346) (xy 241.720633 7.459268) (xy 241.697652 7.451812) (xy 241.685572 7.451344)
			(xy 241.073432 7.451344) (xy 241.061364 7.451891) (xy 241.038406 7.459338) (xy 241.018872 7.473515)
			(xy 241.004675 7.493034) (xy 240.997203 7.515984) (xy 240.996724 7.528052) (xy 239.227287 7.528052)
			(xy 239.236746 7.520909) (xy 239.300116 7.46314) (xy 239.357885 7.39977) (xy 239.409561 7.331341)
			(xy 239.454702 7.258435) (xy 239.492924 7.181675) (xy 239.5239 7.101716) (xy 239.547367 7.01924)
			(xy 239.563123 6.93495) (xy 239.571035 6.849567) (xy 239.57153 6.806692) (xy 239.571035 6.763817)
			(xy 244.066301 6.763817) (xy 244.066301 6.849567) (xy 244.074213 6.93495) (xy 244.089969 7.01924)
			(xy 244.113436 7.101716) (xy 244.144412 7.181675) (xy 244.182634 7.258435) (xy 244.227775 7.331341)
			(xy 244.279451 7.39977) (xy 244.33722 7.46314) (xy 244.40059 7.520909) (xy 244.469019 7.572585) (xy 244.541925 7.617726)
			(xy 244.618685 7.655948) (xy 244.698644 7.686924) (xy 244.78112 7.710391) (xy 244.86541 7.726147)
			(xy 244.950793 7.734059) (xy 245.036543 7.734059) (xy 245.121926 7.726147) (xy 245.206216 7.710391)
			(xy 245.288692 7.686924) (xy 245.368651 7.655948) (xy 245.445411 7.617726) (xy 245.518317 7.572585)
			(xy 245.586746 7.520909) (xy 245.650116 7.46314) (xy 245.707885 7.39977) (xy 245.759561 7.331341)
			(xy 245.804702 7.258435) (xy 245.842924 7.181675) (xy 245.8739 7.101716) (xy 245.897367 7.01924)
			(xy 245.913123 6.93495) (xy 245.921035 6.849567) (xy 245.92153 6.806692) (xy 245.921117 6.770929)
			(xy 251.524757 6.770929) (xy 251.524757 6.856679) (xy 251.532669 6.942062) (xy 251.548425 7.026352)
			(xy 251.571892 7.108828) (xy 251.602868 7.188787) (xy 251.64109 7.265547) (xy 251.686231 7.338453)
			(xy 251.737907 7.406882) (xy 251.795676 7.470252) (xy 251.859046 7.528021) (xy 251.927475 7.579697)
			(xy 252.000381 7.624838) (xy 252.077141 7.66306) (xy 252.1571 7.694036) (xy 252.239576 7.717503)
			(xy 252.323866 7.733259) (xy 252.409249 7.741171) (xy 252.494999 7.741171) (xy 252.580382 7.733259)
			(xy 252.664672 7.717503) (xy 252.747148 7.694036) (xy 252.827107 7.66306) (xy 252.903867 7.624838)
			(xy 252.976773 7.579697) (xy 253.035743 7.535164) (xy 255.683512 7.535164) (xy 255.683512 8.632444)
			(xy 255.683927 8.644523) (xy 255.691404 8.667495) (xy 255.705613 8.687033) (xy 255.725162 8.701225)
			(xy 255.748141 8.708683) (xy 255.76022 8.709152) (xy 256.37236 8.709152) (xy 256.380616 8.708982)
			(xy 256.39676 8.705516) (xy 256.404364 8.702294) (xy 256.412492 8.698484) (xy 256.430272 8.69696)
			(xy 256.510282 8.71855) (xy 256.52476 8.72871) (xy 256.52984 8.735822) (xy 256.545261 8.756827) (xy 256.580858 8.794882)
			(xy 256.6213 8.827741) (xy 256.665837 8.854793) (xy 256.71364 8.875534) (xy 256.76382 8.88958) (xy 256.815444 8.896669)
			(xy 256.841498 8.897112) (xy 256.868754 8.896575) (xy 256.92271 8.888821) (xy 256.975016 8.873472)
			(xy 257.024606 8.850838) (xy 257.070472 8.82138) (xy 257.111682 8.785698) (xy 257.147397 8.744517)
			(xy 257.176891 8.698674) (xy 257.199564 8.649103) (xy 257.214956 8.59681) (xy 257.222753 8.542859)
			(xy 257.22326 8.515604) (xy 257.22326 7.652004) (xy 257.22284 7.624738) (xy 257.215076 7.57076) (xy 257.199705 7.518438)
			(xy 257.177041 7.468838) (xy 257.147545 7.42297) (xy 257.111819 7.38177) (xy 257.070591 7.346076)
			(xy 257.0247 7.316616) (xy 256.975082 7.293991) (xy 256.922748 7.278661) (xy 256.868765 7.270939)
			(xy 256.841498 7.270496) (xy 256.815444 7.27096) (xy 256.763821 7.278047) (xy 256.713641 7.29209)
			(xy 256.665838 7.312827) (xy 256.621299 7.339873) (xy 256.580852 7.372725) (xy 256.54525 7.410773)
			(xy 256.52984 7.431786) (xy 256.52476 7.438898) (xy 256.510282 7.449058) (xy 256.430272 7.470648)
			(xy 256.412492 7.469124) (xy 256.404364 7.465314) (xy 256.39676 7.462097) (xy 256.380615 7.458644)
			(xy 256.37236 7.458456) (xy 255.76022 7.458456) (xy 255.74815 7.458981) (xy 255.72519 7.466433) (xy 255.705655 7.480615)
			(xy 255.691459 7.500139) (xy 255.683989 7.523094) (xy 255.683512 7.535164) (xy 253.035743 7.535164)
			(xy 253.045202 7.528021) (xy 253.108572 7.470252) (xy 253.166341 7.406882) (xy 253.218017 7.338453)
			(xy 253.263158 7.265547) (xy 253.30138 7.188787) (xy 253.332356 7.108828) (xy 253.355823 7.026352)
			(xy 253.371579 6.942062) (xy 253.379491 6.856679) (xy 253.379986 6.813804) (xy 253.379491 6.770929)
			(xy 257.874757 6.770929) (xy 257.874757 6.856679) (xy 257.882669 6.942062) (xy 257.898425 7.026352)
			(xy 257.921892 7.108828) (xy 257.952868 7.188787) (xy 257.99109 7.265547) (xy 258.036231 7.338453)
			(xy 258.087907 7.406882) (xy 258.145676 7.470252) (xy 258.209046 7.528021) (xy 258.277475 7.579697)
			(xy 258.350381 7.624838) (xy 258.427141 7.66306) (xy 258.5071 7.694036) (xy 258.589576 7.717503)
			(xy 258.673866 7.733259) (xy 258.759249 7.741171) (xy 258.844999 7.741171) (xy 258.930382 7.733259)
			(xy 259.014672 7.717503) (xy 259.097148 7.694036) (xy 259.177107 7.66306) (xy 259.253867 7.624838)
			(xy 259.326773 7.579697) (xy 259.395202 7.528021) (xy 259.458572 7.470252) (xy 259.516341 7.406882)
			(xy 259.568017 7.338453) (xy 259.613158 7.265547) (xy 259.65138 7.188787) (xy 259.682356 7.108828)
			(xy 259.705823 7.026352) (xy 259.721579 6.942062) (xy 259.729491 6.856679) (xy 259.729986 6.813804)
			(xy 259.72979 6.796837) (xy 309.725301 6.796837) (xy 309.725301 6.882587) (xy 309.733213 6.96797)
			(xy 309.748969 7.05226) (xy 309.772436 7.134736) (xy 309.803412 7.214695) (xy 309.841634 7.291455)
			(xy 309.886775 7.364361) (xy 309.938451 7.43279) (xy 309.99622 7.49616) (xy 310.05959 7.553929) (xy 310.128019 7.605605)
			(xy 310.200925 7.650746) (xy 310.277685 7.688968) (xy 310.357644 7.719944) (xy 310.44012 7.743411)
			(xy 310.52441 7.759167) (xy 310.609793 7.767079) (xy 310.695543 7.767079) (xy 310.780926 7.759167)
			(xy 310.865216 7.743411) (xy 310.947692 7.719944) (xy 311.027651 7.688968) (xy 311.049854 7.677912)
			(xy 312.231532 7.677912) (xy 312.231532 8.541512) (xy 312.231945 8.568779) (xy 312.239711 8.622756)
			(xy 312.255083 8.675077) (xy 312.277749 8.724677) (xy 312.307245 8.770544) (xy 312.342972 8.811745)
			(xy 312.384201 8.847438) (xy 312.430092 8.876898) (xy 312.47971 8.899524) (xy 312.532044 8.914854)
			(xy 312.586027 8.922577) (xy 312.613294 8.92302) (xy 312.639347 8.922543) (xy 312.69097 8.915457)
			(xy 312.741149 8.901416) (xy 312.788952 8.880681) (xy 312.833491 8.853637) (xy 312.873938 8.820787)
			(xy 312.909541 8.782741) (xy 312.924952 8.76173) (xy 312.930032 8.754618) (xy 312.94451 8.744458)
			(xy 313.02452 8.722868) (xy 313.0423 8.724392) (xy 313.050428 8.728202) (xy 313.058035 8.731412)
			(xy 313.074177 8.73487) (xy 313.082432 8.73506) (xy 313.694572 8.73506) (xy 313.706658 8.734663)
			(xy 313.729648 8.727197) (xy 313.749203 8.712989) (xy 313.763406 8.69343) (xy 313.770866 8.670438)
			(xy 313.77128 8.658352) (xy 313.77128 7.561072) (xy 313.770859 7.548993) (xy 313.763386 7.52602)
			(xy 313.749179 7.506481) (xy 313.72963 7.492289) (xy 313.706651 7.484832) (xy 313.694572 7.484364)
			(xy 313.082432 7.484364) (xy 313.074177 7.484561) (xy 313.058034 7.488009) (xy 313.050428 7.491222)
			(xy 313.0423 7.495032) (xy 313.02452 7.496556) (xy 312.94451 7.474966) (xy 312.930032 7.464806) (xy 312.924952 7.457694)
			(xy 312.909531 7.436688) (xy 312.873935 7.398633) (xy 312.833492 7.365774) (xy 312.788956 7.338722)
			(xy 312.741153 7.31798) (xy 312.690973 7.303935) (xy 312.639348 7.296847) (xy 312.613294 7.296404)
			(xy 312.586038 7.296918) (xy 312.532079 7.304673) (xy 312.479772 7.320024) (xy 312.430181 7.34266)
			(xy 312.384314 7.37212) (xy 312.343104 7.407805) (xy 312.307389 7.448988) (xy 312.277896 7.494834)
			(xy 312.255223 7.544408) (xy 312.239833 7.596703) (xy 312.232038 7.650656) (xy 312.231532 7.677912)
			(xy 311.049854 7.677912) (xy 311.104411 7.650746) (xy 311.177317 7.605605) (xy 311.245746 7.553929)
			(xy 311.309116 7.49616) (xy 311.366885 7.43279) (xy 311.418561 7.364361) (xy 311.463702 7.291455)
			(xy 311.501924 7.214695) (xy 311.5329 7.134736) (xy 311.556367 7.05226) (xy 311.572123 6.96797) (xy 311.580035 6.882587)
			(xy 311.58053 6.839712) (xy 311.580035 6.796837) (xy 316.075301 6.796837) (xy 316.075301 6.882587)
			(xy 316.083213 6.96797) (xy 316.098969 7.05226) (xy 316.122436 7.134736) (xy 316.153412 7.214695)
			(xy 316.191634 7.291455) (xy 316.236775 7.364361) (xy 316.288451 7.43279) (xy 316.34622 7.49616)
			(xy 316.40959 7.553929) (xy 316.478019 7.605605) (xy 316.550925 7.650746) (xy 316.627685 7.688968)
			(xy 316.707644 7.719944) (xy 316.79012 7.743411) (xy 316.87441 7.759167) (xy 316.959793 7.767079)
			(xy 317.045543 7.767079) (xy 317.130926 7.759167) (xy 317.215216 7.743411) (xy 317.297692 7.719944)
			(xy 317.377651 7.688968) (xy 317.454411 7.650746) (xy 317.527317 7.605605) (xy 317.595746 7.553929)
			(xy 317.659116 7.49616) (xy 317.716885 7.43279) (xy 317.768561 7.364361) (xy 317.813702 7.291455)
			(xy 317.851924 7.214695) (xy 317.8829 7.134736) (xy 317.906367 7.05226) (xy 317.922123 6.96797) (xy 317.930035 6.882587)
			(xy 317.93053 6.839712) (xy 317.930117 6.803949) (xy 324.295757 6.803949) (xy 324.295757 6.889699)
			(xy 324.303669 6.975082) (xy 324.319425 7.059372) (xy 324.342892 7.141848) (xy 324.373868 7.221807)
			(xy 324.41209 7.298567) (xy 324.457231 7.371473) (xy 324.508907 7.439902) (xy 324.566676 7.503272)
			(xy 324.630046 7.561041) (xy 324.698475 7.612717) (xy 324.771381 7.657858) (xy 324.848141 7.69608)
			(xy 324.9281 7.727056) (xy 325.010576 7.750523) (xy 325.094866 7.766279) (xy 325.180249 7.774191)
			(xy 325.265999 7.774191) (xy 325.351382 7.766279) (xy 325.435672 7.750523) (xy 325.518148 7.727056)
			(xy 325.598107 7.69608) (xy 325.674867 7.657858) (xy 325.747773 7.612717) (xy 325.806743 7.568184)
			(xy 328.454512 7.568184) (xy 328.454512 8.665464) (xy 328.454944 8.677547) (xy 328.462404 8.700532)
			(xy 328.476604 8.720084) (xy 328.496154 8.734289) (xy 328.519137 8.741754) (xy 328.53122 8.742172)
			(xy 329.14336 8.742172) (xy 329.151617 8.742009) (xy 329.16776 8.738539) (xy 329.175364 8.735314)
			(xy 329.183492 8.731504) (xy 329.201272 8.72998) (xy 329.281282 8.75157) (xy 329.29576 8.76173) (xy 329.30084 8.768842)
			(xy 329.316255 8.789852) (xy 329.351854 8.827906) (xy 329.392298 8.860763) (xy 329.436835 8.887814)
			(xy 329.484639 8.908555) (xy 329.534819 8.9226) (xy 329.586444 8.929689) (xy 329.612498 8.930132)
			(xy 329.639757 8.929675) (xy 329.693721 8.921919) (xy 329.746033 8.906565) (xy 329.795628 8.883926)
			(xy 329.841498 8.854461) (xy 329.88271 8.81877) (xy 329.918425 8.777579) (xy 329.947917 8.731727)
			(xy 329.970586 8.682145) (xy 329.985971 8.629842) (xy 329.993758 8.575883) (xy 329.99426 8.548624)
			(xy 329.99426 7.685024) (xy 329.993821 7.657758) (xy 329.98606 7.603781) (xy 329.970692 7.55146)
			(xy 329.94803 7.50186) (xy 329.918536 7.455992) (xy 329.882812 7.414791) (xy 329.841585 7.379097)
			(xy 329.795696 7.349637) (xy 329.746079 7.327011) (xy 329.693747 7.311681) (xy 329.639764 7.303959)
			(xy 329.612498 7.303516) (xy 329.586444 7.303972) (xy 329.53482 7.311059) (xy 329.48464 7.325103)
			(xy 329.436836 7.345841) (xy 329.392297 7.372888) (xy 329.351851 7.405743) (xy 329.316249 7.443793)
			(xy 329.30084 7.464806) (xy 329.29576 7.471918) (xy 329.281282 7.482078) (xy 329.201272 7.503668)
			(xy 329.183492 7.502144) (xy 329.175364 7.498334) (xy 329.167759 7.495118) (xy 329.151615 7.491665)
			(xy 329.14336 7.491476) (xy 328.53122 7.491476) (xy 328.51914 7.49193) (xy 328.496161 7.49939) (xy 328.476611 7.513586)
			(xy 328.462406 7.533128) (xy 328.454935 7.556104) (xy 328.454512 7.568184) (xy 325.806743 7.568184)
			(xy 325.816202 7.561041) (xy 325.879572 7.503272) (xy 325.937341 7.439902) (xy 325.989017 7.371473)
			(xy 326.034158 7.298567) (xy 326.07238 7.221807) (xy 326.103356 7.141848) (xy 326.126823 7.059372)
			(xy 326.142579 6.975082) (xy 326.150491 6.889699) (xy 326.150986 6.846824) (xy 326.150491 6.803949)
			(xy 330.645757 6.803949) (xy 330.645757 6.889699) (xy 330.653669 6.975082) (xy 330.669425 7.059372)
			(xy 330.692892 7.141848) (xy 330.723868 7.221807) (xy 330.76209 7.298567) (xy 330.807231 7.371473)
			(xy 330.858907 7.439902) (xy 330.916676 7.503272) (xy 330.980046 7.561041) (xy 331.048475 7.612717)
			(xy 331.121381 7.657858) (xy 331.198141 7.69608) (xy 331.2781 7.727056) (xy 331.360576 7.750523)
			(xy 331.444866 7.766279) (xy 331.530249 7.774191) (xy 331.615999 7.774191) (xy 331.701382 7.766279)
			(xy 331.785672 7.750523) (xy 331.868148 7.727056) (xy 331.948107 7.69608) (xy 332.024867 7.657858)
			(xy 332.097773 7.612717) (xy 332.166202 7.561041) (xy 332.229572 7.503272) (xy 332.287341 7.439902)
			(xy 332.339017 7.371473) (xy 332.384158 7.298567) (xy 332.42238 7.221807) (xy 332.453356 7.141848)
			(xy 332.476823 7.059372) (xy 332.492579 6.975082) (xy 332.500491 6.889699) (xy 332.500986 6.846824)
			(xy 332.50079 6.829857) (xy 382.496301 6.829857) (xy 382.496301 6.915607) (xy 382.504213 7.00099)
			(xy 382.519969 7.08528) (xy 382.543436 7.167756) (xy 382.574412 7.247715) (xy 382.612634 7.324475)
			(xy 382.657775 7.397381) (xy 382.709451 7.46581) (xy 382.76722 7.52918) (xy 382.83059 7.586949) (xy 382.899019 7.638625)
			(xy 382.971925 7.683766) (xy 383.048685 7.721988) (xy 383.128644 7.752964) (xy 383.21112 7.776431)
			(xy 383.29541 7.792187) (xy 383.380793 7.800099) (xy 383.466543 7.800099) (xy 383.551926 7.792187)
			(xy 383.636216 7.776431) (xy 383.718692 7.752964) (xy 383.798651 7.721988) (xy 383.820854 7.710932)
			(xy 385.002532 7.710932) (xy 385.002532 8.574532) (xy 385.002926 8.601799) (xy 385.010695 8.655777)
			(xy 385.02607 8.708099) (xy 385.048738 8.757699) (xy 385.078236 8.803566) (xy 385.113965 8.844766)
			(xy 385.155195 8.880459) (xy 385.201088 8.909919) (xy 385.250707 8.932544) (xy 385.303042 8.947874)
			(xy 385.357027 8.955597) (xy 385.384294 8.95604) (xy 385.410349 8.955597) (xy 385.461974 8.948509)
			(xy 385.512155 8.934465) (xy 385.55996 8.913725) (xy 385.604499 8.886675) (xy 385.644944 8.853818)
			(xy 385.680544 8.815765) (xy 385.695952 8.79475) (xy 385.701032 8.787638) (xy 385.71551 8.777478)
			(xy 385.79552 8.755888) (xy 385.8133 8.757412) (xy 385.821428 8.761222) (xy 385.829035 8.764434)
			(xy 385.845177 8.76789) (xy 385.853432 8.76808) (xy 386.465572 8.76808) (xy 386.477656 8.767663)
			(xy 386.500643 8.7602) (xy 386.520196 8.745996) (xy 386.5344 8.726443) (xy 386.541863 8.703456) (xy 386.54228 8.691372)
			(xy 386.54228 7.594092) (xy 386.541894 7.582006) (xy 386.534421 7.559018) (xy 386.520209 7.539466)
			(xy 386.500649 7.525263) (xy 386.477658 7.5178) (xy 386.465572 7.517384) (xy 385.853432 7.517384)
			(xy 385.845177 7.517579) (xy 385.829034 7.521028) (xy 385.821428 7.524242) (xy 385.8133 7.528052)
			(xy 385.79552 7.529576) (xy 385.71551 7.507986) (xy 385.701032 7.497826) (xy 385.695952 7.490714)
			(xy 385.680555 7.469691) (xy 385.644952 7.431639) (xy 385.604504 7.398784) (xy 385.559963 7.371736)
			(xy 385.512158 7.350997) (xy 385.461975 7.336954) (xy 385.410349 7.329867) (xy 385.384294 7.329424)
			(xy 385.357037 7.329918) (xy 385.303076 7.337673) (xy 385.250768 7.353026) (xy 385.201176 7.375663)
			(xy 385.155308 7.405125) (xy 385.114097 7.440812) (xy 385.078382 7.481998) (xy 385.048889 7.527846)
			(xy 385.026218 7.577422) (xy 385.010829 7.62972) (xy 385.003037 7.683675) (xy 385.002532 7.710932)
			(xy 383.820854 7.710932) (xy 383.875411 7.683766) (xy 383.948317 7.638625) (xy 384.016746 7.586949)
			(xy 384.080116 7.52918) (xy 384.137885 7.46581) (xy 384.189561 7.397381) (xy 384.234702 7.324475)
			(xy 384.272924 7.247715) (xy 384.3039 7.167756) (xy 384.327367 7.08528) (xy 384.343123 7.00099) (xy 384.351035 6.915607)
			(xy 384.35153 6.872732) (xy 384.351035 6.829857) (xy 388.846301 6.829857) (xy 388.846301 6.915607)
			(xy 388.854213 7.00099) (xy 388.869969 7.08528) (xy 388.893436 7.167756) (xy 388.924412 7.247715)
			(xy 388.962634 7.324475) (xy 389.007775 7.397381) (xy 389.059451 7.46581) (xy 389.11722 7.52918)
			(xy 389.18059 7.586949) (xy 389.249019 7.638625) (xy 389.321925 7.683766) (xy 389.398685 7.721988)
			(xy 389.478644 7.752964) (xy 389.56112 7.776431) (xy 389.64541 7.792187) (xy 389.730793 7.800099)
			(xy 389.816543 7.800099) (xy 389.901926 7.792187) (xy 389.986216 7.776431) (xy 390.068692 7.752964)
			(xy 390.148651 7.721988) (xy 390.225411 7.683766) (xy 390.298317 7.638625) (xy 390.366746 7.586949)
			(xy 390.430116 7.52918) (xy 390.487885 7.46581) (xy 390.539561 7.397381) (xy 390.584702 7.324475)
			(xy 390.622924 7.247715) (xy 390.6539 7.167756) (xy 390.677367 7.08528) (xy 390.693123 7.00099) (xy 390.701035 6.915607)
			(xy 390.70153 6.872732) (xy 390.701117 6.836969) (xy 396.558757 6.836969) (xy 396.558757 6.922719)
			(xy 396.566669 7.008102) (xy 396.582425 7.092392) (xy 396.605892 7.174868) (xy 396.636868 7.254827)
			(xy 396.67509 7.331587) (xy 396.720231 7.404493) (xy 396.771907 7.472922) (xy 396.829676 7.536292)
			(xy 396.893046 7.594061) (xy 396.961475 7.645737) (xy 397.034381 7.690878) (xy 397.111141 7.7291)
			(xy 397.1911 7.760076) (xy 397.273576 7.783543) (xy 397.357866 7.799299) (xy 397.443249 7.807211)
			(xy 397.528999 7.807211) (xy 397.614382 7.799299) (xy 397.698672 7.783543) (xy 397.781148 7.760076)
			(xy 397.861107 7.7291) (xy 397.937867 7.690878) (xy 398.010773 7.645737) (xy 398.069743 7.601204)
			(xy 400.717512 7.601204) (xy 400.717512 8.698484) (xy 400.717927 8.710568) (xy 400.725392 8.733553)
			(xy 400.739597 8.753106) (xy 400.75915 8.76731) (xy 400.782136 8.774774) (xy 400.79422 8.775192)
			(xy 401.40636 8.775192) (xy 401.414617 8.775028) (xy 401.43076 8.771558) (xy 401.438364 8.768334)
			(xy 401.446492 8.764524) (xy 401.464272 8.763) (xy 401.544282 8.78459) (xy 401.55876 8.79475) (xy 401.56384 8.801862)
			(xy 401.579249 8.822876) (xy 401.614849 8.860929) (xy 401.655295 8.893786) (xy 401.699833 8.920836)
			(xy 401.747637 8.941576) (xy 401.797818 8.95562) (xy 401.849443 8.962709) (xy 401.875498 8.963152)
			(xy 401.902756 8.962675) (xy 401.956718 8.954919) (xy 402.009028 8.939567) (xy 402.058622 8.916929)
			(xy 402.104491 8.887466) (xy 402.145703 8.851777) (xy 402.181418 8.810589) (xy 402.21091 8.764739)
			(xy 402.233581 8.715159) (xy 402.248967 8.662859) (xy 402.256757 8.608902) (xy 402.25726 8.581644)
			(xy 402.25726 7.718044) (xy 402.256803 7.690779) (xy 402.249044 7.636802) (xy 402.233678 7.584481)
			(xy 402.211019 7.534881) (xy 402.181527 7.489013) (xy 402.145805 7.447812) (xy 402.10458 7.412118)
			(xy 402.058692 7.382657) (xy 402.009077 7.360031) (xy 401.956745 7.344701) (xy 401.902764 7.336979)
			(xy 401.875498 7.336536) (xy 401.849443 7.336983) (xy 401.797819 7.344071) (xy 401.747638 7.358116)
			(xy 401.699834 7.378855) (xy 401.655295 7.405904) (xy 401.614849 7.43876) (xy 401.579249 7.476812)
			(xy 401.56384 7.497826) (xy 401.55876 7.504938) (xy 401.544282 7.515098) (xy 401.464272 7.536688)
			(xy 401.446492 7.535164) (xy 401.438364 7.531354) (xy 401.430759 7.528139) (xy 401.414615 7.524685)
			(xy 401.40636 7.524496) (xy 400.79422 7.524496) (xy 400.782138 7.52493) (xy 400.759155 7.532392)
			(xy 400.739604 7.546593) (xy 400.7254 7.566141) (xy 400.717932 7.589122) (xy 400.717512 7.601204)
			(xy 398.069743 7.601204) (xy 398.079202 7.594061) (xy 398.142572 7.536292) (xy 398.200341 7.472922)
			(xy 398.252017 7.404493) (xy 398.297158 7.331587) (xy 398.33538 7.254827) (xy 398.366356 7.174868)
			(xy 398.389823 7.092392) (xy 398.405579 7.008102) (xy 398.413491 6.922719) (xy 398.413986 6.879844)
			(xy 398.413491 6.836969) (xy 402.908757 6.836969) (xy 402.908757 6.922719) (xy 402.916669 7.008102)
			(xy 402.932425 7.092392) (xy 402.955892 7.174868) (xy 402.986868 7.254827) (xy 403.02509 7.331587)
			(xy 403.070231 7.404493) (xy 403.121907 7.472922) (xy 403.179676 7.536292) (xy 403.243046 7.594061)
			(xy 403.311475 7.645737) (xy 403.384381 7.690878) (xy 403.461141 7.7291) (xy 403.5411 7.760076) (xy 403.623576 7.783543)
			(xy 403.707866 7.799299) (xy 403.793249 7.807211) (xy 403.878999 7.807211) (xy 403.964382 7.799299)
			(xy 404.048672 7.783543) (xy 404.131148 7.760076) (xy 404.211107 7.7291) (xy 404.287867 7.690878)
			(xy 404.360773 7.645737) (xy 404.429202 7.594061) (xy 404.492572 7.536292) (xy 404.550341 7.472922)
			(xy 404.602017 7.404493) (xy 404.647158 7.331587) (xy 404.68538 7.254827) (xy 404.716356 7.174868)
			(xy 404.739823 7.092392) (xy 404.755579 7.008102) (xy 404.763491 6.922719) (xy 404.763986 6.879844)
			(xy 404.76379 6.862877) (xy 454.759301 6.862877) (xy 454.759301 6.948627) (xy 454.767213 7.03401)
			(xy 454.782969 7.1183) (xy 454.806436 7.200776) (xy 454.837412 7.280735) (xy 454.875634 7.357495)
			(xy 454.920775 7.430401) (xy 454.972451 7.49883) (xy 455.03022 7.5622) (xy 455.09359 7.619969) (xy 455.162019 7.671645)
			(xy 455.234925 7.716786) (xy 455.311685 7.755008) (xy 455.391644 7.785984) (xy 455.47412 7.809451)
			(xy 455.55841 7.825207) (xy 455.643793 7.833119) (xy 455.729543 7.833119) (xy 455.814926 7.825207)
			(xy 455.899216 7.809451) (xy 455.981692 7.785984) (xy 456.061651 7.755008) (xy 456.083854 7.743952)
			(xy 457.265532 7.743952) (xy 457.265532 8.607552) (xy 457.266001 8.634817) (xy 457.273759 8.688792)
			(xy 457.289124 8.741113) (xy 457.311782 8.790712) (xy 457.341272 8.83658) (xy 457.376993 8.877781)
			(xy 457.418217 8.913475) (xy 457.464104 8.942936) (xy 457.513718 8.965562) (xy 457.566048 8.980893)
			(xy 457.620029 8.988617) (xy 457.647294 8.98906) (xy 457.673348 8.988609) (xy 457.724973 8.981521)
			(xy 457.775154 8.967478) (xy 457.822958 8.946739) (xy 457.867497 8.919691) (xy 457.907943 8.886836)
			(xy 457.943543 8.848784) (xy 457.958952 8.82777) (xy 457.964032 8.820658) (xy 457.97851 8.810498)
			(xy 458.05852 8.788908) (xy 458.0763 8.790432) (xy 458.084428 8.794242) (xy 458.092034 8.797455)
			(xy 458.108177 8.800911) (xy 458.116432 8.8011) (xy 458.728572 8.8011) (xy 458.740654 8.800663) (xy 458.763637 8.793202)
			(xy 458.783189 8.779003) (xy 458.797393 8.759455) (xy 458.80486 8.736474) (xy 458.80528 8.724392)
			(xy 458.80528 7.627112) (xy 458.804876 7.615027) (xy 458.797409 7.59204) (xy 458.783201 7.572487)
			(xy 458.763646 7.558284) (xy 458.740657 7.550821) (xy 458.728572 7.550404) (xy 458.116432 7.550404)
			(xy 458.108177 7.550597) (xy 458.092033 7.554047) (xy 458.084428 7.557262) (xy 458.0763 7.561072)
			(xy 458.05852 7.562596) (xy 457.97851 7.541006) (xy 457.964032 7.530846) (xy 457.958952 7.523734)
			(xy 457.943549 7.502715) (xy 457.907948 7.464663) (xy 457.867501 7.431806) (xy 457.822962 7.404757)
			(xy 457.775156 7.384018) (xy 457.724975 7.369974) (xy 457.673349 7.362887) (xy 457.647294 7.362444)
			(xy 457.620036 7.362918) (xy 457.566074 7.370674) (xy 457.513764 7.386028) (xy 457.46417 7.408666)
			(xy 457.418301 7.43813) (xy 457.37709 7.473819) (xy 457.341375 7.515007) (xy 457.311883 7.560857)
			(xy 457.289212 7.610437) (xy 457.273826 7.662737) (xy 457.266035 7.716694) (xy 457.265532 7.743952)
			(xy 456.083854 7.743952) (xy 456.138411 7.716786) (xy 456.211317 7.671645) (xy 456.279746 7.619969)
			(xy 456.343116 7.5622) (xy 456.400885 7.49883) (xy 456.452561 7.430401) (xy 456.497702 7.357495)
			(xy 456.535924 7.280735) (xy 456.5669 7.200776) (xy 456.590367 7.1183) (xy 456.606123 7.03401) (xy 456.614035 6.948627)
			(xy 456.61453 6.905752) (xy 456.614035 6.862877) (xy 461.109301 6.862877) (xy 461.109301 6.948627)
			(xy 461.117213 7.03401) (xy 461.132969 7.1183) (xy 461.156436 7.200776) (xy 461.187412 7.280735)
			(xy 461.225634 7.357495) (xy 461.270775 7.430401) (xy 461.322451 7.49883) (xy 461.38022 7.5622) (xy 461.44359 7.619969)
			(xy 461.512019 7.671645) (xy 461.584925 7.716786) (xy 461.661685 7.755008) (xy 461.741644 7.785984)
			(xy 461.82412 7.809451) (xy 461.90841 7.825207) (xy 461.993793 7.833119) (xy 462.079543 7.833119)
			(xy 462.164926 7.825207) (xy 462.249216 7.809451) (xy 462.331692 7.785984) (xy 462.411651 7.755008)
			(xy 462.488411 7.716786) (xy 462.561317 7.671645) (xy 462.629746 7.619969) (xy 462.693116 7.5622)
			(xy 462.750885 7.49883) (xy 462.802561 7.430401) (xy 462.847702 7.357495) (xy 462.885924 7.280735)
			(xy 462.9169 7.200776) (xy 462.940367 7.1183) (xy 462.956123 7.03401) (xy 462.964035 6.948627) (xy 462.96453 6.905752)
			(xy 462.964035 6.862877) (xy 462.956123 6.777494) (xy 462.940367 6.693204) (xy 462.9169 6.610728)
			(xy 462.885924 6.530769) (xy 462.847702 6.454009) (xy 462.802561 6.381103) (xy 462.750885 6.312674)
			(xy 462.693116 6.249304) (xy 462.629746 6.191535) (xy 462.561317 6.139859) (xy 462.488411 6.094718)
			(xy 462.411651 6.056496) (xy 462.331692 6.02552) (xy 462.249216 6.002053) (xy 462.164926 5.986297)
			(xy 462.079543 5.978385) (xy 461.993793 5.978385) (xy 461.90841 5.986297) (xy 461.82412 6.002053)
			(xy 461.741644 6.02552) (xy 461.661685 6.056496) (xy 461.584925 6.094718) (xy 461.512019 6.139859)
			(xy 461.44359 6.191535) (xy 461.38022 6.249304) (xy 461.322451 6.312674) (xy 461.270775 6.381103)
			(xy 461.225634 6.454009) (xy 461.187412 6.530769) (xy 461.156436 6.610728) (xy 461.132969 6.693204)
			(xy 461.117213 6.777494) (xy 461.109301 6.862877) (xy 456.614035 6.862877) (xy 456.606123 6.777494)
			(xy 456.590367 6.693204) (xy 456.5669 6.610728) (xy 456.535924 6.530769) (xy 456.497702 6.454009)
			(xy 456.452561 6.381103) (xy 456.400885 6.312674) (xy 456.343116 6.249304) (xy 456.279746 6.191535)
			(xy 456.211317 6.139859) (xy 456.138411 6.094718) (xy 456.061651 6.056496) (xy 455.981692 6.02552)
			(xy 455.899216 6.002053) (xy 455.814926 5.986297) (xy 455.729543 5.978385) (xy 455.643793 5.978385)
			(xy 455.55841 5.986297) (xy 455.47412 6.002053) (xy 455.391644 6.02552) (xy 455.311685 6.056496)
			(xy 455.234925 6.094718) (xy 455.162019 6.139859) (xy 455.09359 6.191535) (xy 455.03022 6.249304)
			(xy 454.972451 6.312674) (xy 454.920775 6.381103) (xy 454.875634 6.454009) (xy 454.837412 6.530769)
			(xy 454.806436 6.610728) (xy 454.782969 6.693204) (xy 454.767213 6.777494) (xy 454.759301 6.862877)
			(xy 404.76379 6.862877) (xy 404.763491 6.836969) (xy 404.755579 6.751586) (xy 404.739823 6.667296)
			(xy 404.716356 6.58482) (xy 404.68538 6.504861) (xy 404.647158 6.428101) (xy 404.602017 6.355195)
			(xy 404.550341 6.286766) (xy 404.492572 6.223396) (xy 404.429202 6.165627) (xy 404.360773 6.113951)
			(xy 404.287867 6.06881) (xy 404.211107 6.030588) (xy 404.131148 5.999612) (xy 404.048672 5.976145)
			(xy 403.964382 5.960389) (xy 403.878999 5.952477) (xy 403.793249 5.952477) (xy 403.707866 5.960389)
			(xy 403.623576 5.976145) (xy 403.5411 5.999612) (xy 403.461141 6.030588) (xy 403.384381 6.06881)
			(xy 403.311475 6.113951) (xy 403.243046 6.165627) (xy 403.179676 6.223396) (xy 403.121907 6.286766)
			(xy 403.070231 6.355195) (xy 403.02509 6.428101) (xy 402.986868 6.504861) (xy 402.955892 6.58482)
			(xy 402.932425 6.667296) (xy 402.916669 6.751586) (xy 402.908757 6.836969) (xy 398.413491 6.836969)
			(xy 398.405579 6.751586) (xy 398.389823 6.667296) (xy 398.366356 6.58482) (xy 398.33538 6.504861)
			(xy 398.297158 6.428101) (xy 398.252017 6.355195) (xy 398.200341 6.286766) (xy 398.142572 6.223396)
			(xy 398.079202 6.165627) (xy 398.010773 6.113951) (xy 397.937867 6.06881) (xy 397.861107 6.030588)
			(xy 397.781148 5.999612) (xy 397.698672 5.976145) (xy 397.614382 5.960389) (xy 397.528999 5.952477)
			(xy 397.443249 5.952477) (xy 397.357866 5.960389) (xy 397.273576 5.976145) (xy 397.1911 5.999612)
			(xy 397.111141 6.030588) (xy 397.034381 6.06881) (xy 396.961475 6.113951) (xy 396.893046 6.165627)
			(xy 396.829676 6.223396) (xy 396.771907 6.286766) (xy 396.720231 6.355195) (xy 396.67509 6.428101)
			(xy 396.636868 6.504861) (xy 396.605892 6.58482) (xy 396.582425 6.667296) (xy 396.566669 6.751586)
			(xy 396.558757 6.836969) (xy 390.701117 6.836969) (xy 390.701035 6.829857) (xy 390.693123 6.744474)
			(xy 390.677367 6.660184) (xy 390.6539 6.577708) (xy 390.622924 6.497749) (xy 390.584702 6.420989)
			(xy 390.539561 6.348083) (xy 390.487885 6.279654) (xy 390.430116 6.216284) (xy 390.366746 6.158515)
			(xy 390.298317 6.106839) (xy 390.225411 6.061698) (xy 390.148651 6.023476) (xy 390.068692 5.9925)
			(xy 389.986216 5.969033) (xy 389.901926 5.953277) (xy 389.816543 5.945365) (xy 389.730793 5.945365)
			(xy 389.64541 5.953277) (xy 389.56112 5.969033) (xy 389.478644 5.9925) (xy 389.398685 6.023476) (xy 389.321925 6.061698)
			(xy 389.249019 6.106839) (xy 389.18059 6.158515) (xy 389.11722 6.216284) (xy 389.059451 6.279654)
			(xy 389.007775 6.348083) (xy 388.962634 6.420989) (xy 388.924412 6.497749) (xy 388.893436 6.577708)
			(xy 388.869969 6.660184) (xy 388.854213 6.744474) (xy 388.846301 6.829857) (xy 384.351035 6.829857)
			(xy 384.343123 6.744474) (xy 384.327367 6.660184) (xy 384.3039 6.577708) (xy 384.272924 6.497749)
			(xy 384.234702 6.420989) (xy 384.189561 6.348083) (xy 384.137885 6.279654) (xy 384.080116 6.216284)
			(xy 384.016746 6.158515) (xy 383.948317 6.106839) (xy 383.875411 6.061698) (xy 383.798651 6.023476)
			(xy 383.718692 5.9925) (xy 383.636216 5.969033) (xy 383.551926 5.953277) (xy 383.466543 5.945365)
			(xy 383.380793 5.945365) (xy 383.29541 5.953277) (xy 383.21112 5.969033) (xy 383.128644 5.9925) (xy 383.048685 6.023476)
			(xy 382.971925 6.061698) (xy 382.899019 6.106839) (xy 382.83059 6.158515) (xy 382.76722 6.216284)
			(xy 382.709451 6.279654) (xy 382.657775 6.348083) (xy 382.612634 6.420989) (xy 382.574412 6.497749)
			(xy 382.543436 6.577708) (xy 382.519969 6.660184) (xy 382.504213 6.744474) (xy 382.496301 6.829857)
			(xy 332.50079 6.829857) (xy 332.500491 6.803949) (xy 332.492579 6.718566) (xy 332.476823 6.634276)
			(xy 332.453356 6.5518) (xy 332.42238 6.471841) (xy 332.384158 6.395081) (xy 332.339017 6.322175)
			(xy 332.287341 6.253746) (xy 332.229572 6.190376) (xy 332.166202 6.132607) (xy 332.097773 6.080931)
			(xy 332.024867 6.03579) (xy 331.948107 5.997568) (xy 331.868148 5.966592) (xy 331.785672 5.943125)
			(xy 331.701382 5.927369) (xy 331.615999 5.919457) (xy 331.530249 5.919457) (xy 331.444866 5.927369)
			(xy 331.360576 5.943125) (xy 331.2781 5.966592) (xy 331.198141 5.997568) (xy 331.121381 6.03579)
			(xy 331.048475 6.080931) (xy 330.980046 6.132607) (xy 330.916676 6.190376) (xy 330.858907 6.253746)
			(xy 330.807231 6.322175) (xy 330.76209 6.395081) (xy 330.723868 6.471841) (xy 330.692892 6.5518)
			(xy 330.669425 6.634276) (xy 330.653669 6.718566) (xy 330.645757 6.803949) (xy 326.150491 6.803949)
			(xy 326.142579 6.718566) (xy 326.126823 6.634276) (xy 326.103356 6.5518) (xy 326.07238 6.471841)
			(xy 326.034158 6.395081) (xy 325.989017 6.322175) (xy 325.937341 6.253746) (xy 325.879572 6.190376)
			(xy 325.816202 6.132607) (xy 325.747773 6.080931) (xy 325.674867 6.03579) (xy 325.598107 5.997568)
			(xy 325.518148 5.966592) (xy 325.435672 5.943125) (xy 325.351382 5.927369) (xy 325.265999 5.919457)
			(xy 325.180249 5.919457) (xy 325.094866 5.927369) (xy 325.010576 5.943125) (xy 324.9281 5.966592)
			(xy 324.848141 5.997568) (xy 324.771381 6.03579) (xy 324.698475 6.080931) (xy 324.630046 6.132607)
			(xy 324.566676 6.190376) (xy 324.508907 6.253746) (xy 324.457231 6.322175) (xy 324.41209 6.395081)
			(xy 324.373868 6.471841) (xy 324.342892 6.5518) (xy 324.319425 6.634276) (xy 324.303669 6.718566)
			(xy 324.295757 6.803949) (xy 317.930117 6.803949) (xy 317.930035 6.796837) (xy 317.922123 6.711454)
			(xy 317.906367 6.627164) (xy 317.8829 6.544688) (xy 317.851924 6.464729) (xy 317.813702 6.387969)
			(xy 317.768561 6.315063) (xy 317.716885 6.246634) (xy 317.659116 6.183264) (xy 317.595746 6.125495)
			(xy 317.527317 6.073819) (xy 317.454411 6.028678) (xy 317.377651 5.990456) (xy 317.297692 5.95948)
			(xy 317.215216 5.936013) (xy 317.130926 5.920257) (xy 317.045543 5.912345) (xy 316.959793 5.912345)
			(xy 316.87441 5.920257) (xy 316.79012 5.936013) (xy 316.707644 5.95948) (xy 316.627685 5.990456)
			(xy 316.550925 6.028678) (xy 316.478019 6.073819) (xy 316.40959 6.125495) (xy 316.34622 6.183264)
			(xy 316.288451 6.246634) (xy 316.236775 6.315063) (xy 316.191634 6.387969) (xy 316.153412 6.464729)
			(xy 316.122436 6.544688) (xy 316.098969 6.627164) (xy 316.083213 6.711454) (xy 316.075301 6.796837)
			(xy 311.580035 6.796837) (xy 311.572123 6.711454) (xy 311.556367 6.627164) (xy 311.5329 6.544688)
			(xy 311.501924 6.464729) (xy 311.463702 6.387969) (xy 311.418561 6.315063) (xy 311.366885 6.246634)
			(xy 311.309116 6.183264) (xy 311.245746 6.125495) (xy 311.177317 6.073819) (xy 311.104411 6.028678)
			(xy 311.027651 5.990456) (xy 310.947692 5.95948) (xy 310.865216 5.936013) (xy 310.780926 5.920257)
			(xy 310.695543 5.912345) (xy 310.609793 5.912345) (xy 310.52441 5.920257) (xy 310.44012 5.936013)
			(xy 310.357644 5.95948) (xy 310.277685 5.990456) (xy 310.200925 6.028678) (xy 310.128019 6.073819)
			(xy 310.05959 6.125495) (xy 309.99622 6.183264) (xy 309.938451 6.246634) (xy 309.886775 6.315063)
			(xy 309.841634 6.387969) (xy 309.803412 6.464729) (xy 309.772436 6.544688) (xy 309.748969 6.627164)
			(xy 309.733213 6.711454) (xy 309.725301 6.796837) (xy 259.72979 6.796837) (xy 259.729491 6.770929)
			(xy 259.721579 6.685546) (xy 259.705823 6.601256) (xy 259.682356 6.51878) (xy 259.65138 6.438821)
			(xy 259.613158 6.362061) (xy 259.568017 6.289155) (xy 259.516341 6.220726) (xy 259.458572 6.157356)
			(xy 259.395202 6.099587) (xy 259.326773 6.047911) (xy 259.253867 6.00277) (xy 259.177107 5.964548)
			(xy 259.097148 5.933572) (xy 259.014672 5.910105) (xy 258.930382 5.894349) (xy 258.844999 5.886437)
			(xy 258.759249 5.886437) (xy 258.673866 5.894349) (xy 258.589576 5.910105) (xy 258.5071 5.933572)
			(xy 258.427141 5.964548) (xy 258.350381 6.00277) (xy 258.277475 6.047911) (xy 258.209046 6.099587)
			(xy 258.145676 6.157356) (xy 258.087907 6.220726) (xy 258.036231 6.289155) (xy 257.99109 6.362061)
			(xy 257.952868 6.438821) (xy 257.921892 6.51878) (xy 257.898425 6.601256) (xy 257.882669 6.685546)
			(xy 257.874757 6.770929) (xy 253.379491 6.770929) (xy 253.371579 6.685546) (xy 253.355823 6.601256)
			(xy 253.332356 6.51878) (xy 253.30138 6.438821) (xy 253.263158 6.362061) (xy 253.218017 6.289155)
			(xy 253.166341 6.220726) (xy 253.108572 6.157356) (xy 253.045202 6.099587) (xy 252.976773 6.047911)
			(xy 252.903867 6.00277) (xy 252.827107 5.964548) (xy 252.747148 5.933572) (xy 252.664672 5.910105)
			(xy 252.580382 5.894349) (xy 252.494999 5.886437) (xy 252.409249 5.886437) (xy 252.323866 5.894349)
			(xy 252.239576 5.910105) (xy 252.1571 5.933572) (xy 252.077141 5.964548) (xy 252.000381 6.00277)
			(xy 251.927475 6.047911) (xy 251.859046 6.099587) (xy 251.795676 6.157356) (xy 251.737907 6.220726)
			(xy 251.686231 6.289155) (xy 251.64109 6.362061) (xy 251.602868 6.438821) (xy 251.571892 6.51878)
			(xy 251.548425 6.601256) (xy 251.532669 6.685546) (xy 251.524757 6.770929) (xy 245.921117 6.770929)
			(xy 245.921035 6.763817) (xy 245.913123 6.678434) (xy 245.897367 6.594144) (xy 245.8739 6.511668)
			(xy 245.842924 6.431709) (xy 245.804702 6.354949) (xy 245.759561 6.282043) (xy 245.707885 6.213614)
			(xy 245.650116 6.150244) (xy 245.586746 6.092475) (xy 245.518317 6.040799) (xy 245.445411 5.995658)
			(xy 245.368651 5.957436) (xy 245.288692 5.92646) (xy 245.206216 5.902993) (xy 245.121926 5.887237)
			(xy 245.036543 5.879325) (xy 244.950793 5.879325) (xy 244.86541 5.887237) (xy 244.78112 5.902993)
			(xy 244.698644 5.92646) (xy 244.618685 5.957436) (xy 244.541925 5.995658) (xy 244.469019 6.040799)
			(xy 244.40059 6.092475) (xy 244.33722 6.150244) (xy 244.279451 6.213614) (xy 244.227775 6.282043)
			(xy 244.182634 6.354949) (xy 244.144412 6.431709) (xy 244.113436 6.511668) (xy 244.089969 6.594144)
			(xy 244.074213 6.678434) (xy 244.066301 6.763817) (xy 239.571035 6.763817) (xy 239.563123 6.678434)
			(xy 239.547367 6.594144) (xy 239.5239 6.511668) (xy 239.492924 6.431709) (xy 239.454702 6.354949)
			(xy 239.409561 6.282043) (xy 239.357885 6.213614) (xy 239.300116 6.150244) (xy 239.236746 6.092475)
			(xy 239.168317 6.040799) (xy 239.095411 5.995658) (xy 239.018651 5.957436) (xy 238.938692 5.92646)
			(xy 238.856216 5.902993) (xy 238.771926 5.887237) (xy 238.686543 5.879325) (xy 238.600793 5.879325)
			(xy 238.51541 5.887237) (xy 238.43112 5.902993) (xy 238.348644 5.92646) (xy 238.268685 5.957436)
			(xy 238.191925 5.995658) (xy 238.119019 6.040799) (xy 238.05059 6.092475) (xy 237.98722 6.150244)
			(xy 237.929451 6.213614) (xy 237.877775 6.282043) (xy 237.832634 6.354949) (xy 237.794412 6.431709)
			(xy 237.763436 6.511668) (xy 237.739969 6.594144) (xy 237.724213 6.678434) (xy 237.716301 6.763817)
			(xy 187.719832 6.763817) (xy 187.712579 6.685546) (xy 187.696823 6.601256) (xy 187.673356 6.51878)
			(xy 187.64238 6.438821) (xy 187.604158 6.362061) (xy 187.559017 6.289155) (xy 187.507341 6.220726)
			(xy 187.449572 6.157356) (xy 187.386202 6.099587) (xy 187.317773 6.047911) (xy 187.244867 6.00277)
			(xy 187.168107 5.964548) (xy 187.088148 5.933572) (xy 187.005672 5.910105) (xy 186.921382 5.894349)
			(xy 186.835999 5.886437) (xy 186.750249 5.886437) (xy 186.664866 5.894349) (xy 186.580576 5.910105)
			(xy 186.4981 5.933572) (xy 186.418141 5.964548) (xy 186.341381 6.00277) (xy 186.268475 6.047911)
			(xy 186.200046 6.099587) (xy 186.136676 6.157356) (xy 186.078907 6.220726) (xy 186.027231 6.289155)
			(xy 185.98209 6.362061) (xy 185.943868 6.438821) (xy 185.912892 6.51878) (xy 185.889425 6.601256)
			(xy 185.873669 6.685546) (xy 185.865757 6.770929) (xy 181.370491 6.770929) (xy 181.362579 6.685546)
			(xy 181.346823 6.601256) (xy 181.323356 6.51878) (xy 181.29238 6.438821) (xy 181.254158 6.362061)
			(xy 181.209017 6.289155) (xy 181.157341 6.220726) (xy 181.099572 6.157356) (xy 181.036202 6.099587)
			(xy 180.967773 6.047911) (xy 180.894867 6.00277) (xy 180.818107 5.964548) (xy 180.738148 5.933572)
			(xy 180.655672 5.910105) (xy 180.571382 5.894349) (xy 180.485999 5.886437) (xy 180.400249 5.886437)
			(xy 180.314866 5.894349) (xy 180.230576 5.910105) (xy 180.1481 5.933572) (xy 180.068141 5.964548)
			(xy 179.991381 6.00277) (xy 179.918475 6.047911) (xy 179.850046 6.099587) (xy 179.786676 6.157356)
			(xy 179.728907 6.220726) (xy 179.677231 6.289155) (xy 179.63209 6.362061) (xy 179.593868 6.438821)
			(xy 179.562892 6.51878) (xy 179.539425 6.601256) (xy 179.523669 6.685546) (xy 179.515757 6.770929)
			(xy 158.039844 6.770929) (xy 158.030561 6.759289) (xy 157.936801 6.654373) (xy 157.837306 6.554879)
			(xy 157.732388 6.46112) (xy 157.622379 6.373391) (xy 157.507624 6.291969) (xy 157.388483 6.21711)
			(xy 157.265333 6.149048) (xy 157.138561 6.087998) (xy 157.008565 6.034153) (xy 156.875754 5.987681)
			(xy 156.740546 5.948729) (xy 156.603367 5.91742) (xy 156.464649 5.893851) (xy 156.324827 5.878098)
			(xy 156.184341 5.870209) (xy 156.113988 5.869686) (xy 17.493996 5.869686) (xy 17.423642 5.870179)
			(xy 17.283156 5.878069) (xy 17.143333 5.893824) (xy 17.004613 5.917393) (xy 16.867433 5.948703) (xy 16.732225 5.987656)
			(xy 16.599413 6.034129) (xy 16.469416 6.087976) (xy 16.342643 6.149026) (xy 16.219492 6.217089) (xy 16.100351 6.29195)
			(xy 15.985596 6.373373) (xy 15.875586 6.461103) (xy 15.770668 6.554863) (xy 15.671172 6.654358) (xy 15.577412 6.759275)
			(xy 15.489682 6.869284) (xy 15.408258 6.98404) (xy 15.333396 7.10318) (xy 15.265333 7.22633) (xy 15.204281 7.353103)
			(xy 15.150434 7.4831) (xy 15.103961 7.615912) (xy 15.065007 7.75112) (xy 15.033696 7.8883) (xy 15.010125 8.027019)
			(xy 14.99437 8.166842) (xy 14.98648 8.307328) (xy 14.986 8.377682) (xy 14.986 24.157686) (xy 14.985478 24.213493)
			(xy 14.977137 24.324795) (xy 14.960501 24.435162) (xy 14.935664 24.543977) (xy 14.902765 24.650632)
			(xy 14.861988 24.754531) (xy 14.81356 24.855091) (xy 14.757753 24.951752) (xy 14.694879 25.043971)
			(xy 14.625289 25.131234) (xy 14.549372 25.213053) (xy 14.467553 25.28897) (xy 14.38029 25.35856)
			(xy 14.28807 25.421434) (xy 14.19141 25.477241) (xy 14.090849 25.525669) (xy 13.986951 25.566446)
			(xy 13.880295 25.599345) (xy 13.77148 25.624182) (xy 13.661113 25.640817) (xy 13.549811 25.649158)
			(xy 13.494004 25.649682) (xy 1.999996 25.649682) (xy 1.944189 25.64916) (xy 1.832887 25.640819) (xy 1.72252 25.624184)
			(xy 1.613704 25.599347) (xy 1.507049 25.566448) (xy 1.40315 25.525671) (xy 1.30259 25.477243) (xy 1.205929 25.421436)
			(xy 1.113709 25.358562) (xy 1.026446 25.288971) (xy 0.944627 25.213055) (xy 0.86871 25.131236) (xy 0.79912 25.043972)
			(xy 0.736245 24.951753) (xy 0.680438 24.855092) (xy 0.63201 24.754532) (xy 0.591233 24.650633) (xy 0.558334 24.543978)
			(xy 0.533497 24.435162) (xy 0.516861 24.324795) (xy 0.50852 24.213493) (xy 0.508 24.157686) (xy 0.508 21.093122)
			(xy 2.904225 21.093122) (xy 2.904225 21.222262) (xy 2.912175 21.351157) (xy 2.928045 21.479317) (xy 2.951774 21.606258)
			(xy 2.983273 21.731497) (xy 3.022422 21.85456) (xy 3.069073 21.974979) (xy 3.123048 22.092298) (xy 3.184143 22.206072)
			(xy 3.252126 22.315869) (xy 3.32674 22.421272) (xy 3.407701 22.521882) (xy 3.494701 22.617317) (xy 3.587412 22.707216)
			(xy 3.685482 22.791237) (xy 3.788537 22.869061) (xy 3.896188 22.940393) (xy 4.008027 23.004963) (xy 4.123628 23.062525)
			(xy 4.242553 23.112862) (xy 4.364352 23.155782) (xy 4.488562 23.191123) (xy 4.614711 23.21875) (xy 4.742323 23.238559)
			(xy 4.870912 23.250475) (xy 4.99999 23.254452) (xy 5.129068 23.250475) (xy 5.257657 23.238559) (xy 5.385269 23.21875)
			(xy 5.511418 23.191123) (xy 5.635628 23.155782) (xy 5.757427 23.112862) (xy 5.876352 23.062525) (xy 5.991953 23.004963)
			(xy 6.103792 22.940393) (xy 6.211443 22.869061) (xy 6.314498 22.791237) (xy 6.412568 22.707216) (xy 6.505279 22.617317)
			(xy 6.592279 22.521882) (xy 6.67324 22.421272) (xy 6.747854 22.315869) (xy 6.815837 22.206072) (xy 6.876932 22.092298)
			(xy 6.930907 21.974979) (xy 6.977558 21.85456) (xy 7.016707 21.731497) (xy 7.048206 21.606258) (xy 7.071935 21.479317)
			(xy 7.087805 21.351157) (xy 7.095755 21.222262) (xy 7.096252 21.157692) (xy 7.095755 21.093122) (xy 7.087805 20.964227)
			(xy 7.071935 20.836067) (xy 7.048206 20.709126) (xy 7.016707 20.583887) (xy 6.977558 20.460824) (xy 6.930907 20.340405)
			(xy 6.876932 20.223086) (xy 6.815837 20.109312) (xy 6.747854 19.999515) (xy 6.67324 19.894112) (xy 6.592279 19.793502)
			(xy 6.505279 19.698067) (xy 6.412568 19.608168) (xy 6.314498 19.524147) (xy 6.211443 19.446323) (xy 6.103792 19.374991)
			(xy 5.991953 19.310421) (xy 5.876352 19.252859) (xy 5.757427 19.202522) (xy 5.635628 19.159602) (xy 5.511418 19.124261)
			(xy 5.385269 19.096634) (xy 5.257657 19.076825) (xy 5.129068 19.064909) (xy 4.99999 19.060933) (xy 4.870912 19.064909)
			(xy 4.742323 19.076825) (xy 4.614711 19.096634) (xy 4.488562 19.124261) (xy 4.364352 19.159602) (xy 4.242553 19.202522)
			(xy 4.123628 19.252859) (xy 4.008027 19.310421) (xy 3.896188 19.374991) (xy 3.788537 19.446323) (xy 3.685482 19.524147)
			(xy 3.587412 19.608168) (xy 3.494701 19.698067) (xy 3.407701 19.793502) (xy 3.32674 19.894112) (xy 3.252126 19.999515)
			(xy 3.184143 20.109312) (xy 3.123048 20.223086) (xy 3.069073 20.340405) (xy 3.022422 20.460824) (xy 2.983273 20.583887)
			(xy 2.951774 20.709126) (xy 2.928045 20.836067) (xy 2.912175 20.964227) (xy 2.904225 21.093122) (xy 0.508 21.093122)
			(xy 0.508 3.999992) (xy 0.508522 3.944185) (xy 0.516863 3.832883) (xy 0.533498 3.722516) (xy 0.558335 3.6137)
			(xy 0.591234 3.507045) (xy 0.632011 3.403146) (xy 0.680438 3.302586) (xy 0.736246 3.205925) (xy 0.79912 3.113705)
			(xy 0.86871 3.026442) (xy 0.944627 2.944623) (xy 1.026446 2.868706) (xy 1.113709 2.799116) (xy 1.205929 2.736242)
			(xy 1.30259 2.680434) (xy 1.40315 2.632007) (xy 1.507049 2.59123) (xy 1.613704 2.558331) (xy 1.72252 2.533494)
			(xy 1.832887 2.516859) (xy 1.944189 2.508518) (xy 1.999996 2.507996) (xy 7.964932 2.507996) (xy 8.035286 2.507503)
			(xy 8.175772 2.499613) (xy 8.315594 2.483859) (xy 8.454314 2.460289) (xy 8.591493 2.428979) (xy 8.726701 2.390026)
			(xy 8.859513 2.343553) (xy 8.989509 2.289707) (xy 9.116282 2.228656) (xy 9.239433 2.160593) (xy 9.358573 2.085732)
			(xy 9.473329 2.004309) (xy 9.583338 1.916579) (xy 9.688255 1.822819) (xy 9.78775 1.723324) (xy 9.88151 1.618406)
			(xy 9.96924 1.508397) (xy 10.050663 1.393641) (xy 10.125524 1.274501) (xy 10.193587 1.151351) (xy 10.254637 1.024578)
			(xy 10.308484 0.894581) (xy 10.354957 0.76177) (xy 10.393909 0.626561) (xy 10.42522 0.489382) (xy 10.448789 0.350662)
			(xy 10.464543 0.21084) (xy 10.472433 0.070354) (xy 10.472928 0) (xy 10.472928 -8.850122) (xy 10.47345 -8.905929)
			(xy 10.481791 -9.017231) (xy 10.498426 -9.127599) (xy 10.523263 -9.236414) (xy 10.556162 -9.34307)
			(xy 10.596939 -9.446968) (xy 10.645366 -9.547529) (xy 10.701173 -9.64419) (xy 10.764048 -9.73641)
			(xy 10.833638 -9.823673) (xy 10.909555 -9.905492) (xy 10.991374 -9.981409) (xy 11.078637 -10.051)
			(xy 11.170857 -10.113875) (xy 11.267517 -10.169682) (xy 11.368078 -10.21811) (xy 11.471977 -10.258887)
			(xy 11.578632 -10.291786) (xy 11.687448 -10.316623) (xy 11.797815 -10.333259) (xy 11.909117 -10.3416)
			(xy 11.964924 -10.342118)
		)
		(stroke
			(width 0)
			(type solid)
		)
		(fill yes)
		(layer "In1.Cu")
		(net "COUPON_GND2")
	)
	(gr_poly
		(pts
			(xy 7.987284 -418.080952) (xy 200.481184 -418.080952) (xy 200.53776 -418.08043) (xy 200.650587 -418.071859)
			(xy 200.762439 -418.054758) (xy 200.872672 -418.029225) (xy 200.980652 -417.995406) (xy 201.085757 -417.953498)
			(xy 201.187381 -417.90374) (xy 201.28494 -417.84642) (xy 201.377872 -417.781868) (xy 201.465642 -417.710455)
			(xy 201.547744 -417.632592) (xy 201.586084 -417.590986) (xy 201.633303 -417.539598) (xy 201.732638 -417.441554)
			(xy 201.837271 -417.349184) (xy 201.946878 -417.262774) (xy 202.06112 -417.182592) (xy 202.179643 -417.108886)
			(xy 202.302081 -417.041884) (xy 202.428054 -416.981794) (xy 202.557174 -416.9288) (xy 202.689041 -416.883067)
			(xy 202.823246 -416.844737) (xy 202.959375 -416.813928) (xy 203.097007 -416.790736) (xy 203.235715 -416.775231)
			(xy 203.37507 -416.767463) (xy 203.444856 -416.76701) (xy 271.794986 -416.76701) (xy 271.864771 -416.767495)
			(xy 272.004124 -416.77527) (xy 272.142829 -416.790779) (xy 272.280457 -416.813975) (xy 272.416584 -416.844786)
			(xy 272.550787 -416.883117) (xy 272.682651 -416.92885) (xy 272.811769 -416.981841) (xy 272.937742 -417.041929)
			(xy 273.06018 -417.108927) (xy 273.178704 -417.182628) (xy 273.292947 -417.262803) (xy 273.402557 -417.349206)
			(xy 273.436768 -417.379404) (xy 313.073796 -417.379404) (xy 313.073796 -394.27912) (xy 326.479662 -394.27912)
			(xy 326.525636 -394.325094) (xy 326.525636 -397.823826) (xy 330.929171 -397.823826) (xy 330.929175 -397.756517)
			(xy 330.937223 -397.689692) (xy 330.953201 -397.624307) (xy 330.976879 -397.561301) (xy 331.007918 -397.501576)
			(xy 331.045873 -397.44599) (xy 331.067664 -397.420338) (xy 331.073477 -397.413205) (xy 331.07998 -397.396005)
			(xy 331.080364 -397.38681) (xy 331.080364 -396.893542) (xy 331.079919 -396.884359) (xy 331.073428 -396.867175)
			(xy 331.067664 -396.860014) (xy 331.045866 -396.83437) (xy 331.007916 -396.778783) (xy 330.976881 -396.719059)
			(xy 330.953208 -396.656053) (xy 330.937235 -396.59067) (xy 330.929191 -396.523846) (xy 330.929192 -396.456539)
			(xy 330.937238 -396.389716) (xy 330.953213 -396.324333) (xy 330.976888 -396.261328) (xy 331.007923 -396.201604)
			(xy 331.045875 -396.146018) (xy 331.067664 -396.120366) (xy 331.073465 -396.113225) (xy 331.079975 -396.096031)
			(xy 331.080364 -396.086838) (xy 331.080364 -395.92885) (xy 331.080805 -395.918678) (xy 331.088579 -395.89988)
			(xy 331.10296 -395.885492) (xy 331.121755 -395.87771) (xy 331.131926 -395.877288) (xy 331.848206 -395.877288)
			(xy 331.858384 -395.87766) (xy 331.877189 -395.885456) (xy 331.891575 -395.899859) (xy 331.899351 -395.918671)
			(xy 331.899768 -395.92885) (xy 331.899768 -396.086838) (xy 331.900167 -396.096026) (xy 331.906689 -396.11321)
			(xy 331.912468 -396.120366) (xy 331.934246 -396.146026) (xy 331.972195 -396.201612) (xy 332.003228 -396.261334)
			(xy 332.026901 -396.324338) (xy 332.042874 -396.389719) (xy 332.050919 -396.45654) (xy 332.05092 -396.523845)
			(xy 332.042877 -396.590666) (xy 332.026905 -396.656048) (xy 332.003234 -396.719052) (xy 331.972202 -396.778775)
			(xy 331.934255 -396.834362) (xy 331.912468 -396.860014) (xy 331.906679 -396.867164) (xy 331.90016 -396.884351)
			(xy 331.899768 -396.893542) (xy 331.899768 -397.38681) (xy 331.90018 -397.395997) (xy 331.906693 -397.413181)
			(xy 331.912468 -397.420338) (xy 331.934218 -397.446021) (xy 331.972167 -397.501603) (xy 332.00059 -397.556296)
			(xy 333.128836 -397.556296) (xy 333.136911 -397.489358) (xy 333.152946 -397.423869) (xy 333.17671 -397.360773)
			(xy 333.20786 -397.300977) (xy 333.245948 -397.245343) (xy 333.267812 -397.219678) (xy 333.273602 -397.212528)
			(xy 333.28012 -397.195341) (xy 333.280512 -397.18615) (xy 333.280512 -397.028924) (xy 333.280936 -397.018802)
			(xy 333.288678 -397.000096) (xy 333.302993 -396.985781) (xy 333.321698 -396.978037) (xy 333.33182 -396.977616)
			(xy 334.0481 -396.977616) (xy 334.058224 -396.978016) (xy 334.076931 -396.985768) (xy 334.091246 -397.000089)
			(xy 334.098988 -397.018799) (xy 334.099408 -397.028924) (xy 334.099408 -397.18615) (xy 334.09984 -397.195335)
			(xy 334.106338 -397.21252) (xy 334.112108 -397.219678) (xy 334.133982 -397.245335) (xy 334.172069 -397.300971)
			(xy 334.203219 -397.360769) (xy 334.226982 -397.423866) (xy 334.243017 -397.489356) (xy 334.251092 -397.556295)
			(xy 334.251091 -397.62372) (xy 334.243014 -397.690658) (xy 334.226978 -397.756148) (xy 334.203213 -397.819245)
			(xy 334.200796 -397.823884) (xy 335.328964 -397.823884) (xy 335.328968 -397.756459) (xy 335.337047 -397.689518)
			(xy 335.353085 -397.624028) (xy 335.376852 -397.560929) (xy 335.408005 -397.501132) (xy 335.446095 -397.445496)
			(xy 335.46796 -397.41983) (xy 335.473776 -397.412699) (xy 335.480277 -397.395497) (xy 335.48066 -397.386302)
			(xy 335.48066 -396.89405) (xy 335.480213 -396.884867) (xy 335.473723 -396.867683) (xy 335.46796 -396.860522)
			(xy 335.446088 -396.834864) (xy 335.408002 -396.779228) (xy 335.376854 -396.71943) (xy 335.353092 -396.656332)
			(xy 335.337058 -396.590843) (xy 335.328984 -396.523904) (xy 335.328985 -396.456481) (xy 335.337061 -396.389542)
			(xy 335.353096 -396.324053) (xy 335.37686 -396.260956) (xy 335.40801 -396.201159) (xy 335.446097 -396.145524)
			(xy 335.46796 -396.119858) (xy 335.473764 -396.112719) (xy 335.480273 -396.095523) (xy 335.48066 -396.08633)
			(xy 335.48066 -395.92885) (xy 335.481168 -395.918724) (xy 335.488883 -395.9) (xy 335.503164 -395.885642)
			(xy 335.521845 -395.877824) (xy 335.531968 -395.877288) (xy 336.248248 -395.877288) (xy 336.258404 -395.877682)
			(xy 336.277155 -395.885491) (xy 336.291476 -395.899896) (xy 336.299176 -395.918692) (xy 336.299556 -395.92885)
			(xy 336.299556 -396.08633) (xy 336.299962 -396.095517) (xy 336.30648 -396.112701) (xy 336.312256 -396.119858)
			(xy 336.334112 -396.145531) (xy 336.372204 -396.201163) (xy 336.403357 -396.260958) (xy 336.427124 -396.324054)
			(xy 336.443161 -396.389542) (xy 336.451239 -396.456481) (xy 336.45124 -396.523904) (xy 336.443164 -396.590843)
			(xy 336.427128 -396.656332) (xy 336.403363 -396.719428) (xy 336.372211 -396.779224) (xy 336.334121 -396.834858)
			(xy 336.312256 -396.860522) (xy 336.306462 -396.867669) (xy 336.299947 -396.884858) (xy 336.299556 -396.89405)
			(xy 336.299556 -397.386302) (xy 336.299975 -397.395488) (xy 336.306484 -397.412672) (xy 336.312256 -397.41983)
			(xy 336.334084 -397.445525) (xy 336.372177 -397.501154) (xy 336.40094 -397.556356) (xy 337.529156 -397.556356)
			(xy 337.537198 -397.489535) (xy 337.553169 -397.424153) (xy 337.576839 -397.361149) (xy 337.607869 -397.301426)
			(xy 337.645814 -397.245839) (xy 337.6676 -397.220186) (xy 337.673385 -397.213033) (xy 337.679907 -397.195848)
			(xy 337.6803 -397.186658) (xy 337.6803 -397.028924) (xy 337.680741 -397.018771) (xy 337.688529 -397.000019)
			(xy 337.70292 -396.985695) (xy 337.721708 -396.977995) (xy 337.731862 -396.977616) (xy 338.448142 -396.977616)
			(xy 338.458268 -396.978091) (xy 338.476986 -396.985829) (xy 338.49134 -397.000118) (xy 338.499162 -397.0188)
			(xy 338.499704 -397.028924) (xy 338.499704 -397.186658) (xy 338.500133 -397.195843) (xy 338.506634 -397.213028)
			(xy 338.512404 -397.220186) (xy 338.5342 -397.245831) (xy 338.572146 -397.301419) (xy 338.603176 -397.361144)
			(xy 338.626847 -397.42415) (xy 338.642818 -397.489532) (xy 338.65086 -397.556355) (xy 338.650859 -397.62366)
			(xy 338.642815 -397.690483) (xy 338.626842 -397.755865) (xy 338.60317 -397.81887) (xy 338.600595 -397.823826)
			(xy 339.729259 -397.823826) (xy 339.729263 -397.756517) (xy 339.737311 -397.689692) (xy 339.753288 -397.624308)
			(xy 339.776965 -397.561301) (xy 339.808004 -397.501577) (xy 339.845958 -397.44599) (xy 339.867748 -397.420338)
			(xy 339.873559 -397.413204) (xy 339.880064 -397.396005) (xy 339.880448 -397.38681) (xy 339.880448 -396.893542)
			(xy 339.880007 -396.884358) (xy 339.873513 -396.867174) (xy 339.867748 -396.860014) (xy 339.84595 -396.83437)
			(xy 339.808001 -396.778783) (xy 339.776968 -396.719058) (xy 339.753295 -396.656052) (xy 339.737322 -396.590669)
			(xy 339.729279 -396.523845) (xy 339.72928 -396.456539) (xy 339.737325 -396.389716) (xy 339.753299 -396.324333)
			(xy 339.776974 -396.261328) (xy 339.808009 -396.201604) (xy 339.845959 -396.146018) (xy 339.867748 -396.120366)
			(xy 339.873547 -396.113223) (xy 339.880059 -396.096031) (xy 339.880448 -396.086838) (xy 339.880448 -395.92885)
			(xy 339.880905 -395.91868) (xy 339.888675 -395.899885) (xy 339.903051 -395.885498) (xy 339.921841 -395.877713)
			(xy 339.93201 -395.877288) (xy 340.64829 -395.877288) (xy 340.658467 -395.877673) (xy 340.677271 -395.885464)
			(xy 340.691658 -395.899862) (xy 340.699435 -395.918672) (xy 340.699852 -395.92885) (xy 340.699852 -396.086838)
			(xy 340.700255 -396.096026) (xy 340.706775 -396.113209) (xy 340.712552 -396.120366) (xy 340.73433 -396.146026)
			(xy 340.77228 -396.201611) (xy 340.803314 -396.261334) (xy 340.826988 -396.324337) (xy 340.842962 -396.389718)
			(xy 340.851007 -396.45654) (xy 340.851007 -396.523845) (xy 340.842964 -396.590667) (xy 340.826992 -396.656048)
			(xy 340.80332 -396.719053) (xy 340.772287 -396.778776) (xy 340.734339 -396.834362) (xy 340.712552 -396.860014)
			(xy 340.706761 -396.867163) (xy 340.700244 -396.884351) (xy 340.699852 -396.893542) (xy 340.699852 -397.38681)
			(xy 340.700268 -397.395996) (xy 340.706779 -397.41318) (xy 340.712552 -397.420338) (xy 340.734302 -397.446021)
			(xy 340.772253 -397.501603) (xy 340.800676 -397.556296) (xy 341.928924 -397.556296) (xy 341.936999 -397.489359)
			(xy 341.953033 -397.42387) (xy 341.976796 -397.360774) (xy 342.007946 -397.300978) (xy 342.046033 -397.245343)
			(xy 342.067896 -397.219678) (xy 342.073684 -397.212527) (xy 342.080204 -397.195341) (xy 342.080596 -397.18615)
			(xy 342.080596 -397.028924) (xy 342.081035 -397.018804) (xy 342.088775 -397.000101) (xy 342.103084 -396.985786)
			(xy 342.121784 -396.978039) (xy 342.131904 -396.977616) (xy 342.848184 -396.977616) (xy 342.858307 -396.978029)
			(xy 342.877014 -396.985775) (xy 342.891329 -397.000093) (xy 342.899072 -397.0188) (xy 342.899492 -397.028924)
			(xy 342.899492 -397.18615) (xy 342.899928 -397.195334) (xy 342.906424 -397.212519) (xy 342.912192 -397.219678)
			(xy 342.934066 -397.245335) (xy 342.972155 -397.300971) (xy 343.003306 -397.360768) (xy 343.02707 -397.423866)
			(xy 343.043105 -397.489356) (xy 343.05118 -397.556295) (xy 343.051179 -397.62372) (xy 343.043102 -397.690659)
			(xy 343.027065 -397.756149) (xy 343.0033 -397.819246) (xy 343.000914 -397.823825) (xy 344.12905 -397.823825)
			(xy 344.129054 -397.756517) (xy 344.137101 -397.689692) (xy 344.153078 -397.624308) (xy 344.176755 -397.561302)
			(xy 344.207793 -397.501577) (xy 344.245746 -397.44599) (xy 344.267536 -397.420338) (xy 344.273346 -397.413202)
			(xy 344.279852 -397.396004) (xy 344.280236 -397.38681) (xy 344.280236 -396.893542) (xy 344.279797 -396.884358)
			(xy 344.273303 -396.867174) (xy 344.267536 -396.860014) (xy 344.245738 -396.83437) (xy 344.20779 -396.778782)
			(xy 344.176757 -396.719058) (xy 344.153085 -396.656052) (xy 344.137113 -396.590669) (xy 344.12907 -396.523845)
			(xy 344.129071 -396.45654) (xy 344.137116 -396.389716) (xy 344.15309 -396.324334) (xy 344.176764 -396.261329)
			(xy 344.207798 -396.201605) (xy 344.245748 -396.146018) (xy 344.267536 -396.120366) (xy 344.273334 -396.113222)
			(xy 344.279847 -396.09603) (xy 344.280236 -396.086838) (xy 344.280236 -395.92885) (xy 344.280705 -395.918682)
			(xy 344.288473 -395.899889) (xy 344.302845 -395.885502) (xy 344.32163 -395.877715) (xy 344.331798 -395.877288)
			(xy 345.048078 -395.877288) (xy 345.058254 -395.877683) (xy 345.077058 -395.88547) (xy 345.091445 -395.899866)
			(xy 345.099222 -395.918673) (xy 345.09964 -395.92885) (xy 345.09964 -396.086838) (xy 345.100045 -396.096025)
			(xy 345.106564 -396.113209) (xy 345.11234 -396.120366) (xy 345.134118 -396.146026) (xy 345.172069 -396.201611)
			(xy 345.203104 -396.261333) (xy 345.226778 -396.324337) (xy 345.242752 -396.389718) (xy 345.250798 -396.45654)
			(xy 345.250798 -396.523845) (xy 345.242755 -396.590667) (xy 345.226782 -396.656049) (xy 345.20311 -396.719053)
			(xy 345.172077 -396.778776) (xy 345.134128 -396.834362) (xy 345.11234 -396.860014) (xy 345.106548 -396.867162)
			(xy 345.100032 -396.884351) (xy 345.09964 -396.893542) (xy 345.09964 -397.38681) (xy 345.100059 -397.395996)
			(xy 345.106568 -397.41318) (xy 345.11234 -397.420338) (xy 345.134091 -397.446021) (xy 345.172042 -397.501602)
			(xy 345.200497 -397.556355) (xy 346.32922 -397.556355) (xy 346.337264 -397.489532) (xy 346.353237 -397.42415)
			(xy 346.37691 -397.361146) (xy 346.407945 -397.301423) (xy 346.445896 -397.245838) (xy 346.467684 -397.220186)
			(xy 346.473467 -397.213031) (xy 346.47999 -397.195848) (xy 346.480384 -397.186658) (xy 346.480384 -397.028924)
			(xy 346.480841 -397.018773) (xy 346.488625 -397.000025) (xy 346.503011 -396.985701) (xy 346.521794 -396.977997)
			(xy 346.531946 -396.977616) (xy 347.248226 -396.977616) (xy 347.258351 -396.978104) (xy 347.277069 -396.985836)
			(xy 347.291423 -397.000121) (xy 347.299246 -397.018801) (xy 347.299788 -397.028924) (xy 347.299788 -397.186658)
			(xy 347.300221 -397.195843) (xy 347.306719 -397.213027) (xy 347.312488 -397.220186) (xy 347.334285 -397.24583)
			(xy 347.372232 -397.301419) (xy 347.403263 -397.361143) (xy 347.426934 -397.424149) (xy 347.442905 -397.489532)
			(xy 347.450948 -397.556355) (xy 347.450947 -397.62366) (xy 347.442903 -397.690483) (xy 347.426929 -397.755865)
			(xy 347.403257 -397.81887) (xy 347.400682 -397.823826) (xy 374.92908 -397.823826) (xy 374.929084 -397.756517)
			(xy 374.937132 -397.689691) (xy 374.95311 -397.624306) (xy 374.976789 -397.5613) (xy 375.007829 -397.501576)
			(xy 375.045785 -397.445989) (xy 375.067576 -397.420338) (xy 375.073379 -397.413197) (xy 375.07989 -397.396003)
			(xy 375.080276 -397.38681) (xy 375.080276 -396.893542) (xy 375.079851 -396.884356) (xy 375.073348 -396.867171)
			(xy 375.067576 -396.860014) (xy 375.045777 -396.83437) (xy 375.007826 -396.778784) (xy 374.976792 -396.719059)
			(xy 374.953118 -396.656053) (xy 374.937144 -396.59067) (xy 374.9291 -396.523846) (xy 374.929101 -396.456539)
			(xy 374.937147 -396.389715) (xy 374.953122 -396.324332) (xy 374.976798 -396.261327) (xy 375.007834 -396.201604)
			(xy 375.045787 -396.146018) (xy 375.067576 -396.120366) (xy 375.073367 -396.113216) (xy 375.079886 -396.096029)
			(xy 375.080276 -396.086838) (xy 375.080276 -395.92885) (xy 375.080706 -395.918677) (xy 375.088481 -395.899876)
			(xy 375.102866 -395.885488) (xy 375.121665 -395.877708) (xy 375.131838 -395.877288) (xy 375.848118 -395.877288)
			(xy 375.858297 -395.87765) (xy 375.877102 -395.885451) (xy 375.891487 -395.899856) (xy 375.899263 -395.91867)
			(xy 375.89968 -395.92885) (xy 375.89968 -396.086838) (xy 375.900076 -396.096027) (xy 375.9066 -396.113211)
			(xy 375.91238 -396.120366) (xy 375.934157 -396.146026) (xy 375.972105 -396.201612) (xy 376.003138 -396.261335)
			(xy 376.02681 -396.324338) (xy 376.042784 -396.389719) (xy 376.050828 -396.456541) (xy 376.050829 -396.523844)
			(xy 376.042786 -396.590666) (xy 376.026815 -396.656047) (xy 376.003144 -396.719051) (xy 375.972113 -396.778775)
			(xy 375.934167 -396.834362) (xy 375.91238 -396.860014) (xy 375.906593 -396.867166) (xy 375.900073 -396.884351)
			(xy 375.89968 -396.893542) (xy 375.89968 -397.38681) (xy 375.90009 -397.395997) (xy 375.906604 -397.413181)
			(xy 375.91238 -397.420338) (xy 375.93413 -397.446021) (xy 375.972078 -397.501604) (xy 376.0005 -397.556296)
			(xy 377.128745 -397.556296) (xy 377.136821 -397.489358) (xy 377.152856 -397.423869) (xy 377.17662 -397.360772)
			(xy 377.207771 -397.300977) (xy 377.24586 -397.245343) (xy 377.267724 -397.219678) (xy 377.273515 -397.212529)
			(xy 377.280032 -397.195341) (xy 377.280424 -397.18615) (xy 377.280424 -397.028924) (xy 377.280836 -397.0188)
			(xy 377.288581 -397.000092) (xy 377.302899 -396.985776) (xy 377.321608 -396.978034) (xy 377.331732 -396.977616)
			(xy 378.048012 -396.977616) (xy 378.058137 -396.978006) (xy 378.076844 -396.985761) (xy 378.091159 -397.000086)
			(xy 378.098901 -397.018798) (xy 378.09932 -397.028924) (xy 378.09932 -397.18615) (xy 378.09975 -397.195335)
			(xy 378.10625 -397.21252) (xy 378.11202 -397.219678) (xy 378.133893 -397.245335) (xy 378.17198 -397.300972)
			(xy 378.203129 -397.360769) (xy 378.226892 -397.423867) (xy 378.242926 -397.489357) (xy 378.251001 -397.556295)
			(xy 378.251 -397.62372) (xy 378.242924 -397.690658) (xy 378.226888 -397.756147) (xy 378.203123 -397.819245)
			(xy 378.200706 -397.823885) (xy 379.328873 -397.823885) (xy 379.328877 -397.756458) (xy 379.336956 -397.689518)
			(xy 379.352995 -397.624027) (xy 379.376762 -397.560929) (xy 379.407915 -397.501131) (xy 379.446007 -397.445496)
			(xy 379.467872 -397.41983) (xy 379.47369 -397.4127) (xy 379.48019 -397.395498) (xy 379.480572 -397.386302)
			(xy 379.480572 -396.89405) (xy 379.480144 -396.884865) (xy 379.473643 -396.86768) (xy 379.467872 -396.860522)
			(xy 379.445999 -396.834864) (xy 379.407913 -396.779228) (xy 379.376764 -396.719431) (xy 379.353002 -396.656333)
			(xy 379.336968 -396.590843) (xy 379.328893 -396.523904) (xy 379.328894 -396.456481) (xy 379.33697 -396.389542)
			(xy 379.353006 -396.324053) (xy 379.37677 -396.260956) (xy 379.40792 -396.201159) (xy 379.446008 -396.145524)
			(xy 379.467872 -396.119858) (xy 379.473678 -396.11272) (xy 379.480185 -396.095524) (xy 379.480572 -396.08633)
			(xy 379.480572 -395.92885) (xy 379.481069 -395.918723) (xy 379.488786 -395.899996) (xy 379.50307 -395.885637)
			(xy 379.521755 -395.877822) (xy 379.53188 -395.877288) (xy 380.24816 -395.877288) (xy 380.258278 -395.877749)
			(xy 380.276979 -395.885481) (xy 380.291294 -395.899784) (xy 380.299043 -395.918478) (xy 380.299468 -395.928596)
			(xy 380.299468 -396.08633) (xy 380.299871 -396.095518) (xy 380.30639 -396.112702) (xy 380.312168 -396.119858)
			(xy 380.334023 -396.145531) (xy 380.372114 -396.201163) (xy 380.403267 -396.260958) (xy 380.427033 -396.324054)
			(xy 380.443071 -396.389543) (xy 380.451148 -396.456481) (xy 380.451149 -396.523904) (xy 380.443073 -396.590842)
			(xy 380.427038 -396.656331) (xy 380.403273 -396.719428) (xy 380.372122 -396.779224) (xy 380.334032 -396.834857)
			(xy 380.312168 -396.860522) (xy 380.306375 -396.86767) (xy 380.299859 -396.884858) (xy 380.299468 -396.89405)
			(xy 380.299468 -397.386302) (xy 380.299884 -397.395488) (xy 380.306394 -397.412672) (xy 380.312168 -397.41983)
			(xy 380.333996 -397.445525) (xy 380.372088 -397.501155) (xy 380.40085 -397.556356) (xy 381.529065 -397.556356)
			(xy 381.537108 -397.489534) (xy 381.553079 -397.424153) (xy 381.576749 -397.361149) (xy 381.60778 -397.301425)
			(xy 381.645726 -397.245838) (xy 381.667512 -397.220186) (xy 381.673298 -397.213034) (xy 381.679819 -397.195849)
			(xy 381.680212 -397.186658) (xy 381.680212 -397.028924) (xy 381.680636 -397.018802) (xy 381.688378 -397.000096)
			(xy 381.702693 -396.985781) (xy 381.721398 -396.978037) (xy 381.73152 -396.977616) (xy 382.448054 -396.977616)
			(xy 382.458175 -396.978164) (xy 382.47689 -396.985872) (xy 382.491247 -397.000139) (xy 382.499072 -397.018806)
			(xy 382.499616 -397.028924) (xy 382.499616 -397.186658) (xy 382.500043 -397.195844) (xy 382.506544 -397.213028)
			(xy 382.512316 -397.220186) (xy 382.534115 -397.245829) (xy 382.572066 -397.301416) (xy 382.603102 -397.36114)
			(xy 382.626776 -397.424146) (xy 382.642749 -397.48953) (xy 382.650793 -397.556354) (xy 382.650793 -397.623661)
			(xy 382.642747 -397.690485) (xy 382.626771 -397.755868) (xy 382.603096 -397.818873) (xy 382.600522 -397.823826)
			(xy 383.729168 -397.823826) (xy 383.729172 -397.756517) (xy 383.73722 -397.689692) (xy 383.753198 -397.624307)
			(xy 383.776876 -397.561301) (xy 383.807914 -397.501576) (xy 383.845869 -397.44599) (xy 383.86766 -397.420338)
			(xy 383.873473 -397.413205) (xy 383.879976 -397.396005) (xy 383.88036 -397.38681) (xy 383.88036 -396.893542)
			(xy 383.879916 -396.884359) (xy 383.873425 -396.867175) (xy 383.86766 -396.860014) (xy 383.845862 -396.83437)
			(xy 383.807912 -396.778783) (xy 383.776878 -396.719058) (xy 383.753205 -396.656053) (xy 383.737232 -396.590669)
			(xy 383.729188 -396.523846) (xy 383.729189 -396.456539) (xy 383.737235 -396.389716) (xy 383.753209 -396.324333)
			(xy 383.776884 -396.261328) (xy 383.80792 -396.201604) (xy 383.845871 -396.146018) (xy 383.86766 -396.120366)
			(xy 383.873461 -396.113224) (xy 383.879971 -396.096031) (xy 383.88036 -396.086838) (xy 383.88036 -395.92885)
			(xy 383.880805 -395.918679) (xy 383.888578 -395.899881) (xy 383.902958 -395.885494) (xy 383.921751 -395.877711)
			(xy 383.931922 -395.877288) (xy 384.648202 -395.877288) (xy 384.65838 -395.877663) (xy 384.677184 -395.885458)
			(xy 384.691571 -395.899859) (xy 384.699347 -395.918672) (xy 384.699764 -395.92885) (xy 384.699764 -396.086838)
			(xy 384.700164 -396.096026) (xy 384.706686 -396.11321) (xy 384.712464 -396.120366) (xy 384.734242 -396.146026)
			(xy 384.772191 -396.201612) (xy 384.803224 -396.261334) (xy 384.826898 -396.324337) (xy 384.842871 -396.389719)
			(xy 384.850916 -396.45654) (xy 384.850917 -396.523845) (xy 384.842874 -396.590666) (xy 384.826902 -396.656048)
			(xy 384.803231 -396.719052) (xy 384.772199 -396.778776) (xy 384.734251 -396.834362) (xy 384.712464 -396.860014)
			(xy 384.706674 -396.867164) (xy 384.700156 -396.884351) (xy 384.699764 -396.893542) (xy 384.699764 -397.38681)
			(xy 384.700177 -397.395997) (xy 384.70669 -397.413181) (xy 384.712464 -397.420338) (xy 384.734214 -397.446021)
			(xy 384.772164 -397.501603) (xy 384.800587 -397.556296) (xy 385.928833 -397.556296) (xy 385.936908 -397.489358)
			(xy 385.952943 -397.42387) (xy 385.976706 -397.360773) (xy 386.007856 -397.300977) (xy 386.045944 -397.245343)
			(xy 386.067808 -397.219678) (xy 386.073597 -397.212528) (xy 386.080116 -397.195341) (xy 386.080508 -397.18615)
			(xy 386.080508 -397.028924) (xy 386.080936 -397.018802) (xy 386.088677 -397.000097) (xy 386.102991 -396.985782)
			(xy 386.121694 -396.978037) (xy 386.131816 -396.977616) (xy 386.848096 -396.977616) (xy 386.85822 -396.97802)
			(xy 386.876927 -396.985769) (xy 386.891242 -397.00009) (xy 386.898984 -397.0188) (xy 386.899404 -397.028924)
			(xy 386.899404 -397.18615) (xy 386.899837 -397.195335) (xy 386.906335 -397.212519) (xy 386.912104 -397.219678)
			(xy 386.933978 -397.245335) (xy 386.972066 -397.300971) (xy 387.003216 -397.360768) (xy 387.026979 -397.423866)
			(xy 387.043014 -397.489356) (xy 387.051089 -397.556295) (xy 387.051088 -397.62372) (xy 387.043011 -397.690659)
			(xy 387.026975 -397.756148) (xy 387.00321 -397.819245) (xy 387.000823 -397.823826) (xy 388.128959 -397.823826)
			(xy 388.128963 -397.756517) (xy 388.137011 -397.689692) (xy 388.152988 -397.624308) (xy 388.176665 -397.561301)
			(xy 388.207704 -397.501577) (xy 388.245658 -397.44599) (xy 388.267448 -397.420338) (xy 388.273259 -397.413204)
			(xy 388.279764 -397.396005) (xy 388.280148 -397.38681) (xy 388.280148 -396.893542) (xy 388.279707 -396.884358)
			(xy 388.273213 -396.867174) (xy 388.267448 -396.860014) (xy 388.24565 -396.83437) (xy 388.207701 -396.778783)
			(xy 388.176668 -396.719058) (xy 388.152995 -396.656052) (xy 388.137022 -396.590669) (xy 388.128979 -396.523845)
			(xy 388.12898 -396.456539) (xy 388.137025 -396.389716) (xy 388.152999 -396.324333) (xy 388.176674 -396.261328)
			(xy 388.207709 -396.201604) (xy 388.245659 -396.146018) (xy 388.267448 -396.120366) (xy 388.273247 -396.113223)
			(xy 388.279759 -396.096031) (xy 388.280148 -396.086838) (xy 388.280148 -395.92885) (xy 388.280605 -395.91868)
			(xy 388.288375 -395.899885) (xy 388.302751 -395.885498) (xy 388.321541 -395.877713) (xy 388.33171 -395.877288)
			(xy 389.04799 -395.877288) (xy 389.058167 -395.877673) (xy 389.076971 -395.885464) (xy 389.091358 -395.899862)
			(xy 389.099135 -395.918672) (xy 389.099552 -395.92885) (xy 389.099552 -396.086838) (xy 389.099955 -396.096026)
			(xy 389.106475 -396.113209) (xy 389.112252 -396.120366) (xy 389.13403 -396.146026) (xy 389.17198 -396.201611)
			(xy 389.203014 -396.261334) (xy 389.226688 -396.324337) (xy 389.242662 -396.389718) (xy 389.250707 -396.45654)
			(xy 389.250707 -396.523845) (xy 389.242664 -396.590667) (xy 389.226692 -396.656048) (xy 389.20302 -396.719053)
			(xy 389.171987 -396.778776) (xy 389.134039 -396.834362) (xy 389.112252 -396.860014) (xy 389.106461 -396.867163)
			(xy 389.099944 -396.884351) (xy 389.099552 -396.893542) (xy 389.099552 -397.38681) (xy 389.099968 -397.395996)
			(xy 389.106479 -397.41318) (xy 389.112252 -397.420338) (xy 389.134002 -397.446021) (xy 389.171953 -397.501603)
			(xy 389.200407 -397.556356) (xy 390.329153 -397.556356) (xy 390.337195 -397.489535) (xy 390.353166 -397.424153)
			(xy 390.376836 -397.36115) (xy 390.407865 -397.301426) (xy 390.44581 -397.245839) (xy 390.467596 -397.220186)
			(xy 390.473381 -397.213032) (xy 390.479903 -397.195848) (xy 390.480296 -397.186658) (xy 390.480296 -397.028924)
			(xy 390.480735 -397.018804) (xy 390.488475 -397.000101) (xy 390.502784 -396.985786) (xy 390.521484 -396.978039)
			(xy 390.531604 -396.977616) (xy 391.248138 -396.977616) (xy 391.258264 -396.978095) (xy 391.276982 -396.985831)
			(xy 391.291336 -397.000119) (xy 391.299158 -397.0188) (xy 391.2997 -397.028924) (xy 391.2997 -397.186658)
			(xy 391.30013 -397.195843) (xy 391.30663 -397.213028) (xy 391.3124 -397.220186) (xy 391.334196 -397.245831)
			(xy 391.372142 -397.301419) (xy 391.403173 -397.361144) (xy 391.426844 -397.424149) (xy 391.442815 -397.489532)
			(xy 391.450857 -397.556355) (xy 391.450856 -397.62366) (xy 391.442812 -397.690483) (xy 391.426839 -397.755865)
			(xy 391.403167 -397.81887) (xy 391.372135 -397.878594) (xy 391.334187 -397.934181) (xy 391.3124 -397.959834)
			(xy 391.306606 -397.966981) (xy 391.30009 -397.98417) (xy 391.2997 -397.993362) (xy 391.2997 -398.486884)
			(xy 391.300118 -398.49607) (xy 391.306626 -398.513255) (xy 391.3124 -398.520412) (xy 391.334222 -398.546036)
			(xy 391.372167 -398.601627) (xy 391.403197 -398.661355) (xy 391.426866 -398.724363) (xy 391.442835 -398.789748)
			(xy 391.450876 -398.856574) (xy 391.450872 -398.923881) (xy 391.442825 -398.990705) (xy 391.42685 -399.056089)
			(xy 391.403175 -399.119095) (xy 391.372139 -399.178819) (xy 391.334189 -399.234407) (xy 391.3124 -399.26006)
			(xy 391.306595 -399.2672) (xy 391.300086 -399.284394) (xy 391.2997 -399.293588) (xy 391.2997 -399.451576)
			(xy 391.299265 -399.461697) (xy 391.291524 -399.4804) (xy 391.277214 -399.494715) (xy 391.258513 -399.502461)
			(xy 391.248392 -399.502884) (xy 390.531858 -399.502884) (xy 390.521732 -399.502409) (xy 390.503014 -399.494671)
			(xy 390.48866 -399.480382) (xy 390.480838 -399.4617) (xy 390.480296 -399.451576) (xy 390.480296 -399.293588)
			(xy 390.479892 -399.2844) (xy 390.473374 -399.267216) (xy 390.467596 -399.26006) (xy 390.445845 -399.234378)
			(xy 390.407898 -399.178795) (xy 390.376865 -399.119075) (xy 390.353192 -399.056075) (xy 390.337218 -398.990696)
			(xy 390.329172 -398.923878) (xy 390.329169 -398.856576) (xy 390.337209 -398.789757) (xy 390.353176 -398.724377)
			(xy 390.376843 -398.661374) (xy 390.40787 -398.601652) (xy 390.445812 -398.546065) (xy 390.467596 -398.520412)
			(xy 390.473412 -398.51328) (xy 390.479915 -398.49608) (xy 390.480296 -398.486884) (xy 390.480296 -397.993362)
			(xy 390.479905 -397.984173) (xy 390.473378 -397.966988) (xy 390.467596 -397.959834) (xy 390.445819 -397.934173)
			(xy 390.407873 -397.878587) (xy 390.376842 -397.818864) (xy 390.35317 -397.755861) (xy 390.337198 -397.69048)
			(xy 390.329154 -397.623659) (xy 390.329153 -397.556356) (xy 389.200407 -397.556356) (xy 389.202988 -397.561322)
			(xy 389.226664 -397.624322) (xy 389.24264 -397.689701) (xy 389.250687 -397.75652) (xy 389.25069 -397.823823)
			(xy 389.24265 -397.890643) (xy 389.226681 -397.956023) (xy 389.203012 -398.019026) (xy 389.171982 -398.078748)
			(xy 389.134038 -398.134334) (xy 389.112252 -398.159986) (xy 389.10643 -398.167113) (xy 389.099932 -398.184318)
			(xy 389.099552 -398.193514) (xy 389.099552 -398.351502) (xy 389.099138 -398.361675) (xy 389.09135 -398.380472)
			(xy 389.076962 -398.394857) (xy 389.058163 -398.40264) (xy 389.04799 -398.403064) (xy 388.33171 -398.403064)
			(xy 388.321539 -398.402628) (xy 388.302745 -398.394847) (xy 388.28836 -398.380465) (xy 388.280574 -398.361673)
			(xy 388.280148 -398.351502) (xy 388.280148 -398.193514) (xy 388.27972 -398.184329) (xy 388.273218 -398.167145)
			(xy 388.267448 -398.159986) (xy 388.245622 -398.134365) (xy 388.207674 -398.078774) (xy 388.176642 -398.019046)
			(xy 388.152971 -397.956038) (xy 388.137 -397.890652) (xy 388.128959 -397.823826) (xy 387.000823 -397.823826)
			(xy 386.972058 -397.879042) (xy 386.933968 -397.934677) (xy 386.912104 -397.960342) (xy 386.906308 -397.967487)
			(xy 386.899793 -397.984678) (xy 386.899404 -397.99387) (xy 386.899404 -398.486376) (xy 386.899825 -398.495562)
			(xy 386.906331 -398.512747) (xy 386.912104 -398.519904) (xy 386.934003 -398.54554) (xy 386.972091 -398.601179)
			(xy 387.003239 -398.660979) (xy 387.027001 -398.72408) (xy 387.043034 -398.789572) (xy 387.051107 -398.856514)
			(xy 387.051104 -398.92394) (xy 387.043025 -398.990881) (xy 387.026985 -399.056372) (xy 387.003217 -399.11947)
			(xy 386.972063 -399.179268) (xy 386.93397 -399.234903) (xy 386.912104 -399.260568) (xy 386.906297 -399.267706)
			(xy 386.899788 -399.284902) (xy 386.899404 -399.294096) (xy 386.899404 -399.451576) (xy 386.898965 -399.461696)
			(xy 386.891225 -399.480399) (xy 386.876916 -399.494714) (xy 386.858216 -399.502461) (xy 386.848096 -399.502884)
			(xy 386.131816 -399.502884) (xy 386.121693 -399.502471) (xy 386.102986 -399.494725) (xy 386.088671 -399.480407)
			(xy 386.080928 -399.4617) (xy 386.080508 -399.451576) (xy 386.080508 -399.294096) (xy 386.080098 -399.284909)
			(xy 386.073584 -399.267725) (xy 386.067808 -399.260568) (xy 386.045979 -399.234874) (xy 386.007889 -399.179244)
			(xy 385.976736 -399.119451) (xy 385.95297 -399.056358) (xy 385.936931 -398.990873) (xy 385.928852 -398.923938)
			(xy 385.928849 -398.856517) (xy 385.936922 -398.789581) (xy 385.952954 -398.724093) (xy 385.976714 -398.660998)
			(xy 386.007861 -398.601203) (xy 386.045946 -398.545569) (xy 386.067808 -398.519904) (xy 386.073586 -398.512746)
			(xy 386.080112 -398.495565) (xy 386.080508 -398.486376) (xy 386.080508 -397.99387) (xy 386.080111 -397.984681)
			(xy 386.073588 -397.967497) (xy 386.067808 -397.960342) (xy 386.045954 -397.934669) (xy 386.007864 -397.879036)
			(xy 385.976712 -397.819241) (xy 385.952947 -397.756145) (xy 385.936911 -397.690657) (xy 385.928834 -397.623719)
			(xy 385.928833 -397.556296) (xy 384.800587 -397.556296) (xy 384.803199 -397.561322) (xy 384.826873 -397.624323)
			(xy 384.842849 -397.689701) (xy 384.850896 -397.75652) (xy 384.850899 -397.823822) (xy 384.842859 -397.890642)
			(xy 384.82689 -397.956022) (xy 384.803222 -398.019025) (xy 384.772193 -398.078748) (xy 384.734249 -398.134334)
			(xy 384.712464 -398.159986) (xy 384.706644 -398.167114) (xy 384.700144 -398.184318) (xy 384.699764 -398.193514)
			(xy 384.699764 -398.351502) (xy 384.699268 -398.36166) (xy 384.691494 -398.380428) (xy 384.677128 -398.394794)
			(xy 384.65836 -398.402568) (xy 384.648202 -398.403064) (xy 383.931922 -398.403064) (xy 383.921752 -398.402618)
			(xy 383.902958 -398.394841) (xy 383.888573 -398.380462) (xy 383.880787 -398.361672) (xy 383.88036 -398.351502)
			(xy 383.88036 -398.193514) (xy 383.87993 -398.184329) (xy 383.873429 -398.167145) (xy 383.86766 -398.159986)
			(xy 383.845834 -398.134365) (xy 383.807885 -398.078775) (xy 383.776852 -398.019047) (xy 383.753181 -397.956038)
			(xy 383.73721 -397.890652) (xy 383.729168 -397.823826) (xy 382.600522 -397.823826) (xy 382.572059 -397.878597)
			(xy 382.534106 -397.934182) (xy 382.512316 -397.959834) (xy 382.506524 -397.966983) (xy 382.500006 -397.98417)
			(xy 382.499616 -397.993362) (xy 382.499616 -398.486884) (xy 382.50003 -398.496071) (xy 382.506541 -398.513255)
			(xy 382.512316 -398.520412) (xy 382.53414 -398.546034) (xy 382.572091 -398.601624) (xy 382.603125 -398.661351)
			(xy 382.626798 -398.72436) (xy 382.64277 -398.789746) (xy 382.650812 -398.856573) (xy 382.650808 -398.923881)
			(xy 382.64276 -398.990707) (xy 382.626782 -399.056092) (xy 382.603103 -399.119098) (xy 382.572063 -399.178822)
			(xy 382.534107 -399.234408) (xy 382.512316 -399.26006) (xy 382.506513 -399.267201) (xy 382.500002 -399.284395)
			(xy 382.499616 -399.293588) (xy 382.499616 -399.451576) (xy 382.499165 -399.461695) (xy 382.491428 -399.480395)
			(xy 382.477122 -399.49471) (xy 382.458427 -399.502459) (xy 382.448308 -399.502884) (xy 381.731774 -399.502884)
			(xy 381.721649 -399.502396) (xy 381.702931 -399.494664) (xy 381.688577 -399.480379) (xy 381.680754 -399.461699)
			(xy 381.680212 -399.451576) (xy 381.680212 -399.293588) (xy 381.679805 -399.284401) (xy 381.673289 -399.267216)
			(xy 381.667512 -399.26006) (xy 381.64576 -399.234378) (xy 381.607812 -399.178796) (xy 381.576779 -399.119076)
			(xy 381.553105 -399.056075) (xy 381.537131 -398.990697) (xy 381.529084 -398.923878) (xy 381.529081 -398.856576)
			(xy 381.537121 -398.789757) (xy 381.553089 -398.724377) (xy 381.576757 -398.661374) (xy 381.607784 -398.601651)
			(xy 381.645727 -398.546064) (xy 381.667512 -398.520412) (xy 381.67333 -398.513282) (xy 381.679831 -398.49608)
			(xy 381.680212 -398.486884) (xy 381.680212 -397.993362) (xy 381.679818 -397.984173) (xy 381.673293 -397.966989)
			(xy 381.667512 -397.959834) (xy 381.645735 -397.934173) (xy 381.607788 -397.878588) (xy 381.576755 -397.818865)
			(xy 381.553083 -397.755862) (xy 381.53711 -397.690481) (xy 381.529066 -397.623659) (xy 381.529065 -397.556356)
			(xy 380.40085 -397.556356) (xy 380.403242 -397.560947) (xy 380.42701 -397.62404) (xy 380.443049 -397.689525)
			(xy 380.451128 -397.756461) (xy 380.451131 -397.823882) (xy 380.443059 -397.890818) (xy 380.427026 -397.956306)
			(xy 380.403265 -398.019401) (xy 380.372117 -398.079196) (xy 380.334031 -398.134829) (xy 380.312168 -398.160494)
			(xy 380.306387 -398.16765) (xy 380.299864 -398.184832) (xy 380.299468 -398.194022) (xy 380.299468 -398.351502)
			(xy 380.298975 -398.361628) (xy 380.291248 -398.380347) (xy 380.276964 -398.394703) (xy 380.258283 -398.402524)
			(xy 380.24816 -398.403064) (xy 379.53188 -398.403064) (xy 379.521752 -398.4027) (xy 379.503041 -398.394938)
			(xy 379.488726 -398.380605) (xy 379.480988 -398.361885) (xy 379.480572 -398.351756) (xy 379.480572 -398.194022)
			(xy 379.480158 -398.184835) (xy 379.473648 -398.16765) (xy 379.467872 -398.160494) (xy 379.445972 -398.134859)
			(xy 379.407886 -398.07922) (xy 379.376738 -398.019419) (xy 379.352978 -397.956318) (xy 379.336946 -397.890826)
			(xy 379.328873 -397.823885) (xy 378.200706 -397.823885) (xy 378.171972 -397.879041) (xy 378.133884 -397.934676)
			(xy 378.11202 -397.960342) (xy 378.106225 -397.967489) (xy 378.099709 -397.984678) (xy 378.09932 -397.99387)
			(xy 378.09932 -398.486376) (xy 378.099737 -398.495563) (xy 378.106245 -398.512747) (xy 378.11202 -398.519904)
			(xy 378.133919 -398.54554) (xy 378.172005 -398.60118) (xy 378.203153 -398.66098) (xy 378.226914 -398.724081)
			(xy 378.242947 -398.789573) (xy 378.251019 -398.856514) (xy 378.251016 -398.92394) (xy 378.242937 -398.99088)
			(xy 378.226898 -399.056371) (xy 378.203131 -399.11947) (xy 378.171977 -399.179267) (xy 378.133885 -399.234902)
			(xy 378.11202 -399.260568) (xy 378.106214 -399.267707) (xy 378.099704 -399.284902) (xy 378.09932 -399.294096)
			(xy 378.09932 -399.451576) (xy 378.098865 -399.461694) (xy 378.091128 -399.480394) (xy 378.076824 -399.494708)
			(xy 378.05813 -399.502458) (xy 378.048012 -399.502884) (xy 377.331732 -399.502884) (xy 377.32161 -399.502458)
			(xy 377.302903 -399.494717) (xy 377.288587 -399.480403) (xy 377.280844 -399.461698) (xy 377.280424 -399.451576)
			(xy 377.280424 -399.294096) (xy 377.280011 -399.284909) (xy 377.273499 -399.267725) (xy 377.267724 -399.260568)
			(xy 377.245895 -399.234874) (xy 377.207803 -399.179244) (xy 377.17665 -399.119452) (xy 377.152882 -399.056359)
			(xy 377.136844 -398.990873) (xy 377.128765 -398.923938) (xy 377.128761 -398.856516) (xy 377.136834 -398.78958)
			(xy 377.152866 -398.724093) (xy 377.176627 -398.660997) (xy 377.207775 -398.601202) (xy 377.245861 -398.545569)
			(xy 377.267724 -398.519904) (xy 377.273504 -398.512747) (xy 377.280028 -398.495565) (xy 377.280424 -398.486376)
			(xy 377.280424 -397.99387) (xy 377.280023 -397.984682) (xy 377.273502 -397.967498) (xy 377.267724 -397.960342)
			(xy 377.245869 -397.934669) (xy 377.207778 -397.879036) (xy 377.176626 -397.819241) (xy 377.15286 -397.756145)
			(xy 377.136823 -397.690657) (xy 377.128746 -397.623719) (xy 377.128745 -397.556296) (xy 376.0005 -397.556296)
			(xy 376.003112 -397.561323) (xy 376.026786 -397.624324) (xy 376.042761 -397.689702) (xy 376.050808 -397.756521)
			(xy 376.050811 -397.823822) (xy 376.042771 -397.890642) (xy 376.026803 -397.956022) (xy 376.003135 -398.019025)
			(xy 375.972108 -398.078747) (xy 375.934165 -398.134333) (xy 375.91238 -398.159986) (xy 375.906562 -398.167116)
			(xy 375.900061 -398.184318) (xy 375.89968 -398.193514) (xy 375.89968 -398.351502) (xy 375.899169 -398.361658)
			(xy 375.891397 -398.380423) (xy 375.877037 -398.394788) (xy 375.858274 -398.402565) (xy 375.848118 -398.403064)
			(xy 375.131838 -398.403064) (xy 375.121669 -398.402605) (xy 375.102876 -398.394833) (xy 375.08849 -398.380458)
			(xy 375.080703 -398.361671) (xy 375.080276 -398.351502) (xy 375.080276 -398.193514) (xy 375.079865 -398.184327)
			(xy 375.073352 -398.167142) (xy 375.067576 -398.159986) (xy 375.04575 -398.134365) (xy 375.007799 -398.078775)
			(xy 374.976766 -398.019048) (xy 374.953093 -397.956039) (xy 374.937122 -397.890652) (xy 374.92908 -397.823826)
			(xy 347.400682 -397.823826) (xy 347.372224 -397.878594) (xy 347.334276 -397.934182) (xy 347.312488 -397.959834)
			(xy 347.306693 -397.96698) (xy 347.300178 -397.98417) (xy 347.299788 -397.993362) (xy 347.299788 -398.486884)
			(xy 347.300209 -398.49607) (xy 347.306715 -398.513254) (xy 347.312488 -398.520412) (xy 347.33431 -398.546035)
			(xy 347.372256 -398.601627) (xy 347.403286 -398.661354) (xy 347.426956 -398.724363) (xy 347.442926 -398.789748)
			(xy 347.450967 -398.856573) (xy 347.450963 -398.923881) (xy 347.442916 -398.990705) (xy 347.42694 -399.056089)
			(xy 347.403264 -399.119095) (xy 347.372228 -399.17882) (xy 347.334277 -399.234407) (xy 347.312488 -399.26006)
			(xy 347.306682 -399.267199) (xy 347.300173 -399.284394) (xy 347.299788 -399.293588) (xy 347.299788 -399.451576)
			(xy 347.299359 -399.46173) (xy 347.291569 -399.480484) (xy 347.277174 -399.494809) (xy 347.258382 -399.502507)
			(xy 347.248226 -399.502884) (xy 346.531946 -399.502884) (xy 346.521825 -399.502336) (xy 346.50311 -399.494628)
			(xy 346.488753 -399.480361) (xy 346.480928 -399.461694) (xy 346.480384 -399.451576) (xy 346.480384 -399.293588)
			(xy 346.479983 -399.2844) (xy 346.473463 -399.267215) (xy 346.467684 -399.26006) (xy 346.44593 -399.234379)
			(xy 346.407977 -399.178798) (xy 346.37694 -399.119079) (xy 346.353263 -399.056078) (xy 346.337287 -398.990699)
			(xy 346.329239 -398.923879) (xy 346.329236 -398.856576) (xy 346.337277 -398.789755) (xy 346.353247 -398.724374)
			(xy 346.376918 -398.661371) (xy 346.40795 -398.601648) (xy 346.445897 -398.546064) (xy 346.467684 -398.520412)
			(xy 346.473499 -398.513279) (xy 346.480003 -398.496079) (xy 346.480384 -398.486884) (xy 346.480384 -397.993362)
			(xy 346.479996 -397.984172) (xy 346.473467 -397.966988) (xy 346.467684 -397.959834) (xy 346.445905 -397.934174)
			(xy 346.407953 -397.87859) (xy 346.376917 -397.818868) (xy 346.353241 -397.755864) (xy 346.337266 -397.690483)
			(xy 346.329221 -397.62366) (xy 346.32922 -397.556355) (xy 345.200497 -397.556355) (xy 345.203078 -397.561321)
			(xy 345.226754 -397.624322) (xy 345.24273 -397.689701) (xy 345.250778 -397.75652) (xy 345.250781 -397.823823)
			(xy 345.242741 -397.890643) (xy 345.226771 -397.956023) (xy 345.203102 -398.019026) (xy 345.172072 -398.078749)
			(xy 345.134126 -398.134334) (xy 345.11234 -398.159986) (xy 345.106517 -398.167112) (xy 345.10002 -398.184318)
			(xy 345.09964 -398.193514) (xy 345.09964 -398.351502) (xy 345.099237 -398.361676) (xy 345.091447 -398.380475)
			(xy 345.077055 -398.394861) (xy 345.058253 -398.402642) (xy 345.048078 -398.403064) (xy 344.331798 -398.403064)
			(xy 344.32164 -398.402568) (xy 344.302872 -398.394794) (xy 344.288506 -398.380428) (xy 344.280732 -398.36166)
			(xy 344.280236 -398.351502) (xy 344.280236 -398.193514) (xy 344.279811 -398.184329) (xy 344.273307 -398.167144)
			(xy 344.267536 -398.159986) (xy 344.245711 -398.134365) (xy 344.207763 -398.078774) (xy 344.176732 -398.019046)
			(xy 344.153061 -397.956037) (xy 344.137091 -397.890651) (xy 344.12905 -397.823825) (xy 343.000914 -397.823825)
			(xy 342.972147 -397.879042) (xy 342.934057 -397.934677) (xy 342.912192 -397.960342) (xy 342.906394 -397.967486)
			(xy 342.899881 -397.984678) (xy 342.899492 -397.99387) (xy 342.899492 -398.486376) (xy 342.899916 -398.495562)
			(xy 342.90642 -398.512746) (xy 342.912192 -398.519904) (xy 342.934092 -398.54554) (xy 342.97218 -398.601178)
			(xy 343.003329 -398.660979) (xy 343.027092 -398.724079) (xy 343.043125 -398.789572) (xy 343.051198 -398.856514)
			(xy 343.051195 -398.92394) (xy 343.043115 -398.990881) (xy 343.027076 -399.056372) (xy 343.003307 -399.119471)
			(xy 342.972152 -399.179268) (xy 342.934058 -399.234903) (xy 342.912192 -399.260568) (xy 342.906383 -399.267704)
			(xy 342.899876 -399.284902) (xy 342.899492 -399.294096) (xy 342.899492 -399.451576) (xy 342.899064 -399.461698)
			(xy 342.891323 -399.480403) (xy 342.877009 -399.494718) (xy 342.858306 -399.502463) (xy 342.848184 -399.502884)
			(xy 342.131904 -399.502884) (xy 342.12178 -399.50248) (xy 342.103073 -399.494731) (xy 342.088758 -399.48041)
			(xy 342.081016 -399.4617) (xy 342.080596 -399.451576) (xy 342.080596 -399.294096) (xy 342.080189 -399.284909)
			(xy 342.073673 -399.267724) (xy 342.067896 -399.260568) (xy 342.046068 -399.234874) (xy 342.007978 -399.179243)
			(xy 341.976826 -399.119451) (xy 341.95306 -399.056358) (xy 341.937022 -398.990872) (xy 341.928943 -398.923937)
			(xy 341.92894 -398.856517) (xy 341.937012 -398.789581) (xy 341.953044 -398.724094) (xy 341.976804 -398.660999)
			(xy 342.00795 -398.601203) (xy 342.046034 -398.545569) (xy 342.067896 -398.519904) (xy 342.073673 -398.512745)
			(xy 342.080199 -398.495565) (xy 342.080596 -398.486376) (xy 342.080596 -397.99387) (xy 342.080201 -397.984681)
			(xy 342.073677 -397.967497) (xy 342.067896 -397.960342) (xy 342.046042 -397.934669) (xy 342.007953 -397.879035)
			(xy 341.976802 -397.81924) (xy 341.953038 -397.756144) (xy 341.937002 -397.690656) (xy 341.928925 -397.623719)
			(xy 341.928924 -397.556296) (xy 340.800676 -397.556296) (xy 340.803288 -397.561322) (xy 340.826964 -397.624322)
			(xy 340.84294 -397.689701) (xy 340.850987 -397.75652) (xy 340.85099 -397.823823) (xy 340.84295 -397.890643)
			(xy 340.826981 -397.956023) (xy 340.803312 -398.019026) (xy 340.772282 -398.078748) (xy 340.734338 -398.134334)
			(xy 340.712552 -398.159986) (xy 340.70673 -398.167113) (xy 340.700232 -398.184318) (xy 340.699852 -398.193514)
			(xy 340.699852 -398.351502) (xy 340.699438 -398.361675) (xy 340.69165 -398.380472) (xy 340.677262 -398.394857)
			(xy 340.658463 -398.40264) (xy 340.64829 -398.403064) (xy 339.93201 -398.403064) (xy 339.921839 -398.402628)
			(xy 339.903045 -398.394847) (xy 339.88866 -398.380465) (xy 339.880874 -398.361673) (xy 339.880448 -398.351502)
			(xy 339.880448 -398.193514) (xy 339.88002 -398.184329) (xy 339.873518 -398.167145) (xy 339.867748 -398.159986)
			(xy 339.845922 -398.134365) (xy 339.807974 -398.078774) (xy 339.776942 -398.019046) (xy 339.753271 -397.956038)
			(xy 339.7373 -397.890652) (xy 339.729259 -397.823826) (xy 338.600595 -397.823826) (xy 338.572138 -397.878594)
			(xy 338.534191 -397.934181) (xy 338.512404 -397.959834) (xy 338.506611 -397.966982) (xy 338.500094 -397.98417)
			(xy 338.499704 -397.993362) (xy 338.499704 -398.486884) (xy 338.500121 -398.49607) (xy 338.50663 -398.513255)
			(xy 338.512404 -398.520412) (xy 338.534226 -398.546036) (xy 338.572171 -398.601627) (xy 338.6032 -398.661355)
			(xy 338.626869 -398.724363) (xy 338.642838 -398.789748) (xy 338.650879 -398.856574) (xy 338.650875 -398.923881)
			(xy 338.642828 -398.990705) (xy 338.626853 -399.056089) (xy 338.603178 -399.119094) (xy 338.572143 -399.178819)
			(xy 338.534193 -399.234407) (xy 338.512404 -399.26006) (xy 338.5066 -399.2672) (xy 338.50009 -399.284394)
			(xy 338.499704 -399.293588) (xy 338.499704 -399.451576) (xy 338.499259 -399.461728) (xy 338.491472 -399.480479)
			(xy 338.477082 -399.494803) (xy 338.458296 -399.502505) (xy 338.448142 -399.502884) (xy 337.731862 -399.502884)
			(xy 337.721736 -399.502405) (xy 337.703018 -399.494669) (xy 337.688664 -399.480381) (xy 337.680842 -399.4617)
			(xy 337.6803 -399.451576) (xy 337.6803 -399.293588) (xy 337.679895 -399.2844) (xy 337.673378 -399.267216)
			(xy 337.6676 -399.26006) (xy 337.645849 -399.234378) (xy 337.607901 -399.178795) (xy 337.576869 -399.119075)
			(xy 337.553196 -399.056075) (xy 337.537221 -398.990697) (xy 337.529175 -398.923878) (xy 337.529172 -398.856576)
			(xy 337.537212 -398.789757) (xy 337.55318 -398.724377) (xy 337.576847 -398.661374) (xy 337.607874 -398.601651)
			(xy 337.645816 -398.546065) (xy 337.6676 -398.520412) (xy 337.673416 -398.513281) (xy 337.679919 -398.49608)
			(xy 337.6803 -398.486884) (xy 337.6803 -397.993362) (xy 337.679908 -397.984173) (xy 337.673382 -397.966989)
			(xy 337.6676 -397.959834) (xy 337.645823 -397.934173) (xy 337.607877 -397.878587) (xy 337.576845 -397.818864)
			(xy 337.553174 -397.755861) (xy 337.537201 -397.69048) (xy 337.529157 -397.623659) (xy 337.529156 -397.556356)
			(xy 336.40094 -397.556356) (xy 336.403332 -397.560946) (xy 336.4271 -397.624039) (xy 336.443139 -397.689525)
			(xy 336.451219 -397.756461) (xy 336.451222 -397.823882) (xy 336.44315 -397.890819) (xy 336.427117 -397.956306)
			(xy 336.403355 -398.019402) (xy 336.372206 -398.079196) (xy 336.334119 -398.13483) (xy 336.312256 -398.160494)
			(xy 336.306474 -398.167649) (xy 336.299952 -398.184832) (xy 336.299556 -398.194022) (xy 336.299556 -398.351502)
			(xy 336.299075 -398.361629) (xy 336.291346 -398.380351) (xy 336.277058 -398.394708) (xy 336.258373 -398.402526)
			(xy 336.248248 -398.403064) (xy 335.531968 -398.403064) (xy 335.521807 -398.402704) (xy 335.503047 -398.394891)
			(xy 335.488724 -398.380475) (xy 335.481032 -398.361665) (xy 335.48066 -398.351502) (xy 335.48066 -398.194022)
			(xy 335.480226 -398.184838) (xy 335.473727 -398.167654) (xy 335.46796 -398.160494) (xy 335.44606 -398.134859)
			(xy 335.407975 -398.079219) (xy 335.376828 -398.019418) (xy 335.353068 -397.956318) (xy 335.337036 -397.890825)
			(xy 335.328964 -397.823884) (xy 334.200796 -397.823884) (xy 334.172062 -397.879042) (xy 334.133972 -397.934677)
			(xy 334.112108 -397.960342) (xy 334.106312 -397.967488) (xy 334.099797 -397.984678) (xy 334.099408 -397.99387)
			(xy 334.099408 -398.486376) (xy 334.099828 -398.495562) (xy 334.106335 -398.512747) (xy 334.112108 -398.519904)
			(xy 334.134007 -398.54554) (xy 334.172094 -398.601179) (xy 334.203243 -398.660979) (xy 334.227005 -398.72408)
			(xy 334.243037 -398.789573) (xy 334.25111 -398.856514) (xy 334.251107 -398.92394) (xy 334.243028 -398.990881)
			(xy 334.226989 -399.056372) (xy 334.203221 -399.11947) (xy 334.172066 -399.179267) (xy 334.133974 -399.234903)
			(xy 334.112108 -399.260568) (xy 334.106301 -399.267706) (xy 334.099792 -399.284902) (xy 334.099408 -399.294096)
			(xy 334.099408 -399.451576) (xy 334.098965 -399.461696) (xy 334.091226 -399.480398) (xy 334.076918 -399.494712)
			(xy 334.05822 -399.50246) (xy 334.0481 -399.502884) (xy 333.33182 -399.502884) (xy 333.321697 -399.502467)
			(xy 333.302991 -399.494723) (xy 333.288675 -399.480406) (xy 333.280932 -399.461699) (xy 333.280512 -399.451576)
			(xy 333.280512 -399.294096) (xy 333.280101 -399.284909) (xy 333.273587 -399.267725) (xy 333.267812 -399.260568)
			(xy 333.245983 -399.234874) (xy 333.207892 -399.179244) (xy 333.176739 -399.119452) (xy 333.152973 -399.056358)
			(xy 333.136934 -398.990873) (xy 333.128855 -398.923938) (xy 333.128852 -398.856516) (xy 333.136925 -398.78958)
			(xy 333.152957 -398.724093) (xy 333.176717 -398.660998) (xy 333.207865 -398.601203) (xy 333.24595 -398.545569)
			(xy 333.267812 -398.519904) (xy 333.273591 -398.512746) (xy 333.280116 -398.495565) (xy 333.280512 -398.486376)
			(xy 333.280512 -397.99387) (xy 333.280114 -397.984682) (xy 333.273592 -397.967497) (xy 333.267812 -397.960342)
			(xy 333.245957 -397.934669) (xy 333.207868 -397.879036) (xy 333.176716 -397.819241) (xy 333.152951 -397.756145)
			(xy 333.136914 -397.690657) (xy 333.128837 -397.623719) (xy 333.128836 -397.556296) (xy 332.00059 -397.556296)
			(xy 332.003202 -397.561323) (xy 332.026877 -397.624323) (xy 332.042852 -397.689701) (xy 332.050899 -397.75652)
			(xy 332.050902 -397.823822) (xy 332.042862 -397.890642) (xy 332.026893 -397.956022) (xy 332.003225 -398.019025)
			(xy 331.972197 -398.078748) (xy 331.934253 -398.134334) (xy 331.912468 -398.159986) (xy 331.906648 -398.167115)
			(xy 331.900148 -398.184318) (xy 331.899768 -398.193514) (xy 331.899768 -398.351502) (xy 331.899268 -398.361659)
			(xy 331.891494 -398.380427) (xy 331.877131 -398.394792) (xy 331.858363 -398.402568) (xy 331.848206 -398.403064)
			(xy 331.131926 -398.403064) (xy 331.121756 -398.402615) (xy 331.102963 -398.394839) (xy 331.088577 -398.380461)
			(xy 331.080791 -398.361671) (xy 331.080364 -398.351502) (xy 331.080364 -398.193514) (xy 331.079933 -398.184329)
			(xy 331.073432 -398.167146) (xy 331.067664 -398.159986) (xy 331.045838 -398.134365) (xy 331.007889 -398.078775)
			(xy 330.976856 -398.019047) (xy 330.953184 -397.956038) (xy 330.937213 -397.890652) (xy 330.929171 -397.823826)
			(xy 326.525636 -397.823826) (xy 326.525636 -401.723737) (xy 330.929183 -401.723737) (xy 330.929184 -401.65643)
			(xy 330.937231 -401.589605) (xy 330.953207 -401.524221) (xy 330.976884 -401.461216) (xy 331.007921 -401.401492)
			(xy 331.045874 -401.345906) (xy 331.067664 -401.320254) (xy 331.07347 -401.313116) (xy 331.079977 -401.29592)
			(xy 331.080364 -401.286726) (xy 331.080364 -400.793458) (xy 331.07996 -400.78427) (xy 331.073441 -400.767087)
			(xy 331.067664 -400.75993) (xy 331.045882 -400.734273) (xy 331.007931 -400.678688) (xy 330.976896 -400.618965)
			(xy 330.953222 -400.555961) (xy 330.937248 -400.490579) (xy 330.929203 -400.423757) (xy 330.929202 -400.356452)
			(xy 330.937246 -400.289629) (xy 330.953219 -400.224247) (xy 330.976892 -400.161243) (xy 331.007926 -400.10152)
			(xy 331.045876 -400.045934) (xy 331.067664 -400.020282) (xy 331.073459 -400.013136) (xy 331.079973 -399.995946)
			(xy 331.080364 -399.986754) (xy 331.080364 -399.828766) (xy 331.080806 -399.818603) (xy 331.088597 -399.799828)
			(xy 331.102978 -399.785463) (xy 331.121762 -399.777694) (xy 331.131926 -399.777204) (xy 331.848206 -399.777204)
			(xy 331.85836 -399.777728) (xy 331.877123 -399.785498) (xy 331.891486 -399.799854) (xy 331.899267 -399.818612)
			(xy 331.899768 -399.828766) (xy 331.899768 -399.986754) (xy 331.900208 -399.995938) (xy 331.906702 -400.013122)
			(xy 331.912468 -400.020282) (xy 331.934262 -400.045929) (xy 331.97221 -400.101517) (xy 332.003242 -400.161241)
			(xy 332.026915 -400.224246) (xy 332.042887 -400.289629) (xy 332.05093 -400.356452) (xy 332.05093 -400.423757)
			(xy 332.042885 -400.49058) (xy 332.026912 -400.555963) (xy 332.003239 -400.618967) (xy 331.972205 -400.678691)
			(xy 331.934256 -400.734278) (xy 331.912468 -400.75993) (xy 331.906672 -400.767076) (xy 331.900158 -400.784266)
			(xy 331.899768 -400.793458) (xy 331.899768 -401.286726) (xy 331.900173 -401.295914) (xy 331.906691 -401.313098)
			(xy 331.912468 -401.320254) (xy 331.934234 -401.345924) (xy 331.972183 -401.401508) (xy 332.003216 -401.461229)
			(xy 332.02689 -401.524231) (xy 332.042864 -401.589611) (xy 332.05091 -401.656432) (xy 332.050912 -401.723735)
			(xy 332.04287 -401.790556) (xy 332.0269 -401.855937) (xy 332.00323 -401.91894) (xy 331.9722 -401.978663)
			(xy 331.934254 -402.03425) (xy 331.912468 -402.059902) (xy 331.906684 -402.067056) (xy 331.900163 -402.08424)
			(xy 331.899768 -402.09343) (xy 331.899768 -402.251418) (xy 331.899282 -402.261576) (xy 331.891502 -402.280345)
			(xy 331.877135 -402.294709) (xy 331.858364 -402.302484) (xy 331.848206 -402.30298) (xy 331.131926 -402.30298)
			(xy 331.121758 -402.302515) (xy 331.102968 -402.294742) (xy 331.088583 -402.280369) (xy 331.080794 -402.261585)
			(xy 331.080364 -402.251418) (xy 331.080364 -402.09343) (xy 331.079925 -402.084246) (xy 331.07343 -402.067062)
			(xy 331.067664 -402.059902) (xy 331.045854 -402.034268) (xy 331.007904 -401.97868) (xy 330.97687 -401.918954)
			(xy 330.953197 -401.855947) (xy 330.937225 -401.790562) (xy 330.929183 -401.723737) (xy 326.525636 -401.723737)
			(xy 326.525636 -402.823878) (xy 333.128796 -402.823878) (xy 333.128801 -402.75645) (xy 333.136882 -402.689508)
			(xy 333.152922 -402.624016) (xy 333.176693 -402.560918) (xy 333.20785 -402.50112) (xy 333.245945 -402.445485)
			(xy 333.267812 -402.41982) (xy 333.273626 -402.412687) (xy 333.28013 -402.395487) (xy 333.280512 -402.386292)
			(xy 333.280512 -401.89404) (xy 333.28008 -401.884855) (xy 333.273581 -401.867671) (xy 333.267812 -401.860512)
			(xy 333.245928 -401.834863) (xy 333.207839 -401.779227) (xy 333.176689 -401.719428) (xy 333.152925 -401.656329)
			(xy 333.136891 -401.590838) (xy 333.128816 -401.523898) (xy 333.128818 -401.456472) (xy 333.136896 -401.389532)
			(xy 333.152934 -401.324042) (xy 333.176701 -401.260944) (xy 333.207855 -401.201148) (xy 333.245946 -401.145513)
			(xy 333.267812 -401.119848) (xy 333.273615 -401.112707) (xy 333.280125 -401.095513) (xy 333.280512 -401.08632)
			(xy 333.280512 -400.92884) (xy 333.280949 -400.918719) (xy 333.288686 -400.900014) (xy 333.302997 -400.885698)
			(xy 333.321699 -400.877953) (xy 333.33182 -400.877532) (xy 334.0481 -400.877532) (xy 334.058226 -400.877917)
			(xy 334.076936 -400.885671) (xy 334.091252 -400.899997) (xy 334.098991 -400.918713) (xy 334.099408 -400.92884)
			(xy 334.099408 -401.08632) (xy 334.099807 -401.095508) (xy 334.106328 -401.112693) (xy 334.112108 -401.119848)
			(xy 334.133952 -401.14553) (xy 334.172041 -401.201162) (xy 334.203192 -401.260956) (xy 334.226957 -401.324051)
			(xy 334.242994 -401.389538) (xy 334.251071 -401.456474) (xy 334.251073 -401.523896) (xy 334.242999 -401.590833)
			(xy 334.226966 -401.656321) (xy 334.203204 -401.719417) (xy 334.200923 -401.723796) (xy 335.328975 -401.723796)
			(xy 335.328977 -401.656371) (xy 335.337055 -401.589432) (xy 335.353091 -401.523942) (xy 335.376856 -401.460845)
			(xy 335.408007 -401.401048) (xy 335.446096 -401.345412) (xy 335.46796 -401.319746) (xy 335.473769 -401.31261)
			(xy 335.480275 -401.295412) (xy 335.48066 -401.286218) (xy 335.48066 -400.793966) (xy 335.480253 -400.784779)
			(xy 335.473735 -400.767595) (xy 335.46796 -400.760438) (xy 335.446103 -400.734767) (xy 335.408017 -400.679133)
			(xy 335.376868 -400.619337) (xy 335.353106 -400.556241) (xy 335.337071 -400.490753) (xy 335.328995 -400.423816)
			(xy 335.328995 -400.356393) (xy 335.337069 -400.289456) (xy 335.353103 -400.223968) (xy 335.376865 -400.160872)
			(xy 335.408012 -400.101075) (xy 335.446098 -400.04544) (xy 335.46796 -400.019774) (xy 335.473757 -400.01263)
			(xy 335.48027 -399.995438) (xy 335.48066 -399.986246) (xy 335.48066 -399.828766) (xy 335.481099 -399.818635)
			(xy 335.488842 -399.799909) (xy 335.503143 -399.785553) (xy 335.521839 -399.777739) (xy 335.531968 -399.777204)
			(xy 336.248248 -399.777204) (xy 336.258406 -399.777583) (xy 336.27716 -399.785395) (xy 336.291482 -399.799804)
			(xy 336.299179 -399.818606) (xy 336.299556 -399.828766) (xy 336.299556 -399.986246) (xy 336.300002 -399.995429)
			(xy 336.306492 -400.012613) (xy 336.312256 -400.019774) (xy 336.334127 -400.045434) (xy 336.372219 -400.101068)
			(xy 336.403372 -400.160864) (xy 336.427138 -400.223962) (xy 336.443174 -400.289452) (xy 336.45125 -400.356392)
			(xy 336.451249 -400.423817) (xy 336.443172 -400.490756) (xy 336.427135 -400.556246) (xy 336.403368 -400.619344)
			(xy 336.372214 -400.67914) (xy 336.334122 -400.734774) (xy 336.312256 -400.760438) (xy 336.306455 -400.76758)
			(xy 336.299944 -400.784773) (xy 336.299556 -400.793966) (xy 336.299556 -401.286218) (xy 336.299967 -401.295405)
			(xy 336.306481 -401.312589) (xy 336.312256 -401.319746) (xy 336.3341 -401.345428) (xy 336.372192 -401.401059)
			(xy 336.403346 -401.460853) (xy 336.427114 -401.523948) (xy 336.443152 -401.589435) (xy 336.45123 -401.656372)
			(xy 336.451232 -401.723795) (xy 336.443158 -401.790732) (xy 336.427123 -401.856221) (xy 336.40336 -401.919317)
			(xy 336.372209 -401.979112) (xy 336.33412 -402.034746) (xy 336.312256 -402.06041) (xy 336.306467 -402.06756)
			(xy 336.299949 -402.084747) (xy 336.299556 -402.093938) (xy 336.299556 -402.251418) (xy 336.299088 -402.261546)
			(xy 336.291354 -402.280269) (xy 336.277062 -402.294625) (xy 336.258374 -402.302443) (xy 336.248248 -402.30298)
			(xy 335.531968 -402.30298) (xy 335.521809 -402.302604) (xy 335.503052 -402.294794) (xy 335.488729 -402.280384)
			(xy 335.481034 -402.261579) (xy 335.48066 -402.251418) (xy 335.48066 -402.093938) (xy 335.480218 -402.084754)
			(xy 335.473725 -402.06757) (xy 335.46796 -402.06041) (xy 335.446076 -402.034762) (xy 335.40799 -401.979124)
			(xy 335.376843 -401.919325) (xy 335.353082 -401.856226) (xy 335.337049 -401.790735) (xy 335.328975 -401.723796)
			(xy 334.200923 -401.723796) (xy 334.172056 -401.779212) (xy 334.13397 -401.834847) (xy 334.112108 -401.860512)
			(xy 334.106325 -401.867667) (xy 334.099802 -401.88485) (xy 334.099408 -401.89404) (xy 334.099408 -402.386292)
			(xy 334.09982 -402.395479) (xy 334.106332 -402.412663) (xy 334.112108 -402.41982) (xy 334.133925 -402.445524)
			(xy 334.172014 -402.501153) (xy 334.203166 -402.560944) (xy 334.226933 -402.624036) (xy 334.242972 -402.68952)
			(xy 334.251051 -402.756454) (xy 334.251055 -402.823818) (xy 337.529116 -402.823818) (xy 337.52912 -402.75651)
			(xy 337.537169 -402.689685) (xy 337.553145 -402.6243) (xy 337.576822 -402.561294) (xy 337.607859 -402.501569)
			(xy 337.645811 -402.445981) (xy 337.6676 -402.420328) (xy 337.67341 -402.413192) (xy 337.679917 -402.395994)
			(xy 337.6803 -402.3868) (xy 337.6803 -401.893532) (xy 337.679874 -401.884346) (xy 337.673371 -401.867162)
			(xy 337.6676 -401.860004) (xy 337.645794 -401.834367) (xy 337.607848 -401.778778) (xy 337.576818 -401.719052)
			(xy 337.553148 -401.656045) (xy 337.537178 -401.590662) (xy 337.529136 -401.523838) (xy 337.529137 -401.456532)
			(xy 337.537183 -401.389709) (xy 337.553157 -401.324326) (xy 337.57683 -401.261321) (xy 337.607864 -401.201596)
			(xy 337.645812 -401.146009) (xy 337.6676 -401.120356) (xy 337.673398 -401.113212) (xy 337.679912 -401.09602)
			(xy 337.6803 -401.086828) (xy 337.6803 -400.92884) (xy 337.680755 -400.918688) (xy 337.688537 -400.899937)
			(xy 337.702924 -400.885612) (xy 337.721709 -400.877911) (xy 337.731862 -400.877532) (xy 338.448142 -400.877532)
			(xy 338.45827 -400.877992) (xy 338.476991 -400.885732) (xy 338.491346 -400.900026) (xy 338.499165 -400.918714)
			(xy 338.499704 -400.92884) (xy 338.499704 -401.086828) (xy 338.5001 -401.096017) (xy 338.506623 -401.113201)
			(xy 338.512404 -401.120356) (xy 338.534171 -401.146025) (xy 338.572117 -401.20161) (xy 338.603149 -401.261332)
			(xy 338.626821 -401.324334) (xy 338.642794 -401.389714) (xy 338.650839 -401.456534) (xy 338.650841 -401.523836)
			(xy 338.6428 -401.590657) (xy 338.62683 -401.656037) (xy 338.603161 -401.719041) (xy 338.600721 -401.723737)
			(xy 339.72927 -401.723737) (xy 339.729272 -401.65643) (xy 339.737319 -401.589606) (xy 339.753294 -401.524222)
			(xy 339.77697 -401.461217) (xy 339.808006 -401.401492) (xy 339.845959 -401.345906) (xy 339.867748 -401.320254)
			(xy 339.873553 -401.313115) (xy 339.880061 -401.295919) (xy 339.880448 -401.286726) (xy 339.880448 -400.793458)
			(xy 339.880047 -400.78427) (xy 339.873526 -400.767086) (xy 339.867748 -400.75993) (xy 339.845966 -400.734273)
			(xy 339.808017 -400.678687) (xy 339.776983 -400.618965) (xy 339.753309 -400.555961) (xy 339.737335 -400.490579)
			(xy 339.729291 -400.423757) (xy 339.72929 -400.356452) (xy 339.737334 -400.28963) (xy 339.753306 -400.224248)
			(xy 339.776979 -400.161244) (xy 339.808012 -400.10152) (xy 339.845961 -400.045934) (xy 339.867748 -400.020282)
			(xy 339.873541 -400.013134) (xy 339.880056 -399.995946) (xy 339.880448 -399.986754) (xy 339.880448 -399.828766)
			(xy 339.880906 -399.818605) (xy 339.888693 -399.799833) (xy 339.90307 -399.785469) (xy 339.921848 -399.777697)
			(xy 339.93201 -399.777204) (xy 340.64829 -399.777204) (xy 340.658443 -399.777741) (xy 340.677205 -399.785506)
			(xy 340.69157 -399.799858) (xy 340.699351 -399.818613) (xy 340.699852 -399.828766) (xy 340.699852 -399.986754)
			(xy 340.700295 -399.995937) (xy 340.706787 -400.013121) (xy 340.712552 -400.020282) (xy 340.734346 -400.045929)
			(xy 340.772295 -400.101516) (xy 340.803329 -400.16124) (xy 340.827002 -400.224245) (xy 340.842975 -400.289628)
			(xy 340.851018 -400.356452) (xy 340.851018 -400.423757) (xy 340.842973 -400.490581) (xy 340.826999 -400.555963)
			(xy 340.803325 -400.618968) (xy 340.772291 -400.678692) (xy 340.734341 -400.734278) (xy 340.712552 -400.75993)
			(xy 340.706754 -400.767074) (xy 340.700242 -400.784266) (xy 340.699852 -400.793458) (xy 340.699852 -401.286726)
			(xy 340.70026 -401.295913) (xy 340.706777 -401.313097) (xy 340.712552 -401.320254) (xy 340.734318 -401.345924)
			(xy 340.772268 -401.401508) (xy 340.803303 -401.461229) (xy 340.826977 -401.524231) (xy 340.842952 -401.589611)
			(xy 340.850998 -401.656432) (xy 340.851 -401.723735) (xy 340.842958 -401.790556) (xy 340.826987 -401.855937)
			(xy 340.803316 -401.918941) (xy 340.772285 -401.978664) (xy 340.734338 -402.03425) (xy 340.712552 -402.059902)
			(xy 340.706766 -402.067055) (xy 340.700246 -402.08424) (xy 340.699852 -402.09343) (xy 340.699852 -402.251418)
			(xy 340.699381 -402.261578) (xy 340.691599 -402.28035) (xy 340.677226 -402.294715) (xy 340.65845 -402.302487)
			(xy 340.64829 -402.30298) (xy 339.93201 -402.30298) (xy 339.921855 -402.302459) (xy 339.90309 -402.294691)
			(xy 339.888725 -402.280334) (xy 339.880947 -402.261573) (xy 339.880448 -402.251418) (xy 339.880448 -402.09343)
			(xy 339.880013 -402.084246) (xy 339.873515 -402.067062) (xy 339.867748 -402.059902) (xy 339.845938 -402.034268)
			(xy 339.807989 -401.978679) (xy 339.776957 -401.918953) (xy 339.753285 -401.855946) (xy 339.737313 -401.790562)
			(xy 339.72927 -401.723737) (xy 338.600721 -401.723737) (xy 338.572133 -401.778764) (xy 338.534189 -401.834351)
			(xy 338.512404 -401.860004) (xy 338.506624 -401.867161) (xy 338.500099 -401.884342) (xy 338.499704 -401.893532)
			(xy 338.499704 -402.3868) (xy 338.500113 -402.395987) (xy 338.506628 -402.413172) (xy 338.512404 -402.420328)
			(xy 338.534143 -402.44602) (xy 338.572091 -402.501601) (xy 338.603124 -402.56132) (xy 338.626797 -402.624319)
			(xy 338.642772 -402.689696) (xy 338.65082 -402.756514) (xy 338.650824 -402.823814) (xy 338.650816 -402.823878)
			(xy 341.928884 -402.823878) (xy 341.928889 -402.75645) (xy 341.936969 -402.689509) (xy 341.95301 -402.624017)
			(xy 341.976779 -402.560918) (xy 342.007935 -402.501121) (xy 342.046029 -402.445485) (xy 342.067896 -402.41982)
			(xy 342.073709 -402.412686) (xy 342.080214 -402.395487) (xy 342.080596 -402.386292) (xy 342.080596 -401.89404)
			(xy 342.080168 -401.884855) (xy 342.073667 -401.86767) (xy 342.067896 -401.860512) (xy 342.046013 -401.834863)
			(xy 342.007925 -401.779226) (xy 341.976775 -401.719428) (xy 341.953012 -401.656329) (xy 341.936978 -401.590838)
			(xy 341.928904 -401.523898) (xy 341.928906 -401.456472) (xy 341.936984 -401.389533) (xy 341.953021 -401.324043)
			(xy 341.976787 -401.260945) (xy 342.00794 -401.201148) (xy 342.046031 -401.145513) (xy 342.067896 -401.119848)
			(xy 342.073697 -401.112706) (xy 342.080209 -401.095513) (xy 342.080596 -401.08632) (xy 342.080596 -400.92884)
			(xy 342.081049 -400.918721) (xy 342.088783 -400.900019) (xy 342.103088 -400.885703) (xy 342.121785 -400.877956)
			(xy 342.131904 -400.877532) (xy 342.848184 -400.877532) (xy 342.858309 -400.87793) (xy 342.877019 -400.885679)
			(xy 342.891335 -400.900001) (xy 342.899075 -400.918714) (xy 342.899492 -400.92884) (xy 342.899492 -401.08632)
			(xy 342.899894 -401.095508) (xy 342.906413 -401.112692) (xy 342.912192 -401.119848) (xy 342.934037 -401.145529)
			(xy 342.972126 -401.201161) (xy 343.003278 -401.260955) (xy 343.027044 -401.32405) (xy 343.043081 -401.389537)
			(xy 343.051159 -401.456474) (xy 343.051161 -401.523896) (xy 343.043087 -401.590833) (xy 343.027053 -401.656321)
			(xy 343.003291 -401.719417) (xy 343.001041 -401.723737) (xy 344.129061 -401.723737) (xy 344.129063 -401.65643)
			(xy 344.13711 -401.589606) (xy 344.153085 -401.524223) (xy 344.17676 -401.461217) (xy 344.207796 -401.401493)
			(xy 344.245747 -401.345906) (xy 344.267536 -401.320254) (xy 344.273339 -401.313114) (xy 344.279849 -401.295919)
			(xy 344.280236 -401.286726) (xy 344.280236 -400.793458) (xy 344.279838 -400.78427) (xy 344.273315 -400.767086)
			(xy 344.267536 -400.75993) (xy 344.245754 -400.734273) (xy 344.207805 -400.678687) (xy 344.176772 -400.618964)
			(xy 344.153099 -400.55596) (xy 344.137126 -400.490579) (xy 344.129081 -400.423757) (xy 344.129081 -400.356452)
			(xy 344.137124 -400.28963) (xy 344.153096 -400.224248) (xy 344.176768 -400.161244) (xy 344.207801 -400.101521)
			(xy 344.245749 -400.045934) (xy 344.267536 -400.020282) (xy 344.273327 -400.013133) (xy 344.279844 -399.995945)
			(xy 344.280236 -399.986754) (xy 344.280236 -399.828766) (xy 344.280705 -399.818606) (xy 344.288491 -399.799837)
			(xy 344.302864 -399.785473) (xy 344.321638 -399.777699) (xy 344.331798 -399.777204) (xy 345.048078 -399.777204)
			(xy 345.05823 -399.77775) (xy 345.076992 -399.785511) (xy 345.091357 -399.799861) (xy 345.099139 -399.818614)
			(xy 345.09964 -399.828766) (xy 345.09964 -399.986754) (xy 345.100086 -399.995937) (xy 345.106576 -400.013121)
			(xy 345.11234 -400.020282) (xy 345.134134 -400.045929) (xy 345.172084 -400.101516) (xy 345.203118 -400.16124)
			(xy 345.226792 -400.224245) (xy 345.242765 -400.289628) (xy 345.250809 -400.356452) (xy 345.250808 -400.423757)
			(xy 345.242763 -400.490581) (xy 345.226789 -400.555964) (xy 345.203115 -400.618968) (xy 345.172079 -400.678692)
			(xy 345.134129 -400.734278) (xy 345.11234 -400.75993) (xy 345.106541 -400.767073) (xy 345.100029 -400.784265)
			(xy 345.09964 -400.793458) (xy 345.09964 -401.286726) (xy 345.100051 -401.295913) (xy 345.106566 -401.313096)
			(xy 345.11234 -401.320254) (xy 345.134107 -401.345924) (xy 345.172057 -401.401507) (xy 345.203093 -401.461228)
			(xy 345.226768 -401.52423) (xy 345.242743 -401.589611) (xy 345.250789 -401.656432) (xy 345.250791 -401.723735)
			(xy 345.242749 -401.790557) (xy 345.226778 -401.855938) (xy 345.203106 -401.918942) (xy 345.172074 -401.978664)
			(xy 345.134127 -402.03425) (xy 345.11234 -402.059902) (xy 345.106553 -402.067053) (xy 345.100034 -402.084239)
			(xy 345.09964 -402.09343) (xy 345.09964 -402.251418) (xy 345.09925 -402.261593) (xy 345.091455 -402.280393)
			(xy 345.077059 -402.294778) (xy 345.058254 -402.302558) (xy 345.048078 -402.30298) (xy 344.331798 -402.30298)
			(xy 344.321642 -402.302469) (xy 344.302877 -402.294697) (xy 344.288512 -402.280337) (xy 344.280735 -402.261574)
			(xy 344.280236 -402.251418) (xy 344.280236 -402.09343) (xy 344.279803 -402.084245) (xy 344.273304 -402.067061)
			(xy 344.267536 -402.059902) (xy 344.245727 -402.034268) (xy 344.207779 -401.978679) (xy 344.176746 -401.918953)
			(xy 344.153075 -401.855946) (xy 344.137104 -401.790561) (xy 344.129061 -401.723737) (xy 343.001041 -401.723737)
			(xy 342.972142 -401.779213) (xy 342.934055 -401.834847) (xy 342.912192 -401.860512) (xy 342.906407 -401.867665)
			(xy 342.899886 -401.88485) (xy 342.899492 -401.89404) (xy 342.899492 -402.386292) (xy 342.899908 -402.395479)
			(xy 342.906418 -402.412663) (xy 342.912192 -402.41982) (xy 342.934009 -402.445524) (xy 342.9721 -402.501153)
			(xy 343.003253 -402.560944) (xy 343.02702 -402.624035) (xy 343.043059 -402.68952) (xy 343.051139 -402.756454)
			(xy 343.051143 -402.823819) (xy 346.329179 -402.823819) (xy 346.329184 -402.756509) (xy 346.337233 -402.689682)
			(xy 346.353213 -402.624297) (xy 346.376893 -402.56129) (xy 346.407934 -402.501566) (xy 346.445892 -402.445979)
			(xy 346.467684 -402.420328) (xy 346.473492 -402.413191) (xy 346.48 -402.395994) (xy 346.480384 -402.3868)
			(xy 346.480384 -401.893532) (xy 346.479962 -401.884346) (xy 346.473457 -401.867161) (xy 346.467684 -401.860004)
			(xy 346.445875 -401.834369) (xy 346.407924 -401.778781) (xy 346.376889 -401.719055) (xy 346.353216 -401.656049)
			(xy 346.337243 -401.590664) (xy 346.3292 -401.523839) (xy 346.329201 -401.456531) (xy 346.337248 -401.389707)
			(xy 346.353225 -401.324323) (xy 346.376902 -401.261317) (xy 346.40794 -401.201593) (xy 346.445894 -401.146008)
			(xy 346.467684 -401.120356) (xy 346.47348 -401.11321) (xy 346.479995 -401.09602) (xy 346.480384 -401.086828)
			(xy 346.480384 -400.92884) (xy 346.480854 -400.91869) (xy 346.488634 -400.899942) (xy 346.503015 -400.885618)
			(xy 346.521795 -400.877914) (xy 346.531946 -400.877532) (xy 347.248226 -400.877532) (xy 347.258353 -400.878005)
			(xy 347.277074 -400.88574) (xy 347.291429 -400.90003) (xy 347.299249 -400.918715) (xy 347.299788 -400.92884)
			(xy 347.299788 -401.086828) (xy 347.300187 -401.096016) (xy 347.306709 -401.1132) (xy 347.312488 -401.120356)
			(xy 347.334255 -401.146025) (xy 347.372203 -401.201609) (xy 347.403236 -401.261331) (xy 347.426908 -401.324333)
			(xy 347.442882 -401.389713) (xy 347.450927 -401.456533) (xy 347.450929 -401.523836) (xy 347.442887 -401.590657)
			(xy 347.426917 -401.656038) (xy 347.403248 -401.719042) (xy 347.400809 -401.723737) (xy 374.929092 -401.723737)
			(xy 374.929094 -401.65643) (xy 374.937141 -401.589605) (xy 374.953117 -401.524221) (xy 374.976794 -401.461216)
			(xy 375.007832 -401.401492) (xy 375.045786 -401.345906) (xy 375.067576 -401.320254) (xy 375.073372 -401.313108)
			(xy 375.079888 -401.295918) (xy 375.080276 -401.286726) (xy 375.080276 -400.793458) (xy 375.079891 -400.784268)
			(xy 375.07336 -400.767084) (xy 375.067576 -400.75993) (xy 375.045793 -400.734273) (xy 375.007842 -400.678688)
			(xy 374.976806 -400.618966) (xy 374.953131 -400.555962) (xy 374.937157 -400.49058) (xy 374.929112 -400.423757)
			(xy 374.929111 -400.356452) (xy 374.937155 -400.289629) (xy 374.953129 -400.224247) (xy 374.976802 -400.161242)
			(xy 375.007837 -400.101519) (xy 375.045788 -400.045934) (xy 375.067576 -400.020282) (xy 375.07336 -400.013128)
			(xy 375.079883 -399.995944) (xy 375.080276 -399.986754) (xy 375.080276 -399.828766) (xy 375.080637 -399.818587)
			(xy 375.08844 -399.799785) (xy 375.102845 -399.7854) (xy 375.121659 -399.777623) (xy 375.131838 -399.777204)
			(xy 375.848118 -399.777204) (xy 375.858273 -399.777718) (xy 375.877036 -399.785492) (xy 375.891399 -399.799851)
			(xy 375.899179 -399.818611) (xy 375.89968 -399.828766) (xy 375.89968 -399.986754) (xy 375.900117 -399.995938)
			(xy 375.906612 -400.013123) (xy 375.91238 -400.020282) (xy 375.934173 -400.045929) (xy 375.972121 -400.101517)
			(xy 376.003152 -400.161241) (xy 376.026824 -400.224247) (xy 376.042796 -400.289629) (xy 376.050839 -400.356452)
			(xy 376.050839 -400.423757) (xy 376.042794 -400.49058) (xy 376.026821 -400.555962) (xy 376.003149 -400.618967)
			(xy 375.972116 -400.678691) (xy 375.934168 -400.734278) (xy 375.91238 -400.75993) (xy 375.906586 -400.767077)
			(xy 375.90007 -400.784266) (xy 375.89968 -400.793458) (xy 375.89968 -401.286726) (xy 375.900082 -401.295914)
			(xy 375.906602 -401.313098) (xy 375.91238 -401.320254) (xy 375.934146 -401.345924) (xy 375.972094 -401.401508)
			(xy 376.003127 -401.46123) (xy 376.0268 -401.524232) (xy 376.042774 -401.589612) (xy 376.05082 -401.656432)
			(xy 376.050822 -401.723735) (xy 376.04278 -401.790556) (xy 376.02681 -401.855937) (xy 376.003141 -401.91894)
			(xy 375.972111 -401.978663) (xy 375.934166 -402.03425) (xy 375.91238 -402.059902) (xy 375.906598 -402.067057)
			(xy 375.900075 -402.08424) (xy 375.89968 -402.09343) (xy 375.89968 -402.251418) (xy 375.899182 -402.261575)
			(xy 375.891405 -402.280341) (xy 375.877041 -402.294705) (xy 375.858275 -402.302482) (xy 375.848118 -402.30298)
			(xy 375.131838 -402.30298) (xy 375.121671 -402.302505) (xy 375.102881 -402.294736) (xy 375.088495 -402.280366)
			(xy 375.080706 -402.261584) (xy 375.080276 -402.251418) (xy 375.080276 -402.09343) (xy 375.079857 -402.084244)
			(xy 375.07335 -402.067059) (xy 375.067576 -402.059902) (xy 375.045766 -402.034268) (xy 375.007815 -401.97868)
			(xy 374.976781 -401.918954) (xy 374.953108 -401.855947) (xy 374.937135 -401.790562) (xy 374.929092 -401.723737)
			(xy 347.400809 -401.723737) (xy 347.372218 -401.778765) (xy 347.334274 -401.834352) (xy 347.312488 -401.860004)
			(xy 347.306706 -401.867159) (xy 347.300183 -401.884342) (xy 347.299788 -401.893532) (xy 347.299788 -402.3868)
			(xy 347.300201 -402.395987) (xy 347.306713 -402.413171) (xy 347.312488 -402.420328) (xy 347.334227 -402.44602)
			(xy 347.372176 -402.501601) (xy 347.40321 -402.561319) (xy 347.426884 -402.624319) (xy 347.442859 -402.689696)
			(xy 347.450907 -402.756514) (xy 347.450911 -402.823814) (xy 347.450903 -402.823878) (xy 377.128705 -402.823878)
			(xy 377.12871 -402.75645) (xy 377.136791 -402.689508) (xy 377.152832 -402.624016) (xy 377.176603 -402.560917)
			(xy 377.20776 -402.50112) (xy 377.245856 -402.445485) (xy 377.267724 -402.41982) (xy 377.27354 -402.412689)
			(xy 377.280042 -402.395487) (xy 377.280424 -402.386292) (xy 377.280424 -401.89404) (xy 377.279989 -401.884856)
			(xy 377.273492 -401.867671) (xy 377.267724 -401.860512) (xy 377.24584 -401.834863) (xy 377.20775 -401.779227)
			(xy 377.176599 -401.719429) (xy 377.152835 -401.65633) (xy 377.1368 -401.590838) (xy 377.128725 -401.523898)
			(xy 377.128727 -401.456472) (xy 377.136805 -401.389532) (xy 377.152843 -401.324042) (xy 377.176611 -401.260944)
			(xy 377.207765 -401.201147) (xy 377.245858 -401.145513) (xy 377.267724 -401.119848) (xy 377.273528 -401.112708)
			(xy 377.280037 -401.095513) (xy 377.280424 -401.08632) (xy 377.280424 -400.92884) (xy 377.280849 -400.918717)
			(xy 377.288589 -400.90001) (xy 377.302903 -400.885693) (xy 377.321609 -400.877951) (xy 377.331732 -400.877532)
			(xy 378.048012 -400.877532) (xy 378.058139 -400.877907) (xy 378.076849 -400.885665) (xy 378.091164 -400.899994)
			(xy 378.098904 -400.918712) (xy 378.09932 -400.92884) (xy 378.09932 -401.08632) (xy 378.099716 -401.095509)
			(xy 378.106239 -401.112693) (xy 378.11202 -401.119848) (xy 378.133864 -401.14553) (xy 378.171952 -401.201162)
			(xy 378.203102 -401.260957) (xy 378.226866 -401.324051) (xy 378.242903 -401.389538) (xy 378.25098 -401.456474)
			(xy 378.250982 -401.523896) (xy 378.242908 -401.590832) (xy 378.226875 -401.65632) (xy 378.203114 -401.719416)
			(xy 378.200833 -401.723796) (xy 379.328885 -401.723796) (xy 379.328887 -401.656371) (xy 379.336964 -401.589432)
			(xy 379.353001 -401.523942) (xy 379.376766 -401.460844) (xy 379.407918 -401.401047) (xy 379.446008 -401.345412)
			(xy 379.467872 -401.319746) (xy 379.473683 -401.312611) (xy 379.480187 -401.295412) (xy 379.480572 -401.286218)
			(xy 379.480572 -400.793966) (xy 379.480184 -400.784776) (xy 379.473656 -400.767592) (xy 379.467872 -400.760438)
			(xy 379.446015 -400.734767) (xy 379.407928 -400.679133) (xy 379.376778 -400.619337) (xy 379.353015 -400.556241)
			(xy 379.33698 -400.490753) (xy 379.328904 -400.423816) (xy 379.328904 -400.356393) (xy 379.336979 -400.289456)
			(xy 379.353013 -400.223967) (xy 379.376775 -400.160871) (xy 379.407923 -400.101075) (xy 379.446009 -400.04544)
			(xy 379.467872 -400.019774) (xy 379.473671 -400.012631) (xy 379.480182 -399.995438) (xy 379.480572 -399.986246)
			(xy 379.480572 -399.828766) (xy 379.481 -399.818633) (xy 379.488744 -399.799905) (xy 379.503049 -399.785549)
			(xy 379.521749 -399.777737) (xy 379.53188 -399.777204) (xy 380.24816 -399.777204) (xy 380.25828 -399.777649)
			(xy 380.276984 -399.785385) (xy 380.2913 -399.799693) (xy 380.299045 -399.818392) (xy 380.299468 -399.828512)
			(xy 380.299468 -399.986246) (xy 380.299911 -399.99543) (xy 380.306403 -400.012614) (xy 380.312168 -400.019774)
			(xy 380.334039 -400.045434) (xy 380.37213 -400.101068) (xy 380.403282 -400.160865) (xy 380.427047 -400.223963)
			(xy 380.443083 -400.289453) (xy 380.451159 -400.356392) (xy 380.451158 -400.423817) (xy 380.443082 -400.490756)
			(xy 380.427044 -400.556246) (xy 380.403278 -400.619343) (xy 380.372125 -400.679139) (xy 380.334033 -400.734773)
			(xy 380.312168 -400.760438) (xy 380.306369 -400.767581) (xy 380.299856 -400.784773) (xy 380.299468 -400.793966)
			(xy 380.299468 -401.286218) (xy 380.299877 -401.295405) (xy 380.306392 -401.312589) (xy 380.312168 -401.319746)
			(xy 380.334011 -401.345429) (xy 380.372103 -401.40106) (xy 380.403256 -401.460853) (xy 380.427023 -401.523948)
			(xy 380.443061 -401.589435) (xy 380.451139 -401.656372) (xy 380.451141 -401.723795) (xy 380.443067 -401.790732)
			(xy 380.427033 -401.85622) (xy 380.40327 -401.919316) (xy 380.37212 -401.979112) (xy 380.334032 -402.034745)
			(xy 380.312168 -402.06041) (xy 380.306381 -402.067562) (xy 380.299861 -402.084747) (xy 380.299468 -402.093938)
			(xy 380.299468 -402.251418) (xy 380.298989 -402.261545) (xy 380.291256 -402.280265) (xy 380.276968 -402.29462)
			(xy 380.258284 -402.30244) (xy 380.24816 -402.30298) (xy 379.53188 -402.30298) (xy 379.521754 -402.3026)
			(xy 379.503046 -402.294842) (xy 379.488731 -402.280514) (xy 379.48099 -402.261799) (xy 379.480572 -402.251672)
			(xy 379.480572 -402.093938) (xy 379.48015 -402.084752) (xy 379.473645 -402.067567) (xy 379.467872 -402.06041)
			(xy 379.445987 -402.034762) (xy 379.407901 -401.979124) (xy 379.376753 -401.919326) (xy 379.352991 -401.856227)
			(xy 379.336958 -401.790736) (xy 379.328885 -401.723796) (xy 378.200833 -401.723796) (xy 378.171967 -401.779212)
			(xy 378.133882 -401.834846) (xy 378.11202 -401.860512) (xy 378.106238 -401.867668) (xy 378.099714 -401.88485)
			(xy 378.09932 -401.89404) (xy 378.09932 -402.386292) (xy 378.099729 -402.395479) (xy 378.106243 -402.412664)
			(xy 378.11202 -402.41982) (xy 378.133836 -402.445524) (xy 378.171925 -402.501154) (xy 378.203077 -402.560945)
			(xy 378.226843 -402.624037) (xy 378.242881 -402.689521) (xy 378.25096 -402.756454) (xy 378.250965 -402.823818)
			(xy 381.529025 -402.823818) (xy 381.529029 -402.75651) (xy 381.537078 -402.689684) (xy 381.553055 -402.6243)
			(xy 381.576732 -402.561293) (xy 381.607769 -402.501568) (xy 381.645722 -402.445981) (xy 381.667512 -402.420328)
			(xy 381.673323 -402.413193) (xy 381.679829 -402.395995) (xy 381.680212 -402.3868) (xy 381.680212 -401.893532)
			(xy 381.679784 -401.884347) (xy 381.673282 -401.867162) (xy 381.667512 -401.860004) (xy 381.645705 -401.834368)
			(xy 381.607759 -401.778778) (xy 381.576728 -401.719052) (xy 381.553058 -401.656046) (xy 381.537087 -401.590662)
			(xy 381.529045 -401.523838) (xy 381.529046 -401.456532) (xy 381.537092 -401.389708) (xy 381.553066 -401.324325)
			(xy 381.57674 -401.26132) (xy 381.607774 -401.201596) (xy 381.645724 -401.146009) (xy 381.667512 -401.120356)
			(xy 381.673311 -401.113213) (xy 381.679824 -401.096021) (xy 381.680212 -401.086828) (xy 381.680212 -400.92884)
			(xy 381.680649 -400.918719) (xy 381.688386 -400.900014) (xy 381.702697 -400.885698) (xy 381.721399 -400.877953)
			(xy 381.73152 -400.877532) (xy 382.448054 -400.877532) (xy 382.458177 -400.878064) (xy 382.476895 -400.885775)
			(xy 382.491253 -400.900048) (xy 382.499075 -400.91872) (xy 382.499616 -400.92884) (xy 382.499616 -401.086828)
			(xy 382.500009 -401.096017) (xy 382.506534 -401.113201) (xy 382.512316 -401.120356) (xy 382.534085 -401.146024)
			(xy 382.572038 -401.201607) (xy 382.603074 -401.261328) (xy 382.62675 -401.32433) (xy 382.642726 -401.389711)
			(xy 382.650772 -401.456533) (xy 382.650774 -401.523837) (xy 382.642731 -401.590659) (xy 382.626759 -401.656041)
			(xy 382.603087 -401.719045) (xy 382.600649 -401.723737) (xy 383.729179 -401.723737) (xy 383.729181 -401.65643)
			(xy 383.737228 -401.589605) (xy 383.753204 -401.524222) (xy 383.77688 -401.461216) (xy 383.807917 -401.401492)
			(xy 383.84587 -401.345906) (xy 383.86766 -401.320254) (xy 383.873466 -401.313116) (xy 383.879973 -401.29592)
			(xy 383.88036 -401.286726) (xy 383.88036 -400.793458) (xy 383.879957 -400.78427) (xy 383.873437 -400.767087)
			(xy 383.86766 -400.75993) (xy 383.845878 -400.734273) (xy 383.807927 -400.678688) (xy 383.776893 -400.618965)
			(xy 383.753219 -400.555961) (xy 383.737245 -400.490579) (xy 383.7292 -400.423757) (xy 383.729199 -400.356452)
			(xy 383.737243 -400.28963) (xy 383.753216 -400.224247) (xy 383.776889 -400.161243) (xy 383.807923 -400.10152)
			(xy 383.845872 -400.045934) (xy 383.86766 -400.020282) (xy 383.873454 -400.013135) (xy 383.879969 -399.995946)
			(xy 383.88036 -399.986754) (xy 383.88036 -399.828766) (xy 383.880806 -399.818603) (xy 383.888596 -399.799829)
			(xy 383.902976 -399.785464) (xy 383.921759 -399.777695) (xy 383.931922 -399.777204) (xy 384.648202 -399.777204)
			(xy 384.658356 -399.777731) (xy 384.677118 -399.7855) (xy 384.691482 -399.799855) (xy 384.699263 -399.818613)
			(xy 384.699764 -399.828766) (xy 384.699764 -399.986754) (xy 384.700205 -399.995938) (xy 384.706698 -400.013122)
			(xy 384.712464 -400.020282) (xy 384.734258 -400.045929) (xy 384.772206 -400.101516) (xy 384.803239 -400.161241)
			(xy 384.826911 -400.224246) (xy 384.842884 -400.289629) (xy 384.850927 -400.356452) (xy 384.850927 -400.423757)
			(xy 384.842882 -400.49058) (xy 384.826909 -400.555963) (xy 384.803235 -400.618968) (xy 384.772201 -400.678691)
			(xy 384.734252 -400.734278) (xy 384.712464 -400.75993) (xy 384.706668 -400.767075) (xy 384.700154 -400.784266)
			(xy 384.699764 -400.793458) (xy 384.699764 -401.286726) (xy 384.70017 -401.295913) (xy 384.706687 -401.313097)
			(xy 384.712464 -401.320254) (xy 384.73423 -401.345924) (xy 384.772179 -401.401508) (xy 384.803213 -401.461229)
			(xy 384.826887 -401.524231) (xy 384.842861 -401.589611) (xy 384.850907 -401.656432) (xy 384.850909 -401.723735)
			(xy 384.842867 -401.790556) (xy 384.826897 -401.855937) (xy 384.803227 -401.918941) (xy 384.772196 -401.978663)
			(xy 384.73425 -402.03425) (xy 384.712464 -402.059902) (xy 384.706679 -402.067056) (xy 384.700158 -402.08424)
			(xy 384.699764 -402.09343) (xy 384.699764 -402.251418) (xy 384.699282 -402.261577) (xy 384.691502 -402.280346)
			(xy 384.677133 -402.294711) (xy 384.658361 -402.302485) (xy 384.648202 -402.30298) (xy 383.931922 -402.30298)
			(xy 383.921754 -402.302518) (xy 383.902963 -402.294744) (xy 383.888578 -402.28037) (xy 383.88079 -402.261586)
			(xy 383.88036 -402.251418) (xy 383.88036 -402.09343) (xy 383.879922 -402.084246) (xy 383.873426 -402.067062)
			(xy 383.86766 -402.059902) (xy 383.84585 -402.034268) (xy 383.8079 -401.97868) (xy 383.776867 -401.918954)
			(xy 383.753194 -401.855947) (xy 383.737222 -401.790562) (xy 383.729179 -401.723737) (xy 382.600649 -401.723737)
			(xy 382.572053 -401.778767) (xy 382.534104 -401.834352) (xy 382.512316 -401.860004) (xy 382.506537 -401.867162)
			(xy 382.500011 -401.884343) (xy 382.499616 -401.893532) (xy 382.499616 -402.3868) (xy 382.500023 -402.395988)
			(xy 382.506538 -402.413172) (xy 382.512316 -402.420328) (xy 382.534058 -402.446018) (xy 382.572011 -402.501598)
			(xy 382.603049 -402.561316) (xy 382.626726 -402.624316) (xy 382.642704 -402.689694) (xy 382.650753 -402.756513)
			(xy 382.650757 -402.823815) (xy 382.650749 -402.823878) (xy 385.928793 -402.823878) (xy 385.928798 -402.75645)
			(xy 385.936878 -402.689508) (xy 385.952919 -402.624017) (xy 385.976689 -402.560918) (xy 386.007846 -402.50112)
			(xy 386.045941 -402.445485) (xy 386.067808 -402.41982) (xy 386.073622 -402.412687) (xy 386.080126 -402.395487)
			(xy 386.080508 -402.386292) (xy 386.080508 -401.89404) (xy 386.080077 -401.884855) (xy 386.073578 -401.867671)
			(xy 386.067808 -401.860512) (xy 386.045924 -401.834863) (xy 386.007835 -401.779226) (xy 385.976685 -401.719428)
			(xy 385.952922 -401.656329) (xy 385.936887 -401.590838) (xy 385.928813 -401.523898) (xy 385.928815 -401.456472)
			(xy 385.936893 -401.389533) (xy 385.952931 -401.324042) (xy 385.976697 -401.260944) (xy 386.007851 -401.201148)
			(xy 386.045943 -401.145513) (xy 386.067808 -401.119848) (xy 386.07361 -401.112707) (xy 386.080121 -401.095513)
			(xy 386.080508 -401.08632) (xy 386.080508 -400.92884) (xy 386.080949 -400.918719) (xy 386.088686 -400.900015)
			(xy 386.102995 -400.885699) (xy 386.121695 -400.877954) (xy 386.131816 -400.877532) (xy 386.848096 -400.877532)
			(xy 386.858222 -400.87792) (xy 386.876932 -400.885673) (xy 386.891247 -400.899998) (xy 386.898987 -400.918714)
			(xy 386.899404 -400.92884) (xy 386.899404 -401.08632) (xy 386.899804 -401.095508) (xy 386.906325 -401.112692)
			(xy 386.912104 -401.119848) (xy 386.933948 -401.14553) (xy 386.972037 -401.201162) (xy 387.003189 -401.260956)
			(xy 387.026954 -401.324051) (xy 387.04299 -401.389538) (xy 387.051068 -401.456474) (xy 387.05107 -401.523896)
			(xy 387.042996 -401.590833) (xy 387.026963 -401.656321) (xy 387.003201 -401.719417) (xy 387.000951 -401.723737)
			(xy 388.12897 -401.723737) (xy 388.128972 -401.65643) (xy 388.137019 -401.589606) (xy 388.152994 -401.524222)
			(xy 388.17667 -401.461217) (xy 388.207706 -401.401492) (xy 388.245659 -401.345906) (xy 388.267448 -401.320254)
			(xy 388.273253 -401.313115) (xy 388.279761 -401.295919) (xy 388.280148 -401.286726) (xy 388.280148 -400.793458)
			(xy 388.279747 -400.78427) (xy 388.273226 -400.767086) (xy 388.267448 -400.75993) (xy 388.245666 -400.734273)
			(xy 388.207717 -400.678687) (xy 388.176683 -400.618965) (xy 388.153009 -400.555961) (xy 388.137035 -400.490579)
			(xy 388.128991 -400.423757) (xy 388.12899 -400.356452) (xy 388.137034 -400.28963) (xy 388.153006 -400.224248)
			(xy 388.176679 -400.161244) (xy 388.207712 -400.10152) (xy 388.245661 -400.045934) (xy 388.267448 -400.020282)
			(xy 388.273241 -400.013134) (xy 388.279756 -399.995946) (xy 388.280148 -399.986754) (xy 388.280148 -399.828766)
			(xy 388.280606 -399.818605) (xy 388.288393 -399.799833) (xy 388.30277 -399.785469) (xy 388.321548 -399.777697)
			(xy 388.33171 -399.777204) (xy 389.04799 -399.777204) (xy 389.058143 -399.777741) (xy 389.076905 -399.785506)
			(xy 389.09127 -399.799858) (xy 389.099051 -399.818613) (xy 389.099552 -399.828766) (xy 389.099552 -399.986754)
			(xy 389.099995 -399.995937) (xy 389.106487 -400.013121) (xy 389.112252 -400.020282) (xy 389.134046 -400.045929)
			(xy 389.171995 -400.101516) (xy 389.203029 -400.16124) (xy 389.226702 -400.224245) (xy 389.242675 -400.289628)
			(xy 389.250718 -400.356452) (xy 389.250718 -400.423757) (xy 389.242673 -400.490581) (xy 389.226699 -400.555963)
			(xy 389.203025 -400.618968) (xy 389.171991 -400.678692) (xy 389.134041 -400.734278) (xy 389.112252 -400.75993)
			(xy 389.106454 -400.767074) (xy 389.099942 -400.784266) (xy 389.099552 -400.793458) (xy 389.099552 -401.286726)
			(xy 389.09996 -401.295913) (xy 389.106477 -401.313097) (xy 389.112252 -401.320254) (xy 389.134018 -401.345924)
			(xy 389.171968 -401.401508) (xy 389.203003 -401.461229) (xy 389.226677 -401.524231) (xy 389.242652 -401.589611)
			(xy 389.250698 -401.656432) (xy 389.2507 -401.723735) (xy 389.242658 -401.790556) (xy 389.226687 -401.855937)
			(xy 389.203016 -401.918941) (xy 389.171985 -401.978664) (xy 389.134038 -402.03425) (xy 389.112252 -402.059902)
			(xy 389.106466 -402.067055) (xy 389.099946 -402.08424) (xy 389.099552 -402.09343) (xy 389.099552 -402.251418)
			(xy 389.099081 -402.261578) (xy 389.091299 -402.28035) (xy 389.076926 -402.294715) (xy 389.05815 -402.302487)
			(xy 389.04799 -402.30298) (xy 388.33171 -402.30298) (xy 388.321555 -402.302459) (xy 388.30279 -402.294691)
			(xy 388.288425 -402.280334) (xy 388.280647 -402.261573) (xy 388.280148 -402.251418) (xy 388.280148 -402.09343)
			(xy 388.279713 -402.084246) (xy 388.273215 -402.067062) (xy 388.267448 -402.059902) (xy 388.245638 -402.034268)
			(xy 388.207689 -401.978679) (xy 388.176657 -401.918953) (xy 388.152985 -401.855946) (xy 388.137013 -401.790562)
			(xy 388.12897 -401.723737) (xy 387.000951 -401.723737) (xy 386.972053 -401.779212) (xy 386.933967 -401.834847)
			(xy 386.912104 -401.860512) (xy 386.90632 -401.867666) (xy 386.899798 -401.88485) (xy 386.899404 -401.89404)
			(xy 386.899404 -402.386292) (xy 386.899817 -402.395479) (xy 386.906329 -402.412663) (xy 386.912104 -402.41982)
			(xy 386.933921 -402.445524) (xy 386.972011 -402.501153) (xy 387.003163 -402.560944) (xy 387.02693 -402.624036)
			(xy 387.042968 -402.68952) (xy 387.051048 -402.756454) (xy 387.051052 -402.823818) (xy 390.329113 -402.823818)
			(xy 390.329117 -402.75651) (xy 390.337166 -402.689685) (xy 390.353142 -402.6243) (xy 390.376819 -402.561294)
			(xy 390.407855 -402.501569) (xy 390.445807 -402.445981) (xy 390.467596 -402.420328) (xy 390.473405 -402.413192)
			(xy 390.479912 -402.395994) (xy 390.480296 -402.3868) (xy 390.480296 -401.893532) (xy 390.479871 -401.884346)
			(xy 390.473368 -401.867162) (xy 390.467596 -401.860004) (xy 390.44579 -401.834367) (xy 390.407845 -401.778778)
			(xy 390.376815 -401.719052) (xy 390.353145 -401.656045) (xy 390.337174 -401.590661) (xy 390.329133 -401.523838)
			(xy 390.329134 -401.456532) (xy 390.33718 -401.389709) (xy 390.353154 -401.324326) (xy 390.376827 -401.261321)
			(xy 390.40786 -401.201596) (xy 390.445808 -401.146009) (xy 390.467596 -401.120356) (xy 390.473393 -401.113211)
			(xy 390.479908 -401.09602) (xy 390.480296 -401.086828) (xy 390.480296 -400.92884) (xy 390.480749 -400.918721)
			(xy 390.488483 -400.900019) (xy 390.502788 -400.885703) (xy 390.521485 -400.877956) (xy 390.531604 -400.877532)
			(xy 391.248138 -400.877532) (xy 391.258266 -400.877995) (xy 391.276987 -400.885734) (xy 391.291341 -400.900027)
			(xy 391.299161 -400.918714) (xy 391.2997 -400.92884) (xy 391.2997 -401.086828) (xy 391.300096 -401.096017)
			(xy 391.30662 -401.113201) (xy 391.3124 -401.120356) (xy 391.334167 -401.146025) (xy 391.372114 -401.20161)
			(xy 391.403146 -401.261331) (xy 391.426818 -401.324334) (xy 391.442791 -401.389713) (xy 391.450836 -401.456534)
			(xy 391.450838 -401.523836) (xy 391.442797 -401.590657) (xy 391.426827 -401.656038) (xy 391.403158 -401.719041)
			(xy 391.372129 -401.778764) (xy 391.334185 -401.834351) (xy 391.3124 -401.860004) (xy 391.306619 -401.86716)
			(xy 391.300095 -401.884342) (xy 391.2997 -401.893532) (xy 391.2997 -402.3868) (xy 391.30011 -402.395987)
			(xy 391.306624 -402.413171) (xy 391.3124 -402.420328) (xy 391.334139 -402.446019) (xy 391.372087 -402.501601)
			(xy 391.40312 -402.56132) (xy 391.426794 -402.624319) (xy 391.442769 -402.689696) (xy 391.450817 -402.756514)
			(xy 391.450821 -402.823814) (xy 391.442782 -402.890633) (xy 391.426815 -402.956012) (xy 391.40315 -403.019014)
			(xy 391.372124 -403.078737) (xy 391.334184 -403.134323) (xy 391.3124 -403.159976) (xy 391.306589 -403.167111)
			(xy 391.300083 -403.184309) (xy 391.2997 -403.193504) (xy 391.2997 -403.351492) (xy 391.299277 -403.361614)
			(xy 391.291532 -403.380317) (xy 391.277217 -403.394632) (xy 391.258514 -403.402377) (xy 391.248392 -403.4028)
			(xy 390.531858 -403.4028) (xy 390.521734 -403.402309) (xy 390.503019 -403.394575) (xy 390.488666 -403.380291)
			(xy 390.480841 -403.361614) (xy 390.480296 -403.351492) (xy 390.480296 -403.193504) (xy 390.479885 -403.184317)
			(xy 390.473372 -403.167133) (xy 390.467596 -403.159976) (xy 390.445763 -403.134362) (xy 390.407818 -403.078769)
			(xy 390.376789 -403.01904) (xy 390.353121 -402.95603) (xy 390.337153 -402.890644) (xy 390.329113 -402.823818)
			(xy 387.051052 -402.823818) (xy 387.051052 -402.823874) (xy 387.042981 -402.890809) (xy 387.026951 -402.956295)
			(xy 387.003193 -403.01939) (xy 386.972048 -403.079185) (xy 386.933965 -403.134819) (xy 386.912104 -403.160484)
			(xy 386.90629 -403.167617) (xy 386.899785 -403.184817) (xy 386.899404 -403.194012) (xy 386.899404 -403.351492)
			(xy 386.898978 -403.361613) (xy 386.891233 -403.380316) (xy 386.87692 -403.394631) (xy 386.858217 -403.402377)
			(xy 386.848096 -403.4028) (xy 386.131816 -403.4028) (xy 386.121695 -403.402371) (xy 386.102991 -403.394628)
			(xy 386.088676 -403.380315) (xy 386.080931 -403.361613) (xy 386.080508 -403.351492) (xy 386.080508 -403.194012)
			(xy 386.08009 -403.184826) (xy 386.073582 -403.167641) (xy 386.067808 -403.160484) (xy 386.045897 -403.134858)
			(xy 386.007809 -403.079218) (xy 385.97666 -403.019416) (xy 385.952898 -402.956314) (xy 385.936865 -402.89082)
			(xy 385.928793 -402.823878) (xy 382.650749 -402.823878) (xy 382.642717 -402.890635) (xy 382.626748 -402.956015)
			(xy 382.603078 -403.019018) (xy 382.572048 -403.07874) (xy 382.534102 -403.134324) (xy 382.512316 -403.159976)
			(xy 382.506507 -403.167112) (xy 382.499999 -403.18431) (xy 382.499616 -403.193504) (xy 382.499616 -403.351492)
			(xy 382.499109 -403.361598) (xy 382.491377 -403.380273) (xy 382.477087 -403.394568) (xy 382.458414 -403.402306)
			(xy 382.448308 -403.4028) (xy 381.731774 -403.4028) (xy 381.721651 -403.402296) (xy 381.702936 -403.394567)
			(xy 381.688582 -403.380287) (xy 381.680757 -403.361613) (xy 381.680212 -403.351492) (xy 381.680212 -403.193504)
			(xy 381.679797 -403.184317) (xy 381.673286 -403.167133) (xy 381.667512 -403.159976) (xy 381.645678 -403.134362)
			(xy 381.607732 -403.07877) (xy 381.576703 -403.019041) (xy 381.553034 -402.956031) (xy 381.537065 -402.890644)
			(xy 381.529025 -402.823818) (xy 378.250965 -402.823818) (xy 378.250965 -402.823874) (xy 378.242894 -402.890808)
			(xy 378.226864 -402.956294) (xy 378.203106 -403.019389) (xy 378.171962 -403.079184) (xy 378.13388 -403.134818)
			(xy 378.11202 -403.160484) (xy 378.106208 -403.167618) (xy 378.099702 -403.184817) (xy 378.09932 -403.194012)
			(xy 378.09932 -403.351492) (xy 378.098809 -403.361598) (xy 378.091078 -403.380272) (xy 378.076789 -403.394566)
			(xy 378.058118 -403.402305) (xy 378.048012 -403.4028) (xy 377.331732 -403.4028) (xy 377.321612 -403.402358)
			(xy 377.302909 -403.39462) (xy 377.288593 -403.380312) (xy 377.280847 -403.361612) (xy 377.280424 -403.351492)
			(xy 377.280424 -403.194012) (xy 377.280002 -403.184826) (xy 377.273496 -403.167642) (xy 377.267724 -403.160484)
			(xy 377.245812 -403.134858) (xy 377.207723 -403.079218) (xy 377.176573 -403.019417) (xy 377.152811 -402.956315)
			(xy 377.136778 -402.890821) (xy 377.128705 -402.823878) (xy 347.450903 -402.823878) (xy 347.442872 -402.890633)
			(xy 347.426905 -402.956012) (xy 347.403239 -403.019015) (xy 347.372213 -403.078737) (xy 347.334272 -403.134323)
			(xy 347.312488 -403.159976) (xy 347.306675 -403.16711) (xy 347.300171 -403.184309) (xy 347.299788 -403.193504)
			(xy 347.299788 -403.351492) (xy 347.299372 -403.361647) (xy 347.291576 -403.380402) (xy 347.277178 -403.394726)
			(xy 347.258383 -403.402424) (xy 347.248226 -403.4028) (xy 346.531946 -403.4028) (xy 346.521827 -403.402237)
			(xy 346.503115 -403.394532) (xy 346.488758 -403.380269) (xy 346.48093 -403.361607) (xy 346.480384 -403.351492)
			(xy 346.480384 -403.193504) (xy 346.479975 -403.184317) (xy 346.473461 -403.167132) (xy 346.467684 -403.159976)
			(xy 346.445847 -403.134364) (xy 346.407897 -403.078772) (xy 346.376863 -403.019044) (xy 346.353191 -402.956034)
			(xy 346.33722 -402.890646) (xy 346.329179 -402.823819) (xy 343.051143 -402.823819) (xy 343.051143 -402.823874)
			(xy 343.043072 -402.890809) (xy 343.027042 -402.956296) (xy 343.003282 -403.019391) (xy 342.972137 -403.079185)
			(xy 342.934053 -403.134819) (xy 342.912192 -403.160484) (xy 342.906376 -403.167616) (xy 342.899873 -403.184817)
			(xy 342.899492 -403.194012) (xy 342.899492 -403.351492) (xy 342.899077 -403.361615) (xy 342.89133 -403.38032)
			(xy 342.877013 -403.394635) (xy 342.858307 -403.402379) (xy 342.848184 -403.4028) (xy 342.131904 -403.4028)
			(xy 342.121782 -403.402381) (xy 342.103078 -403.394634) (xy 342.088764 -403.380318) (xy 342.081019 -403.361614)
			(xy 342.080596 -403.351492) (xy 342.080596 -403.194012) (xy 342.080181 -403.184825) (xy 342.073671 -403.167641)
			(xy 342.067896 -403.160484) (xy 342.045985 -403.134858) (xy 342.007898 -403.079217) (xy 341.97675 -403.019416)
			(xy 341.952988 -402.956314) (xy 341.936956 -402.89082) (xy 341.928884 -402.823878) (xy 338.650816 -402.823878)
			(xy 338.642785 -402.890633) (xy 338.626819 -402.956012) (xy 338.603153 -403.019014) (xy 338.572128 -403.078737)
			(xy 338.534188 -403.134323) (xy 338.512404 -403.159976) (xy 338.506593 -403.167111) (xy 338.500087 -403.184309)
			(xy 338.499704 -403.193504) (xy 338.499704 -403.351492) (xy 338.499272 -403.361645) (xy 338.49148 -403.380397)
			(xy 338.477086 -403.39472) (xy 338.458297 -403.402421) (xy 338.448142 -403.4028) (xy 337.731862 -403.4028)
			(xy 337.721738 -403.402306) (xy 337.703023 -403.394573) (xy 337.68867 -403.38029) (xy 337.680845 -403.361614)
			(xy 337.6803 -403.351492) (xy 337.6803 -403.193504) (xy 337.679888 -403.184317) (xy 337.673375 -403.167133)
			(xy 337.6676 -403.159976) (xy 337.645766 -403.134362) (xy 337.607822 -403.078769) (xy 337.576793 -403.01904)
			(xy 337.553124 -402.956031) (xy 337.537156 -402.890644) (xy 337.529116 -402.823818) (xy 334.251055 -402.823818)
			(xy 334.251055 -402.823874) (xy 334.242984 -402.890809) (xy 334.226954 -402.956295) (xy 334.203196 -403.01939)
			(xy 334.172051 -403.079185) (xy 334.133969 -403.134819) (xy 334.112108 -403.160484) (xy 334.106294 -403.167617)
			(xy 334.09979 -403.184817) (xy 334.099408 -403.194012) (xy 334.099408 -403.351492) (xy 334.098978 -403.361613)
			(xy 334.091234 -403.380315) (xy 334.076922 -403.394629) (xy 334.058221 -403.402376) (xy 334.0481 -403.4028)
			(xy 333.33182 -403.4028) (xy 333.321699 -403.402368) (xy 333.302996 -403.394626) (xy 333.288681 -403.380315)
			(xy 333.280935 -403.361613) (xy 333.280512 -403.351492) (xy 333.280512 -403.194012) (xy 333.280093 -403.184826)
			(xy 333.273585 -403.167642) (xy 333.267812 -403.160484) (xy 333.2459 -403.134858) (xy 333.207812 -403.079218)
			(xy 333.176663 -403.019417) (xy 333.152901 -402.956315) (xy 333.136869 -402.890821) (xy 333.128796 -402.823878)
			(xy 326.525636 -402.823878) (xy 326.525636 -405.623648) (xy 330.929194 -405.623648) (xy 330.929195 -405.556343)
			(xy 330.93724 -405.489519) (xy 330.953214 -405.424136) (xy 330.976889 -405.361131) (xy 331.007924 -405.301408)
			(xy 331.045875 -405.245822) (xy 331.067664 -405.22017) (xy 331.073464 -405.213027) (xy 331.079975 -405.195835)
			(xy 331.080364 -405.186642) (xy 331.080364 -404.693374) (xy 331.079952 -404.684187) (xy 331.073438 -404.667004)
			(xy 331.067664 -404.659846) (xy 331.045897 -404.634176) (xy 331.007946 -404.578593) (xy 330.976911 -404.518872)
			(xy 330.953235 -404.45587) (xy 330.93726 -404.390489) (xy 330.929214 -404.323668) (xy 330.929212 -404.256365)
			(xy 330.937254 -404.189543) (xy 330.953226 -404.124162) (xy 330.976897 -404.061158) (xy 331.007929 -404.001435)
			(xy 331.045877 -403.94585) (xy 331.067664 -403.920198) (xy 331.073452 -403.913047) (xy 331.07997 -403.895861)
			(xy 331.080364 -403.88667) (xy 331.080364 -403.728682) (xy 331.08075 -403.718506) (xy 331.088546 -403.699706)
			(xy 331.102943 -403.685321) (xy 331.12175 -403.677541) (xy 331.131926 -403.67712) (xy 331.848206 -403.67712)
			(xy 331.858362 -403.677628) (xy 331.877128 -403.685401) (xy 331.891492 -403.699762) (xy 331.899269 -403.718526)
			(xy 331.899768 -403.728682) (xy 331.899768 -403.88667) (xy 331.9002 -403.895855) (xy 331.906699 -403.913039)
			(xy 331.912468 -403.920198) (xy 331.934277 -403.945832) (xy 331.972225 -404.001422) (xy 332.003257 -404.061148)
			(xy 332.026928 -404.124154) (xy 332.042899 -404.189539) (xy 332.050942 -404.256363) (xy 332.05094 -404.32367)
			(xy 332.042893 -404.390494) (xy 332.026918 -404.455877) (xy 332.003243 -404.518883) (xy 331.972208 -404.578607)
			(xy 331.934257 -404.634194) (xy 331.912468 -404.659846) (xy 331.906665 -404.666987) (xy 331.900155 -404.684181)
			(xy 331.899768 -404.693374) (xy 331.899768 -405.186642) (xy 331.900165 -405.19583) (xy 331.906689 -405.213014)
			(xy 331.912468 -405.22017) (xy 331.93425 -405.245827) (xy 331.972198 -405.301413) (xy 332.003231 -405.361136)
			(xy 332.026904 -405.42414) (xy 332.042877 -405.489521) (xy 332.050922 -405.556343) (xy 332.050923 -405.623648)
			(xy 332.042879 -405.69047) (xy 332.026907 -405.755852) (xy 332.003235 -405.818856) (xy 331.972203 -405.878579)
			(xy 331.934255 -405.934166) (xy 331.912468 -405.959818) (xy 331.906677 -405.966967) (xy 331.90016 -405.984155)
			(xy 331.899768 -405.993346) (xy 331.899768 -406.151334) (xy 331.899295 -406.161493) (xy 331.89151 -406.180262)
			(xy 331.877138 -406.194626) (xy 331.858365 -406.2024) (xy 331.848206 -406.202896) (xy 331.131926 -406.202896)
			(xy 331.121774 -406.202346) (xy 331.103012 -406.194587) (xy 331.088647 -406.180238) (xy 331.080865 -406.161485)
			(xy 331.080364 -406.151334) (xy 331.080364 -405.993346) (xy 331.079918 -405.984163) (xy 331.073428 -405.966979)
			(xy 331.067664 -405.959818) (xy 331.04587 -405.934171) (xy 331.007919 -405.878584) (xy 330.976885 -405.81886)
			(xy 330.953212 -405.755855) (xy 330.937238 -405.690472) (xy 330.929194 -405.623648) (xy 326.525636 -405.623648)
			(xy 326.525636 -406.723789) (xy 333.128808 -406.723789) (xy 333.128811 -406.656363) (xy 333.13689 -406.589422)
			(xy 333.152929 -406.523931) (xy 333.176697 -406.460833) (xy 333.207852 -406.401036) (xy 333.245946 -406.345401)
			(xy 333.267812 -406.319736) (xy 333.27362 -406.312599) (xy 333.280127 -406.295402) (xy 333.280512 -406.286208)
			(xy 333.280512 -405.793956) (xy 333.28012 -405.784767) (xy 333.273594 -405.767583) (xy 333.267812 -405.760428)
			(xy 333.245944 -405.734766) (xy 333.207854 -405.679131) (xy 333.176703 -405.619335) (xy 333.152939 -405.556238)
			(xy 333.136903 -405.490748) (xy 333.128827 -405.423809) (xy 333.128828 -405.356385) (xy 333.136904 -405.289446)
			(xy 333.15294 -405.223957) (xy 333.176706 -405.16086) (xy 333.207857 -405.101063) (xy 333.245947 -405.045429)
			(xy 333.267812 -405.019764) (xy 333.273608 -405.012618) (xy 333.280123 -404.995428) (xy 333.280512 -404.986236)
			(xy 333.280512 -404.828756) (xy 333.280949 -404.818643) (xy 333.288704 -404.799961) (xy 333.303015 -404.785668)
			(xy 333.321706 -404.777937) (xy 333.33182 -404.777448) (xy 334.0481 -404.777448) (xy 334.058202 -404.777984)
			(xy 334.076871 -404.785712) (xy 334.091163 -404.799993) (xy 334.098907 -404.818654) (xy 334.099408 -404.828756)
			(xy 334.099408 -404.986236) (xy 334.099799 -404.995425) (xy 334.106326 -405.01261) (xy 334.112108 -405.019764)
			(xy 334.133968 -405.045433) (xy 334.172056 -405.101067) (xy 334.203206 -405.160863) (xy 334.226971 -405.223959)
			(xy 334.243006 -405.289448) (xy 334.251082 -405.356385) (xy 334.251082 -405.423809) (xy 334.243007 -405.490746)
			(xy 334.226972 -405.556235) (xy 334.203209 -405.619332) (xy 334.20093 -405.623707) (xy 335.328987 -405.623707)
			(xy 335.328987 -405.556284) (xy 335.337063 -405.489346) (xy 335.353098 -405.423857) (xy 335.376861 -405.36076)
			(xy 335.40801 -405.300963) (xy 335.446097 -405.245328) (xy 335.46796 -405.219662) (xy 335.473763 -405.212521)
			(xy 335.480272 -405.195327) (xy 335.48066 -405.186134) (xy 335.48066 -404.693882) (xy 335.480245 -404.684696)
			(xy 335.473733 -404.667512) (xy 335.46796 -404.660354) (xy 335.446119 -404.63467) (xy 335.408032 -404.579037)
			(xy 335.376883 -404.519243) (xy 335.353119 -404.456149) (xy 335.337083 -404.390663) (xy 335.329006 -404.323727)
			(xy 335.329004 -404.256306) (xy 335.337078 -404.18937) (xy 335.353109 -404.123883) (xy 335.376869 -404.060787)
			(xy 335.408015 -404.000991) (xy 335.446099 -403.945356) (xy 335.46796 -403.91969) (xy 335.473751 -403.912541)
			(xy 335.480267 -403.895353) (xy 335.48066 -403.886162) (xy 335.48066 -403.728682) (xy 335.481112 -403.718552)
			(xy 335.48885 -403.699826) (xy 335.503147 -403.68547) (xy 335.52184 -403.677655) (xy 335.531968 -403.67712)
			(xy 336.248248 -403.67712) (xy 336.258408 -403.677483) (xy 336.277165 -403.685298) (xy 336.291487 -403.699713)
			(xy 336.299182 -403.71852) (xy 336.299556 -403.728682) (xy 336.299556 -403.886162) (xy 336.299995 -403.895346)
			(xy 336.30649 -403.91253) (xy 336.312256 -403.91969) (xy 336.334143 -403.945337) (xy 336.372234 -404.000973)
			(xy 336.403386 -404.060771) (xy 336.427151 -404.123871) (xy 336.443186 -404.189362) (xy 336.451261 -404.256303)
			(xy 336.451259 -404.32373) (xy 336.443181 -404.39067) (xy 336.427141 -404.456161) (xy 336.403373 -404.519259)
			(xy 336.372217 -404.579056) (xy 336.334123 -404.634689) (xy 336.312256 -404.660354) (xy 336.306449 -404.667491)
			(xy 336.299941 -404.684688) (xy 336.299556 -404.693882) (xy 336.299556 -405.186134) (xy 336.29996 -405.195322)
			(xy 336.306479 -405.212505) (xy 336.312256 -405.219662) (xy 336.334116 -405.245331) (xy 336.372207 -405.300964)
			(xy 336.403361 -405.360759) (xy 336.427127 -405.423856) (xy 336.443164 -405.489345) (xy 336.451242 -405.556283)
			(xy 336.451242 -405.623708) (xy 336.443166 -405.690646) (xy 336.42713 -405.756135) (xy 336.403365 -405.819232)
			(xy 336.372212 -405.879028) (xy 336.334121 -405.934662) (xy 336.312256 -405.960326) (xy 336.30646 -405.967472)
			(xy 336.299946 -405.984662) (xy 336.299556 -405.993854) (xy 336.299556 -406.151334) (xy 336.299101 -406.161463)
			(xy 336.291362 -406.180186) (xy 336.277066 -406.194541) (xy 336.258375 -406.202359) (xy 336.248248 -406.202896)
			(xy 335.531968 -406.202896) (xy 335.521811 -406.202505) (xy 335.503057 -406.194698) (xy 335.488735 -406.180292)
			(xy 335.481037 -406.161493) (xy 335.48066 -406.151334) (xy 335.48066 -405.993854) (xy 335.48021 -405.984671)
			(xy 335.473722 -405.967487) (xy 335.46796 -405.960326) (xy 335.446092 -405.934665) (xy 335.408006 -405.879029)
			(xy 335.376857 -405.819232) (xy 335.353095 -405.756134) (xy 335.337062 -405.690645) (xy 335.328987 -405.623707)
			(xy 334.20093 -405.623707) (xy 334.172059 -405.679128) (xy 334.133971 -405.734763) (xy 334.112108 -405.760428)
			(xy 334.106318 -405.767578) (xy 334.099799 -405.784765) (xy 334.099408 -405.793956) (xy 334.099408 -406.286208)
			(xy 334.099813 -406.295396) (xy 334.10633 -406.31258) (xy 334.112108 -406.319736) (xy 334.13394 -406.345427)
			(xy 334.172029 -406.401058) (xy 334.203181 -406.460851) (xy 334.226947 -406.523944) (xy 334.242984 -406.58943)
			(xy 334.251062 -406.656365) (xy 334.251065 -406.723729) (xy 337.529127 -406.723729) (xy 337.52913 -406.656423)
			(xy 337.537177 -406.589598) (xy 337.553152 -406.524215) (xy 337.576827 -406.461209) (xy 337.607861 -406.401484)
			(xy 337.645812 -406.345897) (xy 337.6676 -406.320244) (xy 337.673403 -406.313103) (xy 337.679914 -406.295909)
			(xy 337.6803 -406.286716) (xy 337.6803 -405.793448) (xy 337.679867 -405.784263) (xy 337.673369 -405.767079)
			(xy 337.6676 -405.75992) (xy 337.64581 -405.734271) (xy 337.607863 -405.678683) (xy 337.576832 -405.618958)
			(xy 337.553162 -405.555954) (xy 337.53719 -405.490572) (xy 337.529147 -405.423749) (xy 337.529147 -405.356445)
			(xy 337.537191 -405.289622) (xy 337.553163 -405.224241) (xy 337.576835 -405.161236) (xy 337.607866 -405.101512)
			(xy 337.645813 -405.045925) (xy 337.6676 -405.020272) (xy 337.673391 -405.013123) (xy 337.679909 -404.995935)
			(xy 337.6803 -404.986744) (xy 337.6803 -404.828756) (xy 337.680686 -404.818599) (xy 337.688496 -404.799846)
			(xy 337.702903 -404.785524) (xy 337.721703 -404.777826) (xy 337.731862 -404.777448) (xy 338.448142 -404.777448)
			(xy 338.458272 -404.777892) (xy 338.476996 -404.785635) (xy 338.491351 -404.799934) (xy 338.499167 -404.818628)
			(xy 338.499704 -404.828756) (xy 338.499704 -404.986744) (xy 338.500092 -404.995934) (xy 338.506621 -405.013118)
			(xy 338.512404 -405.020272) (xy 338.534186 -405.045928) (xy 338.572133 -405.101515) (xy 338.603164 -405.161238)
			(xy 338.626835 -405.224242) (xy 338.642807 -405.289624) (xy 338.650851 -405.356445) (xy 338.650851 -405.423749)
			(xy 338.642808 -405.490571) (xy 338.626837 -405.555952) (xy 338.603166 -405.618956) (xy 338.600728 -405.623648)
			(xy 339.729282 -405.623648) (xy 339.729282 -405.556343) (xy 339.737327 -405.489519) (xy 339.753301 -405.424137)
			(xy 339.776975 -405.361132) (xy 339.808009 -405.301408) (xy 339.845959 -405.245822) (xy 339.867748 -405.22017)
			(xy 339.873546 -405.213026) (xy 339.880058 -405.195834) (xy 339.880448 -405.186642) (xy 339.880448 -404.693374)
			(xy 339.88004 -404.684187) (xy 339.873523 -404.667003) (xy 339.867748 -404.659846) (xy 339.845982 -404.634176)
			(xy 339.808032 -404.578592) (xy 339.776997 -404.518871) (xy 339.753323 -404.455869) (xy 339.737348 -404.390489)
			(xy 339.729302 -404.323668) (xy 339.7293 -404.256365) (xy 339.737342 -404.189544) (xy 339.753313 -404.124163)
			(xy 339.776984 -404.061159) (xy 339.808015 -404.001436) (xy 339.845962 -403.94585) (xy 339.867748 -403.920198)
			(xy 339.873534 -403.913045) (xy 339.880054 -403.89586) (xy 339.880448 -403.88667) (xy 339.880448 -403.728682)
			(xy 339.880919 -403.718522) (xy 339.888701 -403.69975) (xy 339.903074 -403.685385) (xy 339.92185 -403.677613)
			(xy 339.93201 -403.67712) (xy 340.64829 -403.67712) (xy 340.658445 -403.677641) (xy 340.67721 -403.685409)
			(xy 340.691575 -403.699766) (xy 340.699353 -403.718527) (xy 340.699852 -403.728682) (xy 340.699852 -403.88667)
			(xy 340.700287 -403.895854) (xy 340.706785 -403.913038) (xy 340.712552 -403.920198) (xy 340.734362 -403.945832)
			(xy 340.772311 -404.001421) (xy 340.803343 -404.061147) (xy 340.827015 -404.124154) (xy 340.842987 -404.189538)
			(xy 340.85103 -404.256363) (xy 340.851028 -404.32367) (xy 340.842981 -404.390494) (xy 340.827006 -404.455878)
			(xy 340.80333 -404.518883) (xy 340.772294 -404.578608) (xy 340.734341 -404.634194) (xy 340.712552 -404.659846)
			(xy 340.706747 -404.666985) (xy 340.700239 -404.684181) (xy 340.699852 -404.693374) (xy 340.699852 -405.186642)
			(xy 340.700253 -405.19583) (xy 340.706774 -405.213014) (xy 340.712552 -405.22017) (xy 340.734334 -405.245827)
			(xy 340.772283 -405.301413) (xy 340.803317 -405.361135) (xy 340.826991 -405.424139) (xy 340.842965 -405.489521)
			(xy 340.851009 -405.556343) (xy 340.85101 -405.623648) (xy 340.842966 -405.69047) (xy 340.826994 -405.755852)
			(xy 340.803321 -405.818856) (xy 340.772288 -405.87858) (xy 340.734339 -405.934166) (xy 340.712552 -405.959818)
			(xy 340.706759 -405.966966) (xy 340.700244 -405.984154) (xy 340.699852 -405.993346) (xy 340.699852 -406.151334)
			(xy 340.699394 -406.161495) (xy 340.691607 -406.180267) (xy 340.67723 -406.194631) (xy 340.658452 -406.202403)
			(xy 340.64829 -406.202896) (xy 339.93201 -406.202896) (xy 339.921857 -406.202359) (xy 339.903095 -406.194594)
			(xy 339.88873 -406.180242) (xy 339.880949 -406.161487) (xy 339.880448 -406.151334) (xy 339.880448 -405.993346)
			(xy 339.880005 -405.984163) (xy 339.873513 -405.966979) (xy 339.867748 -405.959818) (xy 339.845954 -405.934171)
			(xy 339.808005 -405.878584) (xy 339.776971 -405.81886) (xy 339.753298 -405.755855) (xy 339.737325 -405.690472)
			(xy 339.729282 -405.623648) (xy 338.600728 -405.623648) (xy 338.572136 -405.67868) (xy 338.53419 -405.734267)
			(xy 338.512404 -405.75992) (xy 338.506617 -405.767072) (xy 338.500096 -405.784257) (xy 338.499704 -405.793448)
			(xy 338.499704 -406.286716) (xy 338.500106 -406.295904) (xy 338.506625 -406.313088) (xy 338.512404 -406.320244)
			(xy 338.534159 -406.345923) (xy 338.572106 -406.401506) (xy 338.603138 -406.461227) (xy 338.626811 -406.524228)
			(xy 338.642785 -406.589606) (xy 338.650831 -406.656425) (xy 338.650834 -406.723727) (xy 338.650827 -406.723789)
			(xy 341.928896 -406.723789) (xy 341.928898 -406.656363) (xy 341.936977 -406.589423) (xy 341.953016 -406.523932)
			(xy 341.976784 -406.460834) (xy 342.007938 -406.401036) (xy 342.04603 -406.345401) (xy 342.067896 -406.319736)
			(xy 342.073702 -406.312597) (xy 342.080211 -406.295402) (xy 342.080596 -406.286208) (xy 342.080596 -405.793956)
			(xy 342.080208 -405.784766) (xy 342.073679 -405.767582) (xy 342.067896 -405.760428) (xy 342.046028 -405.734766)
			(xy 342.00794 -405.679131) (xy 341.97679 -405.619334) (xy 341.953026 -405.556237) (xy 341.936991 -405.490748)
			(xy 341.928915 -405.423809) (xy 341.928916 -405.356385) (xy 341.936992 -405.289447) (xy 341.953028 -405.223957)
			(xy 341.976792 -405.16086) (xy 342.007943 -405.101064) (xy 342.046032 -405.045429) (xy 342.067896 -405.019764)
			(xy 342.07369 -405.012617) (xy 342.080206 -404.995428) (xy 342.080596 -404.986236) (xy 342.080596 -404.828756)
			(xy 342.081049 -404.818645) (xy 342.0888 -404.799967) (xy 342.103107 -404.785673) (xy 342.121793 -404.77794)
			(xy 342.131904 -404.777448) (xy 342.848184 -404.777448) (xy 342.858285 -404.777997) (xy 342.876953 -404.78572)
			(xy 342.891247 -404.799996) (xy 342.898991 -404.818655) (xy 342.899492 -404.828756) (xy 342.899492 -404.986236)
			(xy 342.899886 -404.995425) (xy 342.906411 -405.012609) (xy 342.912192 -405.019764) (xy 342.934052 -405.045432)
			(xy 342.972142 -405.101066) (xy 343.003293 -405.160862) (xy 343.027058 -405.223958) (xy 343.043094 -405.289447)
			(xy 343.05117 -405.356385) (xy 343.05117 -405.423809) (xy 343.043095 -405.490747) (xy 343.02706 -405.556236)
			(xy 343.003295 -405.619333) (xy 343.001047 -405.623648) (xy 344.129073 -405.623648) (xy 344.129073 -405.556343)
			(xy 344.137118 -405.48952) (xy 344.153091 -405.424137) (xy 344.176765 -405.361132) (xy 344.207799 -405.301409)
			(xy 344.245748 -405.245822) (xy 344.267536 -405.22017) (xy 344.273332 -405.213025) (xy 344.279846 -405.195834)
			(xy 344.280236 -405.186642) (xy 344.280236 -404.693374) (xy 344.27983 -404.684187) (xy 344.273313 -404.667003)
			(xy 344.267536 -404.659846) (xy 344.24577 -404.634176) (xy 344.207821 -404.578592) (xy 344.176787 -404.518871)
			(xy 344.153113 -404.455869) (xy 344.137139 -404.390489) (xy 344.129093 -404.323668) (xy 344.129091 -404.256365)
			(xy 344.137133 -404.189544) (xy 344.153103 -404.124163) (xy 344.176773 -404.061159) (xy 344.207804 -404.001437)
			(xy 344.24575 -403.94585) (xy 344.267536 -403.920198) (xy 344.273321 -403.913044) (xy 344.279842 -403.89586)
			(xy 344.280236 -403.88667) (xy 344.280236 -403.728682) (xy 344.280718 -403.718523) (xy 344.288498 -403.699754)
			(xy 344.302867 -403.685389) (xy 344.321639 -403.677615) (xy 344.331798 -403.67712) (xy 345.048078 -403.67712)
			(xy 345.058246 -403.677582) (xy 345.077037 -403.685356) (xy 345.091422 -403.69973) (xy 345.09921 -403.718514)
			(xy 345.09964 -403.728682) (xy 345.09964 -403.88667) (xy 345.100078 -403.895854) (xy 345.106574 -403.913038)
			(xy 345.11234 -403.920198) (xy 345.13415 -403.945832) (xy 345.1721 -404.00142) (xy 345.203133 -404.061146)
			(xy 345.226806 -404.124153) (xy 345.242778 -404.189538) (xy 345.250821 -404.256363) (xy 345.250819 -404.32367)
			(xy 345.242772 -404.390495) (xy 345.226796 -404.455878) (xy 345.20312 -404.518884) (xy 345.172083 -404.578608)
			(xy 345.13413 -404.634194) (xy 345.11234 -404.659846) (xy 345.106534 -404.666984) (xy 345.100027 -404.68418)
			(xy 345.09964 -404.693374) (xy 345.09964 -405.186642) (xy 345.100043 -405.19583) (xy 345.106563 -405.213013)
			(xy 345.11234 -405.22017) (xy 345.134122 -405.245827) (xy 345.172073 -405.301412) (xy 345.203107 -405.361135)
			(xy 345.226781 -405.424139) (xy 345.242755 -405.489521) (xy 345.2508 -405.556343) (xy 345.250801 -405.623648)
			(xy 345.242757 -405.69047) (xy 345.226784 -405.755853) (xy 345.203111 -405.818857) (xy 345.172077 -405.87858)
			(xy 345.134128 -405.934166) (xy 345.11234 -405.959818) (xy 345.106546 -405.966965) (xy 345.100031 -405.984154)
			(xy 345.09964 -405.993346) (xy 345.09964 -406.151334) (xy 345.099194 -406.161497) (xy 345.091404 -406.180271)
			(xy 345.077024 -406.194636) (xy 345.058241 -406.202405) (xy 345.048078 -406.202896) (xy 344.331798 -406.202896)
			(xy 344.321644 -406.202369) (xy 344.302882 -406.1946) (xy 344.288518 -406.180245) (xy 344.280737 -406.161487)
			(xy 344.280236 -406.151334) (xy 344.280236 -405.993346) (xy 344.279795 -405.984162) (xy 344.273302 -405.966978)
			(xy 344.267536 -405.959818) (xy 344.245742 -405.934171) (xy 344.207794 -405.878584) (xy 344.176761 -405.818859)
			(xy 344.153089 -405.755854) (xy 344.137116 -405.690471) (xy 344.129073 -405.623648) (xy 343.001047 -405.623648)
			(xy 342.972145 -405.679129) (xy 342.934056 -405.734763) (xy 342.912192 -405.760428) (xy 342.9064 -405.767576)
			(xy 342.899883 -405.784765) (xy 342.899492 -405.793956) (xy 342.899492 -406.286208) (xy 342.8999 -406.295395)
			(xy 342.906416 -406.312579) (xy 342.912192 -406.319736) (xy 342.934025 -406.345427) (xy 342.972115 -406.401058)
			(xy 343.003268 -406.46085) (xy 343.027034 -406.523944) (xy 343.043072 -406.58943) (xy 343.05115 -406.656365)
			(xy 343.051153 -406.72373) (xy 346.329191 -406.72373) (xy 346.329194 -406.656422) (xy 346.337242 -406.589596)
			(xy 346.35322 -406.524212) (xy 346.376898 -406.461206) (xy 346.407937 -406.401482) (xy 346.445893 -406.345896)
			(xy 346.467684 -406.320244) (xy 346.473485 -406.313102) (xy 346.479998 -406.295909) (xy 346.480384 -406.286716)
			(xy 346.480384 -405.793448) (xy 346.479955 -405.784263) (xy 346.473455 -405.767078) (xy 346.467684 -405.75992)
			(xy 346.445891 -405.734272) (xy 346.407939 -405.678686) (xy 346.376904 -405.618962) (xy 346.353229 -405.555957)
			(xy 346.337255 -405.490574) (xy 346.329211 -405.42375) (xy 346.329211 -405.356444) (xy 346.337256 -405.28962)
			(xy 346.353231 -405.224237) (xy 346.376906 -405.161232) (xy 346.407942 -405.101509) (xy 346.445895 -405.045924)
			(xy 346.467684 -405.020272) (xy 346.473473 -405.013121) (xy 346.479993 -404.995935) (xy 346.480384 -404.986744)
			(xy 346.480384 -404.828756) (xy 346.480785 -404.818601) (xy 346.488592 -404.799851) (xy 346.502995 -404.78553)
			(xy 346.521789 -404.777829) (xy 346.531946 -404.777448) (xy 347.248226 -404.777448) (xy 347.258355 -404.777905)
			(xy 347.277079 -404.785643) (xy 347.291434 -404.799938) (xy 347.299251 -404.818629) (xy 347.299788 -404.828756)
			(xy 347.299788 -404.986744) (xy 347.30018 -404.995933) (xy 347.306706 -405.013117) (xy 347.312488 -405.020272)
			(xy 347.334271 -405.045928) (xy 347.372218 -405.101514) (xy 347.40325 -405.161238) (xy 347.426922 -405.224242)
			(xy 347.442894 -405.289623) (xy 347.450938 -405.356445) (xy 347.450939 -405.423749) (xy 347.442895 -405.490571)
			(xy 347.426924 -405.555953) (xy 347.403253 -405.618957) (xy 347.400815 -405.623649) (xy 374.929103 -405.623649)
			(xy 374.929104 -405.556342) (xy 374.937149 -405.489519) (xy 374.953124 -405.424136) (xy 374.976799 -405.361131)
			(xy 375.007835 -405.301407) (xy 375.045787 -405.245822) (xy 375.067576 -405.22017) (xy 375.073365 -405.213019)
			(xy 375.079885 -405.195833) (xy 375.080276 -405.186642) (xy 375.080276 -404.693374) (xy 375.079884 -404.684185)
			(xy 375.073358 -404.667) (xy 375.067576 -404.659846) (xy 375.045809 -404.634177) (xy 375.007857 -404.578593)
			(xy 374.976821 -404.518873) (xy 374.953145 -404.45587) (xy 374.937169 -404.39049) (xy 374.929123 -404.323669)
			(xy 374.929121 -404.256365) (xy 374.937164 -404.189543) (xy 374.953135 -404.124161) (xy 374.976807 -404.061158)
			(xy 375.00784 -404.001435) (xy 375.045789 -403.94585) (xy 375.067576 -403.920198) (xy 375.073353 -403.913039)
			(xy 375.07988 -403.895859) (xy 375.080276 -403.88667) (xy 375.080276 -403.728682) (xy 375.08065 -403.718505)
			(xy 375.088448 -403.699702) (xy 375.102849 -403.685317) (xy 375.12166 -403.677539) (xy 375.131838 -403.67712)
			(xy 375.848118 -403.67712) (xy 375.858275 -403.677618) (xy 375.877041 -403.685395) (xy 375.891405 -403.699759)
			(xy 375.899182 -403.718525) (xy 375.89968 -403.728682) (xy 375.89968 -403.88667) (xy 375.900109 -403.895855)
			(xy 375.90661 -403.913039) (xy 375.91238 -403.920198) (xy 375.934189 -403.945833) (xy 375.972136 -404.001422)
			(xy 376.003167 -404.061148) (xy 376.026838 -404.124155) (xy 376.042809 -404.189539) (xy 376.050851 -404.256363)
			(xy 376.050849 -404.32367) (xy 376.042803 -404.390494) (xy 376.026828 -404.455877) (xy 376.003154 -404.518882)
			(xy 375.972119 -404.578606) (xy 375.934169 -404.634194) (xy 375.91238 -404.659846) (xy 375.906579 -404.666988)
			(xy 375.900068 -404.684181) (xy 375.89968 -404.693374) (xy 375.89968 -405.186642) (xy 375.900074 -405.195831)
			(xy 375.9066 -405.213015) (xy 375.91238 -405.22017) (xy 375.934161 -405.245827) (xy 375.972109 -405.301413)
			(xy 376.003142 -405.361136) (xy 376.026814 -405.42414) (xy 376.042787 -405.489522) (xy 376.050831 -405.556343)
			(xy 376.050832 -405.623648) (xy 376.042788 -405.690469) (xy 376.026817 -405.755851) (xy 376.003145 -405.818855)
			(xy 375.972114 -405.878579) (xy 375.934167 -405.934166) (xy 375.91238 -405.959818) (xy 375.906591 -405.966968)
			(xy 375.900072 -405.984155) (xy 375.89968 -405.993346) (xy 375.89968 -406.151334) (xy 375.899195 -406.161492)
			(xy 375.891413 -406.180258) (xy 375.877045 -406.194622) (xy 375.858276 -406.202398) (xy 375.848118 -406.202896)
			(xy 375.131838 -406.202896) (xy 375.121673 -406.202406) (xy 375.102886 -406.19464) (xy 375.088501 -406.180275)
			(xy 375.080708 -406.161498) (xy 375.080276 -406.151334) (xy 375.080276 -405.993346) (xy 375.079849 -405.984161)
			(xy 375.073347 -405.966976) (xy 375.067576 -405.959818) (xy 375.045781 -405.934171) (xy 375.00783 -405.878585)
			(xy 374.976795 -405.818861) (xy 374.953121 -405.755856) (xy 374.937148 -405.690472) (xy 374.929103 -405.623649)
			(xy 347.400815 -405.623649) (xy 347.372221 -405.678681) (xy 347.334275 -405.734268) (xy 347.312488 -405.75992)
			(xy 347.306699 -405.767071) (xy 347.30018 -405.784257) (xy 347.299788 -405.793448) (xy 347.299788 -406.286716)
			(xy 347.300193 -406.295904) (xy 347.30671 -406.313088) (xy 347.312488 -406.320244) (xy 347.334244 -406.345922)
			(xy 347.372192 -406.401506) (xy 347.403225 -406.461226) (xy 347.426898 -406.524227) (xy 347.442873 -406.589606)
			(xy 347.450919 -406.656425) (xy 347.450922 -406.723727) (xy 347.450915 -406.723789) (xy 377.128717 -406.723789)
			(xy 377.12872 -406.656363) (xy 377.136799 -406.589422) (xy 377.152839 -406.523931) (xy 377.176607 -406.460832)
			(xy 377.207763 -406.401035) (xy 377.245857 -406.345401) (xy 377.267724 -406.319736) (xy 377.273533 -406.3126)
			(xy 377.280039 -406.295402) (xy 377.280424 -406.286208) (xy 377.280424 -405.793956) (xy 377.28003 -405.784767)
			(xy 377.273504 -405.767583) (xy 377.267724 -405.760428) (xy 377.245855 -405.734766) (xy 377.207765 -405.679132)
			(xy 377.176613 -405.619335) (xy 377.152848 -405.556238) (xy 377.136812 -405.490748) (xy 377.128736 -405.423809)
			(xy 377.128737 -405.356385) (xy 377.136813 -405.289446) (xy 377.15285 -405.223956) (xy 377.176616 -405.160859)
			(xy 377.207768 -405.101063) (xy 377.245859 -405.045429) (xy 377.267724 -405.019764) (xy 377.273521 -405.012619)
			(xy 377.280035 -404.995428) (xy 377.280424 -404.986236) (xy 377.280424 -404.828756) (xy 377.28085 -404.818641)
			(xy 377.288606 -404.799958) (xy 377.302922 -404.785664) (xy 377.321617 -404.777935) (xy 377.331732 -404.777448)
			(xy 378.048012 -404.777448) (xy 378.058115 -404.777974) (xy 378.076783 -404.785706) (xy 378.091076 -404.79999)
			(xy 378.098819 -404.818653) (xy 378.09932 -404.828756) (xy 378.09932 -404.986236) (xy 378.099709 -404.995426)
			(xy 378.106237 -405.01261) (xy 378.11202 -405.019764) (xy 378.133879 -405.045433) (xy 378.171967 -405.101067)
			(xy 378.203117 -405.160863) (xy 378.22688 -405.22396) (xy 378.242915 -405.289448) (xy 378.250991 -405.356386)
			(xy 378.250992 -405.423808) (xy 378.242916 -405.490746) (xy 378.226882 -405.556235) (xy 378.203119 -405.619331)
			(xy 378.200839 -405.623707) (xy 379.328896 -405.623707) (xy 379.328896 -405.556284) (xy 379.336972 -405.489346)
			(xy 379.353008 -405.423856) (xy 379.376771 -405.360759) (xy 379.407921 -405.300963) (xy 379.446009 -405.245328)
			(xy 379.467872 -405.219662) (xy 379.473676 -405.212522) (xy 379.480184 -405.195327) (xy 379.480572 -405.186134)
			(xy 379.480572 -404.693882) (xy 379.480177 -404.684693) (xy 379.473653 -404.667509) (xy 379.467872 -404.660354)
			(xy 379.446031 -404.63467) (xy 379.407943 -404.579038) (xy 379.376793 -404.519244) (xy 379.353029 -404.45615)
			(xy 379.336993 -404.390663) (xy 379.328915 -404.323727) (xy 379.328913 -404.256306) (xy 379.336987 -404.18937)
			(xy 379.353019 -404.123882) (xy 379.376779 -404.060786) (xy 379.407926 -404.00099) (xy 379.44601 -403.945356)
			(xy 379.467872 -403.91969) (xy 379.473664 -403.912542) (xy 379.480179 -403.895353) (xy 379.480572 -403.886162)
			(xy 379.480572 -403.728682) (xy 379.481013 -403.71855) (xy 379.488752 -403.699822) (xy 379.503053 -403.685466)
			(xy 379.52175 -403.677653) (xy 379.53188 -403.67712) (xy 380.24816 -403.67712) (xy 380.258282 -403.677549)
			(xy 380.276989 -403.685288) (xy 380.291305 -403.699601) (xy 380.299048 -403.718306) (xy 380.299468 -403.728428)
			(xy 380.299468 -403.886162) (xy 380.299904 -403.895346) (xy 380.306401 -403.91253) (xy 380.312168 -403.91969)
			(xy 380.334055 -403.945337) (xy 380.372145 -404.000973) (xy 380.403296 -404.060772) (xy 380.427061 -404.123871)
			(xy 380.443096 -404.189363) (xy 380.45117 -404.256303) (xy 380.451168 -404.32373) (xy 380.44309 -404.39067)
			(xy 380.427051 -404.456161) (xy 380.403283 -404.519259) (xy 380.372128 -404.579055) (xy 380.334034 -404.634689)
			(xy 380.312168 -404.660354) (xy 380.306362 -404.667492) (xy 380.299854 -404.684688) (xy 380.299468 -404.693882)
			(xy 380.299468 -405.186134) (xy 380.299869 -405.195322) (xy 380.30639 -405.212506) (xy 380.312168 -405.219662)
			(xy 380.334027 -405.245332) (xy 380.372118 -405.300965) (xy 380.403271 -405.36076) (xy 380.427037 -405.423856)
			(xy 380.443074 -405.489345) (xy 380.451151 -405.556284) (xy 380.451151 -405.623707) (xy 380.443075 -405.690646)
			(xy 380.42704 -405.756135) (xy 380.403275 -405.819232) (xy 380.372123 -405.879028) (xy 380.334033 -405.934661)
			(xy 380.312168 -405.960326) (xy 380.306374 -405.967473) (xy 380.299858 -405.984662) (xy 380.299468 -405.993854)
			(xy 380.299468 -406.151334) (xy 380.299002 -406.161462) (xy 380.291264 -406.180182) (xy 380.276972 -406.194537)
			(xy 380.258286 -406.202357) (xy 380.24816 -406.202896) (xy 379.53188 -406.202896) (xy 379.521769 -406.202431)
			(xy 379.50309 -406.194686) (xy 379.488796 -406.180383) (xy 379.481062 -406.161699) (xy 379.480572 -406.151588)
			(xy 379.480572 -405.993854) (xy 379.480142 -405.984669) (xy 379.473643 -405.967484) (xy 379.467872 -405.960326)
			(xy 379.446003 -405.934665) (xy 379.407916 -405.879029) (xy 379.376768 -405.819232) (xy 379.353005 -405.756135)
			(xy 379.336971 -405.690646) (xy 379.328896 -405.623707) (xy 378.200839 -405.623707) (xy 378.17197 -405.679128)
			(xy 378.133883 -405.734762) (xy 378.11202 -405.760428) (xy 378.106231 -405.767579) (xy 378.099711 -405.784765)
			(xy 378.09932 -405.793956) (xy 378.09932 -406.286208) (xy 378.099722 -406.295396) (xy 378.106241 -406.312581)
			(xy 378.11202 -406.319736) (xy 378.133852 -406.345428) (xy 378.17194 -406.401059) (xy 378.203091 -406.460852)
			(xy 378.226856 -406.523945) (xy 378.242893 -406.589431) (xy 378.250971 -406.656366) (xy 378.250974 -406.723729)
			(xy 381.529036 -406.723729) (xy 381.529039 -406.656422) (xy 381.537086 -406.589598) (xy 381.553062 -406.524214)
			(xy 381.576737 -406.461209) (xy 381.607772 -406.401484) (xy 381.645723 -406.345897) (xy 381.667512 -406.320244)
			(xy 381.673316 -406.313104) (xy 381.679826 -406.29591) (xy 381.680212 -406.286716) (xy 381.680212 -405.793448)
			(xy 381.679776 -405.784264) (xy 381.67328 -405.767079) (xy 381.667512 -405.75992) (xy 381.645721 -405.734271)
			(xy 381.607774 -405.678683) (xy 381.576743 -405.618959) (xy 381.553071 -405.555954) (xy 381.537099 -405.490572)
			(xy 381.529056 -405.423749) (xy 381.529056 -405.356445) (xy 381.5371 -405.289622) (xy 381.553073 -405.22424)
			(xy 381.576745 -405.161235) (xy 381.607777 -405.101512) (xy 381.645725 -405.045924) (xy 381.667512 -405.020272)
			(xy 381.673304 -405.013124) (xy 381.679821 -404.995936) (xy 381.680212 -404.986744) (xy 381.680212 -404.828756)
			(xy 381.680649 -404.818643) (xy 381.688404 -404.799961) (xy 381.702715 -404.785668) (xy 381.721406 -404.777937)
			(xy 381.73152 -404.777448) (xy 382.448054 -404.777448) (xy 382.458179 -404.777965) (xy 382.4769 -404.785679)
			(xy 382.491258 -404.799956) (xy 382.499078 -404.818634) (xy 382.499616 -404.828756) (xy 382.499616 -404.986744)
			(xy 382.500001 -404.995934) (xy 382.506532 -405.013118) (xy 382.512316 -405.020272) (xy 382.534101 -405.045927)
			(xy 382.572053 -405.101512) (xy 382.603089 -405.161235) (xy 382.626764 -405.224239) (xy 382.642738 -405.289621)
			(xy 382.650784 -405.356444) (xy 382.650784 -405.42375) (xy 382.64274 -405.490573) (xy 382.626766 -405.555955)
			(xy 382.603091 -405.61896) (xy 382.600655 -405.623648) (xy 383.729191 -405.623648) (xy 383.729192 -405.556343)
			(xy 383.737237 -405.489519) (xy 383.753211 -405.424136) (xy 383.776885 -405.361132) (xy 383.807921 -405.301408)
			(xy 383.845871 -405.245822) (xy 383.86766 -405.22017) (xy 383.873459 -405.213027) (xy 383.879971 -405.195835)
			(xy 383.88036 -405.186642) (xy 383.88036 -404.693374) (xy 383.879949 -404.684187) (xy 383.873434 -404.667004)
			(xy 383.86766 -404.659846) (xy 383.845893 -404.634176) (xy 383.807943 -404.578593) (xy 383.776907 -404.518872)
			(xy 383.753232 -404.45587) (xy 383.737257 -404.390489) (xy 383.729211 -404.323668) (xy 383.729209 -404.256365)
			(xy 383.737251 -404.189543) (xy 383.753222 -404.124162) (xy 383.776894 -404.061158) (xy 383.807926 -404.001436)
			(xy 383.845873 -403.94585) (xy 383.86766 -403.920198) (xy 383.873447 -403.913047) (xy 383.879966 -403.895861)
			(xy 383.88036 -403.88667) (xy 383.88036 -403.728682) (xy 383.88075 -403.718507) (xy 383.888545 -403.699707)
			(xy 383.902941 -403.685322) (xy 383.921746 -403.677542) (xy 383.931922 -403.67712) (xy 384.648202 -403.67712)
			(xy 384.658358 -403.677631) (xy 384.677123 -403.685403) (xy 384.691488 -403.699763) (xy 384.699265 -403.718526)
			(xy 384.699764 -403.728682) (xy 384.699764 -403.88667) (xy 384.700197 -403.895855) (xy 384.706696 -403.913039)
			(xy 384.712464 -403.920198) (xy 384.734273 -403.945832) (xy 384.772221 -404.001421) (xy 384.803254 -404.061147)
			(xy 384.826925 -404.124154) (xy 384.842896 -404.189539) (xy 384.850939 -404.256363) (xy 384.850937 -404.32367)
			(xy 384.84289 -404.390494) (xy 384.826915 -404.455877) (xy 384.80324 -404.518883) (xy 384.772204 -404.578607)
			(xy 384.734253 -404.634194) (xy 384.712464 -404.659846) (xy 384.706661 -404.666986) (xy 384.700151 -404.684181)
			(xy 384.699764 -404.693374) (xy 384.699764 -405.186642) (xy 384.700162 -405.19583) (xy 384.706685 -405.213014)
			(xy 384.712464 -405.22017) (xy 384.734246 -405.245827) (xy 384.772195 -405.301413) (xy 384.803228 -405.361136)
			(xy 384.826901 -405.42414) (xy 384.842874 -405.489521) (xy 384.850919 -405.556343) (xy 384.850919 -405.623648)
			(xy 384.842876 -405.69047) (xy 384.826904 -405.755852) (xy 384.803232 -405.818856) (xy 384.772199 -405.878579)
			(xy 384.734251 -405.934166) (xy 384.712464 -405.959818) (xy 384.706673 -405.966967) (xy 384.700156 -405.984155)
			(xy 384.699764 -405.993346) (xy 384.699764 -406.151334) (xy 384.699295 -406.161494) (xy 384.691509 -406.180263)
			(xy 384.677136 -406.194627) (xy 384.658362 -406.202401) (xy 384.648202 -406.202896) (xy 383.931922 -406.202896)
			(xy 383.92177 -406.20235) (xy 383.903008 -406.194589) (xy 383.888643 -406.180239) (xy 383.880861 -406.161486)
			(xy 383.88036 -406.151334) (xy 383.88036 -405.993346) (xy 383.879914 -405.984163) (xy 383.873424 -405.966979)
			(xy 383.86766 -405.959818) (xy 383.845866 -405.934171) (xy 383.807916 -405.878584) (xy 383.776882 -405.81886)
			(xy 383.753208 -405.755855) (xy 383.737235 -405.690472) (xy 383.729191 -405.623648) (xy 382.600655 -405.623648)
			(xy 382.572056 -405.678683) (xy 382.534105 -405.734268) (xy 382.512316 -405.75992) (xy 382.50653 -405.767073)
			(xy 382.500009 -405.784257) (xy 382.499616 -405.793448) (xy 382.499616 -406.286716) (xy 382.500015 -406.295904)
			(xy 382.506536 -406.313089) (xy 382.512316 -406.320244) (xy 382.534074 -406.345921) (xy 382.572026 -406.401503)
			(xy 382.603063 -406.461223) (xy 382.62674 -406.524224) (xy 382.642717 -406.589604) (xy 382.650764 -406.656424)
			(xy 382.650767 -406.723728) (xy 382.65076 -406.723789) (xy 385.928805 -406.723789) (xy 385.928807 -406.656363)
			(xy 385.936887 -406.589422) (xy 385.952926 -406.523931) (xy 385.976694 -406.460833) (xy 386.007849 -406.401036)
			(xy 386.045942 -406.345401) (xy 386.067808 -406.319736) (xy 386.073615 -406.312598) (xy 386.080123 -406.295402)
			(xy 386.080508 -406.286208) (xy 386.080508 -405.793956) (xy 386.080117 -405.784767) (xy 386.07359 -405.767583)
			(xy 386.067808 -405.760428) (xy 386.04594 -405.734766) (xy 386.007851 -405.679131) (xy 385.9767 -405.619335)
			(xy 385.952935 -405.556237) (xy 385.9369 -405.490748) (xy 385.928824 -405.423809) (xy 385.928825 -405.356385)
			(xy 385.936901 -405.289446) (xy 385.952937 -405.223957) (xy 385.976702 -405.16086) (xy 386.007854 -405.101064)
			(xy 386.045944 -405.045429) (xy 386.067808 -405.019764) (xy 386.073603 -405.012618) (xy 386.080118 -404.995428)
			(xy 386.080508 -404.986236) (xy 386.080508 -404.828756) (xy 386.080949 -404.818643) (xy 386.088703 -404.799963)
			(xy 386.103013 -404.785669) (xy 386.121703 -404.777938) (xy 386.131816 -404.777448) (xy 386.848096 -404.777448)
			(xy 386.858198 -404.777987) (xy 386.876866 -404.785714) (xy 386.891159 -404.799993) (xy 386.898903 -404.818654)
			(xy 386.899404 -404.828756) (xy 386.899404 -404.986236) (xy 386.899796 -404.995425) (xy 386.906322 -405.012609)
			(xy 386.912104 -405.019764) (xy 386.933964 -405.045433) (xy 386.972052 -405.101067) (xy 387.003203 -405.160862)
			(xy 387.026967 -405.223959) (xy 387.043003 -405.289448) (xy 387.051079 -405.356385) (xy 387.051079 -405.423809)
			(xy 387.043004 -405.490747) (xy 387.026969 -405.556235) (xy 387.003206 -405.619332) (xy 387.000958 -405.623648)
			(xy 388.128982 -405.623648) (xy 388.128982 -405.556343) (xy 388.137027 -405.489519) (xy 388.153001 -405.424137)
			(xy 388.176675 -405.361132) (xy 388.207709 -405.301408) (xy 388.245659 -405.245822) (xy 388.267448 -405.22017)
			(xy 388.273246 -405.213026) (xy 388.279758 -405.195834) (xy 388.280148 -405.186642) (xy 388.280148 -404.693374)
			(xy 388.27974 -404.684187) (xy 388.273223 -404.667003) (xy 388.267448 -404.659846) (xy 388.245682 -404.634176)
			(xy 388.207732 -404.578592) (xy 388.176697 -404.518871) (xy 388.153023 -404.455869) (xy 388.137048 -404.390489)
			(xy 388.129002 -404.323668) (xy 388.129 -404.256365) (xy 388.137042 -404.189544) (xy 388.153013 -404.124163)
			(xy 388.176684 -404.061159) (xy 388.207715 -404.001436) (xy 388.245662 -403.94585) (xy 388.267448 -403.920198)
			(xy 388.273234 -403.913045) (xy 388.279754 -403.89586) (xy 388.280148 -403.88667) (xy 388.280148 -403.728682)
			(xy 388.280619 -403.718522) (xy 388.288401 -403.69975) (xy 388.302774 -403.685385) (xy 388.32155 -403.677613)
			(xy 388.33171 -403.67712) (xy 389.04799 -403.67712) (xy 389.058145 -403.677641) (xy 389.07691 -403.685409)
			(xy 389.091275 -403.699766) (xy 389.099053 -403.718527) (xy 389.099552 -403.728682) (xy 389.099552 -403.88667)
			(xy 389.099987 -403.895854) (xy 389.106485 -403.913038) (xy 389.112252 -403.920198) (xy 389.134062 -403.945832)
			(xy 389.172011 -404.001421) (xy 389.203043 -404.061147) (xy 389.226715 -404.124154) (xy 389.242687 -404.189538)
			(xy 389.25073 -404.256363) (xy 389.250728 -404.32367) (xy 389.242681 -404.390494) (xy 389.226706 -404.455878)
			(xy 389.20303 -404.518883) (xy 389.171994 -404.578608) (xy 389.134041 -404.634194) (xy 389.112252 -404.659846)
			(xy 389.106447 -404.666985) (xy 389.099939 -404.684181) (xy 389.099552 -404.693374) (xy 389.099552 -405.186642)
			(xy 389.099953 -405.19583) (xy 389.106474 -405.213014) (xy 389.112252 -405.22017) (xy 389.134034 -405.245827)
			(xy 389.171983 -405.301413) (xy 389.203017 -405.361135) (xy 389.226691 -405.424139) (xy 389.242665 -405.489521)
			(xy 389.250709 -405.556343) (xy 389.25071 -405.623648) (xy 389.242666 -405.69047) (xy 389.226694 -405.755852)
			(xy 389.203021 -405.818856) (xy 389.171988 -405.87858) (xy 389.134039 -405.934166) (xy 389.112252 -405.959818)
			(xy 389.106459 -405.966966) (xy 389.099944 -405.984154) (xy 389.099552 -405.993346) (xy 389.099552 -406.151334)
			(xy 389.099094 -406.161495) (xy 389.091307 -406.180267) (xy 389.07693 -406.194631) (xy 389.058152 -406.202403)
			(xy 389.04799 -406.202896) (xy 388.33171 -406.202896) (xy 388.321557 -406.202359) (xy 388.302795 -406.194594)
			(xy 388.28843 -406.180242) (xy 388.280649 -406.161487) (xy 388.280148 -406.151334) (xy 388.280148 -405.993346)
			(xy 388.279705 -405.984163) (xy 388.273213 -405.966979) (xy 388.267448 -405.959818) (xy 388.245654 -405.934171)
			(xy 388.207705 -405.878584) (xy 388.176671 -405.81886) (xy 388.152998 -405.755855) (xy 388.137025 -405.690472)
			(xy 388.128982 -405.623648) (xy 387.000958 -405.623648) (xy 386.972056 -405.679128) (xy 386.933968 -405.734763)
			(xy 386.912104 -405.760428) (xy 386.906314 -405.767578) (xy 386.899795 -405.784765) (xy 386.899404 -405.793956)
			(xy 386.899404 -406.286208) (xy 386.89981 -406.295396) (xy 386.906326 -406.31258) (xy 386.912104 -406.319736)
			(xy 386.933936 -406.345427) (xy 386.972026 -406.401058) (xy 387.003178 -406.460851) (xy 387.026943 -406.523944)
			(xy 387.042981 -406.58943) (xy 387.051059 -406.656365) (xy 387.051062 -406.723729) (xy 390.329124 -406.723729)
			(xy 390.329127 -406.656423) (xy 390.337174 -406.589599) (xy 390.353149 -406.524215) (xy 390.376823 -406.461209)
			(xy 390.407858 -406.401485) (xy 390.445808 -406.345897) (xy 390.467596 -406.320244) (xy 390.473398 -406.313103)
			(xy 390.47991 -406.295909) (xy 390.480296 -406.286716) (xy 390.480296 -405.793448) (xy 390.479864 -405.784263)
			(xy 390.473366 -405.767078) (xy 390.467596 -405.75992) (xy 390.445806 -405.73427) (xy 390.40786 -405.678683)
			(xy 390.376829 -405.618958) (xy 390.353158 -405.555954) (xy 390.337187 -405.490571) (xy 390.329144 -405.423749)
			(xy 390.329144 -405.356445) (xy 390.337188 -405.289623) (xy 390.35316 -405.224241) (xy 390.376832 -405.161236)
			(xy 390.407863 -405.101512) (xy 390.445809 -405.045925) (xy 390.467596 -405.020272) (xy 390.473386 -405.013122)
			(xy 390.479905 -404.995935) (xy 390.480296 -404.986744) (xy 390.480296 -404.828756) (xy 390.480749 -404.818645)
			(xy 390.4885 -404.799967) (xy 390.502807 -404.785673) (xy 390.521493 -404.77794) (xy 390.531604 -404.777448)
			(xy 391.248138 -404.777448) (xy 391.258268 -404.777896) (xy 391.276992 -404.785637) (xy 391.291347 -404.799935)
			(xy 391.299163 -404.818628) (xy 391.2997 -404.828756) (xy 391.2997 -404.986744) (xy 391.300089 -404.995933)
			(xy 391.306617 -405.013118) (xy 391.3124 -405.020272) (xy 391.334183 -405.045928) (xy 391.372129 -405.101515)
			(xy 391.40316 -405.161238) (xy 391.426832 -405.224242) (xy 391.442804 -405.289623) (xy 391.450848 -405.356445)
			(xy 391.450848 -405.423749) (xy 391.442805 -405.490571) (xy 391.426833 -405.555952) (xy 391.403163 -405.618956)
			(xy 391.372132 -405.67868) (xy 391.334186 -405.734267) (xy 391.3124 -405.75992) (xy 391.306612 -405.767072)
			(xy 391.300092 -405.784257) (xy 391.2997 -405.793448) (xy 391.2997 -406.286716) (xy 391.300103 -406.295904)
			(xy 391.306622 -406.313088) (xy 391.3124 -406.320244) (xy 391.334155 -406.345923) (xy 391.372102 -406.401506)
			(xy 391.403135 -406.461226) (xy 391.426808 -406.524227) (xy 391.442782 -406.589606) (xy 391.450828 -406.656425)
			(xy 391.450831 -406.723727) (xy 391.44279 -406.790547) (xy 391.426822 -406.855927) (xy 391.403154 -406.91893)
			(xy 391.372127 -406.978653) (xy 391.334185 -407.034239) (xy 391.3124 -407.059892) (xy 391.306624 -407.067052)
			(xy 391.300097 -407.084231) (xy 391.2997 -407.09342) (xy 391.2997 -407.251408) (xy 391.299221 -407.261517)
			(xy 391.291481 -407.280196) (xy 391.277182 -407.29449) (xy 391.258501 -407.302224) (xy 391.248392 -407.302716)
			(xy 390.531858 -407.302716) (xy 390.521723 -407.302307) (xy 390.502993 -407.294557) (xy 390.488636 -407.280247)
			(xy 390.480826 -407.261541) (xy 390.480296 -407.251408) (xy 390.480296 -407.09342) (xy 390.479877 -407.084234)
			(xy 390.47337 -407.067049) (xy 390.467596 -407.059892) (xy 390.445778 -407.034265) (xy 390.407833 -406.978674)
			(xy 390.376804 -406.918947) (xy 390.353135 -406.855939) (xy 390.337165 -406.790554) (xy 390.329124 -406.723729)
			(xy 387.051062 -406.723729) (xy 387.051062 -406.723787) (xy 387.04299 -406.790723) (xy 387.026958 -406.85621)
			(xy 387.003197 -406.919305) (xy 386.972051 -406.979101) (xy 386.933966 -407.034735) (xy 386.912104 -407.0604)
			(xy 386.906325 -407.067558) (xy 386.8998 -407.084739) (xy 386.899404 -407.093928) (xy 386.899404 -407.251408)
			(xy 386.898921 -407.261517) (xy 386.891182 -407.280194) (xy 386.876884 -407.294489) (xy 386.858205 -407.302224)
			(xy 386.848096 -407.302716) (xy 386.131816 -407.302716) (xy 386.121697 -407.302271) (xy 386.102996 -407.294531)
			(xy 386.088682 -407.280224) (xy 386.080933 -407.261527) (xy 386.080508 -407.251408) (xy 386.080508 -407.093928)
			(xy 386.080083 -407.084742) (xy 386.073579 -407.067558) (xy 386.067808 -407.0604) (xy 386.045912 -407.034761)
			(xy 386.007824 -406.979123) (xy 385.976674 -406.919323) (xy 385.952912 -406.856223) (xy 385.936878 -406.79073)
			(xy 385.928805 -406.723789) (xy 382.65076 -406.723789) (xy 382.642725 -406.790549) (xy 382.626754 -406.85593)
			(xy 382.603083 -406.918933) (xy 382.572051 -406.978655) (xy 382.534103 -407.03424) (xy 382.512316 -407.059892)
			(xy 382.506542 -407.067053) (xy 382.500013 -407.084231) (xy 382.499616 -407.09342) (xy 382.499616 -407.251408)
			(xy 382.499122 -407.261515) (xy 382.491384 -407.28019) (xy 382.47709 -407.294484) (xy 382.458415 -407.302222)
			(xy 382.448308 -407.302716) (xy 381.731774 -407.302716) (xy 381.72164 -407.302294) (xy 381.70291 -407.294549)
			(xy 381.688553 -407.280243) (xy 381.680743 -407.26154) (xy 381.680212 -407.251408) (xy 381.680212 -407.09342)
			(xy 381.679789 -407.084234) (xy 381.673284 -407.06705) (xy 381.667512 -407.059892) (xy 381.645694 -407.034265)
			(xy 381.607748 -406.978675) (xy 381.576717 -406.918947) (xy 381.553047 -406.855939) (xy 381.537077 -406.790554)
			(xy 381.529036 -406.723729) (xy 378.250974 -406.723729) (xy 378.250974 -406.723786) (xy 378.242902 -406.790722)
			(xy 378.226871 -406.856209) (xy 378.203111 -406.919305) (xy 378.171965 -406.9791) (xy 378.133881 -407.034734)
			(xy 378.11202 -407.0604) (xy 378.106243 -407.067559) (xy 378.099716 -407.084739) (xy 378.09932 -407.093928)
			(xy 378.09932 -407.251408) (xy 378.098822 -407.261515) (xy 378.091085 -407.280189) (xy 378.076793 -407.294483)
			(xy 378.058119 -407.302221) (xy 378.048012 -407.302716) (xy 377.331732 -407.302716) (xy 377.321614 -407.302258)
			(xy 377.302914 -407.294524) (xy 377.288599 -407.28022) (xy 377.280849 -407.261526) (xy 377.280424 -407.251408)
			(xy 377.280424 -407.093928) (xy 377.279995 -407.084743) (xy 377.273494 -407.067559) (xy 377.267724 -407.0604)
			(xy 377.245828 -407.034761) (xy 377.207738 -406.979123) (xy 377.176588 -406.919324) (xy 377.152824 -406.856223)
			(xy 377.13679 -406.790731) (xy 377.128717 -406.723789) (xy 347.450915 -406.723789) (xy 347.442881 -406.790547)
			(xy 347.426912 -406.855927) (xy 347.403244 -406.91893) (xy 347.372216 -406.978653) (xy 347.334273 -407.03424)
			(xy 347.312488 -407.059892) (xy 347.306711 -407.067051) (xy 347.300185 -407.084231) (xy 347.299788 -407.09342)
			(xy 347.299788 -407.251408) (xy 347.299385 -407.261564) (xy 347.291584 -407.280319) (xy 347.277182 -407.294642)
			(xy 347.258384 -407.30234) (xy 347.248226 -407.302716) (xy 346.531946 -407.302716) (xy 346.521817 -407.302234)
			(xy 346.503088 -407.294514) (xy 346.488729 -407.280225) (xy 346.480916 -407.261535) (xy 346.480384 -407.251408)
			(xy 346.480384 -407.09342) (xy 346.479968 -407.084233) (xy 346.473459 -407.067049) (xy 346.467684 -407.059892)
			(xy 346.445864 -407.034266) (xy 346.407913 -406.978677) (xy 346.376878 -406.91895) (xy 346.353205 -406.855942)
			(xy 346.337233 -406.790556) (xy 346.329191 -406.72373) (xy 343.051153 -406.72373) (xy 343.051153 -406.723787)
			(xy 343.04308 -406.790723) (xy 343.027048 -406.85621) (xy 343.003287 -406.919306) (xy 342.97214 -406.979101)
			(xy 342.934054 -407.034735) (xy 342.912192 -407.0604) (xy 342.906412 -407.067557) (xy 342.899888 -407.084738)
			(xy 342.899492 -407.093928) (xy 342.899492 -407.251408) (xy 342.89909 -407.261532) (xy 342.891338 -407.280237)
			(xy 342.877017 -407.294551) (xy 342.858308 -407.302295) (xy 342.848184 -407.302716) (xy 342.131904 -407.302716)
			(xy 342.121798 -407.302212) (xy 342.103122 -407.294479) (xy 342.088828 -407.280188) (xy 342.08109 -407.261514)
			(xy 342.080596 -407.251408) (xy 342.080596 -407.093928) (xy 342.080173 -407.084742) (xy 342.073668 -407.067558)
			(xy 342.067896 -407.0604) (xy 342.046001 -407.034761) (xy 342.007913 -406.979122) (xy 341.976764 -406.919322)
			(xy 341.953002 -406.856222) (xy 341.936969 -406.79073) (xy 341.928896 -406.723789) (xy 338.650827 -406.723789)
			(xy 338.642793 -406.790546) (xy 338.626825 -406.855926) (xy 338.603158 -406.918929) (xy 338.572131 -406.978652)
			(xy 338.534188 -407.034239) (xy 338.512404 -407.059892) (xy 338.506629 -407.067052) (xy 338.500101 -407.084231)
			(xy 338.499704 -407.09342) (xy 338.499704 -407.251408) (xy 338.499285 -407.261562) (xy 338.491487 -407.280314)
			(xy 338.47709 -407.294637) (xy 338.458298 -407.302337) (xy 338.448142 -407.302716) (xy 337.731862 -407.302716)
			(xy 337.721727 -407.302303) (xy 337.702997 -407.294555) (xy 337.688641 -407.280246) (xy 337.68083 -407.261541)
			(xy 337.6803 -407.251408) (xy 337.6803 -407.09342) (xy 337.67988 -407.084234) (xy 337.673373 -407.067049)
			(xy 337.6676 -407.059892) (xy 337.645782 -407.034265) (xy 337.607837 -406.978674) (xy 337.576807 -406.918947)
			(xy 337.553138 -406.855939) (xy 337.537168 -406.790554) (xy 337.529127 -406.723729) (xy 334.251065 -406.723729)
			(xy 334.251065 -406.723786) (xy 334.242993 -406.790722) (xy 334.226961 -406.85621) (xy 334.203201 -406.919305)
			(xy 334.172054 -406.9791) (xy 334.13397 -407.034735) (xy 334.112108 -407.0604) (xy 334.10633 -407.067558)
			(xy 334.099804 -407.084739) (xy 334.099408 -407.093928) (xy 334.099408 -407.251408) (xy 334.098921 -407.261516)
			(xy 334.091183 -407.280193) (xy 334.076886 -407.294487) (xy 334.058208 -407.302223) (xy 334.0481 -407.302716)
			(xy 333.33182 -407.302716) (xy 333.321701 -407.302268) (xy 333.303001 -407.29453) (xy 333.288686 -407.280223)
			(xy 333.280937 -407.261527) (xy 333.280512 -407.251408) (xy 333.280512 -407.093928) (xy 333.280086 -407.084743)
			(xy 333.273583 -407.067558) (xy 333.267812 -407.0604) (xy 333.245916 -407.034761) (xy 333.207828 -406.979123)
			(xy 333.176678 -406.919323) (xy 333.152915 -406.856223) (xy 333.136881 -406.790731) (xy 333.128808 -406.723789)
			(xy 326.525636 -406.723789) (xy 326.525636 -409.523827) (xy 330.929173 -409.523827) (xy 330.929176 -409.456519)
			(xy 330.937224 -409.389693) (xy 330.953202 -409.324309) (xy 330.976879 -409.261303) (xy 331.007918 -409.201578)
			(xy 331.045873 -409.145992) (xy 331.067664 -409.12034) (xy 331.073476 -409.113206) (xy 331.07998 -409.096007)
			(xy 331.080364 -409.086812) (xy 331.080364 -408.593544) (xy 331.079919 -408.584361) (xy 331.073428 -408.567177)
			(xy 331.067664 -408.560016) (xy 331.045868 -408.534371) (xy 331.007918 -408.478784) (xy 330.976883 -408.419059)
			(xy 330.95321 -408.356054) (xy 330.937237 -408.290671) (xy 330.929193 -408.223847) (xy 330.929194 -408.156541)
			(xy 330.937239 -408.089717) (xy 330.953213 -408.024334) (xy 330.976888 -407.96133) (xy 331.007924 -407.901606)
			(xy 331.045875 -407.84602) (xy 331.067664 -407.820368) (xy 331.073464 -407.813226) (xy 331.079975 -407.796033)
			(xy 331.080364 -407.78684) (xy 331.080364 -407.628852) (xy 331.080782 -407.618699) (xy 331.088586 -407.599953)
			(xy 331.102983 -407.585633) (xy 331.121771 -407.577928) (xy 331.131926 -407.577544) (xy 331.848206 -407.577544)
			(xy 331.858334 -407.578022) (xy 331.877056 -407.585752) (xy 331.891412 -407.600041) (xy 331.89923 -407.618727)
			(xy 331.899768 -407.628852) (xy 331.899768 -407.78684) (xy 331.900166 -407.796028) (xy 331.906689 -407.813212)
			(xy 331.912468 -407.820368) (xy 331.934248 -407.846027) (xy 331.972196 -407.901612) (xy 332.00323 -407.961335)
			(xy 332.026903 -408.024339) (xy 332.042876 -408.08972) (xy 332.050921 -408.156542) (xy 332.050921 -408.223846)
			(xy 332.042878 -408.290668) (xy 332.026906 -408.35605) (xy 332.003235 -408.419054) (xy 331.972203 -408.478777)
			(xy 331.934255 -408.534364) (xy 331.912468 -408.560016) (xy 331.906678 -408.567166) (xy 331.90016 -408.584353)
			(xy 331.899768 -408.593544) (xy 331.899768 -409.086812) (xy 331.900179 -409.095999) (xy 331.906693 -409.113183)
			(xy 331.912468 -409.12034) (xy 331.93422 -409.146022) (xy 331.972169 -409.201604) (xy 332.003204 -409.261323)
			(xy 332.026878 -409.324324) (xy 332.042853 -409.389703) (xy 332.0509 -409.456522) (xy 332.050904 -409.523824)
			(xy 332.042863 -409.590644) (xy 332.026894 -409.656024) (xy 332.003226 -409.719027) (xy 331.972197 -409.77875)
			(xy 331.934253 -409.834336) (xy 331.912468 -409.859988) (xy 331.906647 -409.867116) (xy 331.900148 -409.88432)
			(xy 331.899768 -409.893516) (xy 331.899768 -410.051504) (xy 331.899381 -410.061662) (xy 331.891578 -410.080421)
			(xy 331.87717 -410.094745) (xy 331.858367 -410.102439) (xy 331.848206 -410.102812) (xy 331.131926 -410.102812)
			(xy 331.121807 -410.102254) (xy 331.103097 -410.094544) (xy 331.088741 -410.08028) (xy 331.080912 -410.061619)
			(xy 331.080364 -410.051504) (xy 331.080364 -409.893516) (xy 331.079932 -409.884331) (xy 331.073432 -409.867148)
			(xy 331.067664 -409.859988) (xy 331.04584 -409.834365) (xy 331.007891 -409.778775) (xy 330.976857 -409.719048)
			(xy 330.953186 -409.656039) (xy 330.937214 -409.590653) (xy 330.929173 -409.523827) (xy 326.525636 -409.523827)
			(xy 326.525636 -410.623701) (xy 333.128819 -410.623701) (xy 333.12882 -410.556275) (xy 333.136898 -410.489336)
			(xy 333.152936 -410.423846) (xy 333.176702 -410.360748) (xy 333.207855 -410.300952) (xy 333.245947 -410.245317)
			(xy 333.267812 -410.219652) (xy 333.273613 -410.21251) (xy 333.280125 -410.195317) (xy 333.280512 -410.186124)
			(xy 333.280512 -409.693872) (xy 333.280113 -409.684684) (xy 333.273591 -409.6675) (xy 333.267812 -409.660344)
			(xy 333.245959 -409.634669) (xy 333.20787 -409.579036) (xy 333.176718 -409.519242) (xy 333.152952 -409.456146)
			(xy 333.136916 -409.390658) (xy 333.128839 -409.32372) (xy 333.128837 -409.256298) (xy 333.136912 -409.18936)
			(xy 333.152947 -409.123871) (xy 333.17671 -409.060775) (xy 333.20786 -409.000979) (xy 333.245948 -408.945345)
			(xy 333.267812 -408.91968) (xy 333.273601 -408.912529) (xy 333.28012 -408.895343) (xy 333.280512 -408.886152)
			(xy 333.280512 -408.728672) (xy 333.280962 -408.71856) (xy 333.288711 -408.699879) (xy 333.303019 -408.685585)
			(xy 333.321708 -408.677853) (xy 333.33182 -408.677364) (xy 334.0481 -408.677364) (xy 334.058204 -408.677884)
			(xy 334.076876 -408.685615) (xy 334.091169 -408.699901) (xy 334.09891 -408.718568) (xy 334.099408 -408.728672)
			(xy 334.099408 -408.886152) (xy 334.099839 -408.895337) (xy 334.106338 -408.912522) (xy 334.112108 -408.91968)
			(xy 334.133983 -408.945336) (xy 334.172071 -409.000972) (xy 334.203221 -409.060769) (xy 334.226984 -409.123867)
			(xy 334.243019 -409.189358) (xy 334.251093 -409.256297) (xy 334.251092 -409.323721) (xy 334.243015 -409.39066)
			(xy 334.226979 -409.45615) (xy 334.203214 -409.519247) (xy 334.200797 -409.523886) (xy 335.328966 -409.523886)
			(xy 335.328969 -409.45646) (xy 335.337048 -409.38952) (xy 335.353086 -409.32403) (xy 335.376852 -409.260931)
			(xy 335.408005 -409.201134) (xy 335.446095 -409.145498) (xy 335.46796 -409.119832) (xy 335.473775 -409.1127)
			(xy 335.480277 -409.095499) (xy 335.48066 -409.086304) (xy 335.48066 -408.594052) (xy 335.480211 -408.584869)
			(xy 335.473723 -408.567685) (xy 335.46796 -408.560524) (xy 335.44609 -408.534865) (xy 335.408004 -408.479228)
			(xy 335.376856 -408.419431) (xy 335.353094 -408.356333) (xy 335.33706 -408.290844) (xy 335.328985 -408.223906)
			(xy 335.328986 -408.156482) (xy 335.337062 -408.089544) (xy 335.353097 -408.024055) (xy 335.376861 -407.960958)
			(xy 335.40801 -407.901161) (xy 335.446097 -407.845526) (xy 335.46796 -407.81986) (xy 335.473763 -407.81272)
			(xy 335.480272 -407.795525) (xy 335.48066 -407.786332) (xy 335.48066 -407.628852) (xy 335.481145 -407.618745)
			(xy 335.488891 -407.600074) (xy 335.503187 -407.585782) (xy 335.521861 -407.578042) (xy 335.531968 -407.577544)
			(xy 336.248248 -407.577544) (xy 336.258353 -407.578045) (xy 336.277021 -407.585788) (xy 336.291312 -407.600079)
			(xy 336.299055 -407.618747) (xy 336.299556 -407.628852) (xy 336.299556 -407.786332) (xy 336.299961 -407.79552)
			(xy 336.306479 -407.812703) (xy 336.312256 -407.81986) (xy 336.334114 -407.845531) (xy 336.372205 -407.901164)
			(xy 336.403359 -407.960959) (xy 336.427126 -408.024055) (xy 336.443163 -408.089544) (xy 336.45124 -408.156482)
			(xy 336.451241 -408.223906) (xy 336.443165 -408.290844) (xy 336.427129 -408.356334) (xy 336.403364 -408.41943)
			(xy 336.372212 -408.479226) (xy 336.334121 -408.53486) (xy 336.312256 -408.560524) (xy 336.306461 -408.56767)
			(xy 336.299947 -408.58486) (xy 336.299556 -408.594052) (xy 336.299556 -409.086304) (xy 336.299974 -409.09549)
			(xy 336.306483 -409.112674) (xy 336.312256 -409.119832) (xy 336.334086 -409.145526) (xy 336.372179 -409.201155)
			(xy 336.403334 -409.260947) (xy 336.427102 -409.32404) (xy 336.443141 -409.389526) (xy 336.45122 -409.456462)
			(xy 336.451224 -409.523884) (xy 336.443151 -409.59082) (xy 336.427118 -409.656308) (xy 336.403356 -409.719404)
			(xy 336.372207 -409.779198) (xy 336.334119 -409.834832) (xy 336.312256 -409.860496) (xy 336.306473 -409.867651)
			(xy 336.299951 -409.884834) (xy 336.299556 -409.894024) (xy 336.299556 -410.051504) (xy 336.299019 -410.061606)
			(xy 336.291291 -410.080274) (xy 336.277011 -410.094566) (xy 336.25835 -410.102311) (xy 336.248248 -410.102812)
			(xy 335.531968 -410.102812) (xy 335.521859 -410.102341) (xy 335.503182 -410.094595) (xy 335.488889 -410.080294)
			(xy 335.481153 -410.061614) (xy 335.48066 -410.051504) (xy 335.48066 -409.894024) (xy 335.480225 -409.88484)
			(xy 335.473727 -409.867656) (xy 335.46796 -409.860496) (xy 335.446062 -409.834859) (xy 335.407977 -409.77922)
			(xy 335.37683 -409.719419) (xy 335.35307 -409.656319) (xy 335.337038 -409.590827) (xy 335.328966 -409.523886)
			(xy 334.200797 -409.523886) (xy 334.172062 -409.579044) (xy 334.133972 -409.634679) (xy 334.112108 -409.660344)
			(xy 334.106311 -409.667489) (xy 334.099796 -409.68468) (xy 334.099408 -409.693872) (xy 334.099408 -410.186124)
			(xy 334.099805 -410.195313) (xy 334.106328 -410.212497) (xy 334.112108 -410.219652) (xy 334.133956 -410.24533)
			(xy 334.172045 -410.300963) (xy 334.203196 -410.360758) (xy 334.22696 -410.423853) (xy 334.242997 -410.48934)
			(xy 334.251074 -410.556277) (xy 334.251075 -410.623641) (xy 337.529138 -410.623641) (xy 337.52914 -410.556335)
			(xy 337.537185 -410.489512) (xy 337.553158 -410.42413) (xy 337.576831 -410.361125) (xy 337.607864 -410.3014)
			(xy 337.645813 -410.245813) (xy 337.6676 -410.22016) (xy 337.673396 -410.213014) (xy 337.679911 -410.195824)
			(xy 337.6803 -410.186632) (xy 337.6803 -409.693364) (xy 337.679907 -409.684175) (xy 337.673382 -409.666991)
			(xy 337.6676 -409.659836) (xy 337.645825 -409.634174) (xy 337.607879 -409.578588) (xy 337.576847 -409.518865)
			(xy 337.553175 -409.455862) (xy 337.537203 -409.390482) (xy 337.529158 -409.323661) (xy 337.529157 -409.256357)
			(xy 337.537199 -409.189536) (xy 337.55317 -409.124155) (xy 337.57684 -409.061151) (xy 337.607869 -409.001428)
			(xy 337.645814 -408.945841) (xy 337.6676 -408.920188) (xy 337.673384 -408.913034) (xy 337.679906 -408.89585)
			(xy 337.6803 -408.88666) (xy 337.6803 -408.728672) (xy 337.680699 -408.718516) (xy 337.688503 -408.699763)
			(xy 337.702907 -408.685441) (xy 337.721704 -408.677742) (xy 337.731862 -408.677364) (xy 338.448142 -408.677364)
			(xy 338.458274 -408.677793) (xy 338.477001 -408.685539) (xy 338.491357 -408.699843) (xy 338.49917 -408.718542)
			(xy 338.499704 -408.728672) (xy 338.499704 -408.88666) (xy 338.500132 -408.895845) (xy 338.506633 -408.91303)
			(xy 338.512404 -408.920188) (xy 338.534202 -408.945831) (xy 338.572148 -409.00142) (xy 338.603178 -409.061145)
			(xy 338.626848 -409.124151) (xy 338.642819 -409.189534) (xy 338.650862 -409.256356) (xy 338.650861 -409.323662)
			(xy 338.642816 -409.390484) (xy 338.626843 -409.455867) (xy 338.603171 -409.518871) (xy 338.600596 -409.523827)
			(xy 339.729261 -409.523827) (xy 339.729264 -409.456519) (xy 339.737312 -409.389694) (xy 339.753289 -409.324309)
			(xy 339.776966 -409.261303) (xy 339.808004 -409.201579) (xy 339.845958 -409.145992) (xy 339.867748 -409.12034)
			(xy 339.873559 -409.113205) (xy 339.880064 -409.096006) (xy 339.880448 -409.086812) (xy 339.880448 -408.593544)
			(xy 339.880006 -408.58436) (xy 339.873513 -408.567176) (xy 339.867748 -408.560016) (xy 339.845952 -408.534371)
			(xy 339.808003 -408.478783) (xy 339.776969 -408.419059) (xy 339.753297 -408.356054) (xy 339.737324 -408.29067)
			(xy 339.72928 -408.223847) (xy 339.729281 -408.156541) (xy 339.737326 -408.089718) (xy 339.7533 -408.024335)
			(xy 339.776974 -407.96133) (xy 339.808009 -407.901606) (xy 339.845959 -407.84602) (xy 339.867748 -407.820368)
			(xy 339.873547 -407.813224) (xy 339.880059 -407.796032) (xy 339.880448 -407.78684) (xy 339.880448 -407.628852)
			(xy 339.880881 -407.618701) (xy 339.888683 -407.599958) (xy 339.903075 -407.585638) (xy 339.921857 -407.577931)
			(xy 339.93201 -407.577544) (xy 340.64829 -407.577544) (xy 340.658417 -407.578035) (xy 340.677138 -407.58576)
			(xy 340.691495 -407.600045) (xy 340.699314 -407.618728) (xy 340.699852 -407.628852) (xy 340.699852 -407.78684)
			(xy 340.700254 -407.796028) (xy 340.706775 -407.813211) (xy 340.712552 -407.820368) (xy 340.734332 -407.846027)
			(xy 340.772282 -407.901612) (xy 340.803316 -407.961335) (xy 340.826989 -408.024338) (xy 340.842963 -408.08972)
			(xy 340.851008 -408.156542) (xy 340.851009 -408.223846) (xy 340.842965 -408.290668) (xy 340.826993 -408.35605)
			(xy 340.803321 -408.419054) (xy 340.772288 -408.478778) (xy 340.734339 -408.534364) (xy 340.712552 -408.560016)
			(xy 340.70676 -408.567164) (xy 340.700244 -408.584353) (xy 340.699852 -408.593544) (xy 340.699852 -409.086812)
			(xy 340.700267 -409.095998) (xy 340.706779 -409.113182) (xy 340.712552 -409.12034) (xy 340.734304 -409.146021)
			(xy 340.772255 -409.201603) (xy 340.80329 -409.261323) (xy 340.826965 -409.324323) (xy 340.842941 -409.389702)
			(xy 340.850988 -409.456522) (xy 340.850992 -409.523824) (xy 340.842951 -409.590644) (xy 340.826981 -409.656025)
			(xy 340.803312 -409.719028) (xy 340.772283 -409.77875) (xy 340.734338 -409.834336) (xy 340.712552 -409.859988)
			(xy 340.70673 -409.867115) (xy 340.700232 -409.88432) (xy 340.699852 -409.893516) (xy 340.699852 -410.051504)
			(xy 340.699383 -410.061652) (xy 340.691595 -410.080394) (xy 340.677214 -410.094716) (xy 340.65844 -410.102424)
			(xy 340.64829 -410.102812) (xy 339.93201 -410.102812) (xy 339.92189 -410.102267) (xy 339.903179 -410.094552)
			(xy 339.888824 -410.080284) (xy 339.880996 -410.061621) (xy 339.880448 -410.051504) (xy 339.880448 -409.893516)
			(xy 339.88002 -409.884331) (xy 339.873517 -409.867147) (xy 339.867748 -409.859988) (xy 339.845924 -409.834365)
			(xy 339.807976 -409.778775) (xy 339.776944 -409.719047) (xy 339.753273 -409.656039) (xy 339.737302 -409.590653)
			(xy 339.729261 -409.523827) (xy 338.600596 -409.523827) (xy 338.572139 -409.578596) (xy 338.534191 -409.634183)
			(xy 338.512404 -409.659836) (xy 338.50661 -409.666983) (xy 338.500094 -409.684172) (xy 338.499704 -409.693364)
			(xy 338.499704 -410.186632) (xy 338.500098 -410.195821) (xy 338.506623 -410.213005) (xy 338.512404 -410.22016)
			(xy 338.534175 -410.245826) (xy 338.572121 -410.301411) (xy 338.603153 -410.361133) (xy 338.626825 -410.424136)
			(xy 338.642797 -410.489516) (xy 338.650842 -410.556336) (xy 338.650844 -410.623639) (xy 338.650837 -410.6237)
			(xy 341.928907 -410.6237) (xy 341.928908 -410.556276) (xy 341.936986 -410.489336) (xy 341.953023 -410.423846)
			(xy 341.976789 -410.360749) (xy 342.007941 -410.300952) (xy 342.046031 -410.245317) (xy 342.067896 -410.219652)
			(xy 342.073695 -410.212508) (xy 342.080208 -410.195317) (xy 342.080596 -410.186124) (xy 342.080596 -409.693872)
			(xy 342.0802 -409.684683) (xy 342.073677 -409.667499) (xy 342.067896 -409.660344) (xy 342.046044 -409.634669)
			(xy 342.007955 -409.579036) (xy 341.976804 -409.519241) (xy 341.953039 -409.456145) (xy 341.937003 -409.390657)
			(xy 341.928927 -409.32372) (xy 341.928925 -409.256298) (xy 341.937 -409.18936) (xy 341.953034 -409.123872)
			(xy 341.976797 -409.060776) (xy 342.007946 -409.00098) (xy 342.046033 -408.945345) (xy 342.067896 -408.91968)
			(xy 342.073683 -408.912528) (xy 342.080204 -408.895343) (xy 342.080596 -408.886152) (xy 342.080596 -408.728672)
			(xy 342.081062 -408.718562) (xy 342.088808 -408.699884) (xy 342.103111 -408.68559) (xy 342.121794 -408.677856)
			(xy 342.131904 -408.677364) (xy 342.848184 -408.677364) (xy 342.858287 -408.677897) (xy 342.876958 -408.685623)
			(xy 342.891252 -408.699905) (xy 342.898994 -408.718569) (xy 342.899492 -408.728672) (xy 342.899492 -408.886152)
			(xy 342.899927 -408.895337) (xy 342.906424 -408.912521) (xy 342.912192 -408.91968) (xy 342.934068 -408.945335)
			(xy 342.972157 -409.000971) (xy 343.003308 -409.060769) (xy 343.027071 -409.123867) (xy 343.043106 -409.189357)
			(xy 343.051181 -409.256297) (xy 343.05118 -409.323721) (xy 343.043103 -409.390661) (xy 343.027066 -409.45615)
			(xy 343.0033 -409.519248) (xy 343.000914 -409.523827) (xy 344.129052 -409.523827) (xy 344.129055 -409.456519)
			(xy 344.137102 -409.389694) (xy 344.153079 -409.32431) (xy 344.176756 -409.261304) (xy 344.207793 -409.201579)
			(xy 344.245746 -409.145992) (xy 344.267536 -409.12034) (xy 344.273345 -409.113204) (xy 344.279851 -409.096006)
			(xy 344.280236 -409.086812) (xy 344.280236 -408.593544) (xy 344.279796 -408.58436) (xy 344.273302 -408.567176)
			(xy 344.267536 -408.560016) (xy 344.24574 -408.53437) (xy 344.207792 -408.478783) (xy 344.176759 -408.419058)
			(xy 344.153087 -408.356053) (xy 344.137115 -408.29067) (xy 344.129071 -408.223847) (xy 344.129072 -408.156541)
			(xy 344.137117 -408.089718) (xy 344.153091 -408.024335) (xy 344.176764 -407.961331) (xy 344.207798 -407.901607)
			(xy 344.245748 -407.84602) (xy 344.267536 -407.820368) (xy 344.273333 -407.813223) (xy 344.279847 -407.796032)
			(xy 344.280236 -407.78684) (xy 344.280236 -407.628852) (xy 344.280583 -407.61869) (xy 344.288401 -407.59993)
			(xy 344.302821 -407.585607) (xy 344.321634 -407.577916) (xy 344.331798 -407.577544) (xy 345.048078 -407.577544)
			(xy 345.058204 -407.578045) (xy 345.076925 -407.585766) (xy 345.091283 -407.600048) (xy 345.099102 -407.618729)
			(xy 345.09964 -407.628852) (xy 345.09964 -407.78684) (xy 345.100044 -407.796028) (xy 345.106563 -407.813211)
			(xy 345.11234 -407.820368) (xy 345.13412 -407.846026) (xy 345.172071 -407.901611) (xy 345.203106 -407.961334)
			(xy 345.22678 -408.024338) (xy 345.242754 -408.089719) (xy 345.250799 -408.156542) (xy 345.2508 -408.223846)
			(xy 345.242756 -408.290669) (xy 345.226783 -408.356051) (xy 345.20311 -408.419055) (xy 345.172077 -408.478778)
			(xy 345.134128 -408.534364) (xy 345.11234 -408.560016) (xy 345.106547 -408.567163) (xy 345.100032 -408.584352)
			(xy 345.09964 -408.593544) (xy 345.09964 -409.086812) (xy 345.100058 -409.095998) (xy 345.106568 -409.113182)
			(xy 345.11234 -409.12034) (xy 345.134093 -409.146021) (xy 345.172044 -409.201603) (xy 345.20308 -409.261322)
			(xy 345.226756 -409.324323) (xy 345.242732 -409.389702) (xy 345.250779 -409.456522) (xy 345.250783 -409.523824)
			(xy 345.242742 -409.590645) (xy 345.226772 -409.656025) (xy 345.203102 -409.719028) (xy 345.172072 -409.778751)
			(xy 345.134126 -409.834336) (xy 345.11234 -409.859988) (xy 345.106516 -409.867114) (xy 345.100019 -409.884319)
			(xy 345.09964 -409.893516) (xy 345.09964 -410.051504) (xy 345.099182 -410.061653) (xy 345.091393 -410.080398)
			(xy 345.077008 -410.09472) (xy 345.058229 -410.102427) (xy 345.048078 -410.102812) (xy 344.331798 -410.102812)
			(xy 344.321678 -410.102277) (xy 344.302966 -410.094558) (xy 344.288612 -410.080287) (xy 344.280784 -410.061621)
			(xy 344.280236 -410.051504) (xy 344.280236 -409.893516) (xy 344.27981 -409.884331) (xy 344.273307 -409.867146)
			(xy 344.267536 -409.859988) (xy 344.245713 -409.834365) (xy 344.207765 -409.778774) (xy 344.176734 -409.719047)
			(xy 344.153063 -409.656038) (xy 344.137093 -409.590653) (xy 344.129052 -409.523827) (xy 343.000914 -409.523827)
			(xy 342.972148 -409.579044) (xy 342.934057 -409.634679) (xy 342.912192 -409.660344) (xy 342.906393 -409.667488)
			(xy 342.89988 -409.684679) (xy 342.899492 -409.693872) (xy 342.899492 -410.186124) (xy 342.899892 -410.195312)
			(xy 342.906413 -410.212496) (xy 342.912192 -410.219652) (xy 342.934041 -410.24533) (xy 342.97213 -410.300963)
			(xy 343.003282 -410.360757) (xy 343.027048 -410.423852) (xy 343.043084 -410.48934) (xy 343.051162 -410.556277)
			(xy 343.051163 -410.623642) (xy 346.329202 -410.623642) (xy 346.329204 -410.556334) (xy 346.33725 -410.48951)
			(xy 346.353226 -410.424126) (xy 346.376903 -410.361121) (xy 346.40794 -410.301397) (xy 346.445894 -410.245812)
			(xy 346.467684 -410.22016) (xy 346.473478 -410.213013) (xy 346.479995 -410.195824) (xy 346.480384 -410.186632)
			(xy 346.480384 -409.693364) (xy 346.479995 -409.684175) (xy 346.473467 -409.66699) (xy 346.467684 -409.659836)
			(xy 346.445907 -409.634175) (xy 346.407955 -409.578591) (xy 346.376918 -409.518869) (xy 346.353243 -409.455865)
			(xy 346.337268 -409.390484) (xy 346.329222 -409.323661) (xy 346.329221 -409.256357) (xy 346.337265 -409.189534)
			(xy 346.353238 -409.124152) (xy 346.376911 -409.061148) (xy 346.407945 -409.001425) (xy 346.445896 -408.94584)
			(xy 346.467684 -408.920188) (xy 346.473466 -408.913033) (xy 346.47999 -408.89585) (xy 346.480384 -408.88666)
			(xy 346.480384 -408.728672) (xy 346.480798 -408.718518) (xy 346.4886 -408.699768) (xy 346.502999 -408.685446)
			(xy 346.52179 -408.677745) (xy 346.531946 -408.677364) (xy 347.248226 -408.677364) (xy 347.258357 -408.677806)
			(xy 347.277084 -408.685547) (xy 347.29144 -408.699847) (xy 347.299254 -408.718543) (xy 347.299788 -408.728672)
			(xy 347.299788 -408.88666) (xy 347.30022 -408.895845) (xy 347.306719 -408.913029) (xy 347.312488 -408.920188)
			(xy 347.334287 -408.945831) (xy 347.372233 -409.001419) (xy 347.403265 -409.061144) (xy 347.426936 -409.12415)
			(xy 347.442907 -409.189533) (xy 347.45095 -409.256356) (xy 347.450949 -409.323662) (xy 347.442904 -409.390485)
			(xy 347.42693 -409.455867) (xy 347.403257 -409.518872) (xy 347.400682 -409.523827) (xy 374.929082 -409.523827)
			(xy 374.929085 -409.456519) (xy 374.937133 -409.389693) (xy 374.953111 -409.324308) (xy 374.97679 -409.261302)
			(xy 375.007829 -409.201578) (xy 375.045785 -409.145991) (xy 375.067576 -409.12034) (xy 375.073378 -409.113198)
			(xy 375.07989 -409.096005) (xy 375.080276 -409.086812) (xy 375.080276 -408.593544) (xy 375.07985 -408.584358)
			(xy 375.073348 -408.567174) (xy 375.067576 -408.560016) (xy 375.045779 -408.534371) (xy 375.007828 -408.478784)
			(xy 374.976793 -408.41906) (xy 374.953119 -408.356055) (xy 374.937146 -408.290671) (xy 374.929102 -408.223847)
			(xy 374.929103 -408.156541) (xy 374.937148 -408.089717) (xy 374.953123 -408.024334) (xy 374.976798 -407.961329)
			(xy 375.007835 -407.901605) (xy 375.045787 -407.84602) (xy 375.067576 -407.820368) (xy 375.073366 -407.813218)
			(xy 375.079885 -407.796031) (xy 375.080276 -407.78684) (xy 375.080276 -407.628852) (xy 375.080682 -407.618698)
			(xy 375.088489 -407.599949) (xy 375.10289 -407.585628) (xy 375.121682 -407.577926) (xy 375.131838 -407.577544)
			(xy 375.848118 -407.577544) (xy 375.858246 -407.578012) (xy 375.876969 -407.585746) (xy 375.891325 -407.600038)
			(xy 375.899143 -407.618726) (xy 375.89968 -407.628852) (xy 375.89968 -407.78684) (xy 375.900075 -407.796029)
			(xy 375.9066 -407.813213) (xy 375.91238 -407.820368) (xy 375.934159 -407.846027) (xy 375.972107 -407.901613)
			(xy 376.00314 -407.961336) (xy 376.026812 -408.024339) (xy 376.042785 -408.08972) (xy 376.05083 -408.156542)
			(xy 376.05083 -408.223846) (xy 376.042787 -408.290668) (xy 376.026816 -408.356049) (xy 376.003145 -408.419053)
			(xy 375.972113 -408.478777) (xy 375.934167 -408.534364) (xy 375.91238 -408.560016) (xy 375.906592 -408.567167)
			(xy 375.900073 -408.584353) (xy 375.89968 -408.593544) (xy 375.89968 -409.086812) (xy 375.900089 -409.095999)
			(xy 375.906604 -409.113183) (xy 375.91238 -409.12034) (xy 375.934131 -409.146022) (xy 375.97208 -409.201604)
			(xy 376.003114 -409.261324) (xy 376.026788 -409.324325) (xy 376.042763 -409.389703) (xy 376.050809 -409.456522)
			(xy 376.050813 -409.523824) (xy 376.042772 -409.590644) (xy 376.026804 -409.656024) (xy 376.003136 -409.719026)
			(xy 375.972108 -409.778749) (xy 375.934165 -409.834335) (xy 375.91238 -409.859988) (xy 375.906561 -409.867117)
			(xy 375.90006 -409.88432) (xy 375.89968 -409.893516) (xy 375.89968 -410.051504) (xy 375.899281 -410.061661)
			(xy 375.891481 -410.080417) (xy 375.877077 -410.094741) (xy 375.858277 -410.102437) (xy 375.848118 -410.102812)
			(xy 375.131838 -410.102812) (xy 375.12172 -410.102244) (xy 375.10301 -410.094538) (xy 375.088654 -410.080277)
			(xy 375.080824 -410.061618) (xy 375.080276 -410.051504) (xy 375.080276 -409.893516) (xy 375.079864 -409.884329)
			(xy 375.073352 -409.867144) (xy 375.067576 -409.859988) (xy 375.045751 -409.834366) (xy 375.007801 -409.778776)
			(xy 374.976768 -409.719048) (xy 374.953095 -409.65604) (xy 374.937124 -409.590654) (xy 374.929082 -409.523827)
			(xy 347.400682 -409.523827) (xy 347.372224 -409.578596) (xy 347.334276 -409.634184) (xy 347.312488 -409.659836)
			(xy 347.306692 -409.666982) (xy 347.300177 -409.684172) (xy 347.299788 -409.693364) (xy 347.299788 -410.186632)
			(xy 347.300185 -410.195821) (xy 347.306708 -410.213005) (xy 347.312488 -410.22016) (xy 347.334259 -410.245825)
			(xy 347.372207 -410.301411) (xy 347.403239 -410.361133) (xy 347.426912 -410.424135) (xy 347.442885 -410.489516)
			(xy 347.45093 -410.556336) (xy 347.450931 -410.62364) (xy 347.450924 -410.623701) (xy 377.128728 -410.623701)
			(xy 377.128729 -410.556275) (xy 377.136807 -410.489335) (xy 377.152845 -410.423845) (xy 377.176612 -410.360748)
			(xy 377.207766 -410.300951) (xy 377.245858 -410.245317) (xy 377.267724 -410.219652) (xy 377.273526 -410.212511)
			(xy 377.280037 -410.195317) (xy 377.280424 -410.186124) (xy 377.280424 -409.693872) (xy 377.280022 -409.684684)
			(xy 377.273502 -409.6675) (xy 377.267724 -409.660344) (xy 377.245871 -409.634669) (xy 377.20778 -409.579037)
			(xy 377.176628 -409.519242) (xy 377.152862 -409.456146) (xy 377.136825 -409.390658) (xy 377.128748 -409.323721)
			(xy 377.128747 -409.256297) (xy 377.136822 -409.18936) (xy 377.152857 -409.123871) (xy 377.17662 -409.060774)
			(xy 377.207771 -409.000979) (xy 377.24586 -408.945345) (xy 377.267724 -408.91968) (xy 377.273514 -408.912531)
			(xy 377.280032 -408.895343) (xy 377.280424 -408.886152) (xy 377.280424 -408.728672) (xy 377.280794 -408.718545)
			(xy 377.288555 -408.699836) (xy 377.302886 -408.685522) (xy 377.321604 -408.677782) (xy 377.331732 -408.677364)
			(xy 378.048012 -408.677364) (xy 378.058117 -408.677875) (xy 378.076789 -408.685609) (xy 378.091082 -408.699898)
			(xy 378.098822 -408.718567) (xy 378.09932 -408.728672) (xy 378.09932 -408.886152) (xy 378.099749 -408.895337)
			(xy 378.106249 -408.912522) (xy 378.11202 -408.91968) (xy 378.133895 -408.945336) (xy 378.171982 -409.000972)
			(xy 378.203131 -409.06077) (xy 378.226894 -409.123868) (xy 378.242928 -409.189358) (xy 378.251002 -409.256297)
			(xy 378.251001 -409.323721) (xy 378.242925 -409.39066) (xy 378.226888 -409.456149) (xy 378.203124 -409.519247)
			(xy 378.200707 -409.523886) (xy 379.328875 -409.523886) (xy 379.328878 -409.45646) (xy 379.336957 -409.38952)
			(xy 379.352995 -409.324029) (xy 379.376762 -409.260931) (xy 379.407916 -409.201133) (xy 379.446007 -409.145498)
			(xy 379.467872 -409.119832) (xy 379.473689 -409.112701) (xy 379.480189 -409.095499) (xy 379.480572 -409.086304)
			(xy 379.480572 -408.594052) (xy 379.480143 -408.584867) (xy 379.473643 -408.567682) (xy 379.467872 -408.560524)
			(xy 379.446001 -408.534865) (xy 379.407915 -408.479229) (xy 379.376766 -408.419431) (xy 379.353003 -408.356334)
			(xy 379.336969 -408.290844) (xy 379.328894 -408.223906) (xy 379.328895 -408.156482) (xy 379.336971 -408.089544)
			(xy 379.353007 -408.024055) (xy 379.376771 -407.960958) (xy 379.407921 -407.901161) (xy 379.446009 -407.845526)
			(xy 379.467872 -407.81986) (xy 379.473677 -407.812721) (xy 379.480185 -407.795525) (xy 379.480572 -407.786332)
			(xy 379.480572 -407.628852) (xy 379.481045 -407.618744) (xy 379.488793 -407.60007) (xy 379.503093 -407.585778)
			(xy 379.521771 -407.57804) (xy 379.53188 -407.577544) (xy 380.24816 -407.577544) (xy 380.258259 -407.578117)
			(xy 380.276926 -407.585831) (xy 380.29122 -407.6001) (xy 380.298966 -407.618754) (xy 380.299468 -407.628852)
			(xy 380.299468 -407.786332) (xy 380.29987 -407.79552) (xy 380.30639 -407.812704) (xy 380.312168 -407.81986)
			(xy 380.334025 -407.845531) (xy 380.372116 -407.901164) (xy 380.403269 -407.960959) (xy 380.427035 -408.024055)
			(xy 380.443072 -408.089544) (xy 380.451149 -408.156482) (xy 380.45115 -408.223906) (xy 380.443074 -408.290844)
			(xy 380.427039 -408.356333) (xy 380.403274 -408.41943) (xy 380.372122 -408.479226) (xy 380.334033 -408.534859)
			(xy 380.312168 -408.560524) (xy 380.306375 -408.567671) (xy 380.299859 -408.58486) (xy 380.299468 -408.594052)
			(xy 380.299468 -409.086304) (xy 380.299883 -409.09549) (xy 380.306394 -409.112675) (xy 380.312168 -409.119832)
			(xy 380.333998 -409.145526) (xy 380.37209 -409.201156) (xy 380.403244 -409.260947) (xy 380.427011 -409.324041)
			(xy 380.44305 -409.389527) (xy 380.451129 -409.456462) (xy 380.451133 -409.523884) (xy 380.44306 -409.59082)
			(xy 380.427027 -409.656308) (xy 380.403266 -409.719403) (xy 380.372117 -409.779198) (xy 380.334031 -409.834831)
			(xy 380.312168 -409.860496) (xy 380.306386 -409.867652) (xy 380.299864 -409.884834) (xy 380.299468 -409.894024)
			(xy 380.299468 -410.051504) (xy 380.299086 -410.061631) (xy 380.291331 -410.08034) (xy 380.277003 -410.094656)
			(xy 380.258287 -410.102395) (xy 380.24816 -410.102812) (xy 379.53188 -410.102812) (xy 379.521771 -410.102332)
			(xy 379.503095 -410.09459) (xy 379.488801 -410.080292) (xy 379.481065 -410.061613) (xy 379.480572 -410.051504)
			(xy 379.480572 -409.894024) (xy 379.480157 -409.884837) (xy 379.473647 -409.867652) (xy 379.467872 -409.860496)
			(xy 379.445974 -409.834859) (xy 379.407888 -409.77922) (xy 379.37674 -409.71942) (xy 379.352979 -409.656319)
			(xy 379.336947 -409.590827) (xy 379.328875 -409.523886) (xy 378.200707 -409.523886) (xy 378.171973 -409.579043)
			(xy 378.133884 -409.634678) (xy 378.11202 -409.660344) (xy 378.106225 -409.66749) (xy 378.099709 -409.68468)
			(xy 378.09932 -409.693872) (xy 378.09932 -410.186124) (xy 378.099714 -410.195313) (xy 378.106239 -410.212497)
			(xy 378.11202 -410.219652) (xy 378.133868 -410.245331) (xy 378.171955 -410.300964) (xy 378.203106 -410.360758)
			(xy 378.22687 -410.423853) (xy 378.242906 -410.48934) (xy 378.250983 -410.556277) (xy 378.250984 -410.623641)
			(xy 381.529047 -410.623641) (xy 381.529049 -410.556335) (xy 381.537094 -410.489512) (xy 381.553068 -410.424129)
			(xy 381.576742 -410.361124) (xy 381.607775 -410.3014) (xy 381.645724 -410.245812) (xy 381.667512 -410.22016)
			(xy 381.673309 -410.213015) (xy 381.679823 -410.195824) (xy 381.680212 -410.186632) (xy 381.680212 -409.693364)
			(xy 381.679817 -409.684175) (xy 381.673292 -409.666991) (xy 381.667512 -409.659836) (xy 381.645737 -409.634174)
			(xy 381.607789 -409.578588) (xy 381.576757 -409.518866) (xy 381.553085 -409.455863) (xy 381.537112 -409.390482)
			(xy 381.529067 -409.323661) (xy 381.529066 -409.256357) (xy 381.537109 -409.189536) (xy 381.553079 -409.124155)
			(xy 381.57675 -409.061151) (xy 381.60778 -409.001427) (xy 381.645726 -408.94584) (xy 381.667512 -408.920188)
			(xy 381.673298 -408.913035) (xy 381.679818 -408.89585) (xy 381.680212 -408.88666) (xy 381.680212 -408.728672)
			(xy 381.680662 -408.71856) (xy 381.688411 -408.699879) (xy 381.702719 -408.685585) (xy 381.721408 -408.677853)
			(xy 381.73152 -408.677364) (xy 382.448054 -408.677364) (xy 382.458181 -408.677865) (xy 382.476905 -408.685582)
			(xy 382.491264 -408.699865) (xy 382.499081 -408.718548) (xy 382.499616 -408.728672) (xy 382.499616 -408.88666)
			(xy 382.500042 -408.895846) (xy 382.506544 -408.91303) (xy 382.512316 -408.920188) (xy 382.534117 -408.94583)
			(xy 382.572068 -409.001417) (xy 382.603103 -409.061141) (xy 382.626778 -409.124147) (xy 382.642751 -409.189531)
			(xy 382.650795 -409.256356) (xy 382.650794 -409.323662) (xy 382.642748 -409.390487) (xy 382.626772 -409.45587)
			(xy 382.603096 -409.518875) (xy 382.600523 -409.523827) (xy 383.72917 -409.523827) (xy 383.729173 -409.456519)
			(xy 383.737221 -409.389693) (xy 383.753198 -409.324309) (xy 383.776876 -409.261303) (xy 383.807915 -409.201578)
			(xy 383.845869 -409.145992) (xy 383.86766 -409.12034) (xy 383.873472 -409.113206) (xy 383.879976 -409.096007)
			(xy 383.88036 -409.086812) (xy 383.88036 -408.593544) (xy 383.879915 -408.584361) (xy 383.873424 -408.567177)
			(xy 383.86766 -408.560016) (xy 383.845864 -408.53437) (xy 383.807914 -408.478784) (xy 383.77688 -408.419059)
			(xy 383.753207 -408.356054) (xy 383.737234 -408.290671) (xy 383.72919 -408.223847) (xy 383.729191 -408.156541)
			(xy 383.737236 -408.089717) (xy 383.75321 -408.024335) (xy 383.776885 -407.96133) (xy 383.80792 -407.901606)
			(xy 383.845871 -407.84602) (xy 383.86766 -407.820368) (xy 383.87346 -407.813226) (xy 383.879971 -407.796033)
			(xy 383.88036 -407.78684) (xy 383.88036 -407.628852) (xy 383.880845 -407.618745) (xy 383.888591 -407.600074)
			(xy 383.902887 -407.585782) (xy 383.921561 -407.578042) (xy 383.931668 -407.577544) (xy 384.648202 -407.577544)
			(xy 384.658329 -407.578025) (xy 384.677051 -407.585754) (xy 384.691408 -407.600042) (xy 384.699226 -407.618727)
			(xy 384.699764 -407.628852) (xy 384.699764 -407.78684) (xy 384.700163 -407.796028) (xy 384.706685 -407.813212)
			(xy 384.712464 -407.820368) (xy 384.734244 -407.846027) (xy 384.772193 -407.901612) (xy 384.803226 -407.961335)
			(xy 384.826899 -408.024339) (xy 384.842873 -408.08972) (xy 384.850918 -408.156542) (xy 384.850918 -408.223846)
			(xy 384.842875 -408.290668) (xy 384.826903 -408.35605) (xy 384.803231 -408.419054) (xy 384.772199 -408.478778)
			(xy 384.734251 -408.534364) (xy 384.712464 -408.560016) (xy 384.706674 -408.567165) (xy 384.700156 -408.584353)
			(xy 384.699764 -408.593544) (xy 384.699764 -409.086812) (xy 384.700176 -409.095999) (xy 384.706689 -409.113183)
			(xy 384.712464 -409.12034) (xy 384.734216 -409.146021) (xy 384.772166 -409.201604) (xy 384.8032 -409.261323)
			(xy 384.826875 -409.324324) (xy 384.84285 -409.389703) (xy 384.850897 -409.456522) (xy 384.850901 -409.523824)
			(xy 384.84286 -409.590644) (xy 384.826891 -409.656024) (xy 384.803222 -409.719027) (xy 384.772194 -409.77875)
			(xy 384.734249 -409.834336) (xy 384.712464 -409.859988) (xy 384.706643 -409.867116) (xy 384.700144 -409.88432)
			(xy 384.699764 -409.893516) (xy 384.699764 -410.051504) (xy 384.699386 -410.061631) (xy 384.69163 -410.080342)
			(xy 384.677301 -410.094657) (xy 384.658584 -410.102396) (xy 384.648456 -410.102812) (xy 383.931922 -410.102812)
			(xy 383.921803 -410.102257) (xy 383.903092 -410.094546) (xy 383.888737 -410.080281) (xy 383.880908 -410.06162)
			(xy 383.88036 -410.051504) (xy 383.88036 -409.893516) (xy 383.879929 -409.884331) (xy 383.873428 -409.867147)
			(xy 383.86766 -409.859988) (xy 383.845836 -409.834365) (xy 383.807887 -409.778775) (xy 383.776854 -409.719048)
			(xy 383.753182 -409.656039) (xy 383.737211 -409.590653) (xy 383.72917 -409.523827) (xy 382.600523 -409.523827)
			(xy 382.572059 -409.578599) (xy 382.534106 -409.634184) (xy 382.512316 -409.659836) (xy 382.506523 -409.666984)
			(xy 382.500006 -409.684172) (xy 382.499616 -409.693364) (xy 382.499616 -410.186632) (xy 382.500007 -410.195821)
			(xy 382.506534 -410.213006) (xy 382.512316 -410.22016) (xy 382.534089 -410.245824) (xy 382.572042 -410.301408)
			(xy 382.603078 -410.36113) (xy 382.626754 -410.424133) (xy 382.642729 -410.489514) (xy 382.650775 -410.556336)
			(xy 382.650777 -410.62364) (xy 382.65077 -410.623701) (xy 385.928816 -410.623701) (xy 385.928817 -410.556275)
			(xy 385.936895 -410.489336) (xy 385.952932 -410.423846) (xy 385.976699 -410.360748) (xy 386.007852 -410.300952)
			(xy 386.045943 -410.245317) (xy 386.067808 -410.219652) (xy 386.073608 -410.21251) (xy 386.080121 -410.195317)
			(xy 386.080508 -410.186124) (xy 386.080508 -409.693872) (xy 386.08011 -409.684684) (xy 386.073588 -409.667499)
			(xy 386.067808 -409.660344) (xy 386.045956 -409.634669) (xy 386.007866 -409.579036) (xy 385.976714 -409.519241)
			(xy 385.952949 -409.456146) (xy 385.936913 -409.390658) (xy 385.928836 -409.32372) (xy 385.928834 -409.256298)
			(xy 385.936909 -409.18936) (xy 385.952944 -409.123871) (xy 385.976707 -409.060775) (xy 386.007857 -409.000979)
			(xy 386.045944 -408.945345) (xy 386.067808 -408.91968) (xy 386.073596 -408.912529) (xy 386.080116 -408.895343)
			(xy 386.080508 -408.886152) (xy 386.080508 -408.728672) (xy 386.080962 -408.71856) (xy 386.088711 -408.69988)
			(xy 386.103017 -408.685586) (xy 386.121704 -408.677854) (xy 386.131816 -408.677364) (xy 386.848096 -408.677364)
			(xy 386.8582 -408.677888) (xy 386.876871 -408.685617) (xy 386.891165 -408.699902) (xy 386.898906 -408.718568)
			(xy 386.899404 -408.728672) (xy 386.899404 -408.886152) (xy 386.899836 -408.895337) (xy 386.906334 -408.912522)
			(xy 386.912104 -408.91968) (xy 386.93398 -408.945336) (xy 386.972068 -409.000972) (xy 387.003218 -409.060769)
			(xy 387.026981 -409.123867) (xy 387.043016 -409.189357) (xy 387.05109 -409.256297) (xy 387.051089 -409.323721)
			(xy 387.043012 -409.39066) (xy 387.026976 -409.45615) (xy 387.00321 -409.519247) (xy 387.000824 -409.523827)
			(xy 388.128961 -409.523827) (xy 388.128964 -409.456519) (xy 388.137012 -409.389694) (xy 388.152989 -409.324309)
			(xy 388.176666 -409.261303) (xy 388.207704 -409.201579) (xy 388.245658 -409.145992) (xy 388.267448 -409.12034)
			(xy 388.273259 -409.113205) (xy 388.279764 -409.096006) (xy 388.280148 -409.086812) (xy 388.280148 -408.593544)
			(xy 388.279706 -408.58436) (xy 388.273213 -408.567176) (xy 388.267448 -408.560016) (xy 388.245652 -408.534371)
			(xy 388.207703 -408.478783) (xy 388.176669 -408.419059) (xy 388.152997 -408.356054) (xy 388.137024 -408.29067)
			(xy 388.12898 -408.223847) (xy 388.128981 -408.156541) (xy 388.137026 -408.089718) (xy 388.153 -408.024335)
			(xy 388.176674 -407.96133) (xy 388.207709 -407.901606) (xy 388.245659 -407.84602) (xy 388.267448 -407.820368)
			(xy 388.273247 -407.813224) (xy 388.279759 -407.796032) (xy 388.280148 -407.78684) (xy 388.280148 -407.628852)
			(xy 388.280645 -407.618747) (xy 388.288388 -407.600077) (xy 388.302681 -407.585786) (xy 388.321351 -407.578044)
			(xy 388.331456 -407.577544) (xy 389.04799 -407.577544) (xy 389.058117 -407.578035) (xy 389.076838 -407.58576)
			(xy 389.091195 -407.600045) (xy 389.099014 -407.618728) (xy 389.099552 -407.628852) (xy 389.099552 -407.78684)
			(xy 389.099954 -407.796028) (xy 389.106475 -407.813211) (xy 389.112252 -407.820368) (xy 389.134032 -407.846027)
			(xy 389.171982 -407.901612) (xy 389.203016 -407.961335) (xy 389.226689 -408.024338) (xy 389.242663 -408.08972)
			(xy 389.250708 -408.156542) (xy 389.250709 -408.223846) (xy 389.242665 -408.290668) (xy 389.226693 -408.35605)
			(xy 389.203021 -408.419054) (xy 389.171988 -408.478778) (xy 389.134039 -408.534364) (xy 389.112252 -408.560016)
			(xy 389.10646 -408.567164) (xy 389.099944 -408.584353) (xy 389.099552 -408.593544) (xy 389.099552 -409.086812)
			(xy 389.099967 -409.095998) (xy 389.106479 -409.113182) (xy 389.112252 -409.12034) (xy 389.134004 -409.146021)
			(xy 389.171955 -409.201603) (xy 389.20299 -409.261323) (xy 389.226665 -409.324323) (xy 389.242641 -409.389702)
			(xy 389.250688 -409.456522) (xy 389.250692 -409.523824) (xy 389.242651 -409.590644) (xy 389.226681 -409.656025)
			(xy 389.203012 -409.719028) (xy 389.171983 -409.77875) (xy 389.134038 -409.834336) (xy 389.112252 -409.859988)
			(xy 389.10643 -409.867115) (xy 389.099932 -409.88432) (xy 389.099552 -409.893516) (xy 389.099552 -410.051504)
			(xy 389.099019 -410.061607) (xy 389.09129 -410.080275) (xy 389.077008 -410.094568) (xy 389.058346 -410.102311)
			(xy 389.048244 -410.102812) (xy 388.33171 -410.102812) (xy 388.32159 -410.102267) (xy 388.302879 -410.094552)
			(xy 388.288524 -410.080284) (xy 388.280696 -410.061621) (xy 388.280148 -410.051504) (xy 388.280148 -409.893516)
			(xy 388.27972 -409.884331) (xy 388.273217 -409.867147) (xy 388.267448 -409.859988) (xy 388.245624 -409.834365)
			(xy 388.207676 -409.778775) (xy 388.176644 -409.719047) (xy 388.152973 -409.656039) (xy 388.137002 -409.590653)
			(xy 388.128961 -409.523827) (xy 387.000824 -409.523827) (xy 386.972058 -409.579044) (xy 386.933969 -409.634679)
			(xy 386.912104 -409.660344) (xy 386.906307 -409.667489) (xy 386.899792 -409.68468) (xy 386.899404 -409.693872)
			(xy 386.899404 -410.186124) (xy 386.899801 -410.195313) (xy 386.906324 -410.212497) (xy 386.912104 -410.219652)
			(xy 386.933952 -410.24533) (xy 386.972041 -410.300963) (xy 387.003192 -410.360757) (xy 387.026957 -410.423853)
			(xy 387.042994 -410.48934) (xy 387.051071 -410.556277) (xy 387.051072 -410.623641) (xy 390.329135 -410.623641)
			(xy 390.329137 -410.556335) (xy 390.337182 -410.489512) (xy 390.353155 -410.42413) (xy 390.376828 -410.361125)
			(xy 390.407861 -410.3014) (xy 390.445809 -410.245813) (xy 390.467596 -410.22016) (xy 390.473392 -410.213014)
			(xy 390.479907 -410.195824) (xy 390.480296 -410.186632) (xy 390.480296 -409.693364) (xy 390.479904 -409.684175)
			(xy 390.473378 -409.666991) (xy 390.467596 -409.659836) (xy 390.445821 -409.634174) (xy 390.407875 -409.578588)
			(xy 390.376844 -409.518865) (xy 390.353172 -409.455862) (xy 390.3372 -409.390481) (xy 390.329155 -409.323661)
			(xy 390.329154 -409.256357) (xy 390.337196 -409.189536) (xy 390.353167 -409.124155) (xy 390.376836 -409.061151)
			(xy 390.407866 -409.001428) (xy 390.44581 -408.945841) (xy 390.467596 -408.920188) (xy 390.47338 -408.913034)
			(xy 390.479902 -408.89585) (xy 390.480296 -408.88666) (xy 390.480296 -408.728672) (xy 390.480762 -408.718562)
			(xy 390.488508 -408.699884) (xy 390.502811 -408.68559) (xy 390.521494 -408.677856) (xy 390.531604 -408.677364)
			(xy 391.248138 -408.677364) (xy 391.25827 -408.677796) (xy 391.276997 -408.685541) (xy 391.291352 -408.699844)
			(xy 391.299166 -408.718542) (xy 391.2997 -408.728672) (xy 391.2997 -408.88666) (xy 391.300129 -408.895845)
			(xy 391.30663 -408.91303) (xy 391.3124 -408.920188) (xy 391.334198 -408.945831) (xy 391.372144 -409.00142)
			(xy 391.403175 -409.061145) (xy 391.426845 -409.12415) (xy 391.442816 -409.189533) (xy 391.450859 -409.256356)
			(xy 391.450858 -409.323662) (xy 391.442813 -409.390484) (xy 391.42684 -409.455867) (xy 391.403167 -409.518872)
			(xy 391.372135 -409.578596) (xy 391.334187 -409.634183) (xy 391.3124 -409.659836) (xy 391.306606 -409.666983)
			(xy 391.30009 -409.684172) (xy 391.2997 -409.693364) (xy 391.2997 -410.186632) (xy 391.300095 -410.195821)
			(xy 391.306619 -410.213005) (xy 391.3124 -410.22016) (xy 391.334171 -410.245826) (xy 391.372118 -410.301411)
			(xy 391.403149 -410.361133) (xy 391.426821 -410.424136) (xy 391.442794 -410.489516) (xy 391.450839 -410.556336)
			(xy 391.450841 -410.623639) (xy 391.442799 -410.69046) (xy 391.426828 -410.755841) (xy 391.403159 -410.818845)
			(xy 391.37213 -410.878568) (xy 391.334186 -410.934155) (xy 391.3124 -410.959808) (xy 391.306618 -410.966963)
			(xy 391.300094 -410.984146) (xy 391.2997 -410.993336) (xy 391.2997 -411.151324) (xy 391.299235 -411.161434)
			(xy 391.291489 -411.180113) (xy 391.277186 -411.194407) (xy 391.258503 -411.202141) (xy 391.248392 -411.202632)
			(xy 390.531858 -411.202632) (xy 390.521725 -411.202207) (xy 390.502998 -411.19446) (xy 390.488642 -411.180155)
			(xy 390.480829 -411.161455) (xy 390.480296 -411.151324) (xy 390.480296 -410.993336) (xy 390.479869 -410.984151)
			(xy 390.473367 -410.966966) (xy 390.467596 -410.959808) (xy 390.445794 -410.934168) (xy 390.407848 -410.878579)
			(xy 390.376818 -410.818853) (xy 390.353148 -410.755847) (xy 390.337178 -410.690464) (xy 390.329135 -410.623641)
			(xy 387.051072 -410.623641) (xy 387.051072 -410.623699) (xy 387.042998 -410.690636) (xy 387.026964 -410.756124)
			(xy 387.003202 -410.819221) (xy 386.972053 -410.879016) (xy 386.933967 -410.934651) (xy 386.912104 -410.960316)
			(xy 386.906319 -410.967469) (xy 386.899797 -410.984654) (xy 386.899404 -410.993844) (xy 386.899404 -411.151324)
			(xy 386.898935 -411.161434) (xy 386.89119 -411.180112) (xy 386.876888 -411.194406) (xy 386.858206 -411.20214)
			(xy 386.848096 -411.202632) (xy 386.131816 -411.202632) (xy 386.121712 -411.202103) (xy 386.10304 -411.194376)
			(xy 386.088746 -411.180093) (xy 386.081005 -411.161427) (xy 386.080508 -411.151324) (xy 386.080508 -410.993844)
			(xy 386.080075 -410.984659) (xy 386.073577 -410.967475) (xy 386.067808 -410.960316) (xy 386.045928 -410.934664)
			(xy 386.007839 -410.879028) (xy 385.976689 -410.81923) (xy 385.952925 -410.756131) (xy 385.936891 -410.69064)
			(xy 385.928816 -410.623701) (xy 382.65077 -410.623701) (xy 382.642733 -410.690463) (xy 382.626761 -410.755844)
			(xy 382.603088 -410.818848) (xy 382.572054 -410.878571) (xy 382.534104 -410.934156) (xy 382.512316 -410.959808)
			(xy 382.506535 -410.966965) (xy 382.500011 -410.984146) (xy 382.499616 -410.993336) (xy 382.499616 -411.151324)
			(xy 382.499135 -411.161432) (xy 382.491392 -411.180108) (xy 382.477095 -411.194401) (xy 382.458416 -411.202138)
			(xy 382.448308 -411.202632) (xy 381.731774 -411.202632) (xy 381.721642 -411.202194) (xy 381.702915 -411.194453)
			(xy 381.688559 -411.180151) (xy 381.680745 -411.161454) (xy 381.680212 -411.151324) (xy 381.680212 -410.993336)
			(xy 381.679782 -410.984151) (xy 381.673282 -410.966967) (xy 381.667512 -410.959808) (xy 381.645709 -410.934168)
			(xy 381.607763 -410.87858) (xy 381.576732 -410.818854) (xy 381.553061 -410.755848) (xy 381.53709 -410.690464)
			(xy 381.529047 -410.623641) (xy 378.250984 -410.623641) (xy 378.250984 -410.623699) (xy 378.24291 -410.690636)
			(xy 378.226877 -410.756124) (xy 378.203116 -410.81922) (xy 378.171968 -410.879016) (xy 378.133882 -410.93465)
			(xy 378.11202 -410.960316) (xy 378.106236 -410.967471) (xy 378.099713 -410.984654) (xy 378.09932 -410.993844)
			(xy 378.09932 -411.151324) (xy 378.098835 -411.161432) (xy 378.091093 -411.180107) (xy 378.076797 -411.1944)
			(xy 378.05812 -411.202138) (xy 378.048012 -411.202632) (xy 377.331732 -411.202632) (xy 377.321615 -411.202159)
			(xy 377.302919 -411.194427) (xy 377.288604 -411.180128) (xy 377.280852 -411.16144) (xy 377.280424 -411.151324)
			(xy 377.280424 -410.993844) (xy 377.279987 -410.98466) (xy 377.273491 -410.967475) (xy 377.267724 -410.960316)
			(xy 377.245843 -410.934664) (xy 377.207754 -410.879028) (xy 377.176602 -410.81923) (xy 377.152838 -410.756132)
			(xy 377.136803 -410.690641) (xy 377.128728 -410.623701) (xy 347.450924 -410.623701) (xy 347.442889 -410.690461)
			(xy 347.426919 -410.755842) (xy 347.403249 -410.818845) (xy 347.372219 -410.878569) (xy 347.334274 -410.934156)
			(xy 347.312488 -410.959808) (xy 347.306704 -410.966962) (xy 347.300182 -410.984146) (xy 347.299788 -410.993336)
			(xy 347.299788 -411.151324) (xy 347.299398 -411.161481) (xy 347.291592 -411.180236) (xy 347.277186 -411.194559)
			(xy 347.258386 -411.202256) (xy 347.248226 -411.202632) (xy 346.531946 -411.202632) (xy 346.521819 -411.202135)
			(xy 346.503093 -411.194417) (xy 346.488735 -411.180133) (xy 346.480919 -411.161449) (xy 346.480384 -411.151324)
			(xy 346.480384 -410.993336) (xy 346.47996 -410.98415) (xy 346.473456 -410.966965) (xy 346.467684 -410.959808)
			(xy 346.445879 -410.934169) (xy 346.407928 -410.878582) (xy 346.376893 -410.818857) (xy 346.353219 -410.755851)
			(xy 346.337246 -410.690466) (xy 346.329202 -410.623642) (xy 343.051163 -410.623642) (xy 343.051163 -410.623699)
			(xy 343.043089 -410.690637) (xy 343.027055 -410.756125) (xy 343.003292 -410.819221) (xy 342.972143 -410.879017)
			(xy 342.934055 -410.934651) (xy 342.912192 -410.960316) (xy 342.906405 -410.967468) (xy 342.899885 -410.984653)
			(xy 342.899492 -410.993844) (xy 342.899492 -411.151324) (xy 342.899034 -411.161435) (xy 342.891287 -411.180116)
			(xy 342.876982 -411.19441) (xy 342.858296 -411.202142) (xy 342.848184 -411.202632) (xy 342.131904 -411.202632)
			(xy 342.121799 -411.202112) (xy 342.103128 -411.194382) (xy 342.088834 -411.180096) (xy 342.081093 -411.161428)
			(xy 342.080596 -411.151324) (xy 342.080596 -410.993844) (xy 342.080166 -410.984659) (xy 342.073666 -410.967474)
			(xy 342.067896 -410.960316) (xy 342.046016 -410.934664) (xy 342.007928 -410.879027) (xy 341.976779 -410.819229)
			(xy 341.953016 -410.756131) (xy 341.936981 -410.69064) (xy 341.928907 -410.6237) (xy 338.650837 -410.6237)
			(xy 338.642802 -410.69046) (xy 338.626832 -410.755841) (xy 338.603163 -410.818845) (xy 338.572134 -410.878568)
			(xy 338.534189 -410.934155) (xy 338.512404 -410.959808) (xy 338.506622 -410.966964) (xy 338.500098 -410.984146)
			(xy 338.499704 -410.993336) (xy 338.499704 -411.151324) (xy 338.499298 -411.161479) (xy 338.491495 -411.180231)
			(xy 338.477094 -411.194554) (xy 338.458299 -411.202253) (xy 338.448142 -411.202632) (xy 337.731862 -411.202632)
			(xy 337.721729 -411.202204) (xy 337.703002 -411.194458) (xy 337.688646 -411.180154) (xy 337.680833 -411.161455)
			(xy 337.6803 -411.151324) (xy 337.6803 -410.993336) (xy 337.679873 -410.984151) (xy 337.673371 -410.966966)
			(xy 337.6676 -410.959808) (xy 337.645798 -410.934168) (xy 337.607852 -410.878579) (xy 337.576822 -410.818853)
			(xy 337.553151 -410.755847) (xy 337.537181 -410.690464) (xy 337.529138 -410.623641) (xy 334.251075 -410.623641)
			(xy 334.251075 -410.623699) (xy 334.243001 -410.690636) (xy 334.226967 -410.756124) (xy 334.203205 -410.81922)
			(xy 334.172057 -410.879016) (xy 334.133971 -410.934651) (xy 334.112108 -410.960316) (xy 334.106323 -410.96747)
			(xy 334.099801 -410.984654) (xy 334.099408 -410.993844) (xy 334.099408 -411.151324) (xy 334.098935 -411.161433)
			(xy 334.091191 -411.180111) (xy 334.07689 -411.194404) (xy 334.05821 -411.20214) (xy 334.0481 -411.202632)
			(xy 333.33182 -411.202632) (xy 333.321716 -411.202099) (xy 333.303045 -411.194374) (xy 333.28875 -411.180092)
			(xy 333.281009 -411.161427) (xy 333.280512 -411.151324) (xy 333.280512 -410.993844) (xy 333.280078 -410.984659)
			(xy 333.273581 -410.967475) (xy 333.267812 -410.960316) (xy 333.245932 -410.934664) (xy 333.207843 -410.879028)
			(xy 333.176692 -410.81923) (xy 333.152928 -410.756131) (xy 333.136894 -410.69064) (xy 333.128819 -410.623701)
			(xy 326.525636 -410.623701) (xy 326.525636 -417.379404) (xy 326.525636 -417.533836) (xy 401.074128 -417.533836)
			(xy 401.074128 -417.366196) (xy 401.074128 -394.27912) (xy 414.451292 -394.27912) (xy 414.525968 -394.353542)
			(xy 414.525968 -397.823826) (xy 418.92899 -397.823826) (xy 418.928993 -397.756517) (xy 418.937042 -397.689691)
			(xy 418.95302 -397.624306) (xy 418.9767 -397.5613) (xy 419.00774 -397.501575) (xy 419.045697 -397.44599)
			(xy 419.067488 -397.420338) (xy 419.073292 -397.413198) (xy 419.079803 -397.396004) (xy 419.080188 -397.38681)
			(xy 419.080188 -396.893542) (xy 419.07976 -396.884357) (xy 419.073259 -396.867172) (xy 419.067488 -396.860014)
			(xy 419.045689 -396.834371) (xy 419.007737 -396.778784) (xy 418.976702 -396.71906) (xy 418.953027 -396.656054)
			(xy 418.937054 -396.59067) (xy 418.92901 -396.523846) (xy 418.92901 -396.456539) (xy 418.937056 -396.389715)
			(xy 418.953032 -396.324332) (xy 418.976708 -396.261327) (xy 419.007745 -396.201603) (xy 419.045698 -396.146018)
			(xy 419.067488 -396.120366) (xy 419.07328 -396.113218) (xy 419.079798 -396.09603) (xy 419.080188 -396.086838)
			(xy 419.080188 -395.92885) (xy 419.080606 -395.918675) (xy 419.088384 -395.899872) (xy 419.102772 -395.885484)
			(xy 419.121575 -395.877706) (xy 419.13175 -395.877288) (xy 419.84803 -395.877288) (xy 419.85821 -395.87764)
			(xy 419.877015 -395.885445) (xy 419.8914 -395.899852) (xy 419.899175 -395.91867) (xy 419.899592 -395.92885)
			(xy 419.899592 -396.086838) (xy 419.899986 -396.096027) (xy 419.906511 -396.113211) (xy 419.912292 -396.120366)
			(xy 419.934069 -396.146027) (xy 419.972016 -396.201613) (xy 420.003048 -396.261335) (xy 420.02672 -396.324339)
			(xy 420.042693 -396.389719) (xy 420.050737 -396.456541) (xy 420.050738 -396.523844) (xy 420.042695 -396.590666)
			(xy 420.026725 -396.656047) (xy 420.003054 -396.719051) (xy 419.972024 -396.778774) (xy 419.934078 -396.834361)
			(xy 419.912292 -396.860014) (xy 419.906506 -396.867167) (xy 419.899985 -396.884351) (xy 419.899592 -396.893542)
			(xy 419.899592 -397.38681) (xy 419.899999 -397.395998) (xy 419.906515 -397.413182) (xy 419.912292 -397.420338)
			(xy 419.934041 -397.446021) (xy 419.971989 -397.501604) (xy 420.00041 -397.556296) (xy 421.128654 -397.556296)
			(xy 421.13673 -397.489357) (xy 421.152765 -397.423869) (xy 421.17653 -397.360772) (xy 421.207681 -397.300976)
			(xy 421.245771 -397.245343) (xy 421.267636 -397.219678) (xy 421.273429 -397.21253) (xy 421.279945 -397.195342)
			(xy 421.280336 -397.18615) (xy 421.280336 -397.028924) (xy 421.280736 -397.018799) (xy 421.288483 -397.000089)
			(xy 421.302805 -396.985772) (xy 421.321518 -396.978032) (xy 421.331644 -396.977616) (xy 422.047924 -396.977616)
			(xy 422.058036 -396.978066) (xy 422.076718 -396.985814) (xy 422.091013 -397.000122) (xy 422.098744 -397.018811)
			(xy 422.099232 -397.028924) (xy 422.099232 -397.18615) (xy 422.099681 -397.195333) (xy 422.106169 -397.212517)
			(xy 422.111932 -397.219678) (xy 422.133805 -397.245336) (xy 422.171891 -397.300972) (xy 422.203039 -397.36077)
			(xy 422.226802 -397.423867) (xy 422.242835 -397.489357) (xy 422.25091 -397.556296) (xy 422.250909 -397.623719)
			(xy 422.242833 -397.690658) (xy 422.226797 -397.756147) (xy 422.203033 -397.819244) (xy 422.200615 -397.823885)
			(xy 423.328782 -397.823885) (xy 423.328786 -397.756458) (xy 423.336865 -397.689518) (xy 423.352904 -397.624027)
			(xy 423.376672 -397.560928) (xy 423.407826 -397.501131) (xy 423.445918 -397.445496) (xy 423.467784 -397.41983)
			(xy 423.473591 -397.412692) (xy 423.4801 -397.395496) (xy 423.480484 -397.386302) (xy 423.480484 -396.89405)
			(xy 423.480054 -396.884865) (xy 423.473554 -396.86768) (xy 423.467784 -396.860522) (xy 423.445911 -396.834865)
			(xy 423.407823 -396.779229) (xy 423.376674 -396.719431) (xy 423.352911 -396.656333) (xy 423.336877 -396.590843)
			(xy 423.328802 -396.523905) (xy 423.328803 -396.45648) (xy 423.33688 -396.389542) (xy 423.352916 -396.324052)
			(xy 423.37668 -396.260955) (xy 423.407831 -396.201159) (xy 423.44592 -396.145524) (xy 423.467784 -396.119858)
			(xy 423.473579 -396.112712) (xy 423.480095 -396.095522) (xy 423.480484 -396.08633) (xy 423.480484 -395.92885)
			(xy 423.480969 -395.918721) (xy 423.488688 -395.899993) (xy 423.502976 -395.885633) (xy 423.521666 -395.87782)
			(xy 423.531792 -395.877288) (xy 424.248072 -395.877288) (xy 424.258223 -395.877744) (xy 424.276972 -395.885528)
			(xy 424.291296 -395.899914) (xy 424.298999 -395.918697) (xy 424.29938 -395.92885) (xy 424.29938 -396.08633)
			(xy 424.29978 -396.095518) (xy 424.306301 -396.112702) (xy 424.31208 -396.119858) (xy 424.333935 -396.145531)
			(xy 424.372025 -396.201164) (xy 424.403177 -396.260959) (xy 424.426943 -396.324055) (xy 424.44298 -396.389543)
			(xy 424.451057 -396.456481) (xy 424.451058 -396.523904) (xy 424.442983 -396.590842) (xy 424.426948 -396.656331)
			(xy 424.403184 -396.719427) (xy 424.372033 -396.779223) (xy 424.333944 -396.834857) (xy 424.31208 -396.860522)
			(xy 424.306289 -396.867671) (xy 424.299772 -396.884859) (xy 424.29938 -396.89405) (xy 424.29938 -397.386302)
			(xy 424.299793 -397.395489) (xy 424.306305 -397.412673) (xy 424.31208 -397.41983) (xy 424.333907 -397.445526)
			(xy 424.371998 -397.501155) (xy 424.40076 -397.556356) (xy 425.528974 -397.556356) (xy 425.537017 -397.489534)
			(xy 425.552988 -397.424152) (xy 425.576659 -397.361148) (xy 425.607691 -397.301425) (xy 425.645637 -397.245838)
			(xy 425.667424 -397.220186) (xy 425.673212 -397.213035) (xy 425.679731 -397.195849) (xy 425.680124 -397.186658)
			(xy 425.680124 -397.028924) (xy 425.680542 -397.018768) (xy 425.688334 -397.000012) (xy 425.702732 -396.985687)
			(xy 425.721528 -396.97799) (xy 425.731686 -396.977616) (xy 426.447966 -396.977616) (xy 426.458088 -396.978154)
			(xy 426.476803 -396.985866) (xy 426.49116 -397.000137) (xy 426.498984 -397.018806) (xy 426.499528 -397.028924)
			(xy 426.499528 -397.186658) (xy 426.499952 -397.195844) (xy 426.506456 -397.213029) (xy 426.512228 -397.220186)
			(xy 426.534026 -397.24583) (xy 426.571977 -397.301417) (xy 426.603012 -397.361141) (xy 426.626685 -397.424147)
			(xy 426.642659 -397.48953) (xy 426.650703 -397.556354) (xy 426.650702 -397.623661) (xy 426.642656 -397.690485)
			(xy 426.626681 -397.755868) (xy 426.603006 -397.818873) (xy 426.600432 -397.823826) (xy 427.729077 -397.823826)
			(xy 427.729081 -397.756517) (xy 427.737129 -397.689691) (xy 427.753107 -397.624307) (xy 427.776786 -397.5613)
			(xy 427.807825 -397.501576) (xy 427.845781 -397.44599) (xy 427.867572 -397.420338) (xy 427.873386 -397.413206)
			(xy 427.879888 -397.396005) (xy 427.880272 -397.38681) (xy 427.880272 -396.893542) (xy 427.879848 -396.884356)
			(xy 427.873344 -396.867171) (xy 427.867572 -396.860014) (xy 427.845774 -396.83437) (xy 427.807823 -396.778783)
			(xy 427.776788 -396.719059) (xy 427.753115 -396.656053) (xy 427.737141 -396.59067) (xy 427.729097 -396.523846)
			(xy 427.729098 -396.456539) (xy 427.737144 -396.389715) (xy 427.753119 -396.324332) (xy 427.776794 -396.261327)
			(xy 427.807831 -396.201604) (xy 427.845783 -396.146018) (xy 427.867572 -396.120366) (xy 427.873374 -396.113225)
			(xy 427.879883 -396.096031) (xy 427.880272 -396.086838) (xy 427.880272 -395.92885) (xy 427.880706 -395.918677)
			(xy 427.88848 -395.899877) (xy 427.902864 -395.885489) (xy 427.921662 -395.877709) (xy 427.931834 -395.877288)
			(xy 428.648114 -395.877288) (xy 428.658293 -395.877654) (xy 428.677097 -395.885453) (xy 428.691483 -395.899857)
			(xy 428.699259 -395.918671) (xy 428.699676 -395.92885) (xy 428.699676 -396.086838) (xy 428.700073 -396.096026)
			(xy 428.706596 -396.11321) (xy 428.712376 -396.120366) (xy 428.734154 -396.146026) (xy 428.772102 -396.201612)
			(xy 428.803135 -396.261335) (xy 428.826807 -396.324338) (xy 428.84278 -396.389719) (xy 428.850825 -396.45654)
			(xy 428.850826 -396.523844) (xy 428.842783 -396.590666) (xy 428.826812 -396.656048) (xy 428.803141 -396.719052)
			(xy 428.772109 -396.778775) (xy 428.734163 -396.834362) (xy 428.712376 -396.860014) (xy 428.706588 -396.867165)
			(xy 428.700069 -396.884351) (xy 428.699676 -396.893542) (xy 428.699676 -397.38681) (xy 428.700087 -397.395997)
			(xy 428.7066 -397.413181) (xy 428.712376 -397.420338) (xy 428.734126 -397.446021) (xy 428.772075 -397.501604)
			(xy 428.800497 -397.556296) (xy 429.928742 -397.556296) (xy 429.936817 -397.489358) (xy 429.952852 -397.423869)
			(xy 429.976616 -397.360773) (xy 430.007767 -397.300977) (xy 430.045856 -397.245343) (xy 430.06772 -397.219678)
			(xy 430.073511 -397.212529) (xy 430.080028 -397.195341) (xy 430.08042 -397.18615) (xy 430.08042 -397.028924)
			(xy 430.080836 -397.018801) (xy 430.08858 -397.000094) (xy 430.102897 -396.985778) (xy 430.121605 -396.978035)
			(xy 430.131728 -396.977616) (xy 430.848008 -396.977616) (xy 430.858133 -396.97801) (xy 430.87684 -396.985764)
			(xy 430.891154 -397.000087) (xy 430.898896 -397.018799) (xy 430.899316 -397.028924) (xy 430.899316 -397.18615)
			(xy 430.899746 -397.195335) (xy 430.906246 -397.21252) (xy 430.912016 -397.219678) (xy 430.933889 -397.245335)
			(xy 430.971977 -397.300971) (xy 431.003126 -397.360769) (xy 431.026889 -397.423867) (xy 431.042923 -397.489357)
			(xy 431.050998 -397.556295) (xy 431.050997 -397.62372) (xy 431.04292 -397.690658) (xy 431.026884 -397.756148)
			(xy 431.00312 -397.819245) (xy 431.000734 -397.823826) (xy 432.128868 -397.823826) (xy 432.128872 -397.756517)
			(xy 432.13692 -397.689692) (xy 432.152898 -397.624307) (xy 432.176576 -397.561301) (xy 432.207614 -397.501576)
			(xy 432.245569 -397.44599) (xy 432.26736 -397.420338) (xy 432.273173 -397.413205) (xy 432.279676 -397.396005)
			(xy 432.28006 -397.38681) (xy 432.28006 -396.893542) (xy 432.279616 -396.884359) (xy 432.273125 -396.867175)
			(xy 432.26736 -396.860014) (xy 432.245562 -396.83437) (xy 432.207612 -396.778783) (xy 432.176578 -396.719058)
			(xy 432.152905 -396.656053) (xy 432.136932 -396.590669) (xy 432.128888 -396.523846) (xy 432.128889 -396.456539)
			(xy 432.136935 -396.389716) (xy 432.152909 -396.324333) (xy 432.176584 -396.261328) (xy 432.20762 -396.201604)
			(xy 432.245571 -396.146018) (xy 432.26736 -396.120366) (xy 432.273161 -396.113224) (xy 432.279671 -396.096031)
			(xy 432.28006 -396.086838) (xy 432.28006 -395.92885) (xy 432.280505 -395.918679) (xy 432.288278 -395.899881)
			(xy 432.302658 -395.885494) (xy 432.321451 -395.877711) (xy 432.331622 -395.877288) (xy 433.047902 -395.877288)
			(xy 433.05808 -395.877663) (xy 433.076884 -395.885458) (xy 433.091271 -395.899859) (xy 433.099047 -395.918672)
			(xy 433.099464 -395.92885) (xy 433.099464 -396.086838) (xy 433.099864 -396.096026) (xy 433.106386 -396.11321)
			(xy 433.112164 -396.120366) (xy 433.133942 -396.146026) (xy 433.171891 -396.201612) (xy 433.202924 -396.261334)
			(xy 433.226598 -396.324337) (xy 433.242571 -396.389719) (xy 433.250616 -396.45654) (xy 433.250617 -396.523845)
			(xy 433.242574 -396.590666) (xy 433.226602 -396.656048) (xy 433.202931 -396.719052) (xy 433.171899 -396.778776)
			(xy 433.133951 -396.834362) (xy 433.112164 -396.860014) (xy 433.106374 -396.867164) (xy 433.099856 -396.884351)
			(xy 433.099464 -396.893542) (xy 433.099464 -397.38681) (xy 433.099877 -397.395997) (xy 433.10639 -397.413181)
			(xy 433.112164 -397.420338) (xy 433.133914 -397.446021) (xy 433.171864 -397.501603) (xy 433.200318 -397.556356)
			(xy 434.329062 -397.556356) (xy 434.337105 -397.489534) (xy 434.353075 -397.424153) (xy 434.376746 -397.361149)
			(xy 434.407776 -397.301426) (xy 434.445722 -397.245839) (xy 434.467508 -397.220186) (xy 434.473294 -397.213033)
			(xy 434.479815 -397.195849) (xy 434.480208 -397.186658) (xy 434.480208 -397.028924) (xy 434.480641 -397.01877)
			(xy 434.48843 -397.000017) (xy 434.502824 -396.985692) (xy 434.521614 -396.977993) (xy 434.53177 -396.977616)
			(xy 435.24805 -396.977616) (xy 435.258171 -396.978167) (xy 435.276886 -396.985874) (xy 435.291243 -397.00014)
			(xy 435.299068 -397.018807) (xy 435.299612 -397.028924) (xy 435.299612 -397.186658) (xy 435.30004 -397.195843)
			(xy 435.306541 -397.213028) (xy 435.312312 -397.220186) (xy 435.334111 -397.245829) (xy 435.372063 -397.301416)
			(xy 435.403098 -397.36114) (xy 435.426773 -397.424146) (xy 435.442746 -397.48953) (xy 435.45079 -397.556354)
			(xy 435.45079 -397.623661) (xy 435.442744 -397.690485) (xy 435.426768 -397.755868) (xy 435.403092 -397.818873)
			(xy 435.372055 -397.878597) (xy 435.334102 -397.934182) (xy 435.312312 -397.959834) (xy 435.30652 -397.966982)
			(xy 435.300002 -397.98417) (xy 435.299612 -397.993362) (xy 435.299612 -398.100042) (xy 459.541382 -398.100042)
			(xy 459.545364 -397.972056) (xy 459.557296 -397.844565) (xy 459.57713 -397.718062) (xy 459.604791 -397.593037)
			(xy 459.640171 -397.469974) (xy 459.683133 -397.349348) (xy 459.733511 -397.231627) (xy 459.791111 -397.117265)
			(xy 459.855709 -397.006706) (xy 459.927056 -396.900376) (xy 460.004875 -396.798688) (xy 460.088865 -396.702034)
			(xy 460.178702 -396.610789) (xy 460.274038 -396.525306) (xy 460.374503 -396.445915) (xy 460.479711 -396.372923)
			(xy 460.589252 -396.306614) (xy 460.702704 -396.247243) (xy 460.819628 -396.195039) (xy 460.939571 -396.150206)
			(xy 461.062069 -396.112917) (xy 461.186649 -396.083315) (xy 461.312827 -396.061516) (xy 461.440117 -396.047603)
			(xy 461.568026 -396.041631) (xy 461.696059 -396.043622) (xy 461.82372 -396.05357) (xy 461.950516 -396.071434)
			(xy 462.075955 -396.097147) (xy 462.199554 -396.130609) (xy 462.320833 -396.17169) (xy 462.439324 -396.220232)
			(xy 462.554568 -396.276046) (xy 462.666118 -396.338917) (xy 462.773545 -396.408601) (xy 462.876431 -396.484829)
			(xy 462.974379 -396.567306) (xy 463.06701 -396.655713) (xy 463.153966 -396.749708) (xy 463.23491 -396.848927)
			(xy 463.309529 -396.952986) (xy 463.377534 -397.061483) (xy 463.438662 -397.173998) (xy 463.492677 -397.290096)
			(xy 463.53937 -397.409327) (xy 463.57856 -397.531231) (xy 463.610096 -397.655335) (xy 463.633855 -397.781159)
			(xy 463.649745 -397.908218) (xy 463.657706 -398.036018) (xy 463.658204 -398.100042) (xy 463.657706 -398.164066)
			(xy 463.649745 -398.291866) (xy 463.633855 -398.418925) (xy 463.610096 -398.544749) (xy 463.57856 -398.668853)
			(xy 463.53937 -398.790757) (xy 463.492677 -398.909988) (xy 463.438662 -399.026086) (xy 463.377534 -399.138601)
			(xy 463.309529 -399.247098) (xy 463.23491 -399.351157) (xy 463.153966 -399.450376) (xy 463.06701 -399.544371)
			(xy 462.974379 -399.632778) (xy 462.876431 -399.715255) (xy 462.773545 -399.791483) (xy 462.666118 -399.861167)
			(xy 462.554568 -399.924038) (xy 462.439324 -399.979852) (xy 462.320833 -400.028394) (xy 462.199554 -400.069475)
			(xy 462.075955 -400.102937) (xy 461.950516 -400.12865) (xy 461.82372 -400.146514) (xy 461.696059 -400.156462)
			(xy 461.568026 -400.158453) (xy 461.440117 -400.152481) (xy 461.312827 -400.138568) (xy 461.186649 -400.116769)
			(xy 461.062069 -400.087167) (xy 460.939571 -400.049878) (xy 460.819628 -400.005045) (xy 460.702704 -399.952841)
			(xy 460.589252 -399.89347) (xy 460.479711 -399.827161) (xy 460.374503 -399.754169) (xy 460.274038 -399.674778)
			(xy 460.178702 -399.589295) (xy 460.088865 -399.49805) (xy 460.004875 -399.401396) (xy 459.927056 -399.299708)
			(xy 459.855709 -399.193378) (xy 459.791111 -399.082819) (xy 459.733511 -398.968457) (xy 459.683133 -398.850736)
			(xy 459.640171 -398.73011) (xy 459.604791 -398.607047) (xy 459.57713 -398.482022) (xy 459.557296 -398.355519)
			(xy 459.545364 -398.228028) (xy 459.541382 -398.100042) (xy 435.299612 -398.100042) (xy 435.299612 -398.486884)
			(xy 435.300027 -398.496071) (xy 435.306537 -398.513255) (xy 435.312312 -398.520412) (xy 435.334137 -398.546034)
			(xy 435.372087 -398.601624) (xy 435.403122 -398.661351) (xy 435.426795 -398.72436) (xy 435.442767 -398.789746)
			(xy 435.450809 -398.856573) (xy 435.450805 -398.923881) (xy 435.442757 -398.990707) (xy 435.426779 -399.056092)
			(xy 435.4031 -399.119098) (xy 435.37206 -399.178823) (xy 435.334103 -399.234408) (xy 435.312312 -399.26006)
			(xy 435.306509 -399.267201) (xy 435.299998 -399.284395) (xy 435.299612 -399.293588) (xy 435.299612 -399.451576)
			(xy 435.299159 -399.461727) (xy 435.291374 -399.480477) (xy 435.276987 -399.494801) (xy 435.258203 -399.502503)
			(xy 435.24805 -399.502884) (xy 434.53177 -399.502884) (xy 434.521644 -399.502399) (xy 434.502927 -399.494666)
			(xy 434.488573 -399.480379) (xy 434.48075 -399.461699) (xy 434.480208 -399.451576) (xy 434.480208 -399.293588)
			(xy 434.479802 -399.2844) (xy 434.473285 -399.267216) (xy 434.467508 -399.26006) (xy 434.445757 -399.234378)
			(xy 434.407809 -399.178795) (xy 434.376776 -399.119076) (xy 434.353102 -399.056075) (xy 434.337128 -398.990697)
			(xy 434.329081 -398.923878) (xy 434.329078 -398.856576) (xy 434.337118 -398.789757) (xy 434.353086 -398.724377)
			(xy 434.376753 -398.661374) (xy 434.407781 -398.601651) (xy 434.445723 -398.546064) (xy 434.467508 -398.520412)
			(xy 434.473325 -398.513282) (xy 434.479827 -398.49608) (xy 434.480208 -398.486884) (xy 434.480208 -397.993362)
			(xy 434.479814 -397.984173) (xy 434.473289 -397.966989) (xy 434.467508 -397.959834) (xy 434.445731 -397.934173)
			(xy 434.407784 -397.878587) (xy 434.376752 -397.818865) (xy 434.35308 -397.755861) (xy 434.337107 -397.690481)
			(xy 434.329063 -397.623659) (xy 434.329062 -397.556356) (xy 433.200318 -397.556356) (xy 433.202899 -397.561322)
			(xy 433.226573 -397.624323) (xy 433.242549 -397.689701) (xy 433.250596 -397.75652) (xy 433.250599 -397.823822)
			(xy 433.242559 -397.890642) (xy 433.22659 -397.956022) (xy 433.202922 -398.019025) (xy 433.171893 -398.078748)
			(xy 433.133949 -398.134334) (xy 433.112164 -398.159986) (xy 433.106344 -398.167114) (xy 433.099844 -398.184318)
			(xy 433.099464 -398.193514) (xy 433.099464 -398.351502) (xy 433.098968 -398.36166) (xy 433.091194 -398.380428)
			(xy 433.076828 -398.394794) (xy 433.05806 -398.402568) (xy 433.047902 -398.403064) (xy 432.331622 -398.403064)
			(xy 432.321452 -398.402618) (xy 432.302658 -398.394841) (xy 432.288273 -398.380462) (xy 432.280487 -398.361672)
			(xy 432.28006 -398.351502) (xy 432.28006 -398.193514) (xy 432.27963 -398.184329) (xy 432.273129 -398.167145)
			(xy 432.26736 -398.159986) (xy 432.245534 -398.134365) (xy 432.207585 -398.078775) (xy 432.176552 -398.019047)
			(xy 432.152881 -397.956038) (xy 432.13691 -397.890652) (xy 432.128868 -397.823826) (xy 431.000734 -397.823826)
			(xy 430.971969 -397.879041) (xy 430.93388 -397.934676) (xy 430.912016 -397.960342) (xy 430.906221 -397.967488)
			(xy 430.899705 -397.984678) (xy 430.899316 -397.99387) (xy 430.899316 -398.486376) (xy 430.899734 -398.495562)
			(xy 430.906242 -398.512747) (xy 430.912016 -398.519904) (xy 430.933915 -398.54554) (xy 430.972001 -398.601179)
			(xy 431.00315 -398.66098) (xy 431.026911 -398.72408) (xy 431.042944 -398.789573) (xy 431.051016 -398.856514)
			(xy 431.051013 -398.92394) (xy 431.042934 -398.990881) (xy 431.026895 -399.056371) (xy 431.003128 -399.11947)
			(xy 430.971974 -399.179267) (xy 430.933882 -399.234902) (xy 430.912016 -399.260568) (xy 430.90621 -399.267707)
			(xy 430.8997 -399.284902) (xy 430.899316 -399.294096) (xy 430.899316 -399.451576) (xy 430.898865 -399.461695)
			(xy 430.891128 -399.480395) (xy 430.876822 -399.49471) (xy 430.858127 -399.502459) (xy 430.848008 -399.502884)
			(xy 430.131728 -399.502884) (xy 430.121605 -399.502461) (xy 430.102899 -399.494719) (xy 430.088583 -399.480404)
			(xy 430.08084 -399.461699) (xy 430.08042 -399.451576) (xy 430.08042 -399.294096) (xy 430.080008 -399.284909)
			(xy 430.073495 -399.267725) (xy 430.06772 -399.260568) (xy 430.045891 -399.234874) (xy 430.0078 -399.179244)
			(xy 429.976646 -399.119452) (xy 429.952879 -399.056359) (xy 429.936841 -398.990873) (xy 429.928761 -398.923938)
			(xy 429.928758 -398.856516) (xy 429.936831 -398.78958) (xy 429.952863 -398.724093) (xy 429.976624 -398.660997)
			(xy 430.007772 -398.601202) (xy 430.045857 -398.545569) (xy 430.06772 -398.519904) (xy 430.0735 -398.512747)
			(xy 430.080024 -398.495565) (xy 430.08042 -398.486376) (xy 430.08042 -397.99387) (xy 430.08002 -397.984682)
			(xy 430.073499 -397.967498) (xy 430.06772 -397.960342) (xy 430.045865 -397.934669) (xy 430.007775 -397.879036)
			(xy 429.976623 -397.819241) (xy 429.952857 -397.756145) (xy 429.93682 -397.690657) (xy 429.928743 -397.623719)
			(xy 429.928742 -397.556296) (xy 428.800497 -397.556296) (xy 428.803109 -397.561323) (xy 428.826783 -397.624323)
			(xy 428.842758 -397.689702) (xy 428.850805 -397.756521) (xy 428.850808 -397.823822) (xy 428.842768 -397.890642)
			(xy 428.8268 -397.956022) (xy 428.803132 -398.019025) (xy 428.772104 -398.078747) (xy 428.734161 -398.134333)
			(xy 428.712376 -398.159986) (xy 428.706558 -398.167116) (xy 428.700057 -398.184318) (xy 428.699676 -398.193514)
			(xy 428.699676 -398.351502) (xy 428.699169 -398.361658) (xy 428.691396 -398.380425) (xy 428.677035 -398.394789)
			(xy 428.65827 -398.402566) (xy 428.648114 -398.403064) (xy 427.931834 -398.403064) (xy 427.921665 -398.402608)
			(xy 427.902871 -398.394835) (xy 427.888485 -398.380459) (xy 427.880699 -398.361671) (xy 427.880272 -398.351502)
			(xy 427.880272 -398.193514) (xy 427.879861 -398.184327) (xy 427.873349 -398.167142) (xy 427.867572 -398.159986)
			(xy 427.845746 -398.134365) (xy 427.807796 -398.078775) (xy 427.776762 -398.019047) (xy 427.75309 -397.956039)
			(xy 427.737119 -397.890652) (xy 427.729077 -397.823826) (xy 426.600432 -397.823826) (xy 426.571969 -397.878596)
			(xy 426.534017 -397.934182) (xy 426.512228 -397.959834) (xy 426.506426 -397.966975) (xy 426.499917 -397.984169)
			(xy 426.499528 -397.993362) (xy 426.499528 -398.486884) (xy 426.499939 -398.496071) (xy 426.506451 -398.513256)
			(xy 426.512228 -398.520412) (xy 426.534052 -398.546034) (xy 426.572002 -398.601624) (xy 426.603036 -398.661352)
			(xy 426.626708 -398.72436) (xy 426.64268 -398.789746) (xy 426.650721 -398.856573) (xy 426.650718 -398.923881)
			(xy 426.64267 -398.990707) (xy 426.626692 -399.056092) (xy 426.603014 -399.119098) (xy 426.571974 -399.178822)
			(xy 426.534019 -399.234408) (xy 426.512228 -399.26006) (xy 426.506415 -399.267193) (xy 426.499912 -399.284393)
			(xy 426.499528 -399.293588) (xy 426.499528 -399.451576) (xy 426.499059 -399.461725) (xy 426.491277 -399.480472)
			(xy 426.476895 -399.494795) (xy 426.458117 -399.502501) (xy 426.447966 -399.502884) (xy 425.731686 -399.502884)
			(xy 425.721561 -399.502385) (xy 425.702845 -399.494657) (xy 425.68849 -399.480375) (xy 425.680667 -399.461698)
			(xy 425.680124 -399.451576) (xy 425.680124 -399.293588) (xy 425.679714 -399.284401) (xy 425.6732 -399.267217)
			(xy 425.667424 -399.26006) (xy 425.645672 -399.234378) (xy 425.607723 -399.178796) (xy 425.576689 -399.119076)
			(xy 425.553015 -399.056076) (xy 425.53704 -398.990697) (xy 425.528994 -398.923878) (xy 425.52899 -398.856576)
			(xy 425.537031 -398.789756) (xy 425.552999 -398.724376) (xy 425.576667 -398.661373) (xy 425.607696 -398.601651)
			(xy 425.645639 -398.546065) (xy 425.667424 -398.520412) (xy 425.673243 -398.513283) (xy 425.679744 -398.49608)
			(xy 425.680124 -398.486884) (xy 425.680124 -397.993362) (xy 425.679727 -397.984174) (xy 425.673204 -397.96699)
			(xy 425.667424 -397.959834) (xy 425.645646 -397.934174) (xy 425.607698 -397.878588) (xy 425.576665 -397.818865)
			(xy 425.552993 -397.755862) (xy 425.53702 -397.690481) (xy 425.528975 -397.62366) (xy 425.528974 -397.556356)
			(xy 424.40076 -397.556356) (xy 424.403152 -397.560947) (xy 424.426919 -397.62404) (xy 424.442958 -397.689526)
			(xy 424.451037 -397.756461) (xy 424.451041 -397.823882) (xy 424.442968 -397.890818) (xy 424.426936 -397.956305)
			(xy 424.403175 -398.019401) (xy 424.372028 -398.079196) (xy 424.333942 -398.134829) (xy 424.31208 -398.160494)
			(xy 424.306301 -398.167652) (xy 424.299777 -398.184833) (xy 424.29938 -398.194022) (xy 424.29938 -398.351502)
			(xy 424.298876 -398.361626) (xy 424.291151 -398.380344) (xy 424.27687 -398.394699) (xy 424.258194 -398.402522)
			(xy 424.248072 -398.403064) (xy 423.531792 -398.403064) (xy 423.521633 -398.402684) (xy 423.502873 -398.394879)
			(xy 423.488549 -398.380469) (xy 423.480856 -398.361663) (xy 423.480484 -398.351502) (xy 423.480484 -398.194022)
			(xy 423.480067 -398.184835) (xy 423.473558 -398.167651) (xy 423.467784 -398.160494) (xy 423.445883 -398.134859)
			(xy 423.407797 -398.07922) (xy 423.376649 -398.019419) (xy 423.352887 -397.956319) (xy 423.336855 -397.890826)
			(xy 423.328782 -397.823885) (xy 422.200615 -397.823885) (xy 422.171883 -397.879041) (xy 422.133795 -397.934676)
			(xy 422.111932 -397.960342) (xy 422.106127 -397.967481) (xy 422.099619 -397.984676) (xy 422.099232 -397.99387)
			(xy 422.099232 -398.486376) (xy 422.099669 -398.49556) (xy 422.106166 -398.512744) (xy 422.111932 -398.519904)
			(xy 422.13383 -398.545541) (xy 422.171916 -398.60118) (xy 422.203063 -398.66098) (xy 422.226824 -398.724081)
			(xy 422.242856 -398.789573) (xy 422.250928 -398.856514) (xy 422.250925 -398.92394) (xy 422.242846 -398.99088)
			(xy 422.226808 -399.056371) (xy 422.203041 -399.119469) (xy 422.171888 -399.179266) (xy 422.133797 -399.234902)
			(xy 422.111932 -399.260568) (xy 422.106116 -399.267699) (xy 422.099615 -399.284901) (xy 422.099232 -399.294096)
			(xy 422.099232 -399.451576) (xy 422.098696 -399.461679) (xy 422.090972 -399.480351) (xy 422.076691 -399.494645)
			(xy 422.058027 -399.502387) (xy 422.047924 -399.502884) (xy 421.331644 -399.502884) (xy 421.321522 -399.502447)
			(xy 421.302817 -399.494711) (xy 421.2885 -399.4804) (xy 421.280756 -399.461697) (xy 421.280336 -399.451576)
			(xy 421.280336 -399.294096) (xy 421.27992 -399.28491) (xy 421.27341 -399.267726) (xy 421.267636 -399.260568)
			(xy 421.245806 -399.234874) (xy 421.207714 -399.179245) (xy 421.17656 -399.119453) (xy 421.152792 -399.056359)
			(xy 421.136753 -398.990873) (xy 421.128674 -398.923938) (xy 421.12867 -398.856516) (xy 421.136743 -398.78958)
			(xy 421.152776 -398.724092) (xy 421.176538 -398.660997) (xy 421.207686 -398.601202) (xy 421.245773 -398.545569)
			(xy 421.267636 -398.519904) (xy 421.273418 -398.512749) (xy 421.27994 -398.495566) (xy 421.280336 -398.486376)
			(xy 421.280336 -397.99387) (xy 421.279932 -397.984682) (xy 421.273413 -397.967498) (xy 421.267636 -397.960342)
			(xy 421.245781 -397.934669) (xy 421.207689 -397.879037) (xy 421.176536 -397.819242) (xy 421.15277 -397.756146)
			(xy 421.136732 -397.690657) (xy 421.128655 -397.623719) (xy 421.128654 -397.556296) (xy 420.00041 -397.556296)
			(xy 420.003023 -397.561324) (xy 420.026696 -397.624324) (xy 420.042671 -397.689702) (xy 420.050718 -397.756521)
			(xy 420.050721 -397.823822) (xy 420.042681 -397.890642) (xy 420.026713 -397.956021) (xy 420.003046 -398.019024)
			(xy 419.972019 -398.078747) (xy 419.934077 -398.134334) (xy 419.912292 -398.159986) (xy 419.906475 -398.167117)
			(xy 419.899973 -398.184318) (xy 419.899592 -398.193514) (xy 419.899592 -398.351502) (xy 419.899069 -398.361656)
			(xy 419.891299 -398.38042) (xy 419.876943 -398.394784) (xy 419.858184 -398.402563) (xy 419.84803 -398.403064)
			(xy 419.13175 -398.403064) (xy 419.121582 -398.402595) (xy 419.102789 -398.394827) (xy 419.088402 -398.380455)
			(xy 419.080615 -398.36167) (xy 419.080188 -398.351502) (xy 419.080188 -398.193514) (xy 419.079774 -398.184327)
			(xy 419.073263 -398.167143) (xy 419.067488 -398.159986) (xy 419.045661 -398.134365) (xy 419.007711 -398.078775)
			(xy 418.976676 -398.019048) (xy 418.953004 -397.956039) (xy 418.937032 -397.890653) (xy 418.92899 -397.823826)
			(xy 414.525968 -397.823826) (xy 414.525968 -401.723737) (xy 418.929001 -401.723737) (xy 418.929003 -401.65643)
			(xy 418.93705 -401.589605) (xy 418.953027 -401.524221) (xy 418.976704 -401.461215) (xy 419.007743 -401.401491)
			(xy 419.045697 -401.345906) (xy 419.067488 -401.320254) (xy 419.073285 -401.313109) (xy 419.0798 -401.295918)
			(xy 419.080188 -401.286726) (xy 419.080188 -400.793458) (xy 419.079801 -400.784268) (xy 419.073272 -400.767084)
			(xy 419.067488 -400.75993) (xy 419.045705 -400.734274) (xy 419.007752 -400.678689) (xy 418.976716 -400.618966)
			(xy 418.953041 -400.555962) (xy 418.937066 -400.49058) (xy 418.929021 -400.423757) (xy 418.92902 -400.356452)
			(xy 418.937065 -400.289629) (xy 418.953038 -400.224246) (xy 418.976713 -400.161242) (xy 419.007748 -400.101519)
			(xy 419.045699 -400.045933) (xy 419.067488 -400.020282) (xy 419.073273 -400.013129) (xy 419.079795 -399.995944)
			(xy 419.080188 -399.986754) (xy 419.080188 -399.828766) (xy 419.080537 -399.818586) (xy 419.088343 -399.799781)
			(xy 419.102752 -399.785395) (xy 419.121569 -399.777621) (xy 419.13175 -399.777204) (xy 419.84803 -399.777204)
			(xy 419.858186 -399.777708) (xy 419.876949 -399.785486) (xy 419.891312 -399.799848) (xy 419.899091 -399.818611)
			(xy 419.899592 -399.828766) (xy 419.899592 -399.986754) (xy 419.900026 -399.995939) (xy 419.906523 -400.013123)
			(xy 419.912292 -400.020282) (xy 419.934085 -400.04593) (xy 419.972031 -400.101518) (xy 420.003063 -400.161242)
			(xy 420.026734 -400.224247) (xy 420.042705 -400.289629) (xy 420.050749 -400.356452) (xy 420.050748 -400.423757)
			(xy 420.042704 -400.490579) (xy 420.026731 -400.555962) (xy 420.003059 -400.618966) (xy 419.972027 -400.67869)
			(xy 419.934079 -400.734277) (xy 419.912292 -400.75993) (xy 419.906499 -400.767078) (xy 419.899983 -400.784266)
			(xy 419.899592 -400.793458) (xy 419.899592 -401.286726) (xy 419.899991 -401.295914) (xy 419.906513 -401.313099)
			(xy 419.912292 -401.320254) (xy 419.934057 -401.345924) (xy 419.972005 -401.401509) (xy 420.003037 -401.46123)
			(xy 420.02671 -401.524232) (xy 420.042683 -401.589612) (xy 420.050729 -401.656432) (xy 420.050731 -401.723735)
			(xy 420.042689 -401.790555) (xy 420.02672 -401.855936) (xy 420.003051 -401.918939) (xy 419.972022 -401.978663)
			(xy 419.934077 -402.034249) (xy 419.912292 -402.059902) (xy 419.906511 -402.067058) (xy 419.899987 -402.08424)
			(xy 419.899592 -402.09343) (xy 419.899592 -402.251418) (xy 419.899082 -402.261573) (xy 419.891308 -402.280337)
			(xy 419.876947 -402.294701) (xy 419.858185 -402.30248) (xy 419.84803 -402.30298) (xy 419.13175 -402.30298)
			(xy 419.121584 -402.302496) (xy 419.102794 -402.29473) (xy 419.088408 -402.280363) (xy 419.080618 -402.261584)
			(xy 419.080188 -402.251418) (xy 419.080188 -402.09343) (xy 419.079766 -402.084244) (xy 419.073261 -402.067059)
			(xy 419.067488 -402.059902) (xy 419.045677 -402.034268) (xy 419.007726 -401.97868) (xy 418.976691 -401.918955)
			(xy 418.953017 -401.855948) (xy 418.937044 -401.790563) (xy 418.929001 -401.723737) (xy 414.525968 -401.723737)
			(xy 414.525968 -402.823878) (xy 421.128614 -402.823878) (xy 421.128619 -402.75645) (xy 421.1367 -402.689508)
			(xy 421.152742 -402.624016) (xy 421.176513 -402.560916) (xy 421.207671 -402.501119) (xy 421.245768 -402.445485)
			(xy 421.267636 -402.41982) (xy 421.273454 -402.41269) (xy 421.279955 -402.395488) (xy 421.280336 -402.386292)
			(xy 421.280336 -401.89404) (xy 421.279898 -401.884856) (xy 421.273403 -401.867672) (xy 421.267636 -401.860512)
			(xy 421.245751 -401.834864) (xy 421.207661 -401.779227) (xy 421.176509 -401.719429) (xy 421.152744 -401.65633)
			(xy 421.136709 -401.590839) (xy 421.128634 -401.523898) (xy 421.128636 -401.456472) (xy 421.136714 -401.389532)
			(xy 421.152753 -401.324041) (xy 421.176521 -401.260943) (xy 421.207676 -401.201147) (xy 421.24577 -401.145513)
			(xy 421.267636 -401.119848) (xy 421.273442 -401.112709) (xy 421.27995 -401.095514) (xy 421.280336 -401.08632)
			(xy 421.280336 -400.92884) (xy 421.28075 -400.918716) (xy 421.288491 -400.900006) (xy 421.302809 -400.885689)
			(xy 421.32152 -400.877949) (xy 421.331644 -400.877532) (xy 422.047924 -400.877532) (xy 422.058052 -400.877897)
			(xy 422.076762 -400.885659) (xy 422.091077 -400.899991) (xy 422.098816 -400.918711) (xy 422.099232 -400.92884)
			(xy 422.099232 -401.08632) (xy 422.099648 -401.095506) (xy 422.106159 -401.11269) (xy 422.111932 -401.119848)
			(xy 422.133775 -401.14553) (xy 422.171862 -401.201163) (xy 422.203012 -401.260957) (xy 422.226776 -401.324052)
			(xy 422.242812 -401.389538) (xy 422.250889 -401.456474) (xy 422.250891 -401.523896) (xy 422.242817 -401.590832)
			(xy 422.226785 -401.65632) (xy 422.203024 -401.719415) (xy 422.200742 -401.723796) (xy 423.328794 -401.723796)
			(xy 423.328796 -401.656371) (xy 423.336873 -401.589431) (xy 423.352911 -401.523941) (xy 423.376677 -401.460844)
			(xy 423.407829 -401.401047) (xy 423.445919 -401.345412) (xy 423.467784 -401.319746) (xy 423.473584 -401.312603)
			(xy 423.480097 -401.295411) (xy 423.480484 -401.286218) (xy 423.480484 -400.793966) (xy 423.480094 -400.784777)
			(xy 423.473566 -400.767592) (xy 423.467784 -400.760438) (xy 423.445926 -400.734768) (xy 423.407839 -400.679133)
			(xy 423.376689 -400.619338) (xy 423.352925 -400.556242) (xy 423.336889 -400.490753) (xy 423.328813 -400.423816)
			(xy 423.328813 -400.356393) (xy 423.336888 -400.289455) (xy 423.352922 -400.223967) (xy 423.376685 -400.16087)
			(xy 423.407834 -400.101074) (xy 423.445921 -400.045439) (xy 423.467784 -400.019774) (xy 423.473572 -400.012623)
			(xy 423.480092 -399.995437) (xy 423.480484 -399.986246) (xy 423.480484 -399.828766) (xy 423.4809 -399.818632)
			(xy 423.488647 -399.799901) (xy 423.502955 -399.785545) (xy 423.521659 -399.777735) (xy 423.531792 -399.777204)
			(xy 424.248072 -399.777204) (xy 424.258225 -399.777644) (xy 424.276977 -399.785431) (xy 424.291302 -399.799823)
			(xy 424.299002 -399.818611) (xy 424.29938 -399.828766) (xy 424.29938 -399.986246) (xy 424.299821 -399.99543)
			(xy 424.306314 -400.012614) (xy 424.31208 -400.019774) (xy 424.333951 -400.045434) (xy 424.37204 -400.101069)
			(xy 424.403192 -400.160866) (xy 424.426957 -400.223963) (xy 424.442992 -400.289453) (xy 424.451068 -400.356392)
			(xy 424.451068 -400.423817) (xy 424.442991 -400.490756) (xy 424.426954 -400.556245) (xy 424.403188 -400.619343)
			(xy 424.372036 -400.679139) (xy 424.333945 -400.734773) (xy 424.31208 -400.760438) (xy 424.306282 -400.767582)
			(xy 424.299769 -400.784774) (xy 424.29938 -400.793966) (xy 424.29938 -401.286218) (xy 424.299786 -401.295406)
			(xy 424.306303 -401.31259) (xy 424.31208 -401.319746) (xy 424.333923 -401.345429) (xy 424.372014 -401.40106)
			(xy 424.403167 -401.460854) (xy 424.426933 -401.523949) (xy 424.44297 -401.589436) (xy 424.451048 -401.656372)
			(xy 424.45105 -401.723795) (xy 424.442976 -401.790732) (xy 424.426943 -401.85622) (xy 424.40318 -401.919316)
			(xy 424.372031 -401.979111) (xy 424.333943 -402.034745) (xy 424.31208 -402.06041) (xy 424.306294 -402.067563)
			(xy 424.299774 -402.084748) (xy 424.29938 -402.093938) (xy 424.29938 -402.251418) (xy 424.298889 -402.261543)
			(xy 424.291159 -402.280261) (xy 424.276874 -402.294616) (xy 424.258195 -402.302438) (xy 424.248072 -402.30298)
			(xy 423.531792 -402.30298) (xy 423.521635 -402.302584) (xy 423.502879 -402.294782) (xy 423.488555 -402.280378)
			(xy 423.480859 -402.261577) (xy 423.480484 -402.251418) (xy 423.480484 -402.093938) (xy 423.480059 -402.084752)
			(xy 423.473556 -402.067568) (xy 423.467784 -402.06041) (xy 423.445899 -402.034762) (xy 423.407812 -401.979125)
			(xy 423.376663 -401.919326) (xy 423.352901 -401.856227) (xy 423.336867 -401.790736) (xy 423.328794 -401.723796)
			(xy 422.200742 -401.723796) (xy 422.171878 -401.779211) (xy 422.133794 -401.834846) (xy 422.111932 -401.860512)
			(xy 422.10614 -401.86766) (xy 422.099624 -401.884849) (xy 422.099232 -401.89404) (xy 422.099232 -402.386292)
			(xy 422.099661 -402.395477) (xy 422.106163 -402.412661) (xy 422.111932 -402.41982) (xy 422.133748 -402.445525)
			(xy 422.171836 -402.501154) (xy 422.202987 -402.560945) (xy 422.226752 -402.624037) (xy 422.24279 -402.689521)
			(xy 422.250869 -402.756454) (xy 422.250874 -402.823818) (xy 425.528934 -402.823818) (xy 425.528938 -402.75651)
			(xy 425.536987 -402.689684) (xy 425.552965 -402.624299) (xy 425.576642 -402.561293) (xy 425.60768 -402.501568)
			(xy 425.645634 -402.44598) (xy 425.667424 -402.420328) (xy 425.673236 -402.413194) (xy 425.679741 -402.395995)
			(xy 425.680124 -402.3868) (xy 425.680124 -401.893532) (xy 425.679693 -401.884347) (xy 425.673193 -401.867163)
			(xy 425.667424 -401.860004) (xy 425.645617 -401.834368) (xy 425.60767 -401.778779) (xy 425.576638 -401.719053)
			(xy 425.552967 -401.656046) (xy 425.536996 -401.590662) (xy 425.528954 -401.523838) (xy 425.528956 -401.456532)
			(xy 425.537001 -401.389708) (xy 425.552976 -401.324325) (xy 425.57665 -401.26132) (xy 425.607685 -401.201595)
			(xy 425.645635 -401.146008) (xy 425.667424 -401.120356) (xy 425.673225 -401.113214) (xy 425.679736 -401.096021)
			(xy 425.680124 -401.086828) (xy 425.680124 -400.92884) (xy 425.680555 -400.918686) (xy 425.688342 -400.899929)
			(xy 425.702736 -400.885604) (xy 425.72153 -400.877907) (xy 425.731686 -400.877532) (xy 426.447966 -400.877532)
			(xy 426.45809 -400.878054) (xy 426.476808 -400.88577) (xy 426.491165 -400.900045) (xy 426.498987 -400.918719)
			(xy 426.499528 -400.92884) (xy 426.499528 -401.086828) (xy 426.499918 -401.096017) (xy 426.506445 -401.113202)
			(xy 426.512228 -401.120356) (xy 426.533997 -401.146024) (xy 426.571949 -401.201607) (xy 426.602985 -401.261328)
			(xy 426.62666 -401.324331) (xy 426.642635 -401.389712) (xy 426.650681 -401.456533) (xy 426.650683 -401.523837)
			(xy 426.642641 -401.590659) (xy 426.626669 -401.65604) (xy 426.602997 -401.719044) (xy 426.600558 -401.723737)
			(xy 427.729089 -401.723737) (xy 427.729091 -401.65643) (xy 427.737138 -401.589605) (xy 427.753114 -401.524221)
			(xy 427.776791 -401.461216) (xy 427.807828 -401.401492) (xy 427.845782 -401.345906) (xy 427.867572 -401.320254)
			(xy 427.873379 -401.313117) (xy 427.879886 -401.29592) (xy 427.880272 -401.286726) (xy 427.880272 -400.793458)
			(xy 427.879888 -400.784268) (xy 427.873357 -400.767084) (xy 427.867572 -400.75993) (xy 427.845789 -400.734273)
			(xy 427.807838 -400.678688) (xy 427.776803 -400.618966) (xy 427.753128 -400.555962) (xy 427.737154 -400.49058)
			(xy 427.729109 -400.423757) (xy 427.729108 -400.356452) (xy 427.737152 -400.289629) (xy 427.753126 -400.224247)
			(xy 427.776799 -400.161243) (xy 427.807833 -400.101519) (xy 427.845784 -400.045934) (xy 427.867572 -400.020282)
			(xy 427.873367 -400.013136) (xy 427.879881 -399.995946) (xy 427.880272 -399.986754) (xy 427.880272 -399.828766)
			(xy 427.880706 -399.818602) (xy 427.888498 -399.799825) (xy 427.902883 -399.78546) (xy 427.921669 -399.777693)
			(xy 427.931834 -399.777204) (xy 428.648114 -399.777204) (xy 428.658268 -399.777721) (xy 428.677031 -399.785494)
			(xy 428.691395 -399.799852) (xy 428.699175 -399.818612) (xy 428.699676 -399.828766) (xy 428.699676 -399.986754)
			(xy 428.700114 -399.995938) (xy 428.706609 -400.013122) (xy 428.712376 -400.020282) (xy 428.734169 -400.045929)
			(xy 428.772117 -400.101517) (xy 428.803149 -400.161241) (xy 428.826821 -400.224246) (xy 428.842793 -400.289629)
			(xy 428.850836 -400.356452) (xy 428.850836 -400.423757) (xy 428.842791 -400.49058) (xy 428.826818 -400.555962)
			(xy 428.803145 -400.618967) (xy 428.772112 -400.678691) (xy 428.734164 -400.734278) (xy 428.712376 -400.75993)
			(xy 428.706581 -400.767076) (xy 428.700066 -400.784266) (xy 428.699676 -400.793458) (xy 428.699676 -401.286726)
			(xy 428.700079 -401.295914) (xy 428.706598 -401.313098) (xy 428.712376 -401.320254) (xy 428.734142 -401.345924)
			(xy 428.77209 -401.401508) (xy 428.803124 -401.46123) (xy 428.826797 -401.524232) (xy 428.842771 -401.589612)
			(xy 428.850817 -401.656432) (xy 428.850819 -401.723735) (xy 428.842777 -401.790556) (xy 428.826807 -401.855937)
			(xy 428.803137 -401.91894) (xy 428.772107 -401.978663) (xy 428.734162 -402.03425) (xy 428.712376 -402.059902)
			(xy 428.706593 -402.067057) (xy 428.700071 -402.08424) (xy 428.699676 -402.09343) (xy 428.699676 -402.251418)
			(xy 428.699182 -402.261575) (xy 428.691404 -402.280342) (xy 428.677039 -402.294706) (xy 428.658271 -402.302483)
			(xy 428.648114 -402.30298) (xy 427.931834 -402.30298) (xy 427.921667 -402.302509) (xy 427.902876 -402.294738)
			(xy 427.888491 -402.280367) (xy 427.880702 -402.261585) (xy 427.880272 -402.251418) (xy 427.880272 -402.09343)
			(xy 427.879854 -402.084244) (xy 427.873347 -402.067059) (xy 427.867572 -402.059902) (xy 427.845762 -402.034268)
			(xy 427.807811 -401.97868) (xy 427.776777 -401.918954) (xy 427.753104 -401.855947) (xy 427.737132 -401.790562)
			(xy 427.729089 -401.723737) (xy 426.600558 -401.723737) (xy 426.571964 -401.778767) (xy 426.534015 -401.834352)
			(xy 426.512228 -401.860004) (xy 426.506438 -401.867154) (xy 426.499922 -401.884341) (xy 426.499528 -401.893532)
			(xy 426.499528 -402.3868) (xy 426.499932 -402.395988) (xy 426.506449 -402.413173) (xy 426.512228 -402.420328)
			(xy 426.53397 -402.446019) (xy 426.571922 -402.501599) (xy 426.602959 -402.561317) (xy 426.626636 -402.624316)
			(xy 426.642613 -402.689694) (xy 426.650662 -402.756513) (xy 426.650666 -402.823815) (xy 426.650658 -402.823878)
			(xy 429.928702 -402.823878) (xy 429.928707 -402.75645) (xy 429.936788 -402.689508) (xy 429.952829 -402.624016)
			(xy 429.976599 -402.560917) (xy 430.007757 -402.50112) (xy 430.045852 -402.445485) (xy 430.06772 -402.41982)
			(xy 430.073535 -402.412688) (xy 430.080038 -402.395487) (xy 430.08042 -402.386292) (xy 430.08042 -401.89404)
			(xy 430.079986 -401.884855) (xy 430.073488 -401.867671) (xy 430.06772 -401.860512) (xy 430.045836 -401.834863)
			(xy 430.007746 -401.779227) (xy 429.976595 -401.719429) (xy 429.952831 -401.656329) (xy 429.936797 -401.590838)
			(xy 429.928722 -401.523898) (xy 429.928724 -401.456472) (xy 429.936802 -401.389532) (xy 429.95284 -401.324042)
			(xy 429.976608 -401.260944) (xy 430.007762 -401.201147) (xy 430.045854 -401.145513) (xy 430.06772 -401.119848)
			(xy 430.073523 -401.112708) (xy 430.080033 -401.095513) (xy 430.08042 -401.08632) (xy 430.08042 -400.92884)
			(xy 430.080849 -400.918718) (xy 430.088588 -400.900011) (xy 430.102901 -400.885695) (xy 430.121606 -400.877952)
			(xy 430.131728 -400.877532) (xy 430.848008 -400.877532) (xy 430.858135 -400.87791) (xy 430.876845 -400.885667)
			(xy 430.89116 -400.899996) (xy 430.898899 -400.918713) (xy 430.899316 -400.92884) (xy 430.899316 -401.08632)
			(xy 430.899713 -401.095509) (xy 430.906236 -401.112693) (xy 430.912016 -401.119848) (xy 430.93386 -401.14553)
			(xy 430.971948 -401.201162) (xy 431.003099 -401.260956) (xy 431.026863 -401.324051) (xy 431.0429 -401.389538)
			(xy 431.050977 -401.456474) (xy 431.050979 -401.523896) (xy 431.042905 -401.590832) (xy 431.026872 -401.65632)
			(xy 431.003111 -401.719416) (xy 431.00086 -401.723737) (xy 432.128879 -401.723737) (xy 432.128881 -401.65643)
			(xy 432.136928 -401.589605) (xy 432.152904 -401.524222) (xy 432.17658 -401.461216) (xy 432.207617 -401.401492)
			(xy 432.24557 -401.345906) (xy 432.26736 -401.320254) (xy 432.273166 -401.313116) (xy 432.279673 -401.29592)
			(xy 432.28006 -401.286726) (xy 432.28006 -400.793458) (xy 432.279657 -400.78427) (xy 432.273137 -400.767087)
			(xy 432.26736 -400.75993) (xy 432.245578 -400.734273) (xy 432.207627 -400.678688) (xy 432.176593 -400.618965)
			(xy 432.152919 -400.555961) (xy 432.136945 -400.490579) (xy 432.1289 -400.423757) (xy 432.128899 -400.356452)
			(xy 432.136943 -400.28963) (xy 432.152916 -400.224247) (xy 432.176589 -400.161243) (xy 432.207623 -400.10152)
			(xy 432.245572 -400.045934) (xy 432.26736 -400.020282) (xy 432.273154 -400.013135) (xy 432.279669 -399.995946)
			(xy 432.28006 -399.986754) (xy 432.28006 -399.828766) (xy 432.280506 -399.818603) (xy 432.288296 -399.799829)
			(xy 432.302676 -399.785464) (xy 432.321459 -399.777695) (xy 432.331622 -399.777204) (xy 433.047902 -399.777204)
			(xy 433.058056 -399.777731) (xy 433.076818 -399.7855) (xy 433.091182 -399.799855) (xy 433.098963 -399.818613)
			(xy 433.099464 -399.828766) (xy 433.099464 -399.986754) (xy 433.099905 -399.995938) (xy 433.106398 -400.013122)
			(xy 433.112164 -400.020282) (xy 433.133958 -400.045929) (xy 433.171906 -400.101516) (xy 433.202939 -400.161241)
			(xy 433.226611 -400.224246) (xy 433.242584 -400.289629) (xy 433.250627 -400.356452) (xy 433.250627 -400.423757)
			(xy 433.242582 -400.49058) (xy 433.226609 -400.555963) (xy 433.202935 -400.618968) (xy 433.171901 -400.678691)
			(xy 433.133952 -400.734278) (xy 433.112164 -400.75993) (xy 433.106368 -400.767075) (xy 433.099854 -400.784266)
			(xy 433.099464 -400.793458) (xy 433.099464 -401.286726) (xy 433.09987 -401.295913) (xy 433.106387 -401.313097)
			(xy 433.112164 -401.320254) (xy 433.13393 -401.345924) (xy 433.171879 -401.401508) (xy 433.202913 -401.461229)
			(xy 433.226587 -401.524231) (xy 433.242561 -401.589611) (xy 433.250607 -401.656432) (xy 433.250609 -401.723735)
			(xy 433.242567 -401.790556) (xy 433.226597 -401.855937) (xy 433.202927 -401.918941) (xy 433.171896 -401.978663)
			(xy 433.13395 -402.03425) (xy 433.112164 -402.059902) (xy 433.106379 -402.067056) (xy 433.099858 -402.08424)
			(xy 433.099464 -402.09343) (xy 433.099464 -402.251418) (xy 433.098982 -402.261577) (xy 433.091202 -402.280346)
			(xy 433.076833 -402.294711) (xy 433.058061 -402.302485) (xy 433.047902 -402.30298) (xy 432.331622 -402.30298)
			(xy 432.321454 -402.302518) (xy 432.302663 -402.294744) (xy 432.288278 -402.28037) (xy 432.28049 -402.261586)
			(xy 432.28006 -402.251418) (xy 432.28006 -402.09343) (xy 432.279622 -402.084246) (xy 432.273126 -402.067062)
			(xy 432.26736 -402.059902) (xy 432.24555 -402.034268) (xy 432.2076 -401.97868) (xy 432.176567 -401.918954)
			(xy 432.152894 -401.855947) (xy 432.136922 -401.790562) (xy 432.128879 -401.723737) (xy 431.00086 -401.723737)
			(xy 430.971963 -401.779212) (xy 430.933878 -401.834847) (xy 430.912016 -401.860512) (xy 430.906234 -401.867667)
			(xy 430.89971 -401.88485) (xy 430.899316 -401.89404) (xy 430.899316 -402.386292) (xy 430.899726 -402.395479)
			(xy 430.90624 -402.412664) (xy 430.912016 -402.41982) (xy 430.933832 -402.445524) (xy 430.971921 -402.501154)
			(xy 431.003073 -402.560945) (xy 431.026839 -402.624036) (xy 431.042878 -402.68952) (xy 431.050957 -402.756454)
			(xy 431.050962 -402.823818) (xy 434.329022 -402.823818) (xy 434.329026 -402.75651) (xy 434.337075 -402.689684)
			(xy 434.353052 -402.6243) (xy 434.376729 -402.561294) (xy 434.407766 -402.501568) (xy 434.445718 -402.445981)
			(xy 434.467508 -402.420328) (xy 434.473319 -402.413193) (xy 434.479825 -402.395995) (xy 434.480208 -402.3868)
			(xy 434.480208 -401.893532) (xy 434.479781 -401.884347) (xy 434.473279 -401.867162) (xy 434.467508 -401.860004)
			(xy 434.445702 -401.834368) (xy 434.407755 -401.778778) (xy 434.376725 -401.719052) (xy 434.353054 -401.656046)
			(xy 434.337084 -401.590662) (xy 434.329042 -401.523838) (xy 434.329043 -401.456532) (xy 434.337089 -401.389709)
			(xy 434.353063 -401.324326) (xy 434.376737 -401.26132) (xy 434.407771 -401.201596) (xy 434.44572 -401.146009)
			(xy 434.467508 -401.120356) (xy 434.473307 -401.113212) (xy 434.47982 -401.096021) (xy 434.480208 -401.086828)
			(xy 434.480208 -400.92884) (xy 434.480655 -400.918688) (xy 434.488438 -400.899934) (xy 434.502828 -400.885609)
			(xy 434.521616 -400.87791) (xy 434.53177 -400.877532) (xy 435.24805 -400.877532) (xy 435.258173 -400.878067)
			(xy 435.276891 -400.885777) (xy 435.291249 -400.900049) (xy 435.299071 -400.918721) (xy 435.299612 -400.92884)
			(xy 435.299612 -401.086828) (xy 435.300006 -401.096017) (xy 435.306531 -401.113201) (xy 435.312312 -401.120356)
			(xy 435.334082 -401.146024) (xy 435.372034 -401.201607) (xy 435.403071 -401.261328) (xy 435.426747 -401.32433)
			(xy 435.442723 -401.389711) (xy 435.450769 -401.456533) (xy 435.450771 -401.523837) (xy 435.442728 -401.590659)
			(xy 435.426756 -401.656041) (xy 435.403083 -401.719045) (xy 435.37205 -401.778767) (xy 435.3341 -401.834353)
			(xy 435.312312 -401.860004) (xy 435.306533 -401.867161) (xy 435.300007 -401.884343) (xy 435.299612 -401.893532)
			(xy 435.299612 -402.3868) (xy 435.30002 -402.395988) (xy 435.306535 -402.413172) (xy 435.312312 -402.420328)
			(xy 435.334054 -402.446018) (xy 435.372008 -402.501598) (xy 435.403046 -402.561316) (xy 435.426723 -402.624316)
			(xy 435.442701 -402.689694) (xy 435.45075 -402.756513) (xy 435.450754 -402.823815) (xy 435.442714 -402.890635)
			(xy 435.426745 -402.956015) (xy 435.403075 -403.019018) (xy 435.372045 -403.07874) (xy 435.334098 -403.134325)
			(xy 435.312312 -403.159976) (xy 435.306502 -403.167112) (xy 435.299995 -403.184309) (xy 435.299612 -403.193504)
			(xy 435.299612 -403.351492) (xy 435.299172 -403.361644) (xy 435.291381 -403.380394) (xy 435.27699 -403.394717)
			(xy 435.258204 -403.402419) (xy 435.24805 -403.4028) (xy 434.53177 -403.4028) (xy 434.521646 -403.402299)
			(xy 434.502932 -403.394569) (xy 434.488578 -403.380288) (xy 434.480753 -403.361613) (xy 434.480208 -403.351492)
			(xy 434.480208 -403.193504) (xy 434.479794 -403.184317) (xy 434.473283 -403.167133) (xy 434.467508 -403.159976)
			(xy 434.445674 -403.134362) (xy 434.407729 -403.07877) (xy 434.376699 -403.01904) (xy 434.353031 -402.956031)
			(xy 434.337062 -402.890644) (xy 434.329022 -402.823818) (xy 431.050962 -402.823818) (xy 431.050962 -402.823874)
			(xy 431.042891 -402.890808) (xy 431.026861 -402.956295) (xy 431.003103 -403.019389) (xy 430.971958 -403.079184)
			(xy 430.933877 -403.134819) (xy 430.912016 -403.160484) (xy 430.906203 -403.167618) (xy 430.899698 -403.184817)
			(xy 430.899316 -403.194012) (xy 430.899316 -403.351492) (xy 430.898809 -403.361598) (xy 430.891077 -403.380273)
			(xy 430.876787 -403.394568) (xy 430.858114 -403.402306) (xy 430.848008 -403.4028) (xy 430.131728 -403.4028)
			(xy 430.121607 -403.402361) (xy 430.102904 -403.394622) (xy 430.088589 -403.380313) (xy 430.080843 -403.361613)
			(xy 430.08042 -403.351492) (xy 430.08042 -403.194012) (xy 430.079999 -403.184826) (xy 430.073492 -403.167642)
			(xy 430.06772 -403.160484) (xy 430.045808 -403.134858) (xy 430.00772 -403.079218) (xy 429.97657 -403.019417)
			(xy 429.952807 -402.956315) (xy 429.936775 -402.890821) (xy 429.928702 -402.823878) (xy 426.650658 -402.823878)
			(xy 426.642626 -402.890635) (xy 426.626657 -402.956015) (xy 426.602989 -403.019017) (xy 426.571959 -403.078739)
			(xy 426.534014 -403.134324) (xy 426.512228 -403.159976) (xy 426.506408 -403.167104) (xy 426.499909 -403.184308)
			(xy 426.499528 -403.193504) (xy 426.499528 -403.351492) (xy 426.499072 -403.361642) (xy 426.491285 -403.380389)
			(xy 426.476899 -403.394712) (xy 426.458118 -403.402417) (xy 426.447966 -403.4028) (xy 425.731686 -403.4028)
			(xy 425.721563 -403.402286) (xy 425.70285 -403.394561) (xy 425.688495 -403.380284) (xy 425.68067 -403.361612)
			(xy 425.680124 -403.351492) (xy 425.680124 -403.193504) (xy 425.679707 -403.184318) (xy 425.673198 -403.167133)
			(xy 425.667424 -403.159976) (xy 425.64559 -403.134362) (xy 425.607643 -403.07877) (xy 425.576613 -403.019041)
			(xy 425.552943 -402.956032) (xy 425.536974 -402.890645) (xy 425.528934 -402.823818) (xy 422.250874 -402.823818)
			(xy 422.250874 -402.823874) (xy 422.242803 -402.890808) (xy 422.226774 -402.956294) (xy 422.203016 -403.019389)
			(xy 422.171873 -403.079184) (xy 422.133792 -403.134818) (xy 422.111932 -403.160484) (xy 422.106109 -403.16761)
			(xy 422.099612 -403.184816) (xy 422.099232 -403.194012) (xy 422.099232 -403.351492) (xy 422.098709 -403.361596)
			(xy 422.09098 -403.380268) (xy 422.076695 -403.394562) (xy 422.058028 -403.402303) (xy 422.047924 -403.4028)
			(xy 421.331644 -403.4028) (xy 421.321524 -403.402348) (xy 421.302822 -403.394614) (xy 421.288506 -403.380308)
			(xy 421.280759 -403.361611) (xy 421.280336 -403.351492) (xy 421.280336 -403.194012) (xy 421.279912 -403.184826)
			(xy 421.273407 -403.167642) (xy 421.267636 -403.160484) (xy 421.245724 -403.134858) (xy 421.207634 -403.079219)
			(xy 421.176483 -403.019418) (xy 421.15272 -402.956315) (xy 421.136687 -402.890821) (xy 421.128614 -402.823878)
			(xy 414.525968 -402.823878) (xy 414.525968 -405.623649) (xy 418.929012 -405.623649) (xy 418.929013 -405.556342)
			(xy 418.937058 -405.489518) (xy 418.953033 -405.424135) (xy 418.976709 -405.36113) (xy 419.007746 -405.301407)
			(xy 419.045698 -405.245822) (xy 419.067488 -405.22017) (xy 419.073278 -405.21302) (xy 419.079797 -405.195833)
			(xy 419.080188 -405.186642) (xy 419.080188 -404.693374) (xy 419.079793 -404.684185) (xy 419.073269 -404.667001)
			(xy 419.067488 -404.659846) (xy 419.04572 -404.634177) (xy 419.007768 -404.578594) (xy 418.976731 -404.518873)
			(xy 418.953055 -404.455871) (xy 418.937079 -404.39049) (xy 418.929032 -404.323669) (xy 418.92903 -404.256364)
			(xy 418.937073 -404.189542) (xy 418.953045 -404.124161) (xy 418.976717 -404.061157) (xy 419.007751 -404.001435)
			(xy 419.0457 -403.945849) (xy 419.067488 -403.920198) (xy 419.073267 -403.91304) (xy 419.079792 -403.895859)
			(xy 419.080188 -403.88667) (xy 419.080188 -403.728682) (xy 419.08055 -403.718503) (xy 419.088351 -403.699698)
			(xy 419.102756 -403.685313) (xy 419.12157 -403.677537) (xy 419.13175 -403.67712) (xy 419.84803 -403.67712)
			(xy 419.858187 -403.677608) (xy 419.876954 -403.685389) (xy 419.891317 -403.699756) (xy 419.899094 -403.718524)
			(xy 419.899592 -403.728682) (xy 419.899592 -403.88667) (xy 419.900018 -403.895855) (xy 419.906521 -403.91304)
			(xy 419.912292 -403.920198) (xy 419.9341 -403.945833) (xy 419.972047 -404.001422) (xy 420.003077 -404.061149)
			(xy 420.026747 -404.124155) (xy 420.042718 -404.189539) (xy 420.05076 -404.256363) (xy 420.050758 -404.32367)
			(xy 420.042712 -404.390493) (xy 420.026738 -404.455876) (xy 420.003064 -404.518882) (xy 419.97203 -404.578606)
			(xy 419.93408 -404.634193) (xy 419.912292 -404.659846) (xy 419.906492 -404.666989) (xy 419.89998 -404.684181)
			(xy 419.899592 -404.693374) (xy 419.899592 -405.186642) (xy 419.899984 -405.195831) (xy 419.90651 -405.213015)
			(xy 419.912292 -405.22017) (xy 419.934073 -405.245827) (xy 419.97202 -405.301414) (xy 420.003052 -405.361137)
			(xy 420.026723 -405.424141) (xy 420.042696 -405.489522) (xy 420.05074 -405.556343) (xy 420.050741 -405.623647)
			(xy 420.042698 -405.690469) (xy 420.026726 -405.755851) (xy 420.003055 -405.818855) (xy 419.972025 -405.878578)
			(xy 419.934078 -405.934165) (xy 419.912292 -405.959818) (xy 419.906504 -405.96697) (xy 419.899985 -405.984155)
			(xy 419.899592 -405.993346) (xy 419.899592 -406.151334) (xy 419.899095 -406.16149) (xy 419.891315 -406.180254)
			(xy 419.876951 -406.194617) (xy 419.858186 -406.202396) (xy 419.84803 -406.202896) (xy 419.13175 -406.202896)
			(xy 419.121586 -406.202396) (xy 419.102799 -406.194634) (xy 419.088413 -406.180272) (xy 419.08062 -406.161497)
			(xy 419.080188 -406.151334) (xy 419.080188 -405.993346) (xy 419.079759 -405.984161) (xy 419.073259 -405.966976)
			(xy 419.067488 -405.959818) (xy 419.045693 -405.934171) (xy 419.007741 -405.878585) (xy 418.976705 -405.818861)
			(xy 418.953031 -405.755856) (xy 418.937057 -405.690473) (xy 418.929012 -405.623649) (xy 414.525968 -405.623649)
			(xy 414.525968 -406.723789) (xy 421.128626 -406.723789) (xy 421.128629 -406.656363) (xy 421.136708 -406.589421)
			(xy 421.152748 -406.52393) (xy 421.176518 -406.460832) (xy 421.207674 -406.401035) (xy 421.245769 -406.345401)
			(xy 421.267636 -406.319736) (xy 421.273447 -406.312601) (xy 421.279952 -406.295403) (xy 421.280336 -406.286208)
			(xy 421.280336 -405.793956) (xy 421.279939 -405.784768) (xy 421.273415 -405.767584) (xy 421.267636 -405.760428)
			(xy 421.245767 -405.734767) (xy 421.207676 -405.679132) (xy 421.176523 -405.619336) (xy 421.152758 -405.556239)
			(xy 421.136722 -405.490749) (xy 421.128645 -405.423809) (xy 421.128646 -405.356385) (xy 421.136723 -405.289445)
			(xy 421.15276 -405.223956) (xy 421.176526 -405.160859) (xy 421.207679 -405.101062) (xy 421.245771 -405.045429)
			(xy 421.267636 -405.019764) (xy 421.273435 -405.012621) (xy 421.279947 -404.995429) (xy 421.280336 -404.986236)
			(xy 421.280336 -404.828756) (xy 421.28075 -404.81864) (xy 421.288509 -404.799954) (xy 421.302828 -404.785659)
			(xy 421.321527 -404.777933) (xy 421.331644 -404.777448) (xy 422.047924 -404.777448) (xy 422.058028 -404.777964)
			(xy 422.076697 -404.7857) (xy 422.090989 -404.799986) (xy 422.098732 -404.818652) (xy 422.099232 -404.828756)
			(xy 422.099232 -404.986236) (xy 422.09964 -404.995423) (xy 422.106157 -405.012607) (xy 422.111932 -405.019764)
			(xy 422.133791 -405.045433) (xy 422.171878 -405.101068) (xy 422.203027 -405.160864) (xy 422.22679 -405.22396)
			(xy 422.242825 -405.289448) (xy 422.2509 -405.356386) (xy 422.250901 -405.423808) (xy 422.242826 -405.490746)
			(xy 422.226792 -405.556234) (xy 422.203029 -405.619331) (xy 422.20075 -405.623707) (xy 423.328805 -405.623707)
			(xy 423.328805 -405.556284) (xy 423.336882 -405.489345) (xy 423.352917 -405.423856) (xy 423.376681 -405.360759)
			(xy 423.407832 -405.300962) (xy 423.44592 -405.245328) (xy 423.467784 -405.219662) (xy 423.473577 -405.212514)
			(xy 423.480094 -405.195326) (xy 423.480484 -405.186134) (xy 423.480484 -404.693882) (xy 423.480086 -404.684693)
			(xy 423.473564 -404.667509) (xy 423.467784 -404.660354) (xy 423.445942 -404.634671) (xy 423.407854 -404.579038)
			(xy 423.376703 -404.519245) (xy 423.352938 -404.45615) (xy 423.336902 -404.390663) (xy 423.328825 -404.323727)
			(xy 423.328823 -404.256306) (xy 423.336896 -404.189369) (xy 423.352929 -404.123882) (xy 423.37669 -404.060786)
			(xy 423.407837 -404.00099) (xy 423.445922 -403.945355) (xy 423.467784 -403.91969) (xy 423.473565 -403.912534)
			(xy 423.48009 -403.895352) (xy 423.480484 -403.886162) (xy 423.480484 -403.728682) (xy 423.480913 -403.718549)
			(xy 423.488655 -403.699819) (xy 423.502959 -403.685461) (xy 423.521661 -403.677651) (xy 423.531792 -403.67712)
			(xy 424.248072 -403.67712) (xy 424.258227 -403.677545) (xy 424.276983 -403.685335) (xy 424.291308 -403.699731)
			(xy 424.299005 -403.718525) (xy 424.29938 -403.728682) (xy 424.29938 -403.886162) (xy 424.299813 -403.895347)
			(xy 424.306311 -403.912531) (xy 424.31208 -403.91969) (xy 424.333966 -403.945337) (xy 424.372056 -404.000974)
			(xy 424.403207 -404.060772) (xy 424.42697 -404.123872) (xy 424.443005 -404.189363) (xy 424.451079 -404.256304)
			(xy 424.451077 -404.323729) (xy 424.442999 -404.39067) (xy 424.426961 -404.45616) (xy 424.403193 -404.519258)
			(xy 424.372039 -404.579055) (xy 424.333946 -404.634689) (xy 424.31208 -404.660354) (xy 424.306276 -404.667494)
			(xy 424.299766 -404.684688) (xy 424.29938 -404.693882) (xy 424.29938 -405.186134) (xy 424.299778 -405.195322)
			(xy 424.306301 -405.212506) (xy 424.31208 -405.219662) (xy 424.333939 -405.245332) (xy 424.372029 -405.300965)
			(xy 424.403181 -405.360761) (xy 424.426946 -405.423857) (xy 424.442983 -405.489346) (xy 424.45106 -405.556284)
			(xy 424.45106 -405.623707) (xy 424.442985 -405.690646) (xy 424.426949 -405.756134) (xy 424.403185 -405.819231)
			(xy 424.372034 -405.879027) (xy 424.333944 -405.934661) (xy 424.31208 -405.960326) (xy 424.306288 -405.967474)
			(xy 424.299771 -405.984662) (xy 424.29938 -405.993854) (xy 424.29938 -406.151334) (xy 424.298902 -406.16146)
			(xy 424.291167 -406.180179) (xy 424.276878 -406.194533) (xy 424.258196 -406.202355) (xy 424.248072 -406.202896)
			(xy 423.531792 -406.202896) (xy 423.521637 -406.202485) (xy 423.502884 -406.194686) (xy 423.48856 -406.180286)
			(xy 423.480862 -406.161491) (xy 423.480484 -406.151334) (xy 423.480484 -405.993854) (xy 423.480051 -405.984669)
			(xy 423.473553 -405.967484) (xy 423.467784 -405.960326) (xy 423.445915 -405.934665) (xy 423.407827 -405.87903)
			(xy 423.376678 -405.819233) (xy 423.352915 -405.756135) (xy 423.33688 -405.690646) (xy 423.328805 -405.623707)
			(xy 422.20075 -405.623707) (xy 422.171881 -405.679127) (xy 422.133795 -405.734762) (xy 422.111932 -405.760428)
			(xy 422.106133 -405.767571) (xy 422.099622 -405.784763) (xy 422.099232 -405.793956) (xy 422.099232 -406.286208)
			(xy 422.099654 -406.295394) (xy 422.106161 -406.312577) (xy 422.111932 -406.319736) (xy 422.133763 -406.345428)
			(xy 422.171851 -406.401059) (xy 422.203001 -406.460852) (xy 422.226766 -406.523945) (xy 422.242803 -406.589431)
			(xy 422.250881 -406.656366) (xy 422.250883 -406.72373) (xy 425.528945 -406.72373) (xy 425.528948 -406.656422)
			(xy 425.536995 -406.589598) (xy 425.552971 -406.524214) (xy 425.576647 -406.461208) (xy 425.607683 -406.401484)
			(xy 425.645635 -406.345896) (xy 425.667424 -406.320244) (xy 425.67323 -406.313105) (xy 425.679738 -406.29591)
			(xy 425.680124 -406.286716) (xy 425.680124 -405.793448) (xy 425.679685 -405.784264) (xy 425.673191 -405.76708)
			(xy 425.667424 -405.75992) (xy 425.645633 -405.734271) (xy 425.607685 -405.678684) (xy 425.576653 -405.61896)
			(xy 425.552981 -405.555955) (xy 425.537009 -405.490572) (xy 425.528965 -405.42375) (xy 425.528965 -405.356444)
			(xy 425.53701 -405.289622) (xy 425.552983 -405.22424) (xy 425.576655 -405.161235) (xy 425.607688 -405.101511)
			(xy 425.645636 -405.045924) (xy 425.667424 -405.020272) (xy 425.673218 -405.013125) (xy 425.679733 -404.995936)
			(xy 425.680124 -404.986744) (xy 425.680124 -404.828756) (xy 425.680486 -404.818596) (xy 425.688301 -404.799838)
			(xy 425.702716 -404.785515) (xy 425.721523 -404.777822) (xy 425.731686 -404.777448) (xy 426.447966 -404.777448)
			(xy 426.458091 -404.777955) (xy 426.476813 -404.785673) (xy 426.491171 -404.799953) (xy 426.49899 -404.818633)
			(xy 426.499528 -404.828756) (xy 426.499528 -404.986744) (xy 426.499911 -404.995934) (xy 426.506443 -405.013119)
			(xy 426.512228 -405.020272) (xy 426.534013 -405.045927) (xy 426.571964 -405.101512) (xy 426.602999 -405.161235)
			(xy 426.626674 -405.224239) (xy 426.642648 -405.289622) (xy 426.650693 -405.356444) (xy 426.650693 -405.42375)
			(xy 426.642649 -405.490573) (xy 426.626675 -405.555955) (xy 426.603002 -405.618959) (xy 426.600565 -405.623649)
			(xy 427.7291 -405.623649) (xy 427.729101 -405.556342) (xy 427.737146 -405.489519) (xy 427.753121 -405.424136)
			(xy 427.776796 -405.361131) (xy 427.807831 -405.301408) (xy 427.845783 -405.245822) (xy 427.867572 -405.22017)
			(xy 427.873373 -405.213028) (xy 427.879883 -405.195835) (xy 427.880272 -405.186642) (xy 427.880272 -404.693374)
			(xy 427.879881 -404.684185) (xy 427.873355 -404.667) (xy 427.867572 -404.659846) (xy 427.845805 -404.634176)
			(xy 427.807853 -404.578593) (xy 427.776817 -404.518872) (xy 427.753142 -404.45587) (xy 427.737166 -404.39049)
			(xy 427.72912 -404.323668) (xy 427.729118 -404.256365) (xy 427.73716 -404.189543) (xy 427.753132 -404.124162)
			(xy 427.776804 -404.061158) (xy 427.807836 -404.001435) (xy 427.845785 -403.94585) (xy 427.867572 -403.920198)
			(xy 427.873361 -403.913048) (xy 427.879878 -403.895861) (xy 427.880272 -403.88667) (xy 427.880272 -403.728682)
			(xy 427.88065 -403.718505) (xy 427.888447 -403.699703) (xy 427.902847 -403.685318) (xy 427.921657 -403.67754)
			(xy 427.931834 -403.67712) (xy 428.648114 -403.67712) (xy 428.65827 -403.677622) (xy 428.677036 -403.685397)
			(xy 428.6914 -403.69976) (xy 428.699178 -403.718526) (xy 428.699676 -403.728682) (xy 428.699676 -403.88667)
			(xy 428.700106 -403.895855) (xy 428.706607 -403.913039) (xy 428.712376 -403.920198) (xy 428.734185 -403.945833)
			(xy 428.772132 -404.001422) (xy 428.803164 -404.061148) (xy 428.826835 -404.124155) (xy 428.842806 -404.189539)
			(xy 428.850848 -404.256363) (xy 428.850846 -404.32367) (xy 428.8428 -404.390494) (xy 428.826825 -404.455877)
			(xy 428.80315 -404.518882) (xy 428.772115 -404.578607) (xy 428.734165 -404.634194) (xy 428.712376 -404.659846)
			(xy 428.706575 -404.666988) (xy 428.700064 -404.684181) (xy 428.699676 -404.693374) (xy 428.699676 -405.186642)
			(xy 428.700071 -405.195831) (xy 428.706596 -405.213015) (xy 428.712376 -405.22017) (xy 428.734157 -405.245827)
			(xy 428.772106 -405.301413) (xy 428.803138 -405.361136) (xy 428.826811 -405.42414) (xy 428.842784 -405.489522)
			(xy 428.850828 -405.556343) (xy 428.850829 -405.623648) (xy 428.842785 -405.69047) (xy 428.826813 -405.755851)
			(xy 428.803142 -405.818856) (xy 428.77211 -405.878579) (xy 428.734163 -405.934166) (xy 428.712376 -405.959818)
			(xy 428.706587 -405.966968) (xy 428.700068 -405.984155) (xy 428.699676 -405.993346) (xy 428.699676 -406.151334)
			(xy 428.699195 -406.161492) (xy 428.691412 -406.180259) (xy 428.677043 -406.194623) (xy 428.658272 -406.202399)
			(xy 428.648114 -406.202896) (xy 427.931834 -406.202896) (xy 427.921683 -406.202339) (xy 427.902921 -406.194583)
			(xy 427.888556 -406.180236) (xy 427.880774 -406.161485) (xy 427.880272 -406.151334) (xy 427.880272 -405.993346)
			(xy 427.879846 -405.98416) (xy 427.873344 -405.966976) (xy 427.867572 -405.959818) (xy 427.845777 -405.934171)
			(xy 427.807827 -405.878585) (xy 427.776792 -405.818861) (xy 427.753118 -405.755855) (xy 427.737144 -405.690472)
			(xy 427.7291 -405.623649) (xy 426.600565 -405.623649) (xy 426.571967 -405.678683) (xy 426.534016 -405.734268)
			(xy 426.512228 -405.75992) (xy 426.506432 -405.767065) (xy 426.499919 -405.784256) (xy 426.499528 -405.793448)
			(xy 426.499528 -406.286716) (xy 426.499924 -406.295905) (xy 426.506447 -406.313089) (xy 426.512228 -406.320244)
			(xy 426.533985 -406.345922) (xy 426.571937 -406.401504) (xy 426.602974 -406.461223) (xy 426.62665 -406.524225)
			(xy 426.642626 -406.589604) (xy 426.650673 -406.656424) (xy 426.650676 -406.723728) (xy 426.650669 -406.723789)
			(xy 429.928714 -406.723789) (xy 429.928717 -406.656363) (xy 429.936796 -406.589422) (xy 429.952835 -406.523931)
			(xy 429.976604 -406.460832) (xy 430.00776 -406.401036) (xy 430.045853 -406.345401) (xy 430.06772 -406.319736)
			(xy 430.073529 -406.312599) (xy 430.080035 -406.295402) (xy 430.08042 -406.286208) (xy 430.08042 -405.793956)
			(xy 430.080027 -405.784767) (xy 430.073501 -405.767583) (xy 430.06772 -405.760428) (xy 430.045851 -405.734766)
			(xy 430.007761 -405.679132) (xy 429.97661 -405.619335) (xy 429.952845 -405.556238) (xy 429.936809 -405.490748)
			(xy 429.928733 -405.423809) (xy 429.928734 -405.356385) (xy 429.93681 -405.289446) (xy 429.952847 -405.223956)
			(xy 429.976612 -405.160859) (xy 430.007765 -405.101063) (xy 430.045855 -405.045429) (xy 430.06772 -405.019764)
			(xy 430.073517 -405.012619) (xy 430.080031 -404.995428) (xy 430.08042 -404.986236) (xy 430.08042 -404.828756)
			(xy 430.08085 -404.818642) (xy 430.088605 -404.799959) (xy 430.102919 -404.785665) (xy 430.121613 -404.777935)
			(xy 430.131728 -404.777448) (xy 430.848008 -404.777448) (xy 430.858111 -404.777977) (xy 430.876779 -404.785708)
			(xy 430.891072 -404.799991) (xy 430.898815 -404.818654) (xy 430.899316 -404.828756) (xy 430.899316 -404.986236)
			(xy 430.899705 -404.995425) (xy 430.906233 -405.01261) (xy 430.912016 -405.019764) (xy 430.933875 -405.045433)
			(xy 430.971963 -405.101067) (xy 431.003113 -405.160863) (xy 431.026877 -405.223959) (xy 431.042912 -405.289448)
			(xy 431.050988 -405.356385) (xy 431.050989 -405.423809) (xy 431.042913 -405.490746) (xy 431.026879 -405.556235)
			(xy 431.003116 -405.619331) (xy 431.000867 -405.623648) (xy 432.128891 -405.623648) (xy 432.128892 -405.556343)
			(xy 432.136937 -405.489519) (xy 432.152911 -405.424136) (xy 432.176585 -405.361132) (xy 432.207621 -405.301408)
			(xy 432.245571 -405.245822) (xy 432.26736 -405.22017) (xy 432.273159 -405.213027) (xy 432.279671 -405.195835)
			(xy 432.28006 -405.186642) (xy 432.28006 -404.693374) (xy 432.279649 -404.684187) (xy 432.273134 -404.667004)
			(xy 432.26736 -404.659846) (xy 432.245593 -404.634176) (xy 432.207643 -404.578593) (xy 432.176607 -404.518872)
			(xy 432.152932 -404.45587) (xy 432.136957 -404.390489) (xy 432.128911 -404.323668) (xy 432.128909 -404.256365)
			(xy 432.136951 -404.189543) (xy 432.152922 -404.124162) (xy 432.176594 -404.061158) (xy 432.207626 -404.001436)
			(xy 432.245573 -403.94585) (xy 432.26736 -403.920198) (xy 432.273147 -403.913047) (xy 432.279666 -403.895861)
			(xy 432.28006 -403.88667) (xy 432.28006 -403.728682) (xy 432.28045 -403.718507) (xy 432.288245 -403.699707)
			(xy 432.302641 -403.685322) (xy 432.321446 -403.677542) (xy 432.331622 -403.67712) (xy 433.047902 -403.67712)
			(xy 433.058058 -403.677631) (xy 433.076823 -403.685403) (xy 433.091188 -403.699763) (xy 433.098965 -403.718526)
			(xy 433.099464 -403.728682) (xy 433.099464 -403.88667) (xy 433.099897 -403.895855) (xy 433.106396 -403.913039)
			(xy 433.112164 -403.920198) (xy 433.133973 -403.945832) (xy 433.171921 -404.001421) (xy 433.202954 -404.061147)
			(xy 433.226625 -404.124154) (xy 433.242596 -404.189539) (xy 433.250639 -404.256363) (xy 433.250637 -404.32367)
			(xy 433.24259 -404.390494) (xy 433.226615 -404.455877) (xy 433.20294 -404.518883) (xy 433.171904 -404.578607)
			(xy 433.133953 -404.634194) (xy 433.112164 -404.659846) (xy 433.106361 -404.666986) (xy 433.099851 -404.684181)
			(xy 433.099464 -404.693374) (xy 433.099464 -405.186642) (xy 433.099862 -405.19583) (xy 433.106385 -405.213014)
			(xy 433.112164 -405.22017) (xy 433.133946 -405.245827) (xy 433.171895 -405.301413) (xy 433.202928 -405.361136)
			(xy 433.226601 -405.42414) (xy 433.242574 -405.489521) (xy 433.250619 -405.556343) (xy 433.250619 -405.623648)
			(xy 433.242576 -405.69047) (xy 433.226604 -405.755852) (xy 433.202932 -405.818856) (xy 433.171899 -405.878579)
			(xy 433.133951 -405.934166) (xy 433.112164 -405.959818) (xy 433.106373 -405.966967) (xy 433.099856 -405.984155)
			(xy 433.099464 -405.993346) (xy 433.099464 -406.151334) (xy 433.098995 -406.161494) (xy 433.091209 -406.180263)
			(xy 433.076836 -406.194627) (xy 433.058062 -406.202401) (xy 433.047902 -406.202896) (xy 432.331622 -406.202896)
			(xy 432.32147 -406.20235) (xy 432.302708 -406.194589) (xy 432.288343 -406.180239) (xy 432.280561 -406.161486)
			(xy 432.28006 -406.151334) (xy 432.28006 -405.993346) (xy 432.279614 -405.984163) (xy 432.273124 -405.966979)
			(xy 432.26736 -405.959818) (xy 432.245566 -405.934171) (xy 432.207616 -405.878584) (xy 432.176582 -405.81886)
			(xy 432.152908 -405.755855) (xy 432.136935 -405.690472) (xy 432.128891 -405.623648) (xy 431.000867 -405.623648)
			(xy 430.971966 -405.679128) (xy 430.933879 -405.734762) (xy 430.912016 -405.760428) (xy 430.906227 -405.767579)
			(xy 430.899707 -405.784765) (xy 430.899316 -405.793956) (xy 430.899316 -406.286208) (xy 430.899719 -406.295396)
			(xy 430.906237 -406.31258) (xy 430.912016 -406.319736) (xy 430.933848 -406.345427) (xy 430.971937 -406.401059)
			(xy 431.003088 -406.460851) (xy 431.026853 -406.523945) (xy 431.04289 -406.58943) (xy 431.050968 -406.656366)
			(xy 431.050971 -406.723729) (xy 434.329033 -406.723729) (xy 434.329036 -406.656422) (xy 434.337083 -406.589598)
			(xy 434.353058 -406.524215) (xy 434.376733 -406.461209) (xy 434.407769 -406.401484) (xy 434.445719 -406.345897)
			(xy 434.467508 -406.320244) (xy 434.473312 -406.313104) (xy 434.479822 -406.295909) (xy 434.480208 -406.286716)
			(xy 434.480208 -405.793448) (xy 434.479773 -405.784263) (xy 434.473276 -405.767079) (xy 434.467508 -405.75992)
			(xy 434.445717 -405.734271) (xy 434.407771 -405.678683) (xy 434.376739 -405.618959) (xy 434.353068 -405.555954)
			(xy 434.337096 -405.490572) (xy 434.329053 -405.423749) (xy 434.329053 -405.356445) (xy 434.337097 -405.289622)
			(xy 434.35307 -405.22424) (xy 434.376742 -405.161236) (xy 434.407774 -405.101512) (xy 434.445721 -405.045925)
			(xy 434.467508 -405.020272) (xy 434.4733 -405.013124) (xy 434.479817 -404.995935) (xy 434.480208 -404.986744)
			(xy 434.480208 -404.828756) (xy 434.480586 -404.818598) (xy 434.488397 -404.799843) (xy 434.502807 -404.785521)
			(xy 434.52161 -404.777824) (xy 434.53177 -404.777448) (xy 435.24805 -404.777448) (xy 435.258175 -404.777968)
			(xy 435.276896 -404.785681) (xy 435.291254 -404.799957) (xy 435.299074 -404.818634) (xy 435.299612 -404.828756)
			(xy 435.299612 -404.986744) (xy 435.299998 -404.995934) (xy 435.306528 -405.013118) (xy 435.312312 -405.020272)
			(xy 435.334097 -405.045927) (xy 435.372049 -405.101512) (xy 435.403086 -405.161234) (xy 435.426761 -405.224239)
			(xy 435.442735 -405.289621) (xy 435.450781 -405.356444) (xy 435.450781 -405.42375) (xy 435.442736 -405.490573)
			(xy 435.426762 -405.555956) (xy 435.403088 -405.61896) (xy 435.372052 -405.678683) (xy 435.334101 -405.734269)
			(xy 435.312312 -405.75992) (xy 435.306526 -405.767073) (xy 435.300005 -405.784257) (xy 435.299612 -405.793448)
			(xy 435.299612 -406.286716) (xy 435.300012 -406.295904) (xy 435.306532 -406.313089) (xy 435.312312 -406.320244)
			(xy 435.33407 -406.345921) (xy 435.372023 -406.401503) (xy 435.40306 -406.461223) (xy 435.426737 -406.524224)
			(xy 435.442713 -406.589604) (xy 435.450761 -406.656424) (xy 435.450764 -406.723728) (xy 435.442722 -406.790549)
			(xy 435.426751 -406.85593) (xy 435.40308 -406.918933) (xy 435.372048 -406.978656) (xy 435.334099 -407.034241)
			(xy 435.312312 -407.059892) (xy 435.306538 -407.067053) (xy 435.300009 -407.084231) (xy 435.299612 -407.09342)
			(xy 435.299612 -407.251408) (xy 435.299185 -407.261561) (xy 435.291389 -407.280311) (xy 435.276994 -407.294634)
			(xy 435.258205 -407.302335) (xy 435.24805 -407.302716) (xy 434.53177 -407.302716) (xy 434.521636 -407.302297)
			(xy 434.502906 -407.294551) (xy 434.488549 -407.280244) (xy 434.480739 -407.26154) (xy 434.480208 -407.251408)
			(xy 434.480208 -407.09342) (xy 434.479786 -407.084234) (xy 434.47328 -407.06705) (xy 434.467508 -407.059892)
			(xy 434.44569 -407.034265) (xy 434.407744 -406.978674) (xy 434.376714 -406.918947) (xy 434.353044 -406.855939)
			(xy 434.337074 -406.790554) (xy 434.329033 -406.723729) (xy 431.050971 -406.723729) (xy 431.050971 -406.723786)
			(xy 431.042899 -406.790722) (xy 431.026867 -406.856209) (xy 431.003107 -406.919305) (xy 430.971961 -406.9791)
			(xy 430.933877 -407.034735) (xy 430.912016 -407.0604) (xy 430.906239 -407.067559) (xy 430.899712 -407.084739)
			(xy 430.899316 -407.093928) (xy 430.899316 -407.251408) (xy 430.898822 -407.261515) (xy 430.891084 -407.28019)
			(xy 430.87679 -407.294484) (xy 430.858115 -407.302222) (xy 430.848008 -407.302716) (xy 430.131728 -407.302716)
			(xy 430.121609 -407.302262) (xy 430.102909 -407.294526) (xy 430.088595 -407.280221) (xy 430.080845 -407.261526)
			(xy 430.08042 -407.251408) (xy 430.08042 -407.093928) (xy 430.079992 -407.084743) (xy 430.07349 -407.067559)
			(xy 430.06772 -407.0604) (xy 430.045824 -407.034761) (xy 430.007735 -406.979123) (xy 429.976584 -406.919324)
			(xy 429.952821 -406.856223) (xy 429.936787 -406.790731) (xy 429.928714 -406.723789) (xy 426.650669 -406.723789)
			(xy 426.642634 -406.790548) (xy 426.626664 -406.855929) (xy 426.602993 -406.918933) (xy 426.571962 -406.978655)
			(xy 426.534015 -407.03424) (xy 426.512228 -407.059892) (xy 426.506444 -407.067045) (xy 426.499924 -407.08423)
			(xy 426.499528 -407.09342) (xy 426.499528 -407.251408) (xy 426.499085 -407.261559) (xy 426.491292 -407.280306)
			(xy 426.476903 -407.294628) (xy 426.458119 -407.302333) (xy 426.447966 -407.302716) (xy 425.731686 -407.302716)
			(xy 425.721553 -407.302283) (xy 425.702823 -407.294543) (xy 425.688466 -407.28024) (xy 425.680655 -407.261539)
			(xy 425.680124 -407.251408) (xy 425.680124 -407.09342) (xy 425.679699 -407.084235) (xy 425.673195 -407.06705)
			(xy 425.667424 -407.059892) (xy 425.645605 -407.034266) (xy 425.607658 -406.978675) (xy 425.576627 -406.918948)
			(xy 425.552957 -406.85594) (xy 425.536987 -406.790555) (xy 425.528945 -406.72373) (xy 422.250883 -406.72373)
			(xy 422.250883 -406.723786) (xy 422.242811 -406.790722) (xy 422.22678 -406.856209) (xy 422.203021 -406.919304)
			(xy 422.171876 -406.9791) (xy 422.133793 -407.034734) (xy 422.111932 -407.0604) (xy 422.106145 -407.067551)
			(xy 422.099626 -407.084737) (xy 422.099232 -407.093928) (xy 422.099232 -407.251408) (xy 422.098722 -407.261513)
			(xy 422.090988 -407.280185) (xy 422.076699 -407.294479) (xy 422.058029 -407.302219) (xy 422.047924 -407.302716)
			(xy 421.331644 -407.302716) (xy 421.321526 -407.302248) (xy 421.302827 -407.294518) (xy 421.288512 -407.280217)
			(xy 421.280762 -407.261525) (xy 421.280336 -407.251408) (xy 421.280336 -407.093928) (xy 421.279904 -407.084743)
			(xy 421.273405 -407.067559) (xy 421.267636 -407.0604) (xy 421.245739 -407.034761) (xy 421.207649 -406.979124)
			(xy 421.176498 -406.919324) (xy 421.152734 -406.856224) (xy 421.1367 -406.790731) (xy 421.128626 -406.723789)
			(xy 414.525968 -406.723789) (xy 414.525968 -409.523827) (xy 418.928991 -409.523827) (xy 418.928995 -409.456519)
			(xy 418.937043 -409.389693) (xy 418.953021 -409.324308) (xy 418.9767 -409.261302) (xy 419.00774 -409.201577)
			(xy 419.045697 -409.145992) (xy 419.067488 -409.12034) (xy 419.073291 -409.113199) (xy 419.079802 -409.096005)
			(xy 419.080188 -409.086812) (xy 419.080188 -408.593544) (xy 419.079759 -408.584359) (xy 419.073259 -408.567174)
			(xy 419.067488 -408.560016) (xy 419.045691 -408.534371) (xy 419.007739 -408.478785) (xy 418.976704 -408.419061)
			(xy 418.953029 -408.356055) (xy 418.937055 -408.290671) (xy 418.929011 -408.223847) (xy 418.929012 -408.156541)
			(xy 418.937057 -408.089717) (xy 418.953033 -408.024333) (xy 418.976708 -407.961328) (xy 419.007745 -407.901605)
			(xy 419.045698 -407.84602) (xy 419.067488 -407.820368) (xy 419.073279 -407.813219) (xy 419.079797 -407.796031)
			(xy 419.080188 -407.78684) (xy 419.080188 -407.628852) (xy 419.080582 -407.618696) (xy 419.088391 -407.599945)
			(xy 419.102796 -407.585624) (xy 419.121592 -407.577924) (xy 419.13175 -407.577544) (xy 419.84803 -407.577544)
			(xy 419.858159 -407.578002) (xy 419.876882 -407.58574) (xy 419.891237 -407.600035) (xy 419.899055 -407.618725)
			(xy 419.899592 -407.628852) (xy 419.899592 -407.78684) (xy 419.899985 -407.796029) (xy 419.906511 -407.813213)
			(xy 419.912292 -407.820368) (xy 419.934071 -407.846027) (xy 419.972018 -407.901613) (xy 420.00305 -407.961336)
			(xy 420.026722 -408.02434) (xy 420.042694 -408.089721) (xy 420.050739 -408.156542) (xy 420.050739 -408.223846)
			(xy 420.042697 -408.290667) (xy 420.026725 -408.356049) (xy 420.003055 -408.419053) (xy 419.972024 -408.478776)
			(xy 419.934078 -408.534363) (xy 419.912292 -408.560016) (xy 419.906505 -408.567168) (xy 419.899985 -408.584353)
			(xy 419.899592 -408.593544) (xy 419.899592 -409.086812) (xy 419.899998 -409.096) (xy 419.906515 -409.113184)
			(xy 419.912292 -409.12034) (xy 419.934043 -409.146022) (xy 419.971991 -409.201605) (xy 420.003024 -409.261324)
			(xy 420.026698 -409.324325) (xy 420.042672 -409.389703) (xy 420.050719 -409.456522) (xy 420.050722 -409.523824)
			(xy 420.042682 -409.590643) (xy 420.026714 -409.656023) (xy 420.003047 -409.719026) (xy 419.972019 -409.778749)
			(xy 419.934077 -409.834336) (xy 419.912292 -409.859988) (xy 419.906475 -409.867118) (xy 419.899973 -409.88432)
			(xy 419.899592 -409.893516) (xy 419.899592 -410.051504) (xy 419.899181 -410.061659) (xy 419.891383 -410.080413)
			(xy 419.876983 -410.094737) (xy 419.858187 -410.102435) (xy 419.84803 -410.102812) (xy 419.13175 -410.102812)
			(xy 419.121633 -410.102234) (xy 419.102923 -410.094532) (xy 419.088567 -410.080274) (xy 419.080736 -410.061618)
			(xy 419.080188 -410.051504) (xy 419.080188 -409.893516) (xy 419.079773 -409.884329) (xy 419.073263 -409.867145)
			(xy 419.067488 -409.859988) (xy 419.045663 -409.834366) (xy 419.007713 -409.778776) (xy 418.976678 -409.719049)
			(xy 418.953005 -409.65604) (xy 418.937033 -409.590654) (xy 418.928991 -409.523827) (xy 414.525968 -409.523827)
			(xy 414.525968 -410.623701) (xy 421.128637 -410.623701) (xy 421.128638 -410.556275) (xy 421.136716 -410.489335)
			(xy 421.152755 -410.423845) (xy 421.176522 -410.360747) (xy 421.207677 -410.300951) (xy 421.24577 -410.245317)
			(xy 421.267636 -410.219652) (xy 421.27344 -410.212512) (xy 421.279949 -410.195317) (xy 421.280336 -410.186124)
			(xy 421.280336 -409.693872) (xy 421.279931 -409.684684) (xy 421.273413 -409.667501) (xy 421.267636 -409.660344)
			(xy 421.245783 -409.63467) (xy 421.207691 -409.579037) (xy 421.176538 -409.519243) (xy 421.152771 -409.456147)
			(xy 421.136734 -409.390659) (xy 421.128657 -409.323721) (xy 421.128656 -409.256297) (xy 421.136731 -409.189359)
			(xy 421.152766 -409.12387) (xy 421.176531 -409.060774) (xy 421.207682 -409.000978) (xy 421.245771 -408.945345)
			(xy 421.267636 -408.91968) (xy 421.273428 -408.912532) (xy 421.279945 -408.895343) (xy 421.280336 -408.886152)
			(xy 421.280336 -408.728672) (xy 421.280694 -408.718543) (xy 421.288458 -408.699832) (xy 421.302793 -408.685517)
			(xy 421.321515 -408.67778) (xy 421.331644 -408.677364) (xy 422.047924 -408.677364) (xy 422.05803 -408.677864)
			(xy 422.076702 -408.685603) (xy 422.090994 -408.699895) (xy 422.098735 -408.718566) (xy 422.099232 -408.728672)
			(xy 422.099232 -408.886152) (xy 422.09968 -408.895335) (xy 422.106169 -408.912519) (xy 422.111932 -408.91968)
			(xy 422.133807 -408.945336) (xy 422.171893 -409.000973) (xy 422.203041 -409.06077) (xy 422.226803 -409.123868)
			(xy 422.242837 -409.189358) (xy 422.250911 -409.256297) (xy 422.25091 -409.323721) (xy 422.242834 -409.39066)
			(xy 422.226798 -409.456149) (xy 422.203034 -409.519246) (xy 422.200617 -409.523886) (xy 423.328784 -409.523886)
			(xy 423.328787 -409.45646) (xy 423.336866 -409.389519) (xy 423.352905 -409.324029) (xy 423.376672 -409.26093)
			(xy 423.407826 -409.201133) (xy 423.445918 -409.145498) (xy 423.467784 -409.119832) (xy 423.47359 -409.112693)
			(xy 423.4801 -409.095498) (xy 423.480484 -409.086304) (xy 423.480484 -408.594052) (xy 423.480052 -408.584867)
			(xy 423.473554 -408.567682) (xy 423.467784 -408.560524) (xy 423.445913 -408.534865) (xy 423.407825 -408.479229)
			(xy 423.376676 -408.419432) (xy 423.352913 -408.356334) (xy 423.336878 -408.290845) (xy 423.328803 -408.223906)
			(xy 423.328804 -408.156482) (xy 423.336881 -408.089543) (xy 423.352916 -408.024054) (xy 423.376681 -407.960957)
			(xy 423.407832 -407.901161) (xy 423.44592 -407.845526) (xy 423.467784 -407.81986) (xy 423.473578 -407.812713)
			(xy 423.480095 -407.795524) (xy 423.480484 -407.786332) (xy 423.480484 -407.628852) (xy 423.480946 -407.618742)
			(xy 423.488696 -407.600066) (xy 423.503 -407.585774) (xy 423.521682 -407.578038) (xy 423.531792 -407.577544)
			(xy 424.248072 -407.577544) (xy 424.258172 -407.578106) (xy 424.276839 -407.585825) (xy 424.291133 -407.600097)
			(xy 424.298879 -407.618753) (xy 424.29938 -407.628852) (xy 424.29938 -407.786332) (xy 424.299779 -407.79552)
			(xy 424.306301 -407.812704) (xy 424.31208 -407.81986) (xy 424.333937 -407.845531) (xy 424.372027 -407.901165)
			(xy 424.403179 -407.96096) (xy 424.426945 -408.024056) (xy 424.442981 -408.089544) (xy 424.451058 -408.156482)
			(xy 424.451059 -408.223906) (xy 424.442984 -408.290844) (xy 424.426948 -408.356333) (xy 424.403184 -408.419429)
			(xy 424.372033 -408.479225) (xy 424.333944 -408.534859) (xy 424.31208 -408.560524) (xy 424.306288 -408.567673)
			(xy 424.299771 -408.584861) (xy 424.29938 -408.594052) (xy 424.29938 -409.086304) (xy 424.299792 -409.095491)
			(xy 424.306305 -409.112675) (xy 424.31208 -409.119832) (xy 424.333909 -409.145526) (xy 424.372 -409.201156)
			(xy 424.403154 -409.260948) (xy 424.426921 -409.324041) (xy 424.442959 -409.389527) (xy 424.451039 -409.456462)
			(xy 424.451042 -409.523884) (xy 424.442969 -409.59082) (xy 424.426937 -409.656307) (xy 424.403176 -409.719403)
			(xy 424.372028 -409.779198) (xy 424.333943 -409.834831) (xy 424.31208 -409.860496) (xy 424.3063 -409.867653)
			(xy 424.299776 -409.884835) (xy 424.29938 -409.894024) (xy 424.29938 -410.051504) (xy 424.298987 -410.061629)
			(xy 424.291234 -410.080337) (xy 424.27691 -410.094651) (xy 424.258197 -410.102393) (xy 424.248072 -410.102812)
			(xy 423.531792 -410.102812) (xy 423.521684 -410.102322) (xy 423.503008 -410.094584) (xy 423.488714 -410.080288)
			(xy 423.480978 -410.061612) (xy 423.480484 -410.051504) (xy 423.480484 -409.894024) (xy 423.480066 -409.884838)
			(xy 423.473558 -409.867653) (xy 423.467784 -409.860496) (xy 423.445885 -409.83486) (xy 423.407799 -409.779221)
			(xy 423.37665 -409.71942) (xy 423.352889 -409.65632) (xy 423.336856 -409.590827) (xy 423.328784 -409.523886)
			(xy 422.200617 -409.523886) (xy 422.171884 -409.579043) (xy 422.133796 -409.634678) (xy 422.111932 -409.660344)
			(xy 422.106126 -409.667482) (xy 422.099619 -409.684678) (xy 422.099232 -409.693872) (xy 422.099232 -410.186124)
			(xy 422.099646 -410.19531) (xy 422.106159 -410.212494) (xy 422.111932 -410.219652) (xy 422.133779 -410.245331)
			(xy 422.171866 -410.300964) (xy 422.203016 -410.360759) (xy 422.22678 -410.423854) (xy 422.242815 -410.489341)
			(xy 422.250892 -410.556277) (xy 422.250893 -410.623641) (xy 425.528957 -410.623641) (xy 425.528958 -410.556335)
			(xy 425.537003 -410.489512) (xy 425.552978 -410.424129) (xy 425.576652 -410.361123) (xy 425.607686 -410.301399)
			(xy 425.645636 -410.245812) (xy 425.667424 -410.22016) (xy 425.673223 -410.213017) (xy 425.679735 -410.195825)
			(xy 425.680124 -410.186632) (xy 425.680124 -409.693364) (xy 425.679726 -409.684176) (xy 425.673203 -409.666992)
			(xy 425.667424 -409.659836) (xy 425.645648 -409.634174) (xy 425.6077 -409.578589) (xy 425.576667 -409.518866)
			(xy 425.552994 -409.455863) (xy 425.537021 -409.390482) (xy 425.528976 -409.323661) (xy 425.528975 -409.256357)
			(xy 425.537018 -409.189536) (xy 425.552989 -409.124154) (xy 425.57666 -409.06115) (xy 425.607691 -409.001427)
			(xy 425.645637 -408.94584) (xy 425.667424 -408.920188) (xy 425.673211 -408.913036) (xy 425.679731 -408.895851)
			(xy 425.680124 -408.88666) (xy 425.680124 -408.728672) (xy 425.680499 -408.718513) (xy 425.688308 -408.699755)
			(xy 425.70272 -408.685432) (xy 425.721525 -408.677738) (xy 425.731686 -408.677364) (xy 426.447966 -408.677364)
			(xy 426.458093 -408.677855) (xy 426.476818 -408.685576) (xy 426.491177 -408.699862) (xy 426.498993 -408.718547)
			(xy 426.499528 -408.728672) (xy 426.499528 -408.88666) (xy 426.499951 -408.895846) (xy 426.506455 -408.913031)
			(xy 426.512228 -408.920188) (xy 426.534028 -408.94583) (xy 426.571979 -409.001417) (xy 426.603014 -409.061142)
			(xy 426.626687 -409.124148) (xy 426.64266 -409.189532) (xy 426.650704 -409.256356) (xy 426.650703 -409.323662)
			(xy 426.642657 -409.390486) (xy 426.626682 -409.45587) (xy 426.603006 -409.518875) (xy 426.600433 -409.523827)
			(xy 427.729079 -409.523827) (xy 427.729082 -409.456519) (xy 427.73713 -409.389693) (xy 427.753108 -409.324308)
			(xy 427.776786 -409.261302) (xy 427.807826 -409.201578) (xy 427.845781 -409.145992) (xy 427.867572 -409.12034)
			(xy 427.873385 -409.113207) (xy 427.879888 -409.096007) (xy 427.880272 -409.086812) (xy 427.880272 -408.593544)
			(xy 427.879847 -408.584358) (xy 427.873344 -408.567174) (xy 427.867572 -408.560016) (xy 427.845776 -408.534371)
			(xy 427.807825 -408.478784) (xy 427.77679 -408.41906) (xy 427.753116 -408.356054) (xy 427.737143 -408.290671)
			(xy 427.729099 -408.223847) (xy 427.7291 -408.156541) (xy 427.737145 -408.089717) (xy 427.75312 -408.024334)
			(xy 427.776795 -407.961329) (xy 427.807831 -407.901606) (xy 427.845783 -407.84602) (xy 427.867572 -407.820368)
			(xy 427.873373 -407.813227) (xy 427.879883 -407.796033) (xy 427.880272 -407.78684) (xy 427.880272 -407.628852)
			(xy 427.880682 -407.618698) (xy 427.888488 -407.59995) (xy 427.902887 -407.58563) (xy 427.921678 -407.577927)
			(xy 427.931834 -407.577544) (xy 428.648114 -407.577544) (xy 428.658242 -407.578015) (xy 428.676964 -407.585749)
			(xy 428.69132 -407.600039) (xy 428.699138 -407.618726) (xy 428.699676 -407.628852) (xy 428.699676 -407.78684)
			(xy 428.700072 -407.796029) (xy 428.706596 -407.813212) (xy 428.712376 -407.820368) (xy 428.734155 -407.846027)
			(xy 428.772104 -407.901613) (xy 428.803136 -407.961335) (xy 428.826809 -408.024339) (xy 428.842782 -408.08972)
			(xy 428.850827 -408.156542) (xy 428.850827 -408.223846) (xy 428.842784 -408.290668) (xy 428.826813 -408.356049)
			(xy 428.803141 -408.419054) (xy 428.77211 -408.478777) (xy 428.734163 -408.534364) (xy 428.712376 -408.560016)
			(xy 428.706587 -408.567167) (xy 428.700069 -408.584353) (xy 428.699676 -408.593544) (xy 428.699676 -409.086812)
			(xy 428.700086 -409.095999) (xy 428.7066 -409.113183) (xy 428.712376 -409.12034) (xy 428.734128 -409.146022)
			(xy 428.772077 -409.201604) (xy 428.803111 -409.261324) (xy 428.826785 -409.324324) (xy 428.84276 -409.389703)
			(xy 428.850806 -409.456522) (xy 428.85081 -409.523824) (xy 428.842769 -409.590644) (xy 428.826801 -409.656024)
			(xy 428.803133 -409.719027) (xy 428.772104 -409.778749) (xy 428.734161 -409.834335) (xy 428.712376 -409.859988)
			(xy 428.706557 -409.867117) (xy 428.700056 -409.88432) (xy 428.699676 -409.893516) (xy 428.699676 -410.051504)
			(xy 428.699281 -410.061661) (xy 428.69148 -410.080418) (xy 428.677074 -410.094742) (xy 428.658274 -410.102438)
			(xy 428.648114 -410.102812) (xy 427.931834 -410.102812) (xy 427.921716 -410.102247) (xy 427.903005 -410.09454)
			(xy 427.88865 -410.080278) (xy 427.88082 -410.061619) (xy 427.880272 -410.051504) (xy 427.880272 -409.893516)
			(xy 427.879861 -409.884329) (xy 427.873349 -409.867144) (xy 427.867572 -409.859988) (xy 427.845748 -409.834366)
			(xy 427.807798 -409.778776) (xy 427.776764 -409.719048) (xy 427.753092 -409.65604) (xy 427.73712 -409.590654)
			(xy 427.729079 -409.523827) (xy 426.600433 -409.523827) (xy 426.57197 -409.578598) (xy 426.534017 -409.634184)
			(xy 426.512228 -409.659836) (xy 426.506425 -409.666976) (xy 426.499916 -409.684171) (xy 426.499528 -409.693364)
			(xy 426.499528 -410.186632) (xy 426.499917 -410.195822) (xy 426.506445 -410.213006) (xy 426.512228 -410.22016)
			(xy 426.534001 -410.245825) (xy 426.571952 -410.301409) (xy 426.602988 -410.36113) (xy 426.626663 -410.424133)
			(xy 426.642638 -410.489514) (xy 426.650684 -410.556336) (xy 426.650686 -410.62364) (xy 426.650679 -410.623701)
			(xy 429.928725 -410.623701) (xy 429.928726 -410.556275) (xy 429.936804 -410.489336) (xy 429.952842 -410.423845)
			(xy 429.976609 -410.360748) (xy 430.007762 -410.300951) (xy 430.045854 -410.245317) (xy 430.06772 -410.219652)
			(xy 430.073522 -410.212511) (xy 430.080033 -410.195317) (xy 430.08042 -410.186124) (xy 430.08042 -409.693872)
			(xy 430.080019 -409.684684) (xy 430.073498 -409.6675) (xy 430.06772 -409.660344) (xy 430.045867 -409.634669)
			(xy 430.007777 -409.579037) (xy 429.976624 -409.519242) (xy 429.952859 -409.456146) (xy 429.936822 -409.390658)
			(xy 429.928745 -409.323721) (xy 429.928744 -409.256297) (xy 429.936819 -409.18936) (xy 429.952853 -409.123871)
			(xy 429.976617 -409.060775) (xy 430.007767 -409.000979) (xy 430.045856 -408.945345) (xy 430.06772 -408.91968)
			(xy 430.07351 -408.91253) (xy 430.080028 -408.895343) (xy 430.08042 -408.886152) (xy 430.08042 -408.728672)
			(xy 430.080863 -408.718559) (xy 430.088613 -408.699876) (xy 430.102923 -408.685582) (xy 430.121614 -408.677852)
			(xy 430.131728 -408.677364) (xy 430.848008 -408.677364) (xy 430.858113 -408.677878) (xy 430.876784 -408.685611)
			(xy 430.891077 -408.699899) (xy 430.898818 -408.718567) (xy 430.899316 -408.728672) (xy 430.899316 -408.886152)
			(xy 430.899745 -408.895337) (xy 430.906245 -408.912522) (xy 430.912016 -408.91968) (xy 430.933891 -408.945336)
			(xy 430.971979 -409.000972) (xy 431.003128 -409.06077) (xy 431.026891 -409.123868) (xy 431.042925 -409.189358)
			(xy 431.050999 -409.256297) (xy 431.050998 -409.323721) (xy 431.042922 -409.39066) (xy 431.026885 -409.456149)
			(xy 431.00312 -409.519247) (xy 431.000734 -409.523827) (xy 432.12887 -409.523827) (xy 432.128873 -409.456519)
			(xy 432.136921 -409.389693) (xy 432.152898 -409.324309) (xy 432.176576 -409.261303) (xy 432.207615 -409.201578)
			(xy 432.245569 -409.145992) (xy 432.26736 -409.12034) (xy 432.273172 -409.113206) (xy 432.279676 -409.096007)
			(xy 432.28006 -409.086812) (xy 432.28006 -408.593544) (xy 432.279615 -408.584361) (xy 432.273124 -408.567177)
			(xy 432.26736 -408.560016) (xy 432.245564 -408.53437) (xy 432.207614 -408.478784) (xy 432.17658 -408.419059)
			(xy 432.152907 -408.356054) (xy 432.136934 -408.290671) (xy 432.12889 -408.223847) (xy 432.128891 -408.156541)
			(xy 432.136936 -408.089717) (xy 432.15291 -408.024335) (xy 432.176585 -407.96133) (xy 432.20762 -407.901606)
			(xy 432.245571 -407.84602) (xy 432.26736 -407.820368) (xy 432.27316 -407.813226) (xy 432.279671 -407.796033)
			(xy 432.28006 -407.78684) (xy 432.28006 -407.628852) (xy 432.280482 -407.6187) (xy 432.288286 -407.599954)
			(xy 432.302681 -407.585634) (xy 432.321468 -407.577929) (xy 432.331622 -407.577544) (xy 433.047902 -407.577544)
			(xy 433.058029 -407.578025) (xy 433.076751 -407.585754) (xy 433.091108 -407.600042) (xy 433.098926 -407.618727)
			(xy 433.099464 -407.628852) (xy 433.099464 -407.78684) (xy 433.099863 -407.796028) (xy 433.106385 -407.813212)
			(xy 433.112164 -407.820368) (xy 433.133944 -407.846027) (xy 433.171893 -407.901612) (xy 433.202926 -407.961335)
			(xy 433.226599 -408.024339) (xy 433.242573 -408.08972) (xy 433.250618 -408.156542) (xy 433.250618 -408.223846)
			(xy 433.242575 -408.290668) (xy 433.226603 -408.35605) (xy 433.202931 -408.419054) (xy 433.171899 -408.478778)
			(xy 433.133951 -408.534364) (xy 433.112164 -408.560016) (xy 433.106374 -408.567165) (xy 433.099856 -408.584353)
			(xy 433.099464 -408.593544) (xy 433.099464 -409.086812) (xy 433.099876 -409.095999) (xy 433.106389 -409.113183)
			(xy 433.112164 -409.12034) (xy 433.133916 -409.146021) (xy 433.171866 -409.201604) (xy 433.2029 -409.261323)
			(xy 433.226575 -409.324324) (xy 433.24255 -409.389703) (xy 433.250597 -409.456522) (xy 433.250601 -409.523824)
			(xy 433.24256 -409.590644) (xy 433.226591 -409.656024) (xy 433.202922 -409.719027) (xy 433.171894 -409.77875)
			(xy 433.133949 -409.834336) (xy 433.112164 -409.859988) (xy 433.106343 -409.867116) (xy 433.099844 -409.88432)
			(xy 433.099464 -409.893516) (xy 433.099464 -410.051504) (xy 433.099081 -410.061663) (xy 433.091277 -410.080422)
			(xy 433.076868 -410.094747) (xy 433.058063 -410.10244) (xy 433.047902 -410.102812) (xy 432.331622 -410.102812)
			(xy 432.321503 -410.102257) (xy 432.302792 -410.094546) (xy 432.288437 -410.080281) (xy 432.280608 -410.06162)
			(xy 432.28006 -410.051504) (xy 432.28006 -409.893516) (xy 432.279629 -409.884331) (xy 432.273128 -409.867147)
			(xy 432.26736 -409.859988) (xy 432.245536 -409.834365) (xy 432.207587 -409.778775) (xy 432.176554 -409.719048)
			(xy 432.152882 -409.656039) (xy 432.136911 -409.590653) (xy 432.12887 -409.523827) (xy 431.000734 -409.523827)
			(xy 430.971969 -409.579043) (xy 430.93388 -409.634678) (xy 430.912016 -409.660344) (xy 430.90622 -409.66749)
			(xy 430.899705 -409.68468) (xy 430.899316 -409.693872) (xy 430.899316 -410.186124) (xy 430.899711 -410.195313)
			(xy 430.906235 -410.212497) (xy 430.912016 -410.219652) (xy 430.933864 -410.24533) (xy 430.971952 -410.300963)
			(xy 431.003102 -410.360758) (xy 431.026867 -410.423853) (xy 431.042903 -410.48934) (xy 431.05098 -410.556277)
			(xy 431.050981 -410.623641) (xy 434.329044 -410.623641) (xy 434.329046 -410.556335) (xy 434.337091 -410.489512)
			(xy 434.353065 -410.424129) (xy 434.376738 -410.361124) (xy 434.407772 -410.3014) (xy 434.44572 -410.245813)
			(xy 434.467508 -410.22016) (xy 434.473305 -410.213015) (xy 434.479819 -410.195824) (xy 434.480208 -410.186632)
			(xy 434.480208 -409.693364) (xy 434.479814 -409.684175) (xy 434.473289 -409.666991) (xy 434.467508 -409.659836)
			(xy 434.445733 -409.634174) (xy 434.407786 -409.578588) (xy 434.376754 -409.518866) (xy 434.353082 -409.455862)
			(xy 434.337109 -409.390482) (xy 434.329064 -409.323661) (xy 434.329063 -409.256357) (xy 434.337106 -409.189536)
			(xy 434.353076 -409.124155) (xy 434.376746 -409.061151) (xy 434.407777 -409.001427) (xy 434.445722 -408.945841)
			(xy 434.467508 -408.920188) (xy 434.473293 -408.913035) (xy 434.479814 -408.89585) (xy 434.480208 -408.88666)
			(xy 434.480208 -408.728672) (xy 434.480599 -408.718515) (xy 434.488405 -408.69976) (xy 434.502811 -408.685438)
			(xy 434.521611 -408.67774) (xy 434.53177 -408.677364) (xy 435.24805 -408.677364) (xy 435.258176 -408.677868)
			(xy 435.276901 -408.685584) (xy 435.29126 -408.699866) (xy 435.299077 -408.718548) (xy 435.299612 -408.728672)
			(xy 435.299612 -408.88666) (xy 435.300039 -408.895846) (xy 435.30654 -408.91303) (xy 435.312312 -408.920188)
			(xy 435.334113 -408.94583) (xy 435.372065 -409.001417) (xy 435.4031 -409.061141) (xy 435.426774 -409.124147)
			(xy 435.442748 -409.189531) (xy 435.450792 -409.256356) (xy 435.450791 -409.323662) (xy 435.442745 -409.390487)
			(xy 435.426769 -409.45587) (xy 435.403093 -409.518875) (xy 435.372055 -409.578599) (xy 435.334102 -409.634184)
			(xy 435.312312 -409.659836) (xy 435.306519 -409.666984) (xy 435.300002 -409.684172) (xy 435.299612 -409.693364)
			(xy 435.299612 -410.186632) (xy 435.300004 -410.195821) (xy 435.30653 -410.213006) (xy 435.312312 -410.22016)
			(xy 435.334085 -410.245824) (xy 435.372038 -410.301408) (xy 435.403075 -410.361129) (xy 435.42675 -410.424132)
			(xy 435.442726 -410.489514) (xy 435.450772 -410.556336) (xy 435.450774 -410.62364) (xy 435.44273 -410.690463)
			(xy 435.426758 -410.755845) (xy 435.403084 -410.818849) (xy 435.37205 -410.878571) (xy 435.3341 -410.934157)
			(xy 435.312312 -410.959808) (xy 435.306531 -410.966964) (xy 435.300007 -410.984146) (xy 435.299612 -410.993336)
			(xy 435.299612 -411.151324) (xy 435.299198 -411.161478) (xy 435.291397 -411.180229) (xy 435.276998 -411.194551)
			(xy 435.258206 -411.202252) (xy 435.24805 -411.202632) (xy 434.53177 -411.202632) (xy 434.521638 -411.202197)
			(xy 434.502911 -411.194454) (xy 434.488554 -411.180152) (xy 434.480741 -411.161454) (xy 434.480208 -411.151324)
			(xy 434.480208 -410.993336) (xy 434.479779 -410.984151) (xy 434.473278 -410.966966) (xy 434.467508 -410.959808)
			(xy 434.445706 -410.934168) (xy 434.407759 -410.878579) (xy 434.376728 -410.818854) (xy 434.353058 -410.755848)
			(xy 434.337087 -410.690464) (xy 434.329044 -410.623641) (xy 431.050981 -410.623641) (xy 431.050981 -410.623699)
			(xy 431.042907 -410.690636) (xy 431.026874 -410.756124) (xy 431.003112 -410.81922) (xy 430.971964 -410.879016)
			(xy 430.933878 -410.934651) (xy 430.912016 -410.960316) (xy 430.906232 -410.96747) (xy 430.899709 -410.984654)
			(xy 430.899316 -410.993844) (xy 430.899316 -411.151324) (xy 430.898835 -411.161432) (xy 430.891092 -411.180108)
			(xy 430.876795 -411.194401) (xy 430.858116 -411.202138) (xy 430.848008 -411.202632) (xy 430.131728 -411.202632)
			(xy 430.121611 -411.202162) (xy 430.102914 -411.194429) (xy 430.0886 -411.180129) (xy 430.080848 -411.16144)
			(xy 430.08042 -411.151324) (xy 430.08042 -410.993844) (xy 430.079984 -410.98466) (xy 430.073488 -410.967475)
			(xy 430.06772 -410.960316) (xy 430.04584 -410.934664) (xy 430.00775 -410.879028) (xy 429.976599 -410.81923)
			(xy 429.952835 -410.756132) (xy 429.9368 -410.690641) (xy 429.928725 -410.623701) (xy 426.650679 -410.623701)
			(xy 426.642643 -410.690462) (xy 426.62667 -410.755844) (xy 426.602998 -410.818848) (xy 426.571965 -410.878571)
			(xy 426.534016 -410.934156) (xy 426.512228 -410.959808) (xy 426.506437 -410.966957) (xy 426.499921 -410.984145)
			(xy 426.499528 -410.993336) (xy 426.499528 -411.151324) (xy 426.499099 -411.161476) (xy 426.4913 -411.180224)
			(xy 426.476907 -411.194545) (xy 426.45812 -411.202249) (xy 426.447966 -411.202632) (xy 425.731686 -411.202632)
			(xy 425.721555 -411.202184) (xy 425.702828 -411.194446) (xy 425.688472 -411.180148) (xy 425.680658 -411.161453)
			(xy 425.680124 -411.151324) (xy 425.680124 -410.993336) (xy 425.679691 -410.984151) (xy 425.673193 -410.966967)
			(xy 425.667424 -410.959808) (xy 425.645621 -410.934169) (xy 425.607674 -410.87858) (xy 425.576642 -410.818855)
			(xy 425.552971 -410.755848) (xy 425.536999 -410.690465) (xy 425.528957 -410.623641) (xy 422.250893 -410.623641)
			(xy 422.250893 -410.623699) (xy 422.242819 -410.690635) (xy 422.226787 -410.756123) (xy 422.203026 -410.819219)
			(xy 422.171879 -410.879015) (xy 422.133794 -410.93465) (xy 422.111932 -410.960316) (xy 422.106138 -410.967463)
			(xy 422.099624 -410.984652) (xy 422.099232 -410.993844) (xy 422.099232 -411.151324) (xy 422.098735 -411.16143)
			(xy 422.090996 -411.180103) (xy 422.076703 -411.194396) (xy 422.05803 -411.202135) (xy 422.047924 -411.202632)
			(xy 421.331644 -411.202632) (xy 421.321528 -411.202149) (xy 421.302832 -411.194421) (xy 421.288517 -411.180125)
			(xy 421.280765 -411.161439) (xy 421.280336 -411.151324) (xy 421.280336 -410.993844) (xy 421.279896 -410.98466)
			(xy 421.273402 -410.967476) (xy 421.267636 -410.960316) (xy 421.245755 -410.934664) (xy 421.207664 -410.879029)
			(xy 421.176512 -410.819231) (xy 421.152748 -410.756132) (xy 421.136712 -410.690641) (xy 421.128637 -410.623701)
			(xy 414.525968 -410.623701) (xy 414.525968 -413.241998) (xy 446.308988 -413.241998) (xy 446.308988 -406.984454)
			(xy 446.309436 -406.960332) (xy 446.317032 -406.912688) (xy 446.331997 -406.866822) (xy 446.353963 -406.823866)
			(xy 446.382386 -406.784882) (xy 446.399158 -406.767538) (xy 446.446148 -406.720548) (xy 446.463578 -406.703857)
			(xy 446.502642 -406.675527) (xy 446.545645 -406.653634) (xy 446.591535 -406.638713) (xy 446.639191 -406.63113)
			(xy 446.663318 -406.630632) (xy 450.76237 -406.630632) (xy 450.786466 -406.631106) (xy 450.834068 -406.638628)
			(xy 450.879911 -406.653491) (xy 450.92287 -406.675331) (xy 450.961891 -406.703613) (xy 450.979286 -406.720294)
			(xy 451.026276 -406.767284) (xy 451.043027 -406.784633) (xy 451.071395 -406.823632) (xy 451.093303 -406.866593)
			(xy 451.108211 -406.912456) (xy 451.11575 -406.960088) (xy 451.116192 -406.9842) (xy 451.116192 -413.520382)
			(xy 451.115176 -413.521652) (xy 451.097784 -413.538387) (xy 451.05872 -413.566731) (xy 451.015709 -413.588626)
			(xy 450.969806 -413.603534) (xy 450.922138 -413.611089) (xy 450.898006 -413.611568) (xy 446.678304 -413.611568)
			(xy 446.654196 -413.611118) (xy 446.606578 -413.603539) (xy 446.560729 -413.588615) (xy 446.517775 -413.566711)
			(xy 446.47877 -413.538365) (xy 446.461388 -413.521652) (xy 446.399158 -413.459422) (xy 446.382389 -413.44201)
			(xy 446.353942 -413.402929) (xy 446.331969 -413.359874) (xy 446.317011 -413.313908) (xy 446.309439 -413.266167)
			(xy 446.308988 -413.241998) (xy 414.525968 -413.241998) (xy 414.525968 -417.366196) (xy 414.52546 -417.366196)
			(xy 414.52546 -417.533836) (xy 414.525117 -417.545925) (xy 414.517634 -417.568917) (xy 414.503411 -417.588471)
			(xy 414.483842 -417.602672) (xy 414.460842 -417.61013) (xy 414.448752 -417.610544) (xy 401.15109 -417.610544)
			(xy 401.138998 -417.610101) (xy 401.115995 -417.602639) (xy 401.096414 -417.588447) (xy 401.082164 -417.568908)
			(xy 401.074635 -417.545926) (xy 401.074128 -417.533836) (xy 326.525636 -417.533836) (xy 326.525172 -417.545885)
			(xy 326.517733 -417.568805) (xy 326.503592 -417.588317) (xy 326.484126 -417.602521) (xy 326.461229 -417.610032)
			(xy 326.449182 -417.610544) (xy 313.151012 -417.610544) (xy 313.138942 -417.610026) (xy 313.115981 -417.602571)
			(xy 313.096447 -417.588387) (xy 313.082251 -417.568862) (xy 313.074781 -417.545906) (xy 313.074304 -417.533836)
			(xy 313.074304 -417.379404) (xy 313.073796 -417.379404) (xy 273.436768 -417.379404) (xy 273.507194 -417.441568)
			(xy 273.606535 -417.539604) (xy 273.653758 -417.590986) (xy 273.692133 -417.632558) (xy 273.77424 -417.71041)
			(xy 273.862012 -417.781815) (xy 273.954943 -417.846362) (xy 274.052499 -417.90368) (xy 274.154119 -417.95344)
			(xy 274.259218 -417.995354) (xy 274.367191 -418.029182) (xy 274.477417 -418.05473) (xy 274.589263 -418.07185)
			(xy 274.702084 -418.080444) (xy 274.758658 -418.080952) (xy 465.600034 -418.080952) (xy 465.655802 -418.080429)
			(xy 465.767025 -418.072092) (xy 465.877315 -418.055466) (xy 465.986054 -418.030644) (xy 466.092633 -417.997766)
			(xy 466.196458 -417.957015) (xy 466.296947 -417.90862) (xy 466.393539 -417.85285) (xy 466.485692 -417.790018)
			(xy 466.572893 -417.720474) (xy 466.654653 -417.644609) (xy 466.730515 -417.562846) (xy 466.800054 -417.475643)
			(xy 466.862883 -417.383486) (xy 466.918649 -417.286892) (xy 466.96704 -417.186401) (xy 467.007787 -417.082575)
			(xy 467.04066 -416.975994) (xy 467.065477 -416.867254) (xy 467.082099 -416.756964) (xy 467.090432 -416.64574)
			(xy 467.091014 -416.589972) (xy 467.09203 -388.238238) (xy 467.09203 -246.488458) (xy 467.091578 -246.436469)
			(xy 467.084337 -246.332743) (xy 467.069893 -246.229773) (xy 467.048316 -246.128058) (xy 467.019711 -246.028092)
			(xy 466.984216 -245.930359) (xy 466.942005 -245.835335) (xy 466.91804 -245.789196) (xy 466.891385 -245.740526)
			(xy 466.831932 -245.646816) (xy 466.765775 -245.557714) (xy 466.693268 -245.473697) (xy 466.654388 -245.434104)
			(xy 464.025996 -242.805712) (xy 463.976572 -242.755595) (xy 463.882762 -242.650635) (xy 463.794985 -242.54058)
			(xy 463.713516 -242.425777) (xy 463.638613 -242.306586) (xy 463.57051 -242.183384) (xy 463.509422 -242.056557)
			(xy 463.455541 -241.926504) (xy 463.409037 -241.793634) (xy 463.370056 -241.658367) (xy 463.33872 -241.521126)
			(xy 463.315128 -241.382345) (xy 463.299355 -241.242459) (xy 463.291449 -241.101908) (xy 463.29092 -241.031522)
			(xy 463.29092 -87.588344) (xy 463.291412 -87.517965) (xy 463.29932 -87.377431) (xy 463.315095 -87.23756)
			(xy 463.33869 -87.098795) (xy 463.370029 -86.961571) (xy 463.409014 -86.82632) (xy 463.455522 -86.693468)
			(xy 463.509407 -86.563433) (xy 463.570498 -86.436625) (xy 463.638605 -86.313442) (xy 463.713512 -86.194272)
			(xy 463.794985 -86.07949) (xy 463.882765 -85.969457) (xy 463.976578 -85.86452) (xy 464.025996 -85.814408)
			(xy 466.654388 -83.185762) (xy 466.691681 -83.1478) (xy 466.76138 -83.067371) (xy 466.825166 -82.982176)
			(xy 466.882712 -82.892649) (xy 466.933726 -82.799245) (xy 466.977949 -82.70244) (xy 467.015155 -82.602728)
			(xy 467.045154 -82.500617) (xy 467.067793 -82.396625) (xy 467.082959 -82.291284) (xy 467.090572 -82.18513)
			(xy 467.091014 -82.131916) (xy 467.091014 -1.999996) (xy 467.090492 -1.944227) (xy 467.082157 -1.833)
			(xy 467.065533 -1.722707) (xy 467.040713 -1.613964) (xy 467.007837 -1.507381) (xy 466.967088 -1.403552)
			(xy 466.918693 -1.303059) (xy 466.862924 -1.206463) (xy 466.800093 -1.114305) (xy 466.73055 -1.0271)
			(xy 466.654685 -0.945336) (xy 466.572923 -0.869469) (xy 466.485719 -0.799925) (xy 466.393562 -0.737092)
			(xy 466.296967 -0.681321) (xy 466.196475 -0.632924) (xy 466.092647 -0.592173) (xy 465.986065 -0.559295)
			(xy 465.877323 -0.534473) (xy 465.76703 -0.517846) (xy 465.655803 -0.509509) (xy 465.600034 -0.509016)
			(xy 446.265046 -0.509016) (xy 446.209275 -0.509523) (xy 446.098046 -0.517855) (xy 445.98775 -0.534476)
			(xy 445.879004 -0.559294) (xy 445.772418 -0.592168) (xy 445.668586 -0.632916) (xy 445.568089 -0.68131)
			(xy 445.471491 -0.737079) (xy 445.37933 -0.79991) (xy 445.292122 -0.869454) (xy 445.210355 -0.945319)
			(xy 445.134486 -1.027084) (xy 445.06494 -1.114289) (xy 445.002105 -1.206448) (xy 444.946333 -1.303045)
			(xy 444.897936 -1.40354) (xy 444.857185 -1.50737) (xy 444.824307 -1.613956) (xy 444.799486 -1.722701)
			(xy 444.782861 -1.832996) (xy 444.774525 -1.944225) (xy 444.774066 -1.999996) (xy 444.774066 -11.850116)
			(xy 444.773596 -11.903993) (xy 444.765907 -12.011472) (xy 444.750571 -12.118128) (xy 444.727665 -12.223419)
			(xy 444.697306 -12.326808) (xy 444.659648 -12.427767) (xy 444.614884 -12.525782) (xy 444.563242 -12.620354)
			(xy 444.504984 -12.711001) (xy 444.440408 -12.797261) (xy 444.369843 -12.878695) (xy 444.293648 -12.954886)
			(xy 444.212211 -13.025448) (xy 444.125949 -13.09002) (xy 444.035299 -13.148274) (xy 443.940725 -13.199913)
			(xy 443.842708 -13.244673) (xy 443.741747 -13.282326) (xy 443.638357 -13.312681) (xy 443.533065 -13.335582)
			(xy 443.426408 -13.350914) (xy 443.318929 -13.358598) (xy 443.265052 -13.35913) (xy 435.265068 -13.35913)
			(xy 435.211191 -13.358648) (xy 435.103712 -13.350959) (xy 434.997055 -13.335622) (xy 434.891765 -13.312715)
			(xy 434.788376 -13.282356) (xy 434.687417 -13.244699) (xy 434.589401 -13.199935) (xy 434.494828 -13.148293)
			(xy 434.404181 -13.090036) (xy 434.31792 -13.025461) (xy 434.236485 -12.954897) (xy 434.160292 -12.878703)
			(xy 434.089729 -12.797268) (xy 434.025155 -12.711006) (xy 433.966899 -12.620358) (xy 433.915258 -12.525785)
			(xy 433.870495 -12.427769) (xy 433.832839 -12.326809) (xy 433.802481 -12.22342) (xy 433.779575 -12.118129)
			(xy 433.764239 -12.011472) (xy 433.756551 -11.903993) (xy 433.756054 -11.850116) (xy 433.756054 -1.999996)
			(xy 433.755545 -1.944227) (xy 433.74721 -1.833001) (xy 433.730585 -1.722708) (xy 433.705765 -1.613967)
			(xy 433.672888 -1.507384) (xy 433.632138 -1.403557) (xy 433.583743 -1.303065) (xy 433.527973 -1.20647)
			(xy 433.465141 -1.114314) (xy 433.395597 -1.02711) (xy 433.319731 -0.945348) (xy 433.237967 -0.869483)
			(xy 433.150762 -0.799942) (xy 433.058604 -0.737111) (xy 432.962009 -0.681343) (xy 432.861516 -0.63295)
			(xy 432.757687 -0.592202) (xy 432.651104 -0.559327) (xy 432.542362 -0.534509) (xy 432.432069 -0.517887)
			(xy 432.320843 -0.509554) (xy 432.265074 -0.509016) (xy 420.265098 -0.509016) (xy 420.209329 -0.509538)
			(xy 420.098103 -0.517873) (xy 419.987811 -0.534497) (xy 419.879069 -0.559317) (xy 419.772486 -0.592193)
			(xy 419.668658 -0.632943) (xy 419.568166 -0.681337) (xy 419.471571 -0.737106) (xy 419.379414 -0.799938)
			(xy 419.29221 -0.869481) (xy 419.210447 -0.945346) (xy 419.134582 -1.027109) (xy 419.065039 -1.114313)
			(xy 419.002207 -1.20647) (xy 418.946438 -1.303064) (xy 418.898043 -1.403557) (xy 418.857294 -1.507384)
			(xy 418.824417 -1.613967) (xy 418.799597 -1.722709) (xy 418.782973 -1.833001) (xy 418.774638 -1.944227)
			(xy 418.774118 -1.999996) (xy 418.774118 -11.850116) (xy 418.773637 -11.903993) (xy 418.765948 -12.011473)
			(xy 418.750612 -12.11813) (xy 418.727707 -12.223421) (xy 418.697348 -12.32681) (xy 418.659691 -12.42777)
			(xy 418.614928 -12.525787) (xy 418.563286 -12.62036) (xy 418.505029 -12.711008) (xy 418.440454 -12.79727)
			(xy 418.36989 -12.878704) (xy 418.293696 -12.954898) (xy 418.21226 -13.025462) (xy 418.125998 -13.090036)
			(xy 418.03535 -13.148292) (xy 417.940776 -13.199933) (xy 417.842759 -13.244696) (xy 417.741799 -13.282352)
			(xy 417.63841 -13.31271) (xy 417.533118 -13.335615) (xy 417.426461 -13.35095) (xy 417.318981 -13.358637)
			(xy 417.265104 -13.35913) (xy 409.26512 -13.35913) (xy 409.211242 -13.358661) (xy 409.103759 -13.350975)
			(xy 408.997099 -13.335641) (xy 408.891804 -13.312737) (xy 408.788412 -13.28238) (xy 408.687448 -13.244724)
			(xy 408.589429 -13.199961) (xy 408.494852 -13.14832) (xy 408.404201 -13.090063) (xy 408.317936 -13.025488)
			(xy 408.236498 -12.954923) (xy 408.160301 -12.878728) (xy 408.089735 -12.797292) (xy 408.025157 -12.711029)
			(xy 407.966898 -12.620379) (xy 407.915255 -12.525803) (xy 407.87049 -12.427785) (xy 407.832832 -12.326822)
			(xy 407.802472 -12.223431) (xy 407.779565 -12.118137) (xy 407.764229 -12.011477) (xy 407.75654 -11.903994)
			(xy 407.756106 -11.850116) (xy 407.756106 -1.999996) (xy 407.755584 -1.944227) (xy 407.747249 -1.833)
			(xy 407.730625 -1.722707) (xy 407.705805 -1.613965) (xy 407.672929 -1.507382) (xy 407.632179 -1.403554)
			(xy 407.583785 -1.303061) (xy 407.528016 -1.206465) (xy 407.465185 -1.114307) (xy 407.395642 -1.027103)
			(xy 407.319777 -0.945339) (xy 407.238014 -0.869472) (xy 407.15081 -0.799929) (xy 407.058653 -0.737096)
			(xy 406.962059 -0.681325) (xy 406.861567 -0.632929) (xy 406.757739 -0.592179) (xy 406.651156 -0.559301)
			(xy 406.542414 -0.534479) (xy 406.432122 -0.517854) (xy 406.320895 -0.509516) (xy 406.265126 -0.509016)
			(xy 394.264896 -0.509016) (xy 394.209127 -0.509538) (xy 394.097901 -0.517873) (xy 393.987609 -0.534497)
			(xy 393.878867 -0.559317) (xy 393.772285 -0.592194) (xy 393.668457 -0.632943) (xy 393.567965 -0.681338)
			(xy 393.47137 -0.737107) (xy 393.379213 -0.799938) (xy 393.292009 -0.869481) (xy 393.210246 -0.945346)
			(xy 393.134381 -1.027109) (xy 393.064838 -1.114313) (xy 393.002007 -1.20647) (xy 392.946238 -1.303065)
			(xy 392.897843 -1.403557) (xy 392.857094 -1.507385) (xy 392.824217 -1.613967) (xy 392.799397 -1.722709)
			(xy 392.782773 -1.833001) (xy 392.774438 -1.944227) (xy 392.773916 -1.999996) (xy 392.773916 -11.850116)
			(xy 392.773435 -11.903993) (xy 392.765746 -12.011473) (xy 392.75041 -12.11813) (xy 392.727505 -12.223421)
			(xy 392.697146 -12.32681) (xy 392.659489 -12.42777) (xy 392.614726 -12.525786) (xy 392.563084 -12.62036)
			(xy 392.504827 -12.711008) (xy 392.440252 -12.797269) (xy 392.369688 -12.878704) (xy 392.293494 -12.954897)
			(xy 392.212058 -13.025461) (xy 392.125796 -13.090035) (xy 392.035148 -13.148291) (xy 391.940574 -13.199932)
			(xy 391.842557 -13.244694) (xy 391.741597 -13.28235) (xy 391.638208 -13.312708) (xy 391.532916 -13.335613)
			(xy 391.426259 -13.350948) (xy 391.318779 -13.358635) (xy 391.264902 -13.35913) (xy 383.264918 -13.35913)
			(xy 383.21104 -13.358661) (xy 383.103557 -13.350975) (xy 382.996897 -13.335641) (xy 382.891603 -13.312737)
			(xy 382.78821 -13.282379) (xy 382.687247 -13.244723) (xy 382.589228 -13.199961) (xy 382.494651 -13.148319)
			(xy 382.404 -13.090063) (xy 382.317735 -13.025487) (xy 382.236297 -12.954923) (xy 382.160101 -12.878728)
			(xy 382.089534 -12.797291) (xy 382.024957 -12.711028) (xy 381.966698 -12.620378) (xy 381.915055 -12.525803)
			(xy 381.87029 -12.427784) (xy 381.832632 -12.326822) (xy 381.802272 -12.22343) (xy 381.779365 -12.118136)
			(xy 381.764029 -12.011477) (xy 381.75634 -11.903994) (xy 381.755904 -11.850116) (xy 381.755904 -1.999996)
			(xy 381.755382 -1.944227) (xy 381.747047 -1.833) (xy 381.730423 -1.722707) (xy 381.705603 -1.613965)
			(xy 381.672727 -1.507382) (xy 381.631977 -1.403554) (xy 381.583583 -1.303061) (xy 381.527814 -1.206466)
			(xy 381.464982 -1.114308) (xy 381.39544 -1.027103) (xy 381.319575 -0.945339) (xy 381.237812 -0.869473)
			(xy 381.150608 -0.799929) (xy 381.058451 -0.737097) (xy 380.961857 -0.681327) (xy 380.861364 -0.632931)
			(xy 380.757537 -0.59218) (xy 380.650954 -0.559302) (xy 380.542212 -0.534481) (xy 380.43192 -0.517855)
			(xy 380.320693 -0.509518) (xy 380.264924 -0.509016) (xy 368.264948 -0.509016) (xy 368.209177 -0.509523)
			(xy 368.097948 -0.517855) (xy 367.987651 -0.534476) (xy 367.878906 -0.559293) (xy 367.772319 -0.592168)
			(xy 367.668487 -0.632916) (xy 367.567991 -0.681309) (xy 367.471392 -0.737078) (xy 367.379231 -0.79991)
			(xy 367.292023 -0.869453) (xy 367.210256 -0.945319) (xy 367.134387 -1.027083) (xy 367.06484 -1.114289)
			(xy 367.002006 -1.206448) (xy 366.946234 -1.303045) (xy 366.897837 -1.403539) (xy 366.857085 -1.50737)
			(xy 366.824207 -1.613956) (xy 366.799386 -1.7227) (xy 366.782761 -1.832996) (xy 366.774425 -1.944225)
			(xy 366.773968 -1.999996) (xy 366.773968 -8.639556) (xy 370.714524 -8.639556) (xy 370.714524 -4.419854)
			(xy 370.715008 -4.395747) (xy 370.722578 -4.348131) (xy 370.737495 -4.302283) (xy 370.759392 -4.259328)
			(xy 370.787731 -4.220321) (xy 370.80444 -4.202938) (xy 370.86667 -4.140708) (xy 370.884055 -4.124)
			(xy 370.92306 -4.09566) (xy 370.966014 -4.073763) (xy 371.011863 -4.058847) (xy 371.059479 -4.05128)
			(xy 371.083586 -4.050792) (xy 377.341638 -4.050792) (xy 377.365749 -4.051252) (xy 377.413378 -4.058794)
			(xy 377.459237 -4.073701) (xy 377.502197 -4.095605) (xy 377.541197 -4.123967) (xy 377.558554 -4.140708)
			(xy 377.605544 -4.187698) (xy 377.622257 -4.205107) (xy 377.650585 -4.244176) (xy 377.672474 -4.287185)
			(xy 377.687389 -4.33308) (xy 377.694966 -4.380739) (xy 377.69546 -4.404868) (xy 377.69546 -8.50392)
			(xy 377.69502 -8.528018) (xy 377.68749 -8.575621) (xy 377.672619 -8.621464) (xy 377.650771 -8.664423)
			(xy 377.622483 -8.703442) (xy 377.605798 -8.720836) (xy 377.558808 -8.767826) (xy 377.541434 -8.784603)
			(xy 377.502409 -8.813052) (xy 377.459403 -8.835026) (xy 377.413483 -8.849981) (xy 377.365785 -8.857548)
			(xy 377.341638 -8.857996) (xy 370.80571 -8.857996) (xy 370.80444 -8.856726) (xy 370.787728 -8.839313)
			(xy 370.759381 -8.800255) (xy 370.737482 -8.757249) (xy 370.722569 -8.711351) (xy 370.715007 -8.663686)
			(xy 370.714524 -8.639556) (xy 366.773968 -8.639556) (xy 366.773968 -11.850116) (xy 366.773498 -11.903993)
			(xy 366.765809 -12.011472) (xy 366.750473 -12.118129) (xy 366.727567 -12.223419) (xy 366.697208 -12.326808)
			(xy 366.65955 -12.427767) (xy 366.614786 -12.525783) (xy 366.563144 -12.620355) (xy 366.504886 -12.711002)
			(xy 366.44031 -12.797262) (xy 366.369745 -12.878695) (xy 366.29355 -12.954887) (xy 366.212114 -13.025449)
			(xy 366.125851 -13.090021) (xy 366.035201 -13.148275) (xy 365.940627 -13.199914) (xy 365.84261 -13.244674)
			(xy 365.741649 -13.282327) (xy 365.638259 -13.312682) (xy 365.532968 -13.335584) (xy 365.42631 -13.350916)
			(xy 365.318831 -13.3586) (xy 365.264954 -13.35913) (xy 357.26497 -13.35913) (xy 357.211093 -13.358648)
			(xy 357.103614 -13.350959) (xy 356.996957 -13.335622) (xy 356.891666 -13.312716) (xy 356.788278 -13.282357)
			(xy 356.687318 -13.244699) (xy 356.589302 -13.199936) (xy 356.494729 -13.148294) (xy 356.404082 -13.090037)
			(xy 356.317821 -13.025462) (xy 356.236386 -12.954897) (xy 356.160193 -12.878704) (xy 356.08963 -12.797268)
			(xy 356.025055 -12.711007) (xy 355.966799 -12.620359) (xy 355.915158 -12.525785) (xy 355.870395 -12.427769)
			(xy 355.832739 -12.326809) (xy 355.802381 -12.22342) (xy 355.779475 -12.118129) (xy 355.764139 -12.011472)
			(xy 355.756451 -11.903993) (xy 355.755956 -11.850116) (xy 355.755956 -1.999996) (xy 355.755447 -1.944227)
			(xy 355.747112 -1.833001) (xy 355.730487 -1.722708) (xy 355.705667 -1.613967) (xy 355.67279 -1.507384)
			(xy 355.63204 -1.403556) (xy 355.583645 -1.303064) (xy 355.527875 -1.20647) (xy 355.465043 -1.114313)
			(xy 355.395499 -1.02711) (xy 355.319633 -0.945347) (xy 355.237869 -0.869483) (xy 355.150664 -0.799941)
			(xy 355.058507 -0.73711) (xy 354.961911 -0.681342) (xy 354.861418 -0.632949) (xy 354.757589 -0.5922)
			(xy 354.651006 -0.559325) (xy 354.542264 -0.534507) (xy 354.431972 -0.517885) (xy 354.320745 -0.509552)
			(xy 354.264976 -0.509016) (xy 330.164948 -0.509016) (xy 330.109177 -0.509523) (xy 329.997948 -0.517855)
			(xy 329.887651 -0.534476) (xy 329.778906 -0.559293) (xy 329.672319 -0.592168) (xy 329.568487 -0.632916)
			(xy 329.467991 -0.681309) (xy 329.371392 -0.737078) (xy 329.279231 -0.79991) (xy 329.192023 -0.869453)
			(xy 329.110256 -0.945319) (xy 329.034387 -1.027083) (xy 328.96484 -1.114289) (xy 328.902006 -1.206448)
			(xy 328.846234 -1.303045) (xy 328.797837 -1.403539) (xy 328.757085 -1.50737) (xy 328.724207 -1.613956)
			(xy 328.699386 -1.7227) (xy 328.682761 -1.832996) (xy 328.674425 -1.944225) (xy 328.673968 -1.999996)
			(xy 328.673968 -11.850116) (xy 328.673498 -11.903993) (xy 328.665809 -12.011472) (xy 328.650473 -12.118129)
			(xy 328.627567 -12.223419) (xy 328.597208 -12.326808) (xy 328.55955 -12.427767) (xy 328.514786 -12.525783)
			(xy 328.463144 -12.620355) (xy 328.404886 -12.711002) (xy 328.34031 -12.797262) (xy 328.269745 -12.878695)
			(xy 328.19355 -12.954887) (xy 328.112114 -13.025449) (xy 328.025851 -13.090021) (xy 327.935201 -13.148275)
			(xy 327.840627 -13.199914) (xy 327.74261 -13.244674) (xy 327.641649 -13.282327) (xy 327.538259 -13.312682)
			(xy 327.432968 -13.335584) (xy 327.32631 -13.350916) (xy 327.218831 -13.3586) (xy 327.164954 -13.35913)
			(xy 319.16497 -13.35913) (xy 319.111093 -13.358648) (xy 319.003614 -13.350959) (xy 318.896957 -13.335622)
			(xy 318.791666 -13.312716) (xy 318.688278 -13.282357) (xy 318.587318 -13.244699) (xy 318.489302 -13.199936)
			(xy 318.394729 -13.148294) (xy 318.304082 -13.090037) (xy 318.217821 -13.025462) (xy 318.136386 -12.954897)
			(xy 318.060193 -12.878704) (xy 317.98963 -12.797268) (xy 317.925055 -12.711007) (xy 317.866799 -12.620359)
			(xy 317.815158 -12.525785) (xy 317.770395 -12.427769) (xy 317.732739 -12.326809) (xy 317.702381 -12.22342)
			(xy 317.679475 -12.118129) (xy 317.664139 -12.011472) (xy 317.656451 -11.903993) (xy 317.655956 -11.850116)
			(xy 317.655956 -1.999996) (xy 317.655447 -1.944227) (xy 317.647112 -1.833001) (xy 317.630487 -1.722708)
			(xy 317.605667 -1.613967) (xy 317.57279 -1.507384) (xy 317.53204 -1.403556) (xy 317.483645 -1.303064)
			(xy 317.427875 -1.20647) (xy 317.365043 -1.114313) (xy 317.295499 -1.02711) (xy 317.219633 -0.945347)
			(xy 317.137869 -0.869483) (xy 317.050664 -0.799941) (xy 316.958507 -0.73711) (xy 316.861911 -0.681342)
			(xy 316.761418 -0.632949) (xy 316.657589 -0.5922) (xy 316.551006 -0.559325) (xy 316.442264 -0.534507)
			(xy 316.331972 -0.517885) (xy 316.220745 -0.509552) (xy 316.164976 -0.509016) (xy 304.165 -0.509016)
			(xy 304.109231 -0.509537) (xy 303.998005 -0.517873) (xy 303.887712 -0.534497) (xy 303.778971 -0.559316)
			(xy 303.672388 -0.592193) (xy 303.56856 -0.632942) (xy 303.468067 -0.681336) (xy 303.371472 -0.737105)
			(xy 303.279315 -0.799937) (xy 303.192111 -0.86948) (xy 303.110348 -0.945345) (xy 303.034482 -1.027108)
			(xy 302.964939 -1.114312) (xy 302.902108 -1.206469) (xy 302.846338 -1.303064) (xy 302.797944 -1.403556)
			(xy 302.757194 -1.507384) (xy 302.724317 -1.613967) (xy 302.699497 -1.722708) (xy 302.682873 -1.833001)
			(xy 302.674538 -1.944227) (xy 302.67402 -1.999996) (xy 302.67402 -11.850116) (xy 302.673539 -11.903993)
			(xy 302.66585 -12.011473) (xy 302.650514 -12.11813) (xy 302.627609 -12.223422) (xy 302.59725 -12.326811)
			(xy 302.559593 -12.427771) (xy 302.51483 -12.525787) (xy 302.463188 -12.62036) (xy 302.404931 -12.711009)
			(xy 302.340356 -12.79727) (xy 302.269792 -12.878705) (xy 302.193598 -12.954899) (xy 302.112162 -13.025462)
			(xy 302.025901 -13.090037) (xy 301.935252 -13.148293) (xy 301.840678 -13.199934) (xy 301.742661 -13.244697)
			(xy 301.641701 -13.282353) (xy 301.538312 -13.312711) (xy 301.43302 -13.335616) (xy 301.326363 -13.350952)
			(xy 301.218883 -13.358639) (xy 301.165006 -13.35913) (xy 293.165022 -13.35913) (xy 293.111143 -13.358661)
			(xy 293.003661 -13.350975) (xy 292.897001 -13.335641) (xy 292.791706 -13.312737) (xy 292.688313 -13.28238)
			(xy 292.58735 -13.244724) (xy 292.48933 -13.199962) (xy 292.394753 -13.148321) (xy 292.304102 -13.090064)
			(xy 292.217837 -13.025489) (xy 292.136399 -12.954924) (xy 292.060202 -12.878729) (xy 291.989635 -12.797293)
			(xy 291.925058 -12.71103) (xy 291.866799 -12.620379) (xy 291.815155 -12.525804) (xy 291.77039 -12.427785)
			(xy 291.732732 -12.326823) (xy 291.702372 -12.223431) (xy 291.679465 -12.118137) (xy 291.664129 -12.011477)
			(xy 291.65644 -11.903994) (xy 291.656008 -11.850116) (xy 291.656008 -1.999996) (xy 291.655486 -1.944227)
			(xy 291.647151 -1.833) (xy 291.630527 -1.722707) (xy 291.605707 -1.613965) (xy 291.572831 -1.507382)
			(xy 291.532081 -1.403553) (xy 291.483687 -1.30306) (xy 291.427918 -1.206465) (xy 291.365087 -1.114307)
			(xy 291.295544 -1.027102) (xy 291.219679 -0.945338) (xy 291.137916 -0.869472) (xy 291.050712 -0.799928)
			(xy 290.958556 -0.737095) (xy 290.861961 -0.681324) (xy 290.761469 -0.632928) (xy 290.657641 -0.592177)
			(xy 290.551058 -0.559299) (xy 290.442316 -0.534478) (xy 290.332024 -0.517852) (xy 290.220797 -0.509515)
			(xy 290.165028 -0.509016) (xy 278.165052 -0.509016) (xy 278.109284 -0.509539) (xy 277.99806 -0.517878)
			(xy 277.887771 -0.534504) (xy 277.779032 -0.559327) (xy 277.672452 -0.592205) (xy 277.568627 -0.632956)
			(xy 277.468138 -0.681352) (xy 277.371546 -0.737122) (xy 277.279392 -0.799954) (xy 277.192191 -0.869497)
			(xy 277.110431 -0.945362) (xy 277.034568 -1.027125) (xy 276.965028 -1.114328) (xy 276.902198 -1.206484)
			(xy 276.846431 -1.303077) (xy 276.798039 -1.403568) (xy 276.75729 -1.507394) (xy 276.724415 -1.613974)
			(xy 276.699596 -1.722714) (xy 276.682973 -1.833004) (xy 276.674638 -1.944228) (xy 276.674072 -1.999996)
			(xy 276.674072 -11.850116) (xy 276.673602 -11.903993) (xy 276.665913 -12.011472) (xy 276.650577 -12.118129)
			(xy 276.627671 -12.22342) (xy 276.597312 -12.326808) (xy 276.559654 -12.427768) (xy 276.51489 -12.525783)
			(xy 276.463248 -12.620356) (xy 276.40499 -12.711003) (xy 276.340414 -12.797263) (xy 276.269849 -12.878697)
			(xy 276.193654 -12.954889) (xy 276.112218 -13.025451) (xy 276.025955 -13.090023) (xy 275.935306 -13.148277)
			(xy 275.840731 -13.199916) (xy 275.742714 -13.244676) (xy 275.641753 -13.28233) (xy 275.538364 -13.312685)
			(xy 275.433072 -13.335587) (xy 275.326414 -13.35092) (xy 275.218935 -13.358604) (xy 275.165058 -13.35913)
			(xy 267.165074 -13.35913) (xy 267.111197 -13.358648) (xy 267.003718 -13.350959) (xy 266.897061 -13.335623)
			(xy 266.791769 -13.312717) (xy 266.688381 -13.282358) (xy 266.587421 -13.2447) (xy 266.489405 -13.199937)
			(xy 266.394832 -13.148295) (xy 266.304184 -13.090038) (xy 266.217923 -13.025463) (xy 266.136488 -12.954899)
			(xy 266.060294 -12.878705) (xy 265.989731 -12.79727) (xy 265.925156 -12.711008) (xy 265.8669 -12.62036)
			(xy 265.815259 -12.525786) (xy 265.770496 -12.42777) (xy 265.732839 -12.32681) (xy 265.702481 -12.223421)
			(xy 265.679575 -12.11813) (xy 265.664239 -12.011472) (xy 265.656551 -11.903993) (xy 265.65606 -11.850116)
			(xy 265.65606 -1.999996) (xy 265.655551 -1.944227) (xy 265.647216 -1.833) (xy 265.630591 -1.722708)
			(xy 265.605771 -1.613966) (xy 265.572894 -1.507384) (xy 265.532144 -1.403556) (xy 265.483749 -1.303063)
			(xy 265.427979 -1.206469) (xy 265.365147 -1.114312) (xy 265.295603 -1.027108) (xy 265.219737 -0.945346)
			(xy 265.137973 -0.869481) (xy 265.050769 -0.799939) (xy 264.958611 -0.737108) (xy 264.862015 -0.68134)
			(xy 264.761522 -0.632946) (xy 264.657694 -0.592198) (xy 264.55111 -0.559322) (xy 264.442368 -0.534504)
			(xy 264.332076 -0.517882) (xy 264.220849 -0.509548) (xy 264.16508 -0.509016) (xy 252.165104 -0.509016)
			(xy 252.109335 -0.509537) (xy 251.998108 -0.517872) (xy 251.887816 -0.534496) (xy 251.779074 -0.559315)
			(xy 251.672491 -0.592191) (xy 251.568663 -0.632941) (xy 251.46817 -0.681335) (xy 251.371575 -0.737104)
			(xy 251.279417 -0.799936) (xy 251.192213 -0.869478) (xy 251.110449 -0.945344) (xy 251.034584 -1.027107)
			(xy 250.96504 -1.114311) (xy 250.902208 -1.206468) (xy 250.846439 -1.303063) (xy 250.798044 -1.403555)
			(xy 250.757294 -1.507383) (xy 250.724417 -1.613966) (xy 250.699597 -1.722708) (xy 250.682973 -1.833)
			(xy 250.674638 -1.944227) (xy 250.674124 -1.999996) (xy 250.674124 -11.850116) (xy 250.673643 -11.903993)
			(xy 250.665954 -12.011473) (xy 250.650618 -12.11813) (xy 250.627713 -12.223422) (xy 250.597354 -12.326811)
			(xy 250.559697 -12.427771) (xy 250.514934 -12.525788) (xy 250.463292 -12.620361) (xy 250.405035 -12.71101)
			(xy 250.34046 -12.797271) (xy 250.269896 -12.878706) (xy 250.193702 -12.9549) (xy 250.112267 -13.025464)
			(xy 250.026005 -13.090039) (xy 249.935356 -13.148295) (xy 249.840782 -13.199936) (xy 249.742766 -13.244699)
			(xy 249.641806 -13.282356) (xy 249.538416 -13.312714) (xy 249.433124 -13.33562) (xy 249.326467 -13.350955)
			(xy 249.218987 -13.358643) (xy 249.16511 -13.35913) (xy 241.164872 -13.35913) (xy 241.110999 -13.358634)
			(xy 241.003529 -13.35092) (xy 240.896884 -13.335561) (xy 240.791604 -13.312636) (xy 240.688228 -13.282262)
			(xy 240.587282 -13.244593) (xy 240.489278 -13.199821) (xy 240.394717 -13.148173) (xy 240.30408 -13.089914)
			(xy 240.217828 -13.02534) (xy 240.136401 -12.954778) (xy 240.060213 -12.87859) (xy 239.989653 -12.797163)
			(xy 239.925079 -12.71091) (xy 239.86682 -12.620273) (xy 239.815174 -12.525711) (xy 239.770403 -12.427707)
			(xy 239.732734 -12.32676) (xy 239.702361 -12.223384) (xy 239.679436 -12.118105) (xy 239.664079 -12.011459)
			(xy 239.656365 -11.903989) (xy 239.655858 -11.850116) (xy 239.655858 -1.999996) (xy 239.655349 -1.944227)
			(xy 239.647014 -1.833001) (xy 239.630389 -1.722708) (xy 239.605569 -1.613967) (xy 239.572692 -1.507384)
			(xy 239.531942 -1.403556) (xy 239.483547 -1.303064) (xy 239.427777 -1.206469) (xy 239.364945 -1.114313)
			(xy 239.295401 -1.027109) (xy 239.219535 -0.945346) (xy 239.137771 -0.869482) (xy 239.050567 -0.79994)
			(xy 238.958409 -0.737109) (xy 238.861813 -0.681341) (xy 238.76132 -0.632947) (xy 238.657492 -0.592199)
			(xy 238.550908 -0.559324) (xy 238.442166 -0.534506) (xy 238.331874 -0.517883) (xy 238.220647 -0.50955)
			(xy 238.164878 -0.509016) (xy 214.065104 -0.509016) (xy 214.009335 -0.509537) (xy 213.898108 -0.517872)
			(xy 213.787816 -0.534496) (xy 213.679074 -0.559315) (xy 213.572491 -0.592191) (xy 213.468663 -0.632941)
			(xy 213.36817 -0.681335) (xy 213.271575 -0.737104) (xy 213.179417 -0.799936) (xy 213.092213 -0.869478)
			(xy 213.010449 -0.945344) (xy 212.934584 -1.027107) (xy 212.86504 -1.114311) (xy 212.802208 -1.206468)
			(xy 212.746439 -1.303063) (xy 212.698044 -1.403555) (xy 212.657294 -1.507383) (xy 212.624417 -1.613966)
			(xy 212.599597 -1.722708) (xy 212.582973 -1.833) (xy 212.574638 -1.944227) (xy 212.574124 -1.999996)
			(xy 212.574124 -11.850116) (xy 212.573643 -11.903993) (xy 212.565954 -12.011473) (xy 212.550618 -12.11813)
			(xy 212.527713 -12.223422) (xy 212.497354 -12.326811) (xy 212.459697 -12.427771) (xy 212.414934 -12.525788)
			(xy 212.363292 -12.620361) (xy 212.305035 -12.71101) (xy 212.24046 -12.797271) (xy 212.169896 -12.878706)
			(xy 212.093702 -12.9549) (xy 212.012267 -13.025464) (xy 211.926005 -13.090039) (xy 211.835356 -13.148295)
			(xy 211.740782 -13.199936) (xy 211.642766 -13.244699) (xy 211.541806 -13.282356) (xy 211.438416 -13.312714)
			(xy 211.333124 -13.33562) (xy 211.226467 -13.350955) (xy 211.118987 -13.358643) (xy 211.06511 -13.35913)
			(xy 203.064872 -13.35913) (xy 203.010999 -13.358634) (xy 202.903529 -13.35092) (xy 202.796884 -13.335561)
			(xy 202.691604 -13.312636) (xy 202.588228 -13.282262) (xy 202.487282 -13.244593) (xy 202.389278 -13.199821)
			(xy 202.294717 -13.148173) (xy 202.20408 -13.089914) (xy 202.117828 -13.02534) (xy 202.036401 -12.954778)
			(xy 201.960213 -12.87859) (xy 201.889653 -12.797163) (xy 201.825079 -12.71091) (xy 201.76682 -12.620273)
			(xy 201.715174 -12.525711) (xy 201.670403 -12.427707) (xy 201.632734 -12.32676) (xy 201.602361 -12.223384)
			(xy 201.579436 -12.118105) (xy 201.564079 -12.011459) (xy 201.556365 -11.903989) (xy 201.555858 -11.850116)
			(xy 201.555858 -1.999996) (xy 201.555349 -1.944227) (xy 201.547014 -1.833001) (xy 201.530389 -1.722708)
			(xy 201.505569 -1.613967) (xy 201.472692 -1.507384) (xy 201.431942 -1.403556) (xy 201.383547 -1.303064)
			(xy 201.327777 -1.206469) (xy 201.264945 -1.114313) (xy 201.195401 -1.027109) (xy 201.119535 -0.945346)
			(xy 201.037771 -0.869482) (xy 200.950567 -0.79994) (xy 200.858409 -0.737109) (xy 200.761813 -0.681341)
			(xy 200.66132 -0.632947) (xy 200.557492 -0.592199) (xy 200.450908 -0.559324) (xy 200.342166 -0.534506)
			(xy 200.231874 -0.517883) (xy 200.120647 -0.50955) (xy 200.064878 -0.509016) (xy 188.064902 -0.509016)
			(xy 188.009133 -0.509537) (xy 187.897906 -0.517873) (xy 187.787614 -0.534496) (xy 187.678872 -0.559316)
			(xy 187.572289 -0.592192) (xy 187.468461 -0.632941) (xy 187.367969 -0.681336) (xy 187.271374 -0.737105)
			(xy 187.179216 -0.799936) (xy 187.092012 -0.869479) (xy 187.010248 -0.945344) (xy 186.934383 -1.027107)
			(xy 186.86484 -1.114311) (xy 186.802008 -1.206468) (xy 186.746239 -1.303063) (xy 186.697844 -1.403556)
			(xy 186.657094 -1.507384) (xy 186.624217 -1.613966) (xy 186.599397 -1.722708) (xy 186.582773 -1.833001)
			(xy 186.574438 -1.944227) (xy 186.573922 -1.999996) (xy 186.573922 -11.850116) (xy 186.573441 -11.903993)
			(xy 186.565752 -12.011473) (xy 186.550416 -12.11813) (xy 186.527511 -12.223422) (xy 186.497152 -12.326811)
			(xy 186.459495 -12.427771) (xy 186.414732 -12.525787) (xy 186.36309 -12.620361) (xy 186.304833 -12.711009)
			(xy 186.240258 -12.797271) (xy 186.169694 -12.878706) (xy 186.0935 -12.954899) (xy 186.012065 -13.025463)
			(xy 185.925803 -13.090038) (xy 185.835154 -13.148294) (xy 185.74058 -13.199935) (xy 185.642564 -13.244698)
			(xy 185.541603 -13.282355) (xy 185.438214 -13.312713) (xy 185.332922 -13.335618) (xy 185.226265 -13.350953)
			(xy 185.118785 -13.358641) (xy 185.064908 -13.35913) (xy 177.064924 -13.35913) (xy 177.011045 -13.358661)
			(xy 176.903563 -13.350975) (xy 176.796902 -13.335642) (xy 176.691607 -13.312738) (xy 176.588215 -13.282381)
			(xy 176.487251 -13.244725) (xy 176.389231 -13.199962) (xy 176.294654 -13.148321) (xy 176.204003 -13.090065)
			(xy 176.117738 -13.025489) (xy 176.036299 -12.954925) (xy 175.960103 -12.87873) (xy 175.889536 -12.797293)
			(xy 175.824958 -12.71103) (xy 175.766699 -12.62038) (xy 175.715056 -12.525804) (xy 175.67029 -12.427786)
			(xy 175.632632 -12.326823) (xy 175.602272 -12.223431) (xy 175.579365 -12.118137) (xy 175.564029 -12.011477)
			(xy 175.55634 -11.903995) (xy 175.55591 -11.850116) (xy 175.55591 -1.999996) (xy 175.555388 -1.944227)
			(xy 175.547053 -1.833) (xy 175.530429 -1.722707) (xy 175.505609 -1.613965) (xy 175.472733 -1.507381)
			(xy 175.431983 -1.403553) (xy 175.383589 -1.30306) (xy 175.32782 -1.206464) (xy 175.264989 -1.114306)
			(xy 175.195446 -1.027101) (xy 175.119581 -0.945337) (xy 175.037818 -0.869471) (xy 174.950615 -0.799927)
			(xy 174.858458 -0.737094) (xy 174.761863 -0.681323) (xy 174.661371 -0.632927) (xy 174.557543 -0.592176)
			(xy 174.45096 -0.559298) (xy 174.342219 -0.534476) (xy 174.231926 -0.51785) (xy 174.120699 -0.509513)
			(xy 174.06493 -0.509016) (xy 162.064954 -0.509016) (xy 162.009186 -0.509539) (xy 161.897962 -0.517878)
			(xy 161.787672 -0.534504) (xy 161.678934 -0.559326) (xy 161.572354 -0.592204) (xy 161.468529 -0.632956)
			(xy 161.368039 -0.681351) (xy 161.271447 -0.737121) (xy 161.179293 -0.799953) (xy 161.092092 -0.869496)
			(xy 161.010331 -0.945361) (xy 160.934469 -1.027124) (xy 160.864928 -1.114327) (xy 160.802099 -1.206483)
			(xy 160.746332 -1.303076) (xy 160.697939 -1.403567) (xy 160.657191 -1.507393) (xy 160.624315 -1.613974)
			(xy 160.599496 -1.722714) (xy 160.582873 -1.833004) (xy 160.574538 -1.944228) (xy 160.573974 -1.999996)
			(xy 160.573974 -11.850116) (xy 160.573504 -11.903993) (xy 160.565815 -12.011472) (xy 160.550479 -12.118129)
			(xy 160.527573 -12.22342) (xy 160.497214 -12.326809) (xy 160.459556 -12.427768) (xy 160.414792 -12.525784)
			(xy 160.36315 -12.620356) (xy 160.304892 -12.711003) (xy 160.240316 -12.797264) (xy 160.169751 -12.878697)
			(xy 160.093556 -12.954889) (xy 160.01212 -13.025452) (xy 159.925857 -13.090024) (xy 159.835208 -13.148278)
			(xy 159.740634 -13.199917) (xy 159.642616 -13.244678) (xy 159.541655 -13.282332) (xy 159.438266 -13.312687)
			(xy 159.332974 -13.335589) (xy 159.226316 -13.350921) (xy 159.118837 -13.358606) (xy 159.06496 -13.35913)
			(xy 151.064976 -13.35913) (xy 151.011099 -13.358648) (xy 150.903619 -13.35096) (xy 150.796962 -13.335623)
			(xy 150.691671 -13.312717) (xy 150.588282 -13.282358) (xy 150.487322 -13.244701) (xy 150.389306 -13.199937)
			(xy 150.294733 -13.148296) (xy 150.204085 -13.090039) (xy 150.117823 -13.025464) (xy 150.036389 -12.954899)
			(xy 149.960195 -12.878706) (xy 149.889631 -12.79727) (xy 149.825057 -12.711009) (xy 149.7668 -12.62036)
			(xy 149.715159 -12.525787) (xy 149.670396 -12.42777) (xy 149.632739 -12.32681) (xy 149.602381 -12.223421)
			(xy 149.579475 -12.11813) (xy 149.564139 -12.011473) (xy 149.556451 -11.903993) (xy 149.555962 -11.850116)
			(xy 149.555962 -1.999996) (xy 149.555453 -1.944227) (xy 149.547118 -1.833) (xy 149.530493 -1.722708)
			(xy 149.505673 -1.613966) (xy 149.472796 -1.507383) (xy 149.432046 -1.403555) (xy 149.383651 -1.303063)
			(xy 149.327881 -1.206468) (xy 149.265049 -1.114311) (xy 149.195505 -1.027108) (xy 149.11964 -0.945345)
			(xy 149.037876 -0.86948) (xy 148.950671 -0.799938) (xy 148.858513 -0.737107) (xy 148.761917 -0.681339)
			(xy 148.661424 -0.632945) (xy 148.557596 -0.592196) (xy 148.451013 -0.559321) (xy 148.34227 -0.534503)
			(xy 148.231978 -0.51788) (xy 148.120751 -0.509546) (xy 148.064982 -0.509016) (xy 136.065006 -0.509016)
			(xy 136.009236 -0.509524) (xy 135.898009 -0.517859) (xy 135.787715 -0.534483) (xy 135.678972 -0.559302)
			(xy 135.572388 -0.592179) (xy 135.468559 -0.632928) (xy 135.368065 -0.681323) (xy 135.271469 -0.737092)
			(xy 135.17931 -0.799924) (xy 135.092105 -0.869468) (xy 135.010341 -0.945334) (xy 134.934474 -1.027098)
			(xy 134.86493 -1.114302) (xy 134.802098 -1.20646) (xy 134.746328 -1.303056) (xy 134.697932 -1.403549)
			(xy 134.657182 -1.507378) (xy 134.624305 -1.613962) (xy 134.599485 -1.722705) (xy 134.58286 -1.832999)
			(xy 134.574525 -1.944226) (xy 134.574026 -1.999996) (xy 134.574026 -11.850116) (xy 134.573545 -11.903993)
			(xy 134.565856 -12.011473) (xy 134.55052 -12.11813) (xy 134.527615 -12.223422) (xy 134.497256 -12.326811)
			(xy 134.459599 -12.427772) (xy 134.414836 -12.525788) (xy 134.363194 -12.620362) (xy 134.304937 -12.71101)
			(xy 134.240362 -12.797272) (xy 134.169798 -12.878707) (xy 134.093604 -12.954901) (xy 134.012169 -13.025465)
			(xy 133.925907 -13.09004) (xy 133.835258 -13.148296) (xy 133.740685 -13.199938) (xy 133.642668 -13.244701)
			(xy 133.541708 -13.282357) (xy 133.438318 -13.312716) (xy 133.333026 -13.335621) (xy 133.226369 -13.350957)
			(xy 133.118889 -13.358645) (xy 133.065012 -13.35913) (xy 125.065028 -13.35913) (xy 125.011149 -13.358661)
			(xy 124.903666 -13.350976) (xy 124.797006 -13.335642) (xy 124.691711 -13.312739) (xy 124.588318 -13.282382)
			(xy 124.487354 -13.244726) (xy 124.389334 -13.199964) (xy 124.294757 -13.148323) (xy 124.204105 -13.090066)
			(xy 124.11784 -13.025491) (xy 124.036401 -12.954926) (xy 123.960204 -12.878731) (xy 123.889637 -12.797295)
			(xy 123.825059 -12.711032) (xy 123.7668 -12.620381) (xy 123.715156 -12.525806) (xy 123.670391 -12.427787)
			(xy 123.632732 -12.326824) (xy 123.602372 -12.223432) (xy 123.579466 -12.118138) (xy 123.564129 -12.011477)
			(xy 123.55644 -11.903995) (xy 123.556014 -11.850116) (xy 123.556014 -1.999996) (xy 123.555492 -1.944227)
			(xy 123.547157 -1.833) (xy 123.530533 -1.722707) (xy 123.505713 -1.613964) (xy 123.472837 -1.507381)
			(xy 123.432088 -1.403552) (xy 123.383693 -1.303059) (xy 123.327924 -1.206463) (xy 123.265093 -1.114305)
			(xy 123.19555 -1.0271) (xy 123.119685 -0.945336) (xy 123.037923 -0.869469) (xy 122.950719 -0.799925)
			(xy 122.858562 -0.737092) (xy 122.761967 -0.681321) (xy 122.661475 -0.632924) (xy 122.557647 -0.592173)
			(xy 122.451065 -0.559295) (xy 122.342323 -0.534473) (xy 122.23203 -0.517846) (xy 122.120803 -0.509509)
			(xy 122.065034 -0.509016) (xy 97.965006 -0.509016) (xy 97.909236 -0.509524) (xy 97.798009 -0.517859)
			(xy 97.687715 -0.534483) (xy 97.578972 -0.559302) (xy 97.472388 -0.592179) (xy 97.368559 -0.632928)
			(xy 97.268065 -0.681323) (xy 97.171469 -0.737092) (xy 97.07931 -0.799924) (xy 96.992105 -0.869468)
			(xy 96.910341 -0.945334) (xy 96.834474 -1.027098) (xy 96.76493 -1.114302) (xy 96.702098 -1.20646)
			(xy 96.646328 -1.303056) (xy 96.597932 -1.403549) (xy 96.557182 -1.507378) (xy 96.524305 -1.613962)
			(xy 96.499485 -1.722705) (xy 96.48286 -1.832999) (xy 96.474525 -1.944226) (xy 96.474026 -1.999996)
			(xy 96.474026 -11.850116) (xy 96.473545 -11.903993) (xy 96.465856 -12.011473) (xy 96.45052 -12.11813)
			(xy 96.427615 -12.223422) (xy 96.397256 -12.326811) (xy 96.359599 -12.427772) (xy 96.314836 -12.525788)
			(xy 96.263194 -12.620362) (xy 96.204937 -12.71101) (xy 96.140362 -12.797272) (xy 96.069798 -12.878707)
			(xy 95.993604 -12.954901) (xy 95.912169 -13.025465) (xy 95.825907 -13.09004) (xy 95.735258 -13.148296)
			(xy 95.640685 -13.199938) (xy 95.542668 -13.244701) (xy 95.441708 -13.282357) (xy 95.338318 -13.312716)
			(xy 95.233026 -13.335621) (xy 95.126369 -13.350957) (xy 95.018889 -13.358645) (xy 94.965012 -13.35913)
			(xy 86.965028 -13.35913) (xy 86.911149 -13.358661) (xy 86.803666 -13.350976) (xy 86.697006 -13.335642)
			(xy 86.591711 -13.312739) (xy 86.488318 -13.282382) (xy 86.387354 -13.244726) (xy 86.289334 -13.199964)
			(xy 86.194757 -13.148323) (xy 86.104105 -13.090066) (xy 86.01784 -13.025491) (xy 85.936401 -12.954926)
			(xy 85.860204 -12.878731) (xy 85.789637 -12.797295) (xy 85.725059 -12.711032) (xy 85.6668 -12.620381)
			(xy 85.615156 -12.525806) (xy 85.570391 -12.427787) (xy 85.532732 -12.326824) (xy 85.502372 -12.223432)
			(xy 85.479466 -12.118138) (xy 85.464129 -12.011477) (xy 85.45644 -11.903995) (xy 85.456014 -11.850116)
			(xy 85.456014 -1.999996) (xy 85.455492 -1.944227) (xy 85.447157 -1.833) (xy 85.430533 -1.722707)
			(xy 85.405713 -1.613964) (xy 85.372837 -1.507381) (xy 85.332088 -1.403552) (xy 85.283693 -1.303059)
			(xy 85.227924 -1.206463) (xy 85.165093 -1.114305) (xy 85.09555 -1.0271) (xy 85.019685 -0.945336)
			(xy 84.937923 -0.869469) (xy 84.850719 -0.799925) (xy 84.758562 -0.737092) (xy 84.661967 -0.681321)
			(xy 84.561475 -0.632924) (xy 84.457647 -0.592173) (xy 84.351065 -0.559295) (xy 84.242323 -0.534473)
			(xy 84.13203 -0.517846) (xy 84.020803 -0.509509) (xy 83.965034 -0.509016) (xy 71.965058 -0.509016)
			(xy 71.90929 -0.509539) (xy 71.798066 -0.517877) (xy 71.687776 -0.534503) (xy 71.579037 -0.559325)
			(xy 71.472457 -0.592203) (xy 71.368631 -0.632954) (xy 71.268142 -0.68135) (xy 71.17155 -0.73712)
			(xy 71.079395 -0.799952) (xy 70.992194 -0.869495) (xy 70.910433 -0.94536) (xy 70.83457 -1.027122)
			(xy 70.765029 -1.114326) (xy 70.7022 -1.206482) (xy 70.646432 -1.303075) (xy 70.598039 -1.403566)
			(xy 70.557291 -1.507392) (xy 70.524415 -1.613974) (xy 70.499596 -1.722713) (xy 70.482973 -1.833004)
			(xy 70.474638 -1.944228) (xy 70.474078 -1.999996) (xy 70.474078 -7.817358) (xy 74.11466 -7.817358)
			(xy 74.11466 -3.597656) (xy 74.115163 -3.57355) (xy 74.122732 -3.525936) (xy 74.137645 -3.480088)
			(xy 74.159537 -3.437133) (xy 74.18787 -3.398125) (xy 74.204576 -3.38074) (xy 74.266806 -3.31851)
			(xy 74.284214 -3.301737) (xy 74.323295 -3.273288) (xy 74.366351 -3.251315) (xy 74.412318 -3.236358)
			(xy 74.460061 -3.228789) (xy 74.48423 -3.22834) (xy 80.741774 -3.22834) (xy 80.765894 -3.228847)
			(xy 80.813535 -3.236431) (xy 80.859399 -3.251383) (xy 80.902356 -3.273335) (xy 80.941343 -3.301745)
			(xy 80.95869 -3.31851) (xy 81.00568 -3.3655) (xy 81.0224 -3.382903) (xy 81.050726 -3.421974) (xy 81.072613 -3.464984)
			(xy 81.087526 -3.510881) (xy 81.095102 -3.558541) (xy 81.095596 -3.58267) (xy 81.095596 -7.681722)
			(xy 81.095147 -7.705819) (xy 81.087618 -7.753421) (xy 81.072748 -7.799264) (xy 81.050903 -7.842223)
			(xy 81.022617 -7.881244) (xy 81.005934 -7.898638) (xy 80.958944 -7.945628) (xy 80.941574 -7.962357)
			(xy 80.902582 -7.99073) (xy 80.859626 -8.012643) (xy 80.813768 -8.027556) (xy 80.766139 -8.035099)
			(xy 80.742028 -8.035544) (xy 74.205846 -8.035544) (xy 74.204576 -8.034528) (xy 74.187871 -8.017109)
			(xy 74.159522 -7.978053) (xy 74.137621 -7.935049) (xy 74.122706 -7.889151) (xy 74.115144 -7.841488)
			(xy 74.11466 -7.817358) (xy 70.474078 -7.817358) (xy 70.474078 -11.850116) (xy 70.473608 -11.903993)
			(xy 70.465919 -12.011472) (xy 70.450583 -12.118129) (xy 70.427677 -12.22342) (xy 70.397318 -12.326809)
			(xy 70.35966 -12.427769) (xy 70.314896 -12.525784) (xy 70.263254 -12.620357) (xy 70.204996 -12.711004)
			(xy 70.140421 -12.797265) (xy 70.069855 -12.878699) (xy 69.993661 -12.954891) (xy 69.912224 -13.025453)
			(xy 69.825962 -13.090026) (xy 69.735312 -13.148281) (xy 69.640738 -13.19992) (xy 69.542721 -13.24468)
			(xy 69.44176 -13.282334) (xy 69.33837 -13.31269) (xy 69.233078 -13.335592) (xy 69.126421 -13.350925)
			(xy 69.018941 -13.358609) (xy 68.965064 -13.35913) (xy 60.96508 -13.35913) (xy 60.911203 -13.358648)
			(xy 60.803723 -13.35096) (xy 60.697066 -13.335624) (xy 60.591774 -13.312718) (xy 60.488385 -13.282359)
			(xy 60.387425 -13.244702) (xy 60.289409 -13.199939) (xy 60.194835 -13.148297) (xy 60.104187 -13.09004)
			(xy 60.017925 -13.025465) (xy 59.93649 -12.954901) (xy 59.860296 -12.878707) (xy 59.789732 -12.797272)
			(xy 59.725157 -12.71101) (xy 59.666901 -12.620361) (xy 59.61526 -12.525788) (xy 59.570496 -12.427771)
			(xy 59.53284 -12.326811) (xy 59.502481 -12.223422) (xy 59.479575 -12.11813) (xy 59.464239 -12.011473)
			(xy 59.456551 -11.903993) (xy 59.456066 -11.850116) (xy 59.456066 -1.999996) (xy 59.455557 -1.944227)
			(xy 59.447222 -1.833) (xy 59.430597 -1.722708) (xy 59.405777 -1.613966) (xy 59.3729 -1.507383) (xy 59.33215 -1.403555)
			(xy 59.283755 -1.303062) (xy 59.227986 -1.206467) (xy 59.165153 -1.11431) (xy 59.09561 -1.027107)
			(xy 59.019744 -0.945344) (xy 58.93798 -0.869479) (xy 58.850775 -0.799936) (xy 58.758617 -0.737105)
			(xy 58.662022 -0.681336) (xy 58.561529 -0.632942) (xy 58.4577 -0.592194) (xy 58.351117 -0.559318)
			(xy 58.242375 -0.534499) (xy 58.132082 -0.517876) (xy 58.020855 -0.509542) (xy 57.965086 -0.509016)
			(xy 45.96511 -0.509016) (xy 45.90934 -0.509524) (xy 45.798112 -0.517859) (xy 45.687819 -0.534482)
			(xy 45.579075 -0.559301) (xy 45.472491 -0.592178) (xy 45.368661 -0.632927) (xy 45.268167 -0.681322)
			(xy 45.171571 -0.737091) (xy 45.079412 -0.799923) (xy 44.992207 -0.869466) (xy 44.910442 -0.945332)
			(xy 44.834576 -1.027096) (xy 44.765031 -1.114301) (xy 44.702198 -1.206459) (xy 44.646428 -1.303055)
			(xy 44.598033 -1.403549) (xy 44.557282 -1.507378) (xy 44.524405 -1.613962) (xy 44.499585 -1.722705)
			(xy 44.48296 -1.832999) (xy 44.474625 -1.944226) (xy 44.47413 -1.999996) (xy 44.47413 -11.850116)
			(xy 44.473649 -11.903993) (xy 44.46596 -12.011473) (xy 44.450624 -12.118131) (xy 44.427719 -12.223422)
			(xy 44.39736 -12.326812) (xy 44.359703 -12.427772) (xy 44.31494 -12.525789) (xy 44.263298 -12.620363)
			(xy 44.205042 -12.711011) (xy 44.140467 -12.797273) (xy 44.069902 -12.878708) (xy 43.993708 -12.954902)
			(xy 43.912273 -13.025467) (xy 43.826011 -13.090042) (xy 43.735363 -13.148298) (xy 43.640789 -13.19994)
			(xy 43.542772 -13.244703) (xy 43.441812 -13.28236) (xy 43.338422 -13.312719) (xy 43.233131 -13.335624)
			(xy 43.126473 -13.35096) (xy 43.018993 -13.358649) (xy 42.965116 -13.35913) (xy 34.964878 -13.35913)
			(xy 34.911001 -13.358648) (xy 34.803521 -13.35096) (xy 34.696864 -13.335624) (xy 34.591573 -13.312718)
			(xy 34.488184 -13.282359) (xy 34.387224 -13.244702) (xy 34.289207 -13.199938) (xy 34.194634 -13.148296)
			(xy 34.103986 -13.09004) (xy 34.017724 -13.025464) (xy 33.936289 -12.9549) (xy 33.860096 -12.878706)
			(xy 33.789532 -12.797271) (xy 33.724957 -12.711009) (xy 33.666701 -12.620361) (xy 33.615059 -12.525787)
			(xy 33.570296 -12.427771) (xy 33.532639 -12.326811) (xy 33.502281 -12.223422) (xy 33.479375 -12.11813)
			(xy 33.464039 -12.011473) (xy 33.456351 -11.903993) (xy 33.455864 -11.850116) (xy 33.455864 -1.999996)
			(xy 33.455355 -1.944227) (xy 33.44702 -1.833) (xy 33.430395 -1.722708) (xy 33.405575 -1.613966) (xy 33.372698 -1.507383)
			(xy 33.331948 -1.403555) (xy 33.283553 -1.303063) (xy 33.227783 -1.206468) (xy 33.164951 -1.114311)
			(xy 33.095408 -1.027107) (xy 33.019542 -0.945344) (xy 32.937778 -0.869479) (xy 32.850573 -0.799937)
			(xy 32.758415 -0.737106) (xy 32.66182 -0.681337) (xy 32.561327 -0.632944) (xy 32.457498 -0.592195)
			(xy 32.350915 -0.559319) (xy 32.242173 -0.534501) (xy 32.13188 -0.517878) (xy 32.020653 -0.509544)
			(xy 31.964884 -0.509016) (xy 19.964908 -0.509016) (xy 19.909138 -0.509524) (xy 19.797911 -0.517859)
			(xy 19.687617 -0.534483) (xy 19.578874 -0.559302) (xy 19.472289 -0.592178) (xy 19.36846 -0.632928)
			(xy 19.267966 -0.681322) (xy 19.17137 -0.737092) (xy 19.079211 -0.799924) (xy 18.992006 -0.869467)
			(xy 18.910241 -0.945333) (xy 18.834375 -1.027097) (xy 18.764831 -1.114302) (xy 18.701998 -1.20646)
			(xy 18.646228 -1.303056) (xy 18.597832 -1.403549) (xy 18.557082 -1.507378) (xy 18.524205 -1.613962)
			(xy 18.499385 -1.722705) (xy 18.48276 -1.832999) (xy 18.474425 -1.944226) (xy 18.473928 -1.999996)
			(xy 18.473928 -11.850116) (xy 18.473447 -11.903994) (xy 18.46576 -12.011474) (xy 18.450426 -12.118132)
			(xy 18.427521 -12.223425) (xy 18.397163 -12.326815) (xy 18.359507 -12.427777) (xy 18.314744 -12.525794)
			(xy 18.263103 -12.620369) (xy 18.204846 -12.711018) (xy 18.140271 -12.797281) (xy 18.069707 -12.878717)
			(xy 17.993513 -12.954911) (xy 17.912077 -13.025476) (xy 17.825815 -13.090052) (xy 17.735166 -13.148309)
			(xy 17.640591 -13.19995) (xy 17.542574 -13.244714) (xy 17.441613 -13.282371) (xy 17.338223 -13.312729)
			(xy 17.23293 -13.335634) (xy 17.126272 -13.35097) (xy 17.018792 -13.358657) (xy 16.964914 -13.35913)
			(xy 8.96493 -13.35913) (xy 8.911052 -13.35866) (xy 8.803571 -13.350973) (xy 8.696913 -13.335638)
			(xy 8.59162 -13.312733) (xy 8.488229 -13.282374) (xy 8.387268 -13.244718) (xy 8.28925 -13.199954)
			(xy 8.194675 -13.148313) (xy 8.104026 -13.090055) (xy 8.017763 -13.02548) (xy 7.936327 -12.954915)
			(xy 7.860132 -12.87872) (xy 7.789568 -12.797284) (xy 7.724992 -12.711021) (xy 7.666735 -12.620371)
			(xy 7.615094 -12.525797) (xy 7.570331 -12.427779) (xy 7.532674 -12.326817) (xy 7.502316 -12.223426)
			(xy 7.479412 -12.118133) (xy 7.464077 -12.011475) (xy 7.45639 -11.903994) (xy 7.455916 -11.850116)
			(xy 7.455916 -1.999996) (xy 7.455394 -1.944227) (xy 7.447059 -1.833001) (xy 7.430435 -1.722709) (xy 7.405615 -1.613968)
			(xy 7.372738 -1.507386) (xy 7.331989 -1.403558) (xy 7.283594 -1.303066) (xy 7.227825 -1.206472) (xy 7.164993 -1.114315)
			(xy 7.09545 -1.027112) (xy 7.019585 -0.945349) (xy 6.937822 -0.869484) (xy 6.850618 -0.799942) (xy 6.758461 -0.737111)
			(xy 6.661866 -0.681342) (xy 6.561374 -0.632948) (xy 6.457547 -0.592199) (xy 6.350964 -0.559323) (xy 6.242223 -0.534504)
			(xy 6.131931 -0.51788) (xy 6.020705 -0.509545) (xy 5.964936 -0.509016) (xy 4.689348 -0.509016) (xy 4.688332 -0.508)
			(xy 3.140456 -0.508) (xy 3.13944 -0.509016) (xy 1.999996 -0.509016) (xy 1.944227 -0.509538) (xy 1.833001 -0.517873)
			(xy 1.722709 -0.534497) (xy 1.613967 -0.559317) (xy 1.507385 -0.592194) (xy 1.403557 -0.632943) (xy 1.303065 -0.681338)
			(xy 1.20647 -0.737107) (xy 1.114313 -0.799938) (xy 1.027109 -0.869481) (xy 0.945346 -0.945346) (xy 0.869481 -1.027109)
			(xy 0.799938 -1.114313) (xy 0.737107 -1.20647) (xy 0.681338 -1.303065) (xy 0.632943 -1.403557) (xy 0.592194 -1.507385)
			(xy 0.559317 -1.613967) (xy 0.534497 -1.722709) (xy 0.517873 -1.833001) (xy 0.509538 -1.944227) (xy 0.509016 -1.999996)
			(xy 0.509016 -15.200122) (xy 459.541372 -15.200122) (xy 459.541372 -13.599922) (xy 459.54188 -13.535242)
			(xy 459.550003 -13.406136) (xy 459.566216 -13.277796) (xy 459.590456 -13.150726) (xy 459.622626 -13.02543)
			(xy 459.662601 -12.9024) (xy 459.710222 -12.782124) (xy 459.765301 -12.665075) (xy 459.827621 -12.551715)
			(xy 459.896936 -12.442492) (xy 459.972972 -12.337837) (xy 460.05543 -12.238163) (xy 460.143983 -12.143863)
			(xy 460.238283 -12.05531) (xy 460.337957 -11.972852) (xy 460.442612 -11.896816) (xy 460.551835 -11.827501)
			(xy 460.665195 -11.765181) (xy 460.782244 -11.710102) (xy 460.90252 -11.662481) (xy 461.02555 -11.622506)
			(xy 461.150846 -11.590336) (xy 461.277916 -11.566096) (xy 461.406256 -11.549883) (xy 461.535362 -11.54176)
			(xy 461.664722 -11.54176) (xy 461.793828 -11.549883) (xy 461.922168 -11.566096) (xy 462.049238 -11.590336)
			(xy 462.174534 -11.622506) (xy 462.297564 -11.662481) (xy 462.41784 -11.710102) (xy 462.534889 -11.765181)
			(xy 462.648249 -11.827501) (xy 462.757472 -11.896816) (xy 462.862127 -11.972852) (xy 462.961801 -12.05531)
			(xy 463.056101 -12.143863) (xy 463.144654 -12.238163) (xy 463.227112 -12.337837) (xy 463.303148 -12.442492)
			(xy 463.372463 -12.551715) (xy 463.434783 -12.665075) (xy 463.489862 -12.782124) (xy 463.537483 -12.9024)
			(xy 463.577458 -13.02543) (xy 463.609628 -13.150726) (xy 463.633868 -13.277796) (xy 463.650081 -13.406136)
			(xy 463.658204 -13.535242) (xy 463.658712 -13.599922) (xy 463.658712 -15.200122) (xy 463.658204 -15.264802)
			(xy 463.650081 -15.393908) (xy 463.633868 -15.522248) (xy 463.609628 -15.649318) (xy 463.577458 -15.774614)
			(xy 463.537483 -15.897644) (xy 463.489862 -16.01792) (xy 463.434783 -16.134969) (xy 463.372463 -16.248329)
			(xy 463.303148 -16.357552) (xy 463.227112 -16.462207) (xy 463.144654 -16.561881) (xy 463.056101 -16.656181)
			(xy 462.961801 -16.744734) (xy 462.862127 -16.827192) (xy 462.757472 -16.903228) (xy 462.648249 -16.972543)
			(xy 462.534889 -17.034863) (xy 462.41784 -17.089942) (xy 462.297564 -17.137563) (xy 462.174534 -17.177538)
			(xy 462.049238 -17.209708) (xy 461.922168 -17.233948) (xy 461.793828 -17.250161) (xy 461.664722 -17.258284)
			(xy 461.535362 -17.258284) (xy 461.406256 -17.250161) (xy 461.277916 -17.233948) (xy 461.150846 -17.209708)
			(xy 461.02555 -17.177538) (xy 460.90252 -17.137563) (xy 460.782244 -17.089942) (xy 460.665195 -17.034863)
			(xy 460.551835 -16.972543) (xy 460.442612 -16.903228) (xy 460.337957 -16.827192) (xy 460.238283 -16.744734)
			(xy 460.143983 -16.656181) (xy 460.05543 -16.561881) (xy 459.972972 -16.462207) (xy 459.896936 -16.357552)
			(xy 459.827621 -16.248329) (xy 459.765301 -16.134969) (xy 459.710222 -16.01792) (xy 459.662601 -15.897644)
			(xy 459.622626 -15.774614) (xy 459.590456 -15.649318) (xy 459.566216 -15.522248) (xy 459.550003 -15.393908)
			(xy 459.54188 -15.264802) (xy 459.541372 -15.200122) (xy 0.509016 -15.200122) (xy 0.509016 -16.969994)
			(xy 13.748265 -16.969994) (xy 13.75227 -16.882086) (xy 13.764253 -16.794906) (xy 13.784113 -16.709177)
			(xy 13.811688 -16.625609) (xy 13.846747 -16.544895) (xy 13.889 -16.467703) (xy 13.938098 -16.394674)
			(xy 13.993634 -16.326412) (xy 14.055146 -16.263482) (xy 14.122127 -16.206408) (xy 14.19402 -16.15566)
			(xy 14.270229 -16.11166) (xy 14.350124 -16.074773) (xy 14.433043 -16.045304) (xy 14.518298 -16.023497)
			(xy 14.605182 -16.009533) (xy 14.692976 -16.003527) (xy 14.780953 -16.005531) (xy 14.868383 -16.015526)
			(xy 14.954542 -16.03343) (xy 15.038716 -16.059094) (xy 15.120207 -16.092307) (xy 15.198341 -16.132793)
			(xy 15.272469 -16.180215) (xy 15.341977 -16.234182) (xy 15.406291 -16.294247) (xy 15.464875 -16.359911)
			(xy 15.517246 -16.43063) (xy 15.562969 -16.505818) (xy 15.601666 -16.584853) (xy 15.633015 -16.667079)
			(xy 15.656757 -16.751815) (xy 15.672695 -16.838359) (xy 15.680697 -16.925994) (xy 15.681198 -16.969994)
			(xy 39.748213 -16.969994) (xy 39.752218 -16.882086) (xy 39.764201 -16.794906) (xy 39.784061 -16.709177)
			(xy 39.811636 -16.625609) (xy 39.846695 -16.544895) (xy 39.888948 -16.467703) (xy 39.938046 -16.394674)
			(xy 39.993582 -16.326412) (xy 40.055094 -16.263482) (xy 40.122075 -16.206408) (xy 40.193968 -16.15566)
			(xy 40.270177 -16.11166) (xy 40.350072 -16.074773) (xy 40.432991 -16.045304) (xy 40.518246 -16.023497)
			(xy 40.60513 -16.009533) (xy 40.692924 -16.003527) (xy 40.780901 -16.005531) (xy 40.868331 -16.015526)
			(xy 40.95449 -16.03343) (xy 41.038664 -16.059094) (xy 41.120155 -16.092307) (xy 41.198289 -16.132793)
			(xy 41.272417 -16.180215) (xy 41.341925 -16.234182) (xy 41.406239 -16.294247) (xy 41.464823 -16.359911)
			(xy 41.517194 -16.43063) (xy 41.562917 -16.505818) (xy 41.601614 -16.584853) (xy 41.632963 -16.667079)
			(xy 41.656705 -16.751815) (xy 41.672643 -16.838359) (xy 41.680645 -16.925994) (xy 41.681146 -16.969994)
			(xy 65.748161 -16.969994) (xy 65.752166 -16.882086) (xy 65.764149 -16.794906) (xy 65.784009 -16.709177)
			(xy 65.811584 -16.625609) (xy 65.846643 -16.544895) (xy 65.888896 -16.467703) (xy 65.937994 -16.394674)
			(xy 65.99353 -16.326412) (xy 66.055042 -16.263482) (xy 66.122023 -16.206408) (xy 66.193916 -16.15566)
			(xy 66.270125 -16.11166) (xy 66.35002 -16.074773) (xy 66.432939 -16.045304) (xy 66.518194 -16.023497)
			(xy 66.605078 -16.009533) (xy 66.692872 -16.003527) (xy 66.780849 -16.005531) (xy 66.868279 -16.015526)
			(xy 66.954438 -16.03343) (xy 67.038612 -16.059094) (xy 67.120103 -16.092307) (xy 67.198237 -16.132793)
			(xy 67.272365 -16.180215) (xy 67.341873 -16.234182) (xy 67.406187 -16.294247) (xy 67.464771 -16.359911)
			(xy 67.517142 -16.43063) (xy 67.562865 -16.505818) (xy 67.601562 -16.584853) (xy 67.632911 -16.667079)
			(xy 67.656653 -16.751815) (xy 67.672591 -16.838359) (xy 67.680593 -16.925994) (xy 67.681094 -16.969994)
			(xy 91.748109 -16.969994) (xy 91.752114 -16.882086) (xy 91.764097 -16.794906) (xy 91.783957 -16.709177)
			(xy 91.811532 -16.625609) (xy 91.846591 -16.544895) (xy 91.888844 -16.467703) (xy 91.937942 -16.394674)
			(xy 91.993478 -16.326412) (xy 92.05499 -16.263482) (xy 92.121971 -16.206408) (xy 92.193864 -16.15566)
			(xy 92.270073 -16.11166) (xy 92.349968 -16.074773) (xy 92.432887 -16.045304) (xy 92.518142 -16.023497)
			(xy 92.605026 -16.009533) (xy 92.69282 -16.003527) (xy 92.780797 -16.005531) (xy 92.868227 -16.015526)
			(xy 92.954386 -16.03343) (xy 93.03856 -16.059094) (xy 93.120051 -16.092307) (xy 93.198185 -16.132793)
			(xy 93.272313 -16.180215) (xy 93.341821 -16.234182) (xy 93.406135 -16.294247) (xy 93.464719 -16.359911)
			(xy 93.51709 -16.43063) (xy 93.562813 -16.505818) (xy 93.60151 -16.584853) (xy 93.632859 -16.667079)
			(xy 93.656601 -16.751815) (xy 93.672539 -16.838359) (xy 93.680541 -16.925994) (xy 93.681042 -16.969994)
			(xy 129.848363 -16.969994) (xy 129.852368 -16.882086) (xy 129.864351 -16.794906) (xy 129.884211 -16.709177)
			(xy 129.911786 -16.625609) (xy 129.946845 -16.544895) (xy 129.989098 -16.467703) (xy 130.038196 -16.394674)
			(xy 130.093732 -16.326412) (xy 130.155244 -16.263482) (xy 130.222225 -16.206408) (xy 130.294118 -16.15566)
			(xy 130.370327 -16.11166) (xy 130.450222 -16.074773) (xy 130.533141 -16.045304) (xy 130.618396 -16.023497)
			(xy 130.70528 -16.009533) (xy 130.793074 -16.003527) (xy 130.881051 -16.005531) (xy 130.968481 -16.015526)
			(xy 131.05464 -16.03343) (xy 131.138814 -16.059094) (xy 131.220305 -16.092307) (xy 131.298439 -16.132793)
			(xy 131.372567 -16.180215) (xy 131.442075 -16.234182) (xy 131.506389 -16.294247) (xy 131.564973 -16.359911)
			(xy 131.617344 -16.43063) (xy 131.663067 -16.505818) (xy 131.701764 -16.584853) (xy 131.733113 -16.667079)
			(xy 131.756855 -16.751815) (xy 131.772793 -16.838359) (xy 131.780795 -16.925994) (xy 131.781296 -16.969994)
			(xy 155.848311 -16.969994) (xy 155.852316 -16.882086) (xy 155.864299 -16.794906) (xy 155.884159 -16.709177)
			(xy 155.911734 -16.625609) (xy 155.946793 -16.544895) (xy 155.989046 -16.467703) (xy 156.038144 -16.394674)
			(xy 156.09368 -16.326412) (xy 156.155192 -16.263482) (xy 156.222173 -16.206408) (xy 156.294066 -16.15566)
			(xy 156.370275 -16.11166) (xy 156.45017 -16.074773) (xy 156.533089 -16.045304) (xy 156.618344 -16.023497)
			(xy 156.705228 -16.009533) (xy 156.793022 -16.003527) (xy 156.880999 -16.005531) (xy 156.968429 -16.015526)
			(xy 157.054588 -16.03343) (xy 157.138762 -16.059094) (xy 157.220253 -16.092307) (xy 157.298387 -16.132793)
			(xy 157.372515 -16.180215) (xy 157.442023 -16.234182) (xy 157.506337 -16.294247) (xy 157.564921 -16.359911)
			(xy 157.617292 -16.43063) (xy 157.663015 -16.505818) (xy 157.701712 -16.584853) (xy 157.733061 -16.667079)
			(xy 157.756803 -16.751815) (xy 157.772741 -16.838359) (xy 157.780743 -16.925994) (xy 157.781244 -16.969994)
			(xy 181.848259 -16.969994) (xy 181.852264 -16.882086) (xy 181.864247 -16.794906) (xy 181.884107 -16.709177)
			(xy 181.911682 -16.625609) (xy 181.946741 -16.544895) (xy 181.988994 -16.467703) (xy 182.038092 -16.394674)
			(xy 182.093628 -16.326412) (xy 182.15514 -16.263482) (xy 182.222121 -16.206408) (xy 182.294014 -16.15566)
			(xy 182.370223 -16.11166) (xy 182.450118 -16.074773) (xy 182.533037 -16.045304) (xy 182.618292 -16.023497)
			(xy 182.705176 -16.009533) (xy 182.79297 -16.003527) (xy 182.880947 -16.005531) (xy 182.968377 -16.015526)
			(xy 183.054536 -16.03343) (xy 183.13871 -16.059094) (xy 183.220201 -16.092307) (xy 183.298335 -16.132793)
			(xy 183.372463 -16.180215) (xy 183.441971 -16.234182) (xy 183.506285 -16.294247) (xy 183.564869 -16.359911)
			(xy 183.61724 -16.43063) (xy 183.662963 -16.505818) (xy 183.70166 -16.584853) (xy 183.733009 -16.667079)
			(xy 183.756751 -16.751815) (xy 183.772689 -16.838359) (xy 183.780691 -16.925994) (xy 183.781192 -16.969994)
			(xy 207.848207 -16.969994) (xy 207.852212 -16.882086) (xy 207.864195 -16.794906) (xy 207.884055 -16.709177)
			(xy 207.91163 -16.625609) (xy 207.946689 -16.544895) (xy 207.988942 -16.467703) (xy 208.03804 -16.394674)
			(xy 208.093576 -16.326412) (xy 208.155088 -16.263482) (xy 208.222069 -16.206408) (xy 208.293962 -16.15566)
			(xy 208.370171 -16.11166) (xy 208.450066 -16.074773) (xy 208.532985 -16.045304) (xy 208.61824 -16.023497)
			(xy 208.705124 -16.009533) (xy 208.792918 -16.003527) (xy 208.880895 -16.005531) (xy 208.968325 -16.015526)
			(xy 209.054484 -16.03343) (xy 209.138658 -16.059094) (xy 209.220149 -16.092307) (xy 209.298283 -16.132793)
			(xy 209.372411 -16.180215) (xy 209.441919 -16.234182) (xy 209.506233 -16.294247) (xy 209.564817 -16.359911)
			(xy 209.617188 -16.43063) (xy 209.662911 -16.505818) (xy 209.701608 -16.584853) (xy 209.732957 -16.667079)
			(xy 209.756699 -16.751815) (xy 209.772637 -16.838359) (xy 209.780639 -16.925994) (xy 209.78114 -16.969994)
			(xy 245.948207 -16.969994) (xy 245.952212 -16.882086) (xy 245.964195 -16.794906) (xy 245.984055 -16.709177)
			(xy 246.01163 -16.625609) (xy 246.046689 -16.544895) (xy 246.088942 -16.467703) (xy 246.13804 -16.394674)
			(xy 246.193576 -16.326412) (xy 246.255088 -16.263482) (xy 246.322069 -16.206408) (xy 246.393962 -16.15566)
			(xy 246.470171 -16.11166) (xy 246.550066 -16.074773) (xy 246.632985 -16.045304) (xy 246.71824 -16.023497)
			(xy 246.805124 -16.009533) (xy 246.892918 -16.003527) (xy 246.980895 -16.005531) (xy 247.068325 -16.015526)
			(xy 247.154484 -16.03343) (xy 247.238658 -16.059094) (xy 247.320149 -16.092307) (xy 247.398283 -16.132793)
			(xy 247.472411 -16.180215) (xy 247.541919 -16.234182) (xy 247.606233 -16.294247) (xy 247.664817 -16.359911)
			(xy 247.717188 -16.43063) (xy 247.762911 -16.505818) (xy 247.801608 -16.584853) (xy 247.832957 -16.667079)
			(xy 247.856699 -16.751815) (xy 247.872637 -16.838359) (xy 247.880639 -16.925994) (xy 247.88114 -16.969994)
			(xy 271.948155 -16.969994) (xy 271.95216 -16.882086) (xy 271.964143 -16.794906) (xy 271.984003 -16.709177)
			(xy 272.011578 -16.625609) (xy 272.046637 -16.544895) (xy 272.08889 -16.467703) (xy 272.137988 -16.394674)
			(xy 272.193524 -16.326412) (xy 272.255036 -16.263482) (xy 272.322017 -16.206408) (xy 272.39391 -16.15566)
			(xy 272.470119 -16.11166) (xy 272.550014 -16.074773) (xy 272.632933 -16.045304) (xy 272.718188 -16.023497)
			(xy 272.805072 -16.009533) (xy 272.892866 -16.003527) (xy 272.980843 -16.005531) (xy 273.068273 -16.015526)
			(xy 273.154432 -16.03343) (xy 273.238606 -16.059094) (xy 273.320097 -16.092307) (xy 273.398231 -16.132793)
			(xy 273.472359 -16.180215) (xy 273.541867 -16.234182) (xy 273.606181 -16.294247) (xy 273.664765 -16.359911)
			(xy 273.717136 -16.43063) (xy 273.762859 -16.505818) (xy 273.801556 -16.584853) (xy 273.832905 -16.667079)
			(xy 273.856647 -16.751815) (xy 273.872585 -16.838359) (xy 273.880587 -16.925994) (xy 273.881088 -16.969994)
			(xy 297.948103 -16.969994) (xy 297.952108 -16.882086) (xy 297.964091 -16.794906) (xy 297.983951 -16.709177)
			(xy 298.011526 -16.625609) (xy 298.046585 -16.544895) (xy 298.088838 -16.467703) (xy 298.137936 -16.394674)
			(xy 298.193472 -16.326412) (xy 298.254984 -16.263482) (xy 298.321965 -16.206408) (xy 298.393858 -16.15566)
			(xy 298.470067 -16.11166) (xy 298.549962 -16.074773) (xy 298.632881 -16.045304) (xy 298.718136 -16.023497)
			(xy 298.80502 -16.009533) (xy 298.892814 -16.003527) (xy 298.980791 -16.005531) (xy 299.068221 -16.015526)
			(xy 299.15438 -16.03343) (xy 299.238554 -16.059094) (xy 299.320045 -16.092307) (xy 299.398179 -16.132793)
			(xy 299.472307 -16.180215) (xy 299.541815 -16.234182) (xy 299.606129 -16.294247) (xy 299.664713 -16.359911)
			(xy 299.717084 -16.43063) (xy 299.762807 -16.505818) (xy 299.801504 -16.584853) (xy 299.832853 -16.667079)
			(xy 299.856595 -16.751815) (xy 299.872533 -16.838359) (xy 299.880535 -16.925994) (xy 299.881036 -16.969994)
			(xy 323.948051 -16.969994) (xy 323.952056 -16.882086) (xy 323.964039 -16.794906) (xy 323.983899 -16.709177)
			(xy 324.011474 -16.625609) (xy 324.046533 -16.544895) (xy 324.088786 -16.467703) (xy 324.137884 -16.394674)
			(xy 324.19342 -16.326412) (xy 324.254932 -16.263482) (xy 324.321913 -16.206408) (xy 324.393806 -16.15566)
			(xy 324.470015 -16.11166) (xy 324.54991 -16.074773) (xy 324.632829 -16.045304) (xy 324.718084 -16.023497)
			(xy 324.804968 -16.009533) (xy 324.892762 -16.003527) (xy 324.980739 -16.005531) (xy 325.068169 -16.015526)
			(xy 325.154328 -16.03343) (xy 325.238502 -16.059094) (xy 325.319993 -16.092307) (xy 325.398127 -16.132793)
			(xy 325.472255 -16.180215) (xy 325.541763 -16.234182) (xy 325.606077 -16.294247) (xy 325.664661 -16.359911)
			(xy 325.717032 -16.43063) (xy 325.762755 -16.505818) (xy 325.801452 -16.584853) (xy 325.832801 -16.667079)
			(xy 325.856543 -16.751815) (xy 325.872481 -16.838359) (xy 325.880483 -16.925994) (xy 325.880984 -16.969994)
			(xy 362.048305 -16.969994) (xy 362.05231 -16.882086) (xy 362.064293 -16.794906) (xy 362.084153 -16.709177)
			(xy 362.111728 -16.625609) (xy 362.146787 -16.544895) (xy 362.18904 -16.467703) (xy 362.238138 -16.394674)
			(xy 362.293674 -16.326412) (xy 362.355186 -16.263482) (xy 362.422167 -16.206408) (xy 362.49406 -16.15566)
			(xy 362.570269 -16.11166) (xy 362.650164 -16.074773) (xy 362.733083 -16.045304) (xy 362.818338 -16.023497)
			(xy 362.905222 -16.009533) (xy 362.993016 -16.003527) (xy 363.080993 -16.005531) (xy 363.168423 -16.015526)
			(xy 363.254582 -16.03343) (xy 363.338756 -16.059094) (xy 363.420247 -16.092307) (xy 363.498381 -16.132793)
			(xy 363.572509 -16.180215) (xy 363.642017 -16.234182) (xy 363.706331 -16.294247) (xy 363.764915 -16.359911)
			(xy 363.817286 -16.43063) (xy 363.863009 -16.505818) (xy 363.901706 -16.584853) (xy 363.933055 -16.667079)
			(xy 363.956797 -16.751815) (xy 363.972735 -16.838359) (xy 363.980737 -16.925994) (xy 363.981238 -16.969994)
			(xy 388.048253 -16.969994) (xy 388.052258 -16.882086) (xy 388.064241 -16.794906) (xy 388.084101 -16.709177)
			(xy 388.111676 -16.625609) (xy 388.146735 -16.544895) (xy 388.188988 -16.467703) (xy 388.238086 -16.394674)
			(xy 388.293622 -16.326412) (xy 388.355134 -16.263482) (xy 388.422115 -16.206408) (xy 388.494008 -16.15566)
			(xy 388.570217 -16.11166) (xy 388.650112 -16.074773) (xy 388.733031 -16.045304) (xy 388.818286 -16.023497)
			(xy 388.90517 -16.009533) (xy 388.992964 -16.003527) (xy 389.080941 -16.005531) (xy 389.168371 -16.015526)
			(xy 389.25453 -16.03343) (xy 389.338704 -16.059094) (xy 389.420195 -16.092307) (xy 389.498329 -16.132793)
			(xy 389.572457 -16.180215) (xy 389.641965 -16.234182) (xy 389.706279 -16.294247) (xy 389.764863 -16.359911)
			(xy 389.817234 -16.43063) (xy 389.862957 -16.505818) (xy 389.901654 -16.584853) (xy 389.933003 -16.667079)
			(xy 389.956745 -16.751815) (xy 389.972683 -16.838359) (xy 389.980685 -16.925994) (xy 389.981186 -16.969994)
			(xy 414.048201 -16.969994) (xy 414.052206 -16.882086) (xy 414.064189 -16.794906) (xy 414.084049 -16.709177)
			(xy 414.111624 -16.625609) (xy 414.146683 -16.544895) (xy 414.188936 -16.467703) (xy 414.238034 -16.394674)
			(xy 414.29357 -16.326412) (xy 414.355082 -16.263482) (xy 414.422063 -16.206408) (xy 414.493956 -16.15566)
			(xy 414.570165 -16.11166) (xy 414.65006 -16.074773) (xy 414.732979 -16.045304) (xy 414.818234 -16.023497)
			(xy 414.905118 -16.009533) (xy 414.992912 -16.003527) (xy 415.080889 -16.005531) (xy 415.168319 -16.015526)
			(xy 415.254478 -16.03343) (xy 415.338652 -16.059094) (xy 415.420143 -16.092307) (xy 415.498277 -16.132793)
			(xy 415.572405 -16.180215) (xy 415.641913 -16.234182) (xy 415.706227 -16.294247) (xy 415.764811 -16.359911)
			(xy 415.817182 -16.43063) (xy 415.862905 -16.505818) (xy 415.901602 -16.584853) (xy 415.932951 -16.667079)
			(xy 415.956693 -16.751815) (xy 415.972631 -16.838359) (xy 415.980633 -16.925994) (xy 415.981134 -16.969994)
			(xy 440.048149 -16.969994) (xy 440.052154 -16.882086) (xy 440.064137 -16.794906) (xy 440.083997 -16.709177)
			(xy 440.111572 -16.625609) (xy 440.146631 -16.544895) (xy 440.188884 -16.467703) (xy 440.237982 -16.394674)
			(xy 440.293518 -16.326412) (xy 440.35503 -16.263482) (xy 440.422011 -16.206408) (xy 440.493904 -16.15566)
			(xy 440.570113 -16.11166) (xy 440.650008 -16.074773) (xy 440.732927 -16.045304) (xy 440.818182 -16.023497)
			(xy 440.905066 -16.009533) (xy 440.99286 -16.003527) (xy 441.080837 -16.005531) (xy 441.168267 -16.015526)
			(xy 441.254426 -16.03343) (xy 441.3386 -16.059094) (xy 441.420091 -16.092307) (xy 441.498225 -16.132793)
			(xy 441.572353 -16.180215) (xy 441.641861 -16.234182) (xy 441.706175 -16.294247) (xy 441.764759 -16.359911)
			(xy 441.81713 -16.43063) (xy 441.862853 -16.505818) (xy 441.90155 -16.584853) (xy 441.932899 -16.667079)
			(xy 441.956641 -16.751815) (xy 441.972579 -16.838359) (xy 441.980581 -16.925994) (xy 441.981082 -16.969994)
			(xy 441.980581 -17.013994) (xy 441.972579 -17.101629) (xy 441.956641 -17.188173) (xy 441.932899 -17.272909)
			(xy 441.90155 -17.355135) (xy 441.862853 -17.43417) (xy 441.81713 -17.509358) (xy 441.764759 -17.580077)
			(xy 441.706175 -17.645741) (xy 441.641861 -17.705806) (xy 441.572353 -17.759773) (xy 441.498225 -17.807195)
			(xy 441.420091 -17.847681) (xy 441.3386 -17.880894) (xy 441.254426 -17.906558) (xy 441.168267 -17.924462)
			(xy 441.080837 -17.934457) (xy 440.99286 -17.936461) (xy 440.905066 -17.930455) (xy 440.818182 -17.916491)
			(xy 440.732927 -17.894684) (xy 440.650008 -17.865215) (xy 440.570113 -17.828328) (xy 440.493904 -17.784328)
			(xy 440.422011 -17.73358) (xy 440.35503 -17.676506) (xy 440.293518 -17.613576) (xy 440.237982 -17.545314)
			(xy 440.188884 -17.472285) (xy 440.146631 -17.395093) (xy 440.111572 -17.314379) (xy 440.083997 -17.230811)
			(xy 440.064137 -17.145082) (xy 440.052154 -17.057902) (xy 440.048149 -16.969994) (xy 415.981134 -16.969994)
			(xy 415.980633 -17.013994) (xy 415.972631 -17.101629) (xy 415.956693 -17.188173) (xy 415.932951 -17.272909)
			(xy 415.901602 -17.355135) (xy 415.862905 -17.43417) (xy 415.817182 -17.509358) (xy 415.764811 -17.580077)
			(xy 415.706227 -17.645741) (xy 415.641913 -17.705806) (xy 415.572405 -17.759773) (xy 415.498277 -17.807195)
			(xy 415.420143 -17.847681) (xy 415.338652 -17.880894) (xy 415.254478 -17.906558) (xy 415.168319 -17.924462)
			(xy 415.080889 -17.934457) (xy 414.992912 -17.936461) (xy 414.905118 -17.930455) (xy 414.818234 -17.916491)
			(xy 414.732979 -17.894684) (xy 414.65006 -17.865215) (xy 414.570165 -17.828328) (xy 414.493956 -17.784328)
			(xy 414.422063 -17.73358) (xy 414.355082 -17.676506) (xy 414.29357 -17.613576) (xy 414.238034 -17.545314)
			(xy 414.188936 -17.472285) (xy 414.146683 -17.395093) (xy 414.111624 -17.314379) (xy 414.084049 -17.230811)
			(xy 414.064189 -17.145082) (xy 414.052206 -17.057902) (xy 414.048201 -16.969994) (xy 389.981186 -16.969994)
			(xy 389.980685 -17.013994) (xy 389.972683 -17.101629) (xy 389.956745 -17.188173) (xy 389.933003 -17.272909)
			(xy 389.901654 -17.355135) (xy 389.862957 -17.43417) (xy 389.817234 -17.509358) (xy 389.764863 -17.580077)
			(xy 389.706279 -17.645741) (xy 389.641965 -17.705806) (xy 389.572457 -17.759773) (xy 389.498329 -17.807195)
			(xy 389.420195 -17.847681) (xy 389.338704 -17.880894) (xy 389.25453 -17.906558) (xy 389.168371 -17.924462)
			(xy 389.080941 -17.934457) (xy 388.992964 -17.936461) (xy 388.90517 -17.930455) (xy 388.818286 -17.916491)
			(xy 388.733031 -17.894684) (xy 388.650112 -17.865215) (xy 388.570217 -17.828328) (xy 388.494008 -17.784328)
			(xy 388.422115 -17.73358) (xy 388.355134 -17.676506) (xy 388.293622 -17.613576) (xy 388.238086 -17.545314)
			(xy 388.188988 -17.472285) (xy 388.146735 -17.395093) (xy 388.111676 -17.314379) (xy 388.084101 -17.230811)
			(xy 388.064241 -17.145082) (xy 388.052258 -17.057902) (xy 388.048253 -16.969994) (xy 363.981238 -16.969994)
			(xy 363.980737 -17.013994) (xy 363.972735 -17.101629) (xy 363.956797 -17.188173) (xy 363.933055 -17.272909)
			(xy 363.901706 -17.355135) (xy 363.863009 -17.43417) (xy 363.817286 -17.509358) (xy 363.764915 -17.580077)
			(xy 363.706331 -17.645741) (xy 363.642017 -17.705806) (xy 363.572509 -17.759773) (xy 363.498381 -17.807195)
			(xy 363.420247 -17.847681) (xy 363.338756 -17.880894) (xy 363.254582 -17.906558) (xy 363.168423 -17.924462)
			(xy 363.080993 -17.934457) (xy 362.993016 -17.936461) (xy 362.905222 -17.930455) (xy 362.818338 -17.916491)
			(xy 362.733083 -17.894684) (xy 362.650164 -17.865215) (xy 362.570269 -17.828328) (xy 362.49406 -17.784328)
			(xy 362.422167 -17.73358) (xy 362.355186 -17.676506) (xy 362.293674 -17.613576) (xy 362.238138 -17.545314)
			(xy 362.18904 -17.472285) (xy 362.146787 -17.395093) (xy 362.111728 -17.314379) (xy 362.084153 -17.230811)
			(xy 362.064293 -17.145082) (xy 362.05231 -17.057902) (xy 362.048305 -16.969994) (xy 325.880984 -16.969994)
			(xy 325.880483 -17.013994) (xy 325.872481 -17.101629) (xy 325.856543 -17.188173) (xy 325.832801 -17.272909)
			(xy 325.801452 -17.355135) (xy 325.762755 -17.43417) (xy 325.717032 -17.509358) (xy 325.664661 -17.580077)
			(xy 325.606077 -17.645741) (xy 325.541763 -17.705806) (xy 325.472255 -17.759773) (xy 325.398127 -17.807195)
			(xy 325.319993 -17.847681) (xy 325.238502 -17.880894) (xy 325.154328 -17.906558) (xy 325.068169 -17.924462)
			(xy 324.980739 -17.934457) (xy 324.892762 -17.936461) (xy 324.804968 -17.930455) (xy 324.718084 -17.916491)
			(xy 324.632829 -17.894684) (xy 324.54991 -17.865215) (xy 324.470015 -17.828328) (xy 324.393806 -17.784328)
			(xy 324.321913 -17.73358) (xy 324.254932 -17.676506) (xy 324.19342 -17.613576) (xy 324.137884 -17.545314)
			(xy 324.088786 -17.472285) (xy 324.046533 -17.395093) (xy 324.011474 -17.314379) (xy 323.983899 -17.230811)
			(xy 323.964039 -17.145082) (xy 323.952056 -17.057902) (xy 323.948051 -16.969994) (xy 299.881036 -16.969994)
			(xy 299.880535 -17.013994) (xy 299.872533 -17.101629) (xy 299.856595 -17.188173) (xy 299.832853 -17.272909)
			(xy 299.801504 -17.355135) (xy 299.762807 -17.43417) (xy 299.717084 -17.509358) (xy 299.664713 -17.580077)
			(xy 299.606129 -17.645741) (xy 299.541815 -17.705806) (xy 299.472307 -17.759773) (xy 299.398179 -17.807195)
			(xy 299.320045 -17.847681) (xy 299.238554 -17.880894) (xy 299.15438 -17.906558) (xy 299.068221 -17.924462)
			(xy 298.980791 -17.934457) (xy 298.892814 -17.936461) (xy 298.80502 -17.930455) (xy 298.718136 -17.916491)
			(xy 298.632881 -17.894684) (xy 298.549962 -17.865215) (xy 298.470067 -17.828328) (xy 298.393858 -17.784328)
			(xy 298.321965 -17.73358) (xy 298.254984 -17.676506) (xy 298.193472 -17.613576) (xy 298.137936 -17.545314)
			(xy 298.088838 -17.472285) (xy 298.046585 -17.395093) (xy 298.011526 -17.314379) (xy 297.983951 -17.230811)
			(xy 297.964091 -17.145082) (xy 297.952108 -17.057902) (xy 297.948103 -16.969994) (xy 273.881088 -16.969994)
			(xy 273.880587 -17.013994) (xy 273.872585 -17.101629) (xy 273.856647 -17.188173) (xy 273.832905 -17.272909)
			(xy 273.801556 -17.355135) (xy 273.762859 -17.43417) (xy 273.717136 -17.509358) (xy 273.664765 -17.580077)
			(xy 273.606181 -17.645741) (xy 273.541867 -17.705806) (xy 273.472359 -17.759773) (xy 273.398231 -17.807195)
			(xy 273.320097 -17.847681) (xy 273.238606 -17.880894) (xy 273.154432 -17.906558) (xy 273.068273 -17.924462)
			(xy 272.980843 -17.934457) (xy 272.892866 -17.936461) (xy 272.805072 -17.930455) (xy 272.718188 -17.916491)
			(xy 272.632933 -17.894684) (xy 272.550014 -17.865215) (xy 272.470119 -17.828328) (xy 272.39391 -17.784328)
			(xy 272.322017 -17.73358) (xy 272.255036 -17.676506) (xy 272.193524 -17.613576) (xy 272.137988 -17.545314)
			(xy 272.08889 -17.472285) (xy 272.046637 -17.395093) (xy 272.011578 -17.314379) (xy 271.984003 -17.230811)
			(xy 271.964143 -17.145082) (xy 271.95216 -17.057902) (xy 271.948155 -16.969994) (xy 247.88114 -16.969994)
			(xy 247.880639 -17.013994) (xy 247.872637 -17.101629) (xy 247.856699 -17.188173) (xy 247.832957 -17.272909)
			(xy 247.801608 -17.355135) (xy 247.762911 -17.43417) (xy 247.717188 -17.509358) (xy 247.664817 -17.580077)
			(xy 247.606233 -17.645741) (xy 247.541919 -17.705806) (xy 247.472411 -17.759773) (xy 247.398283 -17.807195)
			(xy 247.320149 -17.847681) (xy 247.238658 -17.880894) (xy 247.154484 -17.906558) (xy 247.068325 -17.924462)
			(xy 246.980895 -17.934457) (xy 246.892918 -17.936461) (xy 246.805124 -17.930455) (xy 246.71824 -17.916491)
			(xy 246.632985 -17.894684) (xy 246.550066 -17.865215) (xy 246.470171 -17.828328) (xy 246.393962 -17.784328)
			(xy 246.322069 -17.73358) (xy 246.255088 -17.676506) (xy 246.193576 -17.613576) (xy 246.13804 -17.545314)
			(xy 246.088942 -17.472285) (xy 246.046689 -17.395093) (xy 246.01163 -17.314379) (xy 245.984055 -17.230811)
			(xy 245.964195 -17.145082) (xy 245.952212 -17.057902) (xy 245.948207 -16.969994) (xy 209.78114 -16.969994)
			(xy 209.780639 -17.013994) (xy 209.772637 -17.101629) (xy 209.756699 -17.188173) (xy 209.732957 -17.272909)
			(xy 209.701608 -17.355135) (xy 209.662911 -17.43417) (xy 209.617188 -17.509358) (xy 209.564817 -17.580077)
			(xy 209.506233 -17.645741) (xy 209.441919 -17.705806) (xy 209.372411 -17.759773) (xy 209.298283 -17.807195)
			(xy 209.220149 -17.847681) (xy 209.138658 -17.880894) (xy 209.054484 -17.906558) (xy 208.968325 -17.924462)
			(xy 208.880895 -17.934457) (xy 208.792918 -17.936461) (xy 208.705124 -17.930455) (xy 208.61824 -17.916491)
			(xy 208.532985 -17.894684) (xy 208.450066 -17.865215) (xy 208.370171 -17.828328) (xy 208.293962 -17.784328)
			(xy 208.222069 -17.73358) (xy 208.155088 -17.676506) (xy 208.093576 -17.613576) (xy 208.03804 -17.545314)
			(xy 207.988942 -17.472285) (xy 207.946689 -17.395093) (xy 207.91163 -17.314379) (xy 207.884055 -17.230811)
			(xy 207.864195 -17.145082) (xy 207.852212 -17.057902) (xy 207.848207 -16.969994) (xy 183.781192 -16.969994)
			(xy 183.780691 -17.013994) (xy 183.772689 -17.101629) (xy 183.756751 -17.188173) (xy 183.733009 -17.272909)
			(xy 183.70166 -17.355135) (xy 183.662963 -17.43417) (xy 183.61724 -17.509358) (xy 183.564869 -17.580077)
			(xy 183.506285 -17.645741) (xy 183.441971 -17.705806) (xy 183.372463 -17.759773) (xy 183.298335 -17.807195)
			(xy 183.220201 -17.847681) (xy 183.13871 -17.880894) (xy 183.054536 -17.906558) (xy 182.968377 -17.924462)
			(xy 182.880947 -17.934457) (xy 182.79297 -17.936461) (xy 182.705176 -17.930455) (xy 182.618292 -17.916491)
			(xy 182.533037 -17.894684) (xy 182.450118 -17.865215) (xy 182.370223 -17.828328) (xy 182.294014 -17.784328)
			(xy 182.222121 -17.73358) (xy 182.15514 -17.676506) (xy 182.093628 -17.613576) (xy 182.038092 -17.545314)
			(xy 181.988994 -17.472285) (xy 181.946741 -17.395093) (xy 181.911682 -17.314379) (xy 181.884107 -17.230811)
			(xy 181.864247 -17.145082) (xy 181.852264 -17.057902) (xy 181.848259 -16.969994) (xy 157.781244 -16.969994)
			(xy 157.780743 -17.013994) (xy 157.772741 -17.101629) (xy 157.756803 -17.188173) (xy 157.733061 -17.272909)
			(xy 157.701712 -17.355135) (xy 157.663015 -17.43417) (xy 157.617292 -17.509358) (xy 157.564921 -17.580077)
			(xy 157.506337 -17.645741) (xy 157.442023 -17.705806) (xy 157.372515 -17.759773) (xy 157.298387 -17.807195)
			(xy 157.220253 -17.847681) (xy 157.138762 -17.880894) (xy 157.054588 -17.906558) (xy 156.968429 -17.924462)
			(xy 156.880999 -17.934457) (xy 156.793022 -17.936461) (xy 156.705228 -17.930455) (xy 156.618344 -17.916491)
			(xy 156.533089 -17.894684) (xy 156.45017 -17.865215) (xy 156.370275 -17.828328) (xy 156.294066 -17.784328)
			(xy 156.222173 -17.73358) (xy 156.155192 -17.676506) (xy 156.09368 -17.613576) (xy 156.038144 -17.545314)
			(xy 155.989046 -17.472285) (xy 155.946793 -17.395093) (xy 155.911734 -17.314379) (xy 155.884159 -17.230811)
			(xy 155.864299 -17.145082) (xy 155.852316 -17.057902) (xy 155.848311 -16.969994) (xy 131.781296 -16.969994)
			(xy 131.780795 -17.013994) (xy 131.772793 -17.101629) (xy 131.756855 -17.188173) (xy 131.733113 -17.272909)
			(xy 131.701764 -17.355135) (xy 131.663067 -17.43417) (xy 131.617344 -17.509358) (xy 131.564973 -17.580077)
			(xy 131.506389 -17.645741) (xy 131.442075 -17.705806) (xy 131.372567 -17.759773) (xy 131.298439 -17.807195)
			(xy 131.220305 -17.847681) (xy 131.138814 -17.880894) (xy 131.05464 -17.906558) (xy 130.968481 -17.924462)
			(xy 130.881051 -17.934457) (xy 130.793074 -17.936461) (xy 130.70528 -17.930455) (xy 130.618396 -17.916491)
			(xy 130.533141 -17.894684) (xy 130.450222 -17.865215) (xy 130.370327 -17.828328) (xy 130.294118 -17.784328)
			(xy 130.222225 -17.73358) (xy 130.155244 -17.676506) (xy 130.093732 -17.613576) (xy 130.038196 -17.545314)
			(xy 129.989098 -17.472285) (xy 129.946845 -17.395093) (xy 129.911786 -17.314379) (xy 129.884211 -17.230811)
			(xy 129.864351 -17.145082) (xy 129.852368 -17.057902) (xy 129.848363 -16.969994) (xy 93.681042 -16.969994)
			(xy 93.680541 -17.013994) (xy 93.672539 -17.101629) (xy 93.656601 -17.188173) (xy 93.632859 -17.272909)
			(xy 93.60151 -17.355135) (xy 93.562813 -17.43417) (xy 93.51709 -17.509358) (xy 93.464719 -17.580077)
			(xy 93.406135 -17.645741) (xy 93.341821 -17.705806) (xy 93.272313 -17.759773) (xy 93.198185 -17.807195)
			(xy 93.120051 -17.847681) (xy 93.03856 -17.880894) (xy 92.954386 -17.906558) (xy 92.868227 -17.924462)
			(xy 92.780797 -17.934457) (xy 92.69282 -17.936461) (xy 92.605026 -17.930455) (xy 92.518142 -17.916491)
			(xy 92.432887 -17.894684) (xy 92.349968 -17.865215) (xy 92.270073 -17.828328) (xy 92.193864 -17.784328)
			(xy 92.121971 -17.73358) (xy 92.05499 -17.676506) (xy 91.993478 -17.613576) (xy 91.937942 -17.545314)
			(xy 91.888844 -17.472285) (xy 91.846591 -17.395093) (xy 91.811532 -17.314379) (xy 91.783957 -17.230811)
			(xy 91.764097 -17.145082) (xy 91.752114 -17.057902) (xy 91.748109 -16.969994) (xy 67.681094 -16.969994)
			(xy 67.680593 -17.013994) (xy 67.672591 -17.101629) (xy 67.656653 -17.188173) (xy 67.632911 -17.272909)
			(xy 67.601562 -17.355135) (xy 67.562865 -17.43417) (xy 67.517142 -17.509358) (xy 67.464771 -17.580077)
			(xy 67.406187 -17.645741) (xy 67.341873 -17.705806) (xy 67.272365 -17.759773) (xy 67.198237 -17.807195)
			(xy 67.120103 -17.847681) (xy 67.038612 -17.880894) (xy 66.954438 -17.906558) (xy 66.868279 -17.924462)
			(xy 66.780849 -17.934457) (xy 66.692872 -17.936461) (xy 66.605078 -17.930455) (xy 66.518194 -17.916491)
			(xy 66.432939 -17.894684) (xy 66.35002 -17.865215) (xy 66.270125 -17.828328) (xy 66.193916 -17.784328)
			(xy 66.122023 -17.73358) (xy 66.055042 -17.676506) (xy 65.99353 -17.613576) (xy 65.937994 -17.545314)
			(xy 65.888896 -17.472285) (xy 65.846643 -17.395093) (xy 65.811584 -17.314379) (xy 65.784009 -17.230811)
			(xy 65.764149 -17.145082) (xy 65.752166 -17.057902) (xy 65.748161 -16.969994) (xy 41.681146 -16.969994)
			(xy 41.680645 -17.013994) (xy 41.672643 -17.101629) (xy 41.656705 -17.188173) (xy 41.632963 -17.272909)
			(xy 41.601614 -17.355135) (xy 41.562917 -17.43417) (xy 41.517194 -17.509358) (xy 41.464823 -17.580077)
			(xy 41.406239 -17.645741) (xy 41.341925 -17.705806) (xy 41.272417 -17.759773) (xy 41.198289 -17.807195)
			(xy 41.120155 -17.847681) (xy 41.038664 -17.880894) (xy 40.95449 -17.906558) (xy 40.868331 -17.924462)
			(xy 40.780901 -17.934457) (xy 40.692924 -17.936461) (xy 40.60513 -17.930455) (xy 40.518246 -17.916491)
			(xy 40.432991 -17.894684) (xy 40.350072 -17.865215) (xy 40.270177 -17.828328) (xy 40.193968 -17.784328)
			(xy 40.122075 -17.73358) (xy 40.055094 -17.676506) (xy 39.993582 -17.613576) (xy 39.938046 -17.545314)
			(xy 39.888948 -17.472285) (xy 39.846695 -17.395093) (xy 39.811636 -17.314379) (xy 39.784061 -17.230811)
			(xy 39.764201 -17.145082) (xy 39.752218 -17.057902) (xy 39.748213 -16.969994) (xy 15.681198 -16.969994)
			(xy 15.680697 -17.013994) (xy 15.672695 -17.101629) (xy 15.656757 -17.188173) (xy 15.633015 -17.272909)
			(xy 15.601666 -17.355135) (xy 15.562969 -17.43417) (xy 15.517246 -17.509358) (xy 15.464875 -17.580077)
			(xy 15.406291 -17.645741) (xy 15.341977 -17.705806) (xy 15.272469 -17.759773) (xy 15.198341 -17.807195)
			(xy 15.120207 -17.847681) (xy 15.038716 -17.880894) (xy 14.954542 -17.906558) (xy 14.868383 -17.924462)
			(xy 14.780953 -17.934457) (xy 14.692976 -17.936461) (xy 14.605182 -17.930455) (xy 14.518298 -17.916491)
			(xy 14.433043 -17.894684) (xy 14.350124 -17.865215) (xy 14.270229 -17.828328) (xy 14.19402 -17.784328)
			(xy 14.122127 -17.73358) (xy 14.055146 -17.676506) (xy 13.993634 -17.613576) (xy 13.938098 -17.545314)
			(xy 13.889 -17.472285) (xy 13.846747 -17.395093) (xy 13.811688 -17.314379) (xy 13.784113 -17.230811)
			(xy 13.764253 -17.145082) (xy 13.75227 -17.057902) (xy 13.748265 -16.969994) (xy 0.509016 -16.969994)
			(xy 0.509016 -27.405838) (xy 14.565884 -27.405838) (xy 14.565884 -26.37409) (xy 14.56632 -26.363957)
			(xy 14.574059 -26.345228) (xy 14.588361 -26.33087) (xy 14.607061 -26.323059) (xy 14.617192 -26.322528)
			(xy 15.849092 -26.322528) (xy 15.859249 -26.322929) (xy 15.878007 -26.330727) (xy 15.892331 -26.34513)
			(xy 15.900026 -26.363931) (xy 15.9004 -26.37409) (xy 15.9004 -27.342846) (xy 16.523716 -27.342846)
			(xy 16.523716 -26.479246) (xy 16.524206 -26.449278) (xy 16.532029 -26.389856) (xy 16.547542 -26.331963)
			(xy 16.570478 -26.27659) (xy 16.600445 -26.224684) (xy 16.636932 -26.177134) (xy 16.679312 -26.134754)
			(xy 16.726862 -26.098267) (xy 16.778768 -26.0683) (xy 16.834141 -26.045364) (xy 16.892034 -26.029851)
			(xy 16.951456 -26.022028) (xy 17.011392 -26.022028) (xy 17.070814 -26.029851) (xy 17.128707 -26.045364)
			(xy 17.18408 -26.0683) (xy 17.235986 -26.098267) (xy 17.283536 -26.134754) (xy 17.325916 -26.177134)
			(xy 17.362403 -26.224684) (xy 17.39237 -26.27659) (xy 17.415306 -26.331963) (xy 17.430819 -26.389856)
			(xy 17.438642 -26.449278) (xy 17.439132 -26.479246) (xy 17.439132 -27.342846) (xy 17.438642 -27.372814)
			(xy 17.434294 -27.405838) (xy 40.565832 -27.405838) (xy 40.565832 -26.37409) (xy 40.566318 -26.363964)
			(xy 40.574048 -26.345244) (xy 40.588334 -26.330888) (xy 40.607016 -26.323068) (xy 40.61714 -26.322528)
			(xy 41.84904 -26.322528) (xy 41.8592 -26.322889) (xy 41.877959 -26.330703) (xy 41.892282 -26.345119)
			(xy 41.899975 -26.363927) (xy 41.900348 -26.37409) (xy 41.900348 -27.342846) (xy 42.523664 -27.342846)
			(xy 42.523664 -26.479246) (xy 42.524154 -26.449278) (xy 42.531977 -26.389856) (xy 42.54749 -26.331963)
			(xy 42.570426 -26.27659) (xy 42.600393 -26.224684) (xy 42.63688 -26.177134) (xy 42.67926 -26.134754)
			(xy 42.72681 -26.098267) (xy 42.778716 -26.0683) (xy 42.834089 -26.045364) (xy 42.891982 -26.029851)
			(xy 42.951404 -26.022028) (xy 43.01134 -26.022028) (xy 43.070762 -26.029851) (xy 43.128655 -26.045364)
			(xy 43.184028 -26.0683) (xy 43.235934 -26.098267) (xy 43.283484 -26.134754) (xy 43.325864 -26.177134)
			(xy 43.362351 -26.224684) (xy 43.392318 -26.27659) (xy 43.415254 -26.331963) (xy 43.430767 -26.389856)
			(xy 43.43859 -26.449278) (xy 43.43908 -26.479246) (xy 43.43908 -27.342846) (xy 43.43859 -27.372814)
			(xy 43.434242 -27.405838) (xy 66.56578 -27.405838) (xy 66.56578 -26.37409) (xy 66.56622 -26.363958)
			(xy 66.573958 -26.345229) (xy 66.588259 -26.330872) (xy 66.606958 -26.32306) (xy 66.617088 -26.322528)
			(xy 67.848988 -26.322528) (xy 67.859145 -26.322932) (xy 67.877902 -26.330729) (xy 67.892227 -26.345131)
			(xy 67.899922 -26.363931) (xy 67.900296 -26.37409) (xy 67.900296 -27.342846) (xy 68.523612 -27.342846)
			(xy 68.523612 -26.479246) (xy 68.524102 -26.449278) (xy 68.531925 -26.389856) (xy 68.547438 -26.331963)
			(xy 68.570374 -26.27659) (xy 68.600341 -26.224684) (xy 68.636828 -26.177134) (xy 68.679208 -26.134754)
			(xy 68.726758 -26.098267) (xy 68.778664 -26.0683) (xy 68.834037 -26.045364) (xy 68.89193 -26.029851)
			(xy 68.951352 -26.022028) (xy 69.011288 -26.022028) (xy 69.07071 -26.029851) (xy 69.128603 -26.045364)
			(xy 69.183976 -26.0683) (xy 69.235882 -26.098267) (xy 69.283432 -26.134754) (xy 69.325812 -26.177134)
			(xy 69.362299 -26.224684) (xy 69.392266 -26.27659) (xy 69.415202 -26.331963) (xy 69.430715 -26.389856)
			(xy 69.438538 -26.449278) (xy 69.439028 -26.479246) (xy 69.439028 -27.342846) (xy 69.438538 -27.372814)
			(xy 69.43419 -27.405838) (xy 92.565728 -27.405838) (xy 92.565728 -26.37409) (xy 92.566218 -26.363964)
			(xy 92.573947 -26.345245) (xy 92.588232 -26.33089) (xy 92.606913 -26.323069) (xy 92.617036 -26.322528)
			(xy 93.848936 -26.322528) (xy 93.859096 -26.322893) (xy 93.877855 -26.330705) (xy 93.892178 -26.34512)
			(xy 93.899871 -26.363927) (xy 93.900244 -26.37409) (xy 93.900244 -27.342846) (xy 94.52356 -27.342846)
			(xy 94.52356 -26.479246) (xy 94.52405 -26.449278) (xy 94.531873 -26.389856) (xy 94.547386 -26.331963)
			(xy 94.570322 -26.27659) (xy 94.600289 -26.224684) (xy 94.636776 -26.177134) (xy 94.679156 -26.134754)
			(xy 94.726706 -26.098267) (xy 94.778612 -26.0683) (xy 94.833985 -26.045364) (xy 94.891878 -26.029851)
			(xy 94.9513 -26.022028) (xy 95.011236 -26.022028) (xy 95.070658 -26.029851) (xy 95.128551 -26.045364)
			(xy 95.183924 -26.0683) (xy 95.23583 -26.098267) (xy 95.28338 -26.134754) (xy 95.32576 -26.177134)
			(xy 95.362247 -26.224684) (xy 95.392214 -26.27659) (xy 95.41515 -26.331963) (xy 95.430663 -26.389856)
			(xy 95.438486 -26.449278) (xy 95.438976 -26.479246) (xy 95.438976 -27.342846) (xy 95.438486 -27.372814)
			(xy 95.434138 -27.405838) (xy 130.665728 -27.405838) (xy 130.665728 -26.37409) (xy 130.666225 -26.363933)
			(xy 130.674001 -26.345165) (xy 130.688365 -26.330801) (xy 130.707133 -26.323025) (xy 130.71729 -26.322528)
			(xy 131.94919 -26.322528) (xy 131.959346 -26.323041) (xy 131.978113 -26.330811) (xy 131.992478 -26.34517)
			(xy 132.000255 -26.363934) (xy 132.000752 -26.37409) (xy 132.000752 -27.342846) (xy 132.62356 -27.342846)
			(xy 132.62356 -26.479246) (xy 132.62405 -26.449262) (xy 132.631878 -26.389806) (xy 132.647399 -26.331881)
			(xy 132.670348 -26.276477) (xy 132.700332 -26.224543) (xy 132.736838 -26.176967) (xy 132.779243 -26.134562)
			(xy 132.826819 -26.098056) (xy 132.878753 -26.068072) (xy 132.934157 -26.045123) (xy 132.992082 -26.029602)
			(xy 133.051538 -26.021774) (xy 133.111506 -26.021774) (xy 133.170962 -26.029602) (xy 133.228887 -26.045123)
			(xy 133.284291 -26.068072) (xy 133.336225 -26.098056) (xy 133.383801 -26.134562) (xy 133.426206 -26.176967)
			(xy 133.462712 -26.224543) (xy 133.492696 -26.276477) (xy 133.515645 -26.331881) (xy 133.531166 -26.389806)
			(xy 133.538994 -26.449262) (xy 133.539484 -26.479246) (xy 133.539484 -27.342846) (xy 133.538994 -27.37283)
			(xy 133.534648 -27.405838) (xy 156.665676 -27.405838) (xy 156.665676 -26.37409) (xy 156.666057 -26.363913)
			(xy 156.673852 -26.345111) (xy 156.688251 -26.330725) (xy 156.707061 -26.322947) (xy 156.717238 -26.322528)
			(xy 157.949138 -26.322528) (xy 157.959297 -26.323002) (xy 157.978065 -26.330787) (xy 157.992429 -26.345158)
			(xy 158.000204 -26.363931) (xy 158.0007 -26.37409) (xy 158.0007 -27.342846) (xy 158.623508 -27.342846)
			(xy 158.623508 -26.479246) (xy 158.623998 -26.449262) (xy 158.631826 -26.389806) (xy 158.647347 -26.331881)
			(xy 158.670296 -26.276477) (xy 158.70028 -26.224543) (xy 158.736786 -26.176967) (xy 158.779191 -26.134562)
			(xy 158.826767 -26.098056) (xy 158.878701 -26.068072) (xy 158.934105 -26.045123) (xy 158.99203 -26.029602)
			(xy 159.051486 -26.021774) (xy 159.111454 -26.021774) (xy 159.17091 -26.029602) (xy 159.228835 -26.045123)
			(xy 159.284239 -26.068072) (xy 159.336173 -26.098056) (xy 159.383749 -26.134562) (xy 159.426154 -26.176967)
			(xy 159.46266 -26.224543) (xy 159.492644 -26.276477) (xy 159.515593 -26.331881) (xy 159.531114 -26.389806)
			(xy 159.538942 -26.449262) (xy 159.539432 -26.479246) (xy 159.539432 -27.342846) (xy 159.538942 -27.37283)
			(xy 159.534596 -27.405838) (xy 182.665624 -27.405838) (xy 182.665624 -26.37409) (xy 182.666125 -26.363933)
			(xy 182.6739 -26.345167) (xy 182.688263 -26.330802) (xy 182.707029 -26.323026) (xy 182.717186 -26.322528)
			(xy 183.949086 -26.322528) (xy 183.959256 -26.322975) (xy 183.978048 -26.330753) (xy 183.992433 -26.345132)
			(xy 184.00022 -26.363921) (xy 184.000648 -26.37409) (xy 184.000648 -27.342846) (xy 184.623456 -27.342846)
			(xy 184.623456 -26.479246) (xy 184.623946 -26.449262) (xy 184.631774 -26.389806) (xy 184.647295 -26.331881)
			(xy 184.670244 -26.276477) (xy 184.700228 -26.224543) (xy 184.736734 -26.176967) (xy 184.779139 -26.134562)
			(xy 184.826715 -26.098056) (xy 184.878649 -26.068072) (xy 184.934053 -26.045123) (xy 184.991978 -26.029602)
			(xy 185.051434 -26.021774) (xy 185.111402 -26.021774) (xy 185.170858 -26.029602) (xy 185.228783 -26.045123)
			(xy 185.284187 -26.068072) (xy 185.336121 -26.098056) (xy 185.383697 -26.134562) (xy 185.426102 -26.176967)
			(xy 185.462608 -26.224543) (xy 185.492592 -26.276477) (xy 185.515541 -26.331881) (xy 185.531062 -26.389806)
			(xy 185.53889 -26.449262) (xy 185.53938 -26.479246) (xy 185.53938 -27.342846) (xy 185.53889 -27.37283)
			(xy 185.534544 -27.405838) (xy 208.665572 -27.405838) (xy 208.665572 -26.37409) (xy 208.665957 -26.363914)
			(xy 208.673751 -26.345112) (xy 208.688149 -26.330726) (xy 208.706957 -26.322948) (xy 208.717134 -26.322528)
			(xy 209.949034 -26.322528) (xy 209.959193 -26.323005) (xy 209.977961 -26.330789) (xy 209.992324 -26.345159)
			(xy 210.000099 -26.363931) (xy 210.000596 -26.37409) (xy 210.000596 -27.342846) (xy 210.623404 -27.342846)
			(xy 210.623404 -26.479246) (xy 210.623894 -26.449262) (xy 210.631722 -26.389806) (xy 210.647243 -26.331881)
			(xy 210.670192 -26.276477) (xy 210.700176 -26.224543) (xy 210.736682 -26.176967) (xy 210.779087 -26.134562)
			(xy 210.826663 -26.098056) (xy 210.878597 -26.068072) (xy 210.934001 -26.045123) (xy 210.991926 -26.029602)
			(xy 211.051382 -26.021774) (xy 211.11135 -26.021774) (xy 211.170806 -26.029602) (xy 211.228731 -26.045123)
			(xy 211.284135 -26.068072) (xy 211.336069 -26.098056) (xy 211.383645 -26.134562) (xy 211.42605 -26.176967)
			(xy 211.462556 -26.224543) (xy 211.49254 -26.276477) (xy 211.515489 -26.331881) (xy 211.53101 -26.389806)
			(xy 211.538838 -26.449262) (xy 211.539328 -26.479246) (xy 211.539328 -27.342846) (xy 211.538838 -27.37283)
			(xy 211.534492 -27.405838) (xy 246.765572 -27.405838) (xy 246.765572 -26.37409) (xy 246.765957 -26.363914)
			(xy 246.773751 -26.345112) (xy 246.788149 -26.330726) (xy 246.806957 -26.322948) (xy 246.817134 -26.322528)
			(xy 248.049034 -26.322528) (xy 248.059193 -26.323005) (xy 248.077961 -26.330789) (xy 248.092324 -26.345159)
			(xy 248.100099 -26.363931) (xy 248.100596 -26.37409) (xy 248.100596 -27.342846) (xy 248.723404 -27.342846)
			(xy 248.723404 -26.479246) (xy 248.723894 -26.449262) (xy 248.731722 -26.389806) (xy 248.747243 -26.331881)
			(xy 248.770192 -26.276477) (xy 248.800176 -26.224543) (xy 248.836682 -26.176967) (xy 248.879087 -26.134562)
			(xy 248.926663 -26.098056) (xy 248.978597 -26.068072) (xy 249.034001 -26.045123) (xy 249.091926 -26.029602)
			(xy 249.151382 -26.021774) (xy 249.21135 -26.021774) (xy 249.270806 -26.029602) (xy 249.328731 -26.045123)
			(xy 249.384135 -26.068072) (xy 249.436069 -26.098056) (xy 249.483645 -26.134562) (xy 249.52605 -26.176967)
			(xy 249.562556 -26.224543) (xy 249.59254 -26.276477) (xy 249.615489 -26.331881) (xy 249.63101 -26.389806)
			(xy 249.638838 -26.449262) (xy 249.639328 -26.479246) (xy 249.639328 -27.342846) (xy 249.638838 -27.37283)
			(xy 249.634492 -27.405838) (xy 272.76552 -27.405838) (xy 272.76552 -26.37409) (xy 272.766025 -26.363934)
			(xy 272.773799 -26.345168) (xy 272.788161 -26.330804) (xy 272.806926 -26.323027) (xy 272.817082 -26.322528)
			(xy 274.048982 -26.322528) (xy 274.059151 -26.322978) (xy 274.077944 -26.330755) (xy 274.092329 -26.345133)
			(xy 274.100116 -26.363921) (xy 274.100544 -26.37409) (xy 274.100544 -27.342846) (xy 274.723352 -27.342846)
			(xy 274.723352 -26.479246) (xy 274.723842 -26.449262) (xy 274.73167 -26.389806) (xy 274.747191 -26.331881)
			(xy 274.77014 -26.276477) (xy 274.800124 -26.224543) (xy 274.83663 -26.176967) (xy 274.879035 -26.134562)
			(xy 274.926611 -26.098056) (xy 274.978545 -26.068072) (xy 275.033949 -26.045123) (xy 275.091874 -26.029602)
			(xy 275.15133 -26.021774) (xy 275.211298 -26.021774) (xy 275.270754 -26.029602) (xy 275.328679 -26.045123)
			(xy 275.384083 -26.068072) (xy 275.436017 -26.098056) (xy 275.483593 -26.134562) (xy 275.525998 -26.176967)
			(xy 275.562504 -26.224543) (xy 275.592488 -26.276477) (xy 275.615437 -26.331881) (xy 275.630958 -26.389806)
			(xy 275.638786 -26.449262) (xy 275.639276 -26.479246) (xy 275.639276 -27.342846) (xy 275.638786 -27.37283)
			(xy 275.63444 -27.405838) (xy 298.765468 -27.405838) (xy 298.765468 -26.37409) (xy 298.765856 -26.363914)
			(xy 298.77365 -26.345113) (xy 298.788047 -26.330728) (xy 298.806854 -26.322949) (xy 298.81703 -26.322528)
			(xy 300.04893 -26.322528) (xy 300.059088 -26.323008) (xy 300.077856 -26.330791) (xy 300.09222 -26.34516)
			(xy 300.099995 -26.363931) (xy 300.100492 -26.37409) (xy 300.100492 -27.342846) (xy 300.7233 -27.342846)
			(xy 300.7233 -26.479246) (xy 300.72379 -26.449262) (xy 300.731618 -26.389806) (xy 300.747139 -26.331881)
			(xy 300.770088 -26.276477) (xy 300.800072 -26.224543) (xy 300.836578 -26.176967) (xy 300.878983 -26.134562)
			(xy 300.926559 -26.098056) (xy 300.978493 -26.068072) (xy 301.033897 -26.045123) (xy 301.091822 -26.029602)
			(xy 301.151278 -26.021774) (xy 301.211246 -26.021774) (xy 301.270702 -26.029602) (xy 301.328627 -26.045123)
			(xy 301.384031 -26.068072) (xy 301.435965 -26.098056) (xy 301.483541 -26.134562) (xy 301.525946 -26.176967)
			(xy 301.562452 -26.224543) (xy 301.592436 -26.276477) (xy 301.615385 -26.331881) (xy 301.630906 -26.389806)
			(xy 301.638734 -26.449262) (xy 301.639224 -26.479246) (xy 301.639224 -27.342846) (xy 301.638734 -27.37283)
			(xy 301.634388 -27.405838) (xy 324.765416 -27.405838) (xy 324.765416 -26.37409) (xy 324.765925 -26.363934)
			(xy 324.773698 -26.345169) (xy 324.788059 -26.330805) (xy 324.806822 -26.323027) (xy 324.816978 -26.322528)
			(xy 326.048878 -26.322528) (xy 326.059047 -26.322982) (xy 326.077839 -26.330758) (xy 326.092224 -26.345134)
			(xy 326.100012 -26.363921) (xy 326.10044 -26.37409) (xy 326.10044 -27.342846) (xy 326.723248 -27.342846)
			(xy 326.723248 -26.479246) (xy 326.723738 -26.449262) (xy 326.731566 -26.389806) (xy 326.747087 -26.331881)
			(xy 326.770036 -26.276477) (xy 326.80002 -26.224543) (xy 326.836526 -26.176967) (xy 326.878931 -26.134562)
			(xy 326.926507 -26.098056) (xy 326.978441 -26.068072) (xy 327.033845 -26.045123) (xy 327.09177 -26.029602)
			(xy 327.151226 -26.021774) (xy 327.211194 -26.021774) (xy 327.27065 -26.029602) (xy 327.328575 -26.045123)
			(xy 327.383979 -26.068072) (xy 327.435913 -26.098056) (xy 327.483489 -26.134562) (xy 327.525894 -26.176967)
			(xy 327.5624 -26.224543) (xy 327.592384 -26.276477) (xy 327.615333 -26.331881) (xy 327.630854 -26.389806)
			(xy 327.638682 -26.449262) (xy 327.639172 -26.479246) (xy 327.639172 -27.342846) (xy 327.638682 -27.37283)
			(xy 327.634336 -27.405838) (xy 362.865924 -27.405838) (xy 362.865924 -26.37409) (xy 362.866418 -26.363965)
			(xy 362.874146 -26.345246) (xy 362.88843 -26.330891) (xy 362.907109 -26.323069) (xy 362.917232 -26.322528)
			(xy 364.149132 -26.322528) (xy 364.159292 -26.322896) (xy 364.17805 -26.330707) (xy 364.192373 -26.345121)
			(xy 364.200067 -26.363928) (xy 364.20044 -26.37409) (xy 364.20044 -27.342846) (xy 364.823756 -27.342846)
			(xy 364.823756 -26.479246) (xy 364.824246 -26.449278) (xy 364.832069 -26.389856) (xy 364.847582 -26.331963)
			(xy 364.870518 -26.27659) (xy 364.900485 -26.224684) (xy 364.936972 -26.177134) (xy 364.979352 -26.134754)
			(xy 365.026902 -26.098267) (xy 365.078808 -26.0683) (xy 365.134181 -26.045364) (xy 365.192074 -26.029851)
			(xy 365.251496 -26.022028) (xy 365.311432 -26.022028) (xy 365.370854 -26.029851) (xy 365.428747 -26.045364)
			(xy 365.48412 -26.0683) (xy 365.536026 -26.098267) (xy 365.583576 -26.134754) (xy 365.625956 -26.177134)
			(xy 365.662443 -26.224684) (xy 365.69241 -26.27659) (xy 365.715346 -26.331963) (xy 365.730859 -26.389856)
			(xy 365.738682 -26.449278) (xy 365.739172 -26.479246) (xy 365.739172 -27.342846) (xy 365.738682 -27.372814)
			(xy 365.734334 -27.405838) (xy 388.865872 -27.405838) (xy 388.865872 -26.37409) (xy 388.866319 -26.363959)
			(xy 388.874056 -26.345231) (xy 388.888355 -26.330874) (xy 388.907051 -26.323061) (xy 388.91718 -26.322528)
			(xy 390.14908 -26.322528) (xy 390.159236 -26.322938) (xy 390.177994 -26.330733) (xy 390.192319 -26.345133)
			(xy 390.200014 -26.363932) (xy 390.200388 -26.37409) (xy 390.200388 -27.342846) (xy 390.823704 -27.342846)
			(xy 390.823704 -26.479246) (xy 390.824194 -26.449278) (xy 390.832017 -26.389856) (xy 390.84753 -26.331963)
			(xy 390.870466 -26.27659) (xy 390.900433 -26.224684) (xy 390.93692 -26.177134) (xy 390.9793 -26.134754)
			(xy 391.02685 -26.098267) (xy 391.078756 -26.0683) (xy 391.134129 -26.045364) (xy 391.192022 -26.029851)
			(xy 391.251444 -26.022028) (xy 391.31138 -26.022028) (xy 391.370802 -26.029851) (xy 391.428695 -26.045364)
			(xy 391.484068 -26.0683) (xy 391.535974 -26.098267) (xy 391.583524 -26.134754) (xy 391.625904 -26.177134)
			(xy 391.662391 -26.224684) (xy 391.692358 -26.27659) (xy 391.715294 -26.331963) (xy 391.730807 -26.389856)
			(xy 391.73863 -26.449278) (xy 391.73912 -26.479246) (xy 391.73912 -27.342846) (xy 391.73863 -27.372814)
			(xy 391.734282 -27.405838) (xy 414.86582 -27.405838) (xy 414.86582 -26.37409) (xy 414.866318 -26.363965)
			(xy 414.874045 -26.345248) (xy 414.888328 -26.330892) (xy 414.907006 -26.32307) (xy 414.917128 -26.322528)
			(xy 416.149028 -26.322528) (xy 416.159187 -26.322899) (xy 416.177946 -26.330709) (xy 416.192269 -26.345122)
			(xy 416.199963 -26.363928) (xy 416.200336 -26.37409) (xy 416.200336 -27.342846) (xy 416.823652 -27.342846)
			(xy 416.823652 -26.479246) (xy 416.824142 -26.449278) (xy 416.831965 -26.389856) (xy 416.847478 -26.331963)
			(xy 416.870414 -26.27659) (xy 416.900381 -26.224684) (xy 416.936868 -26.177134) (xy 416.979248 -26.134754)
			(xy 417.026798 -26.098267) (xy 417.078704 -26.0683) (xy 417.134077 -26.045364) (xy 417.19197 -26.029851)
			(xy 417.251392 -26.022028) (xy 417.311328 -26.022028) (xy 417.37075 -26.029851) (xy 417.428643 -26.045364)
			(xy 417.484016 -26.0683) (xy 417.535922 -26.098267) (xy 417.583472 -26.134754) (xy 417.625852 -26.177134)
			(xy 417.662339 -26.224684) (xy 417.692306 -26.27659) (xy 417.715242 -26.331963) (xy 417.730755 -26.389856)
			(xy 417.738578 -26.449278) (xy 417.739068 -26.479246) (xy 417.739068 -27.342846) (xy 417.738578 -27.372814)
			(xy 417.73423 -27.405838) (xy 440.865768 -27.405838) (xy 440.865768 -26.37409) (xy 440.866219 -26.363959)
			(xy 440.873956 -26.345233) (xy 440.888253 -26.330876) (xy 440.906947 -26.323062) (xy 440.917076 -26.322528)
			(xy 442.148976 -26.322528) (xy 442.159132 -26.322942) (xy 442.177889 -26.330735) (xy 442.192215 -26.345134)
			(xy 442.19991 -26.363932) (xy 442.200284 -26.37409) (xy 442.200284 -27.342846) (xy 442.8236 -27.342846)
			(xy 442.8236 -26.479246) (xy 442.82409 -26.449278) (xy 442.831913 -26.389856) (xy 442.847426 -26.331963)
			(xy 442.870362 -26.27659) (xy 442.900329 -26.224684) (xy 442.936816 -26.177134) (xy 442.979196 -26.134754)
			(xy 443.026746 -26.098267) (xy 443.078652 -26.0683) (xy 443.134025 -26.045364) (xy 443.191918 -26.029851)
			(xy 443.25134 -26.022028) (xy 443.311276 -26.022028) (xy 443.370698 -26.029851) (xy 443.428591 -26.045364)
			(xy 443.483964 -26.0683) (xy 443.53587 -26.098267) (xy 443.58342 -26.134754) (xy 443.6258 -26.177134)
			(xy 443.662287 -26.224684) (xy 443.692254 -26.27659) (xy 443.71519 -26.331963) (xy 443.730703 -26.389856)
			(xy 443.738526 -26.449278) (xy 443.739016 -26.479246) (xy 443.739016 -27.342846) (xy 443.738526 -27.372814)
			(xy 443.730703 -27.432236) (xy 443.71519 -27.490129) (xy 443.692254 -27.545502) (xy 443.662287 -27.597408)
			(xy 443.6258 -27.644958) (xy 443.58342 -27.687338) (xy 443.53587 -27.723825) (xy 443.483964 -27.753792)
			(xy 443.428591 -27.776728) (xy 443.370698 -27.792241) (xy 443.311276 -27.800064) (xy 443.25134 -27.800064)
			(xy 443.191918 -27.792241) (xy 443.134025 -27.776728) (xy 443.078652 -27.753792) (xy 443.026746 -27.723825)
			(xy 442.979196 -27.687338) (xy 442.936816 -27.644958) (xy 442.900329 -27.597408) (xy 442.870362 -27.545502)
			(xy 442.847426 -27.490129) (xy 442.831913 -27.432236) (xy 442.82409 -27.372814) (xy 442.8236 -27.342846)
			(xy 442.200284 -27.342846) (xy 442.200284 -27.405838) (xy 442.199805 -27.415964) (xy 442.192069 -27.434682)
			(xy 442.177781 -27.449036) (xy 442.1591 -27.456858) (xy 442.148976 -27.4574) (xy 440.917076 -27.4574)
			(xy 440.90692 -27.456998) (xy 440.888167 -27.449195) (xy 440.873845 -27.434792) (xy 440.866146 -27.415996)
			(xy 440.865768 -27.405838) (xy 417.73423 -27.405838) (xy 417.730755 -27.432236) (xy 417.715242 -27.490129)
			(xy 417.692306 -27.545502) (xy 417.662339 -27.597408) (xy 417.625852 -27.644958) (xy 417.583472 -27.687338)
			(xy 417.535922 -27.723825) (xy 417.484016 -27.753792) (xy 417.428643 -27.776728) (xy 417.37075 -27.792241)
			(xy 417.311328 -27.800064) (xy 417.251392 -27.800064) (xy 417.19197 -27.792241) (xy 417.134077 -27.776728)
			(xy 417.078704 -27.753792) (xy 417.026798 -27.723825) (xy 416.979248 -27.687338) (xy 416.936868 -27.644958)
			(xy 416.900381 -27.597408) (xy 416.870414 -27.545502) (xy 416.847478 -27.490129) (xy 416.831965 -27.432236)
			(xy 416.824142 -27.372814) (xy 416.823652 -27.342846) (xy 416.200336 -27.342846) (xy 416.200336 -27.405838)
			(xy 416.199904 -27.41597) (xy 416.192159 -27.434697) (xy 416.177856 -27.449052) (xy 416.159158 -27.456866)
			(xy 416.149028 -27.4574) (xy 414.917128 -27.4574) (xy 414.906976 -27.456956) (xy 414.888224 -27.449169)
			(xy 414.873899 -27.434779) (xy 414.866199 -27.415992) (xy 414.86582 -27.405838) (xy 391.734282 -27.405838)
			(xy 391.730807 -27.432236) (xy 391.715294 -27.490129) (xy 391.692358 -27.545502) (xy 391.662391 -27.597408)
			(xy 391.625904 -27.644958) (xy 391.583524 -27.687338) (xy 391.535974 -27.723825) (xy 391.484068 -27.753792)
			(xy 391.428695 -27.776728) (xy 391.370802 -27.792241) (xy 391.31138 -27.800064) (xy 391.251444 -27.800064)
			(xy 391.192022 -27.792241) (xy 391.134129 -27.776728) (xy 391.078756 -27.753792) (xy 391.02685 -27.723825)
			(xy 390.9793 -27.687338) (xy 390.93692 -27.644958) (xy 390.900433 -27.597408) (xy 390.870466 -27.545502)
			(xy 390.84753 -27.490129) (xy 390.832017 -27.432236) (xy 390.824194 -27.372814) (xy 390.823704 -27.342846)
			(xy 390.200388 -27.342846) (xy 390.200388 -27.405838) (xy 390.199905 -27.415964) (xy 390.19217 -27.43468)
			(xy 390.177884 -27.449034) (xy 390.159203 -27.456857) (xy 390.14908 -27.4574) (xy 388.91718 -27.4574)
			(xy 388.907025 -27.456995) (xy 388.888272 -27.449193) (xy 388.873949 -27.434791) (xy 388.86625 -27.415996)
			(xy 388.865872 -27.405838) (xy 365.734334 -27.405838) (xy 365.730859 -27.432236) (xy 365.715346 -27.490129)
			(xy 365.69241 -27.545502) (xy 365.662443 -27.597408) (xy 365.625956 -27.644958) (xy 365.583576 -27.687338)
			(xy 365.536026 -27.723825) (xy 365.48412 -27.753792) (xy 365.428747 -27.776728) (xy 365.370854 -27.792241)
			(xy 365.311432 -27.800064) (xy 365.251496 -27.800064) (xy 365.192074 -27.792241) (xy 365.134181 -27.776728)
			(xy 365.078808 -27.753792) (xy 365.026902 -27.723825) (xy 364.979352 -27.687338) (xy 364.936972 -27.644958)
			(xy 364.900485 -27.597408) (xy 364.870518 -27.545502) (xy 364.847582 -27.490129) (xy 364.832069 -27.432236)
			(xy 364.824246 -27.372814) (xy 364.823756 -27.342846) (xy 364.20044 -27.342846) (xy 364.20044 -27.405838)
			(xy 364.200004 -27.41597) (xy 364.19226 -27.434695) (xy 364.177958 -27.449051) (xy 364.159262 -27.456865)
			(xy 364.149132 -27.4574) (xy 362.917232 -27.4574) (xy 362.90708 -27.456952) (xy 362.888328 -27.449167)
			(xy 362.874004 -27.434778) (xy 362.866303 -27.415992) (xy 362.865924 -27.405838) (xy 327.634336 -27.405838)
			(xy 327.630854 -27.432286) (xy 327.615333 -27.490211) (xy 327.592384 -27.545615) (xy 327.5624 -27.597549)
			(xy 327.525894 -27.645125) (xy 327.483489 -27.68753) (xy 327.435913 -27.724036) (xy 327.383979 -27.75402)
			(xy 327.328575 -27.776969) (xy 327.27065 -27.79249) (xy 327.211194 -27.800318) (xy 327.151226 -27.800318)
			(xy 327.09177 -27.79249) (xy 327.033845 -27.776969) (xy 326.978441 -27.75402) (xy 326.926507 -27.724036)
			(xy 326.878931 -27.68753) (xy 326.836526 -27.645125) (xy 326.80002 -27.597549) (xy 326.770036 -27.545615)
			(xy 326.747087 -27.490211) (xy 326.731566 -27.432286) (xy 326.723738 -27.37283) (xy 326.723248 -27.342846)
			(xy 326.10044 -27.342846) (xy 326.10044 -27.405838) (xy 326.099997 -27.416001) (xy 326.092206 -27.434775)
			(xy 326.077825 -27.44914) (xy 326.059042 -27.456909) (xy 326.048878 -27.4574) (xy 324.816978 -27.4574)
			(xy 324.806823 -27.456886) (xy 324.788061 -27.449111) (xy 324.773698 -27.434752) (xy 324.765917 -27.415992)
			(xy 324.765416 -27.405838) (xy 301.634388 -27.405838) (xy 301.630906 -27.432286) (xy 301.615385 -27.490211)
			(xy 301.592436 -27.545615) (xy 301.562452 -27.597549) (xy 301.525946 -27.645125) (xy 301.483541 -27.68753)
			(xy 301.435965 -27.724036) (xy 301.384031 -27.75402) (xy 301.328627 -27.776969) (xy 301.270702 -27.79249)
			(xy 301.211246 -27.800318) (xy 301.151278 -27.800318) (xy 301.091822 -27.79249) (xy 301.033897 -27.776969)
			(xy 300.978493 -27.75402) (xy 300.926559 -27.724036) (xy 300.878983 -27.68753) (xy 300.836578 -27.645125)
			(xy 300.800072 -27.597549) (xy 300.770088 -27.545615) (xy 300.747139 -27.490211) (xy 300.731618 -27.432286)
			(xy 300.72379 -27.37283) (xy 300.7233 -27.342846) (xy 300.100492 -27.342846) (xy 300.100492 -27.405838)
			(xy 300.099998 -27.415995) (xy 300.092217 -27.434759) (xy 300.077852 -27.449122) (xy 300.059087 -27.4569)
			(xy 300.04893 -27.4574) (xy 298.81703 -27.4574) (xy 298.806879 -27.456843) (xy 298.788117 -27.449086)
			(xy 298.773752 -27.43474) (xy 298.76597 -27.415989) (xy 298.765468 -27.405838) (xy 275.63444 -27.405838)
			(xy 275.630958 -27.432286) (xy 275.615437 -27.490211) (xy 275.592488 -27.545615) (xy 275.562504 -27.597549)
			(xy 275.525998 -27.645125) (xy 275.483593 -27.68753) (xy 275.436017 -27.724036) (xy 275.384083 -27.75402)
			(xy 275.328679 -27.776969) (xy 275.270754 -27.79249) (xy 275.211298 -27.800318) (xy 275.15133 -27.800318)
			(xy 275.091874 -27.79249) (xy 275.033949 -27.776969) (xy 274.978545 -27.75402) (xy 274.926611 -27.724036)
			(xy 274.879035 -27.68753) (xy 274.83663 -27.645125) (xy 274.800124 -27.597549) (xy 274.77014 -27.545615)
			(xy 274.747191 -27.490211) (xy 274.73167 -27.432286) (xy 274.723842 -27.37283) (xy 274.723352 -27.342846)
			(xy 274.100544 -27.342846) (xy 274.100544 -27.405838) (xy 274.100097 -27.416) (xy 274.092307 -27.434774)
			(xy 274.077927 -27.449138) (xy 274.059145 -27.456908) (xy 274.048982 -27.4574) (xy 272.817082 -27.4574)
			(xy 272.806928 -27.456883) (xy 272.788165 -27.449109) (xy 272.773802 -27.434751) (xy 272.766021 -27.415992)
			(xy 272.76552 -27.405838) (xy 249.634492 -27.405838) (xy 249.63101 -27.432286) (xy 249.615489 -27.490211)
			(xy 249.59254 -27.545615) (xy 249.562556 -27.597549) (xy 249.52605 -27.645125) (xy 249.483645 -27.68753)
			(xy 249.436069 -27.724036) (xy 249.384135 -27.75402) (xy 249.328731 -27.776969) (xy 249.270806 -27.79249)
			(xy 249.21135 -27.800318) (xy 249.151382 -27.800318) (xy 249.091926 -27.79249) (xy 249.034001 -27.776969)
			(xy 248.978597 -27.75402) (xy 248.926663 -27.724036) (xy 248.879087 -27.68753) (xy 248.836682 -27.645125)
			(xy 248.800176 -27.597549) (xy 248.770192 -27.545615) (xy 248.747243 -27.490211) (xy 248.731722 -27.432286)
			(xy 248.723894 -27.37283) (xy 248.723404 -27.342846) (xy 248.100596 -27.342846) (xy 248.100596 -27.405838)
			(xy 248.100099 -27.415994) (xy 248.092318 -27.434758) (xy 248.077954 -27.44912) (xy 248.05919 -27.456899)
			(xy 248.049034 -27.4574) (xy 246.817134 -27.4574) (xy 246.806983 -27.45684) (xy 246.788222 -27.449083)
			(xy 246.773857 -27.434738) (xy 246.766075 -27.415988) (xy 246.765572 -27.405838) (xy 211.534492 -27.405838)
			(xy 211.53101 -27.432286) (xy 211.515489 -27.490211) (xy 211.49254 -27.545615) (xy 211.462556 -27.597549)
			(xy 211.42605 -27.645125) (xy 211.383645 -27.68753) (xy 211.336069 -27.724036) (xy 211.284135 -27.75402)
			(xy 211.228731 -27.776969) (xy 211.170806 -27.79249) (xy 211.11135 -27.800318) (xy 211.051382 -27.800318)
			(xy 210.991926 -27.79249) (xy 210.934001 -27.776969) (xy 210.878597 -27.75402) (xy 210.826663 -27.724036)
			(xy 210.779087 -27.68753) (xy 210.736682 -27.645125) (xy 210.700176 -27.597549) (xy 210.670192 -27.545615)
			(xy 210.647243 -27.490211) (xy 210.631722 -27.432286) (xy 210.623894 -27.37283) (xy 210.623404 -27.342846)
			(xy 210.000596 -27.342846) (xy 210.000596 -27.405838) (xy 210.000099 -27.415994) (xy 209.992318 -27.434758)
			(xy 209.977954 -27.44912) (xy 209.95919 -27.456899) (xy 209.949034 -27.4574) (xy 208.717134 -27.4574)
			(xy 208.706983 -27.45684) (xy 208.688222 -27.449083) (xy 208.673857 -27.434738) (xy 208.666075 -27.415988)
			(xy 208.665572 -27.405838) (xy 185.534544 -27.405838) (xy 185.531062 -27.432286) (xy 185.515541 -27.490211)
			(xy 185.492592 -27.545615) (xy 185.462608 -27.597549) (xy 185.426102 -27.645125) (xy 185.383697 -27.68753)
			(xy 185.336121 -27.724036) (xy 185.284187 -27.75402) (xy 185.228783 -27.776969) (xy 185.170858 -27.79249)
			(xy 185.111402 -27.800318) (xy 185.051434 -27.800318) (xy 184.991978 -27.79249) (xy 184.934053 -27.776969)
			(xy 184.878649 -27.75402) (xy 184.826715 -27.724036) (xy 184.779139 -27.68753) (xy 184.736734 -27.645125)
			(xy 184.700228 -27.597549) (xy 184.670244 -27.545615) (xy 184.647295 -27.490211) (xy 184.631774 -27.432286)
			(xy 184.623946 -27.37283) (xy 184.623456 -27.342846) (xy 184.000648 -27.342846) (xy 184.000648 -27.405838)
			(xy 184.000197 -27.416) (xy 183.992408 -27.434773) (xy 183.978029 -27.449137) (xy 183.959248 -27.456908)
			(xy 183.949086 -27.4574) (xy 182.717186 -27.4574) (xy 182.707032 -27.456879) (xy 182.68827 -27.449107)
			(xy 182.673907 -27.43475) (xy 182.666126 -27.415992) (xy 182.665624 -27.405838) (xy 159.534596 -27.405838)
			(xy 159.531114 -27.432286) (xy 159.515593 -27.490211) (xy 159.492644 -27.545615) (xy 159.46266 -27.597549)
			(xy 159.426154 -27.645125) (xy 159.383749 -27.68753) (xy 159.336173 -27.724036) (xy 159.284239 -27.75402)
			(xy 159.228835 -27.776969) (xy 159.17091 -27.79249) (xy 159.111454 -27.800318) (xy 159.051486 -27.800318)
			(xy 158.99203 -27.79249) (xy 158.934105 -27.776969) (xy 158.878701 -27.75402) (xy 158.826767 -27.724036)
			(xy 158.779191 -27.68753) (xy 158.736786 -27.645125) (xy 158.70028 -27.597549) (xy 158.670296 -27.545615)
			(xy 158.647347 -27.490211) (xy 158.631826 -27.432286) (xy 158.623998 -27.37283) (xy 158.623508 -27.342846)
			(xy 158.0007 -27.342846) (xy 158.0007 -27.405838) (xy 158.000199 -27.415994) (xy 157.992419 -27.434756)
			(xy 157.978056 -27.449119) (xy 157.959294 -27.456899) (xy 157.949138 -27.4574) (xy 156.717238 -27.4574)
			(xy 156.707087 -27.456836) (xy 156.688326 -27.449081) (xy 156.673961 -27.434737) (xy 156.666179 -27.415988)
			(xy 156.665676 -27.405838) (xy 133.534648 -27.405838) (xy 133.531166 -27.432286) (xy 133.515645 -27.490211)
			(xy 133.492696 -27.545615) (xy 133.462712 -27.597549) (xy 133.426206 -27.645125) (xy 133.383801 -27.68753)
			(xy 133.336225 -27.724036) (xy 133.284291 -27.75402) (xy 133.228887 -27.776969) (xy 133.170962 -27.79249)
			(xy 133.111506 -27.800318) (xy 133.051538 -27.800318) (xy 132.992082 -27.79249) (xy 132.934157 -27.776969)
			(xy 132.878753 -27.75402) (xy 132.826819 -27.724036) (xy 132.779243 -27.68753) (xy 132.736838 -27.645125)
			(xy 132.700332 -27.597549) (xy 132.670348 -27.545615) (xy 132.647399 -27.490211) (xy 132.631878 -27.432286)
			(xy 132.62405 -27.37283) (xy 132.62356 -27.342846) (xy 132.000752 -27.342846) (xy 132.000752 -27.405838)
			(xy 132.000297 -27.415999) (xy 131.992509 -27.434771) (xy 131.978131 -27.449136) (xy 131.959352 -27.456907)
			(xy 131.94919 -27.4574) (xy 130.71729 -27.4574) (xy 130.707136 -27.456876) (xy 130.688374 -27.449105)
			(xy 130.674011 -27.434749) (xy 130.66623 -27.415991) (xy 130.665728 -27.405838) (xy 95.434138 -27.405838)
			(xy 95.430663 -27.432236) (xy 95.41515 -27.490129) (xy 95.392214 -27.545502) (xy 95.362247 -27.597408)
			(xy 95.32576 -27.644958) (xy 95.28338 -27.687338) (xy 95.23583 -27.723825) (xy 95.183924 -27.753792)
			(xy 95.128551 -27.776728) (xy 95.070658 -27.792241) (xy 95.011236 -27.800064) (xy 94.9513 -27.800064)
			(xy 94.891878 -27.792241) (xy 94.833985 -27.776728) (xy 94.778612 -27.753792) (xy 94.726706 -27.723825)
			(xy 94.679156 -27.687338) (xy 94.636776 -27.644958) (xy 94.600289 -27.597408) (xy 94.570322 -27.545502)
			(xy 94.547386 -27.490129) (xy 94.531873 -27.432236) (xy 94.52405 -27.372814) (xy 94.52356 -27.342846)
			(xy 93.900244 -27.342846) (xy 93.900244 -27.405838) (xy 93.899804 -27.415969) (xy 93.892061 -27.434694)
			(xy 93.87776 -27.44905) (xy 93.859065 -27.456865) (xy 93.848936 -27.4574) (xy 92.617036 -27.4574)
			(xy 92.606884 -27.456949) (xy 92.588133 -27.449165) (xy 92.573808 -27.434777) (xy 92.566107 -27.415991)
			(xy 92.565728 -27.405838) (xy 69.43419 -27.405838) (xy 69.430715 -27.432236) (xy 69.415202 -27.490129)
			(xy 69.392266 -27.545502) (xy 69.362299 -27.597408) (xy 69.325812 -27.644958) (xy 69.283432 -27.687338)
			(xy 69.235882 -27.723825) (xy 69.183976 -27.753792) (xy 69.128603 -27.776728) (xy 69.07071 -27.792241)
			(xy 69.011288 -27.800064) (xy 68.951352 -27.800064) (xy 68.89193 -27.792241) (xy 68.834037 -27.776728)
			(xy 68.778664 -27.753792) (xy 68.726758 -27.723825) (xy 68.679208 -27.687338) (xy 68.636828 -27.644958)
			(xy 68.600341 -27.597408) (xy 68.570374 -27.545502) (xy 68.547438 -27.490129) (xy 68.531925 -27.432236)
			(xy 68.524102 -27.372814) (xy 68.523612 -27.342846) (xy 67.900296 -27.342846) (xy 67.900296 -27.405838)
			(xy 67.899806 -27.415963) (xy 67.892072 -27.434678) (xy 67.877788 -27.449032) (xy 67.85911 -27.456856)
			(xy 67.848988 -27.4574) (xy 66.617088 -27.4574) (xy 66.606933 -27.456988) (xy 66.58818 -27.449189)
			(xy 66.573857 -27.434789) (xy 66.566158 -27.415995) (xy 66.56578 -27.405838) (xy 43.434242 -27.405838)
			(xy 43.430767 -27.432236) (xy 43.415254 -27.490129) (xy 43.392318 -27.545502) (xy 43.362351 -27.597408)
			(xy 43.325864 -27.644958) (xy 43.283484 -27.687338) (xy 43.235934 -27.723825) (xy 43.184028 -27.753792)
			(xy 43.128655 -27.776728) (xy 43.070762 -27.792241) (xy 43.01134 -27.800064) (xy 42.951404 -27.800064)
			(xy 42.891982 -27.792241) (xy 42.834089 -27.776728) (xy 42.778716 -27.753792) (xy 42.72681 -27.723825)
			(xy 42.67926 -27.687338) (xy 42.63688 -27.644958) (xy 42.600393 -27.597408) (xy 42.570426 -27.545502)
			(xy 42.54749 -27.490129) (xy 42.531977 -27.432236) (xy 42.524154 -27.372814) (xy 42.523664 -27.342846)
			(xy 41.900348 -27.342846) (xy 41.900348 -27.405838) (xy 41.899904 -27.415969) (xy 41.892162 -27.434693)
			(xy 41.877862 -27.449048) (xy 41.859169 -27.456864) (xy 41.84904 -27.4574) (xy 40.61714 -27.4574)
			(xy 40.606988 -27.456945) (xy 40.588237 -27.449163) (xy 40.573912 -27.434776) (xy 40.566211 -27.415991)
			(xy 40.565832 -27.405838) (xy 17.434294 -27.405838) (xy 17.430819 -27.432236) (xy 17.415306 -27.490129)
			(xy 17.39237 -27.545502) (xy 17.362403 -27.597408) (xy 17.325916 -27.644958) (xy 17.283536 -27.687338)
			(xy 17.235986 -27.723825) (xy 17.18408 -27.753792) (xy 17.128707 -27.776728) (xy 17.070814 -27.792241)
			(xy 17.011392 -27.800064) (xy 16.951456 -27.800064) (xy 16.892034 -27.792241) (xy 16.834141 -27.776728)
			(xy 16.778768 -27.753792) (xy 16.726862 -27.723825) (xy 16.679312 -27.687338) (xy 16.636932 -27.644958)
			(xy 16.600445 -27.597408) (xy 16.570478 -27.545502) (xy 16.547542 -27.490129) (xy 16.532029 -27.432236)
			(xy 16.524206 -27.372814) (xy 16.523716 -27.342846) (xy 15.9004 -27.342846) (xy 15.9004 -27.405838)
			(xy 15.899906 -27.415962) (xy 15.892173 -27.434677) (xy 15.87789 -27.44903) (xy 15.859214 -27.456855)
			(xy 15.849092 -27.4574) (xy 14.617192 -27.4574) (xy 14.607037 -27.456985) (xy 14.588285 -27.449187)
			(xy 14.573962 -27.434788) (xy 14.566262 -27.415995) (xy 14.565884 -27.405838) (xy 0.509016 -27.405838)
			(xy 0.509016 -29.12237) (xy 8.607044 -29.12237) (xy 8.607044 -28.25877) (xy 8.607534 -28.228802)
			(xy 8.615357 -28.16938) (xy 8.63087 -28.111487) (xy 8.653806 -28.056114) (xy 8.683773 -28.004208)
			(xy 8.72026 -27.956658) (xy 8.76264 -27.914278) (xy 8.81019 -27.877791) (xy 8.862096 -27.847824)
			(xy 8.917469 -27.824888) (xy 8.975362 -27.809375) (xy 9.034784 -27.801552) (xy 9.09472 -27.801552)
			(xy 9.154142 -27.809375) (xy 9.212035 -27.824888) (xy 9.267408 -27.847824) (xy 9.319314 -27.877791)
			(xy 9.366864 -27.914278) (xy 9.409244 -27.956658) (xy 9.445731 -28.004208) (xy 9.475698 -28.056114)
			(xy 9.498634 -28.111487) (xy 9.514147 -28.16938) (xy 9.52197 -28.228802) (xy 9.52246 -28.25877) (xy 9.52246 -29.12237)
			(xy 9.52197 -29.152338) (xy 9.514914 -29.205936) (xy 10.029444 -29.205936) (xy 10.029444 -28.174188)
			(xy 10.029974 -28.164085) (xy 10.037705 -28.145418) (xy 10.051988 -28.131125) (xy 10.07065 -28.123381)
			(xy 10.080752 -28.12288) (xy 11.312652 -28.12288) (xy 11.322769 -28.123355) (xy 11.341468 -28.131083)
			(xy 11.355783 -28.145382) (xy 11.363533 -28.164072) (xy 11.36396 -28.174188) (xy 11.36396 -29.205936)
			(xy 14.565884 -29.205936) (xy 14.565884 -28.174188) (xy 14.566375 -28.164081) (xy 14.574114 -28.145405)
			(xy 14.588409 -28.131111) (xy 14.607084 -28.123374) (xy 14.617192 -28.12288) (xy 15.849092 -28.12288)
			(xy 15.859198 -28.123391) (xy 15.877872 -28.131122) (xy 15.892166 -28.145411) (xy 15.899905 -28.164082)
			(xy 15.9004 -28.174188) (xy 15.9004 -29.205936) (xy 15.899944 -29.216047) (xy 15.892195 -29.234726)
			(xy 15.877889 -29.24902) (xy 15.859203 -29.256753) (xy 15.849092 -29.257244) (xy 14.617192 -29.257244)
			(xy 14.607088 -29.256722) (xy 14.588418 -29.24899) (xy 14.574125 -29.234705) (xy 14.566383 -29.216039)
			(xy 14.565884 -29.205936) (xy 11.36396 -29.205936) (xy 11.363613 -29.216066) (xy 11.355845 -29.234778)
			(xy 11.341507 -29.249092) (xy 11.322782 -29.256829) (xy 11.312652 -29.257244) (xy 10.080752 -29.257244)
			(xy 10.070646 -29.256755) (xy 10.051975 -29.24901) (xy 10.037683 -29.234715) (xy 10.029942 -29.216042)
			(xy 10.029444 -29.205936) (xy 9.514914 -29.205936) (xy 9.514147 -29.21176) (xy 9.498634 -29.269653)
			(xy 9.494516 -29.279596) (xy 17.372584 -29.279596) (xy 17.372584 -29.036772) (xy 17.579848 -28.720542)
			(xy 17.584166 -28.713938) (xy 17.588034 -28.70761) (xy 17.592294 -28.69341) (xy 17.592548 -28.685998)
			(xy 17.592548 -28.67914) (xy 17.592311 -28.672417) (xy 17.58885 -28.659424) (xy 17.58569 -28.653486)
			(xy 17.460722 -28.461716) (xy 17.441418 -28.431998) (xy 17.385792 -28.346654) (xy 17.381474 -28.340558)
			(xy 17.378172 -28.33497) (xy 17.377664 -28.333954) (xy 17.372584 -28.32608) (xy 17.372584 -28.083256)
			(xy 17.373172 -28.071731) (xy 17.38306 -28.050909) (xy 17.400913 -28.036326) (xy 17.411954 -28.032964)
			(xy 17.412208 -28.032964) (xy 17.424146 -28.03144) (xy 18.160746 -28.03144) (xy 18.16712 -28.031659)
			(xy 18.179457 -28.034876) (xy 18.18513 -28.03779) (xy 18.193136 -28.042537) (xy 18.205371 -28.056545)
			(xy 18.211912 -28.073957) (xy 18.212308 -28.083256) (xy 18.212308 -28.32608) (xy 17.996408 -28.656534)
			(xy 17.992417 -28.664768) (xy 17.989861 -28.68287) (xy 17.993794 -28.700723) (xy 17.99844 -28.708604)
			(xy 18.030698 -28.758388) (xy 18.046192 -28.78201) (xy 18.212308 -29.035502) (xy 18.212308 -29.114242)
			(xy 18.847308 -29.114242) (xy 18.847308 -28.250642) (xy 18.847798 -28.220658) (xy 18.855626 -28.161202)
			(xy 18.871147 -28.103277) (xy 18.894096 -28.047873) (xy 18.92408 -27.995939) (xy 18.960586 -27.948363)
			(xy 19.002991 -27.905958) (xy 19.050567 -27.869452) (xy 19.102501 -27.839468) (xy 19.157905 -27.816519)
			(xy 19.21583 -27.800998) (xy 19.275286 -27.79317) (xy 19.335254 -27.79317) (xy 19.39471 -27.800998)
			(xy 19.452635 -27.816519) (xy 19.508039 -27.839468) (xy 19.559973 -27.869452) (xy 19.607549 -27.905958)
			(xy 19.649954 -27.948363) (xy 19.68646 -27.995939) (xy 19.716444 -28.047873) (xy 19.739393 -28.103277)
			(xy 19.754914 -28.161202) (xy 19.762742 -28.220658) (xy 19.763232 -28.250642) (xy 19.763232 -29.114242)
			(xy 19.763099 -29.12237) (xy 34.606992 -29.12237) (xy 34.606992 -28.25877) (xy 34.607482 -28.228802)
			(xy 34.615305 -28.16938) (xy 34.630818 -28.111487) (xy 34.653754 -28.056114) (xy 34.683721 -28.004208)
			(xy 34.720208 -27.956658) (xy 34.762588 -27.914278) (xy 34.810138 -27.877791) (xy 34.862044 -27.847824)
			(xy 34.917417 -27.824888) (xy 34.97531 -27.809375) (xy 35.034732 -27.801552) (xy 35.094668 -27.801552)
			(xy 35.15409 -27.809375) (xy 35.211983 -27.824888) (xy 35.267356 -27.847824) (xy 35.319262 -27.877791)
			(xy 35.366812 -27.914278) (xy 35.409192 -27.956658) (xy 35.445679 -28.004208) (xy 35.475646 -28.056114)
			(xy 35.498582 -28.111487) (xy 35.514095 -28.16938) (xy 35.521918 -28.228802) (xy 35.522408 -28.25877)
			(xy 35.522408 -29.12237) (xy 35.521918 -29.152338) (xy 35.514862 -29.205936) (xy 36.029392 -29.205936)
			(xy 36.029392 -28.174188) (xy 36.029875 -28.16408) (xy 36.037615 -28.145403) (xy 36.051913 -28.131109)
			(xy 36.070591 -28.123373) (xy 36.0807 -28.12288) (xy 37.3126 -28.12288) (xy 37.322706 -28.123385)
			(xy 37.341381 -28.131119) (xy 37.355675 -28.145409) (xy 37.363413 -28.164082) (xy 37.363908 -28.174188)
			(xy 37.363908 -29.205936) (xy 40.565832 -29.205936) (xy 40.565832 -28.174188) (xy 40.566207 -28.164061)
			(xy 40.573965 -28.145351) (xy 40.588294 -28.131036) (xy 40.607012 -28.123296) (xy 40.61714 -28.12288)
			(xy 41.84904 -28.12288) (xy 41.859149 -28.123352) (xy 41.877824 -28.131099) (xy 41.892117 -28.145399)
			(xy 41.899854 -28.164079) (xy 41.900348 -28.174188) (xy 41.900348 -29.205936) (xy 41.899846 -29.216041)
			(xy 41.892105 -29.234711) (xy 41.877814 -29.249003) (xy 41.859145 -29.256745) (xy 41.84904 -29.257244)
			(xy 40.61714 -29.257244) (xy 40.607026 -29.256752) (xy 40.588331 -29.249025) (xy 40.574017 -29.234733)
			(xy 40.566263 -29.21605) (xy 40.565832 -29.205936) (xy 37.363908 -29.205936) (xy 37.363445 -29.216046)
			(xy 37.355697 -29.234724) (xy 37.341393 -29.249017) (xy 37.32271 -29.256752) (xy 37.3126 -29.257244)
			(xy 36.0807 -29.257244) (xy 36.070597 -29.256716) (xy 36.051927 -29.248986) (xy 36.037634 -29.234703)
			(xy 36.029891 -29.216039) (xy 36.029392 -29.205936) (xy 35.514862 -29.205936) (xy 35.514095 -29.21176)
			(xy 35.498582 -29.269653) (xy 35.494464 -29.279596) (xy 43.372532 -29.279596) (xy 43.372532 -29.036772)
			(xy 43.566588 -28.740608) (xy 43.5864 -28.710382) (xy 43.591359 -28.701925) (xy 43.595091 -28.682697)
			(xy 43.591357 -28.663468) (xy 43.5864 -28.65501) (xy 43.419522 -28.39847) (xy 43.380914 -28.339288)
			(xy 43.380406 -28.338526) (xy 43.379898 -28.337764) (xy 43.379644 -28.337256) (xy 43.379136 -28.336494)
			(xy 43.372532 -28.32608) (xy 43.372532 -28.083256) (xy 43.37315 -28.071701) (xy 43.383121 -28.05085)
			(xy 43.401072 -28.036291) (xy 43.412156 -28.032964) (xy 43.424094 -28.03144) (xy 44.160694 -28.03144)
			(xy 44.171453 -28.031945) (xy 44.191143 -28.040621) (xy 44.198794 -28.048204) (xy 44.205015 -28.055586)
			(xy 44.211915 -28.073606) (xy 44.212256 -28.083256) (xy 44.212256 -28.32608) (xy 43.996356 -28.656534)
			(xy 43.99237 -28.664769) (xy 43.989817 -28.68287) (xy 43.993745 -28.700722) (xy 43.998388 -28.708604)
			(xy 44.030646 -28.758388) (xy 44.212256 -29.035502) (xy 44.212256 -29.114242) (xy 44.847256 -29.114242)
			(xy 44.847256 -28.250642) (xy 44.847746 -28.220658) (xy 44.855574 -28.161202) (xy 44.871095 -28.103277)
			(xy 44.894044 -28.047873) (xy 44.924028 -27.995939) (xy 44.960534 -27.948363) (xy 45.002939 -27.905958)
			(xy 45.050515 -27.869452) (xy 45.102449 -27.839468) (xy 45.157853 -27.816519) (xy 45.215778 -27.800998)
			(xy 45.275234 -27.79317) (xy 45.335202 -27.79317) (xy 45.394658 -27.800998) (xy 45.452583 -27.816519)
			(xy 45.507987 -27.839468) (xy 45.559921 -27.869452) (xy 45.607497 -27.905958) (xy 45.649902 -27.948363)
			(xy 45.686408 -27.995939) (xy 45.716392 -28.047873) (xy 45.739341 -28.103277) (xy 45.754862 -28.161202)
			(xy 45.76269 -28.220658) (xy 45.76318 -28.250642) (xy 45.76318 -29.114242) (xy 45.763047 -29.12237)
			(xy 60.60694 -29.12237) (xy 60.60694 -28.25877) (xy 60.60743 -28.228802) (xy 60.615253 -28.16938)
			(xy 60.630766 -28.111487) (xy 60.653702 -28.056114) (xy 60.683669 -28.004208) (xy 60.720156 -27.956658)
			(xy 60.762536 -27.914278) (xy 60.810086 -27.877791) (xy 60.861992 -27.847824) (xy 60.917365 -27.824888)
			(xy 60.975258 -27.809375) (xy 61.03468 -27.801552) (xy 61.094616 -27.801552) (xy 61.154038 -27.809375)
			(xy 61.211931 -27.824888) (xy 61.267304 -27.847824) (xy 61.31921 -27.877791) (xy 61.36676 -27.914278)
			(xy 61.40914 -27.956658) (xy 61.445627 -28.004208) (xy 61.475594 -28.056114) (xy 61.49853 -28.111487)
			(xy 61.514043 -28.16938) (xy 61.521866 -28.228802) (xy 61.522356 -28.25877) (xy 61.522356 -29.12237)
			(xy 61.521866 -29.152338) (xy 61.51481 -29.205936) (xy 62.02934 -29.205936) (xy 62.02934 -28.174188)
			(xy 62.029707 -28.16406) (xy 62.037466 -28.145348) (xy 62.051799 -28.131033) (xy 62.070519 -28.123295)
			(xy 62.080648 -28.12288) (xy 63.312548 -28.12288) (xy 63.322657 -28.123345) (xy 63.341333 -28.131095)
			(xy 63.355625 -28.145398) (xy 63.363362 -28.164078) (xy 63.363856 -28.174188) (xy 63.363856 -29.205936)
			(xy 66.56578 -29.205936) (xy 66.56578 -28.174188) (xy 66.566275 -28.164081) (xy 66.574013 -28.145406)
			(xy 66.588306 -28.131113) (xy 66.606981 -28.123375) (xy 66.617088 -28.12288) (xy 67.848988 -28.12288)
			(xy 67.859094 -28.123394) (xy 67.877768 -28.131124) (xy 67.892062 -28.145412) (xy 67.899801 -28.164083)
			(xy 67.900296 -28.174188) (xy 67.900296 -29.205936) (xy 67.899844 -29.216048) (xy 67.892094 -29.234727)
			(xy 67.877787 -29.249021) (xy 67.8591 -29.256754) (xy 67.848988 -29.257244) (xy 66.617088 -29.257244)
			(xy 66.606984 -29.256726) (xy 66.588314 -29.248992) (xy 66.574021 -29.234706) (xy 66.566279 -29.21604)
			(xy 66.56578 -29.205936) (xy 63.363856 -29.205936) (xy 63.363346 -29.21604) (xy 63.355607 -29.234708)
			(xy 63.341319 -29.249) (xy 63.322652 -29.256743) (xy 63.312548 -29.257244) (xy 62.080648 -29.257244)
			(xy 62.070534 -29.256746) (xy 62.05184 -29.249022) (xy 62.037526 -29.234731) (xy 62.029771 -29.216049)
			(xy 62.02934 -29.205936) (xy 61.51481 -29.205936) (xy 61.514043 -29.21176) (xy 61.49853 -29.269653)
			(xy 61.494412 -29.279596) (xy 69.37248 -29.279596) (xy 69.37248 -29.036772) (xy 69.566536 -28.740608)
			(xy 69.586348 -28.710382) (xy 69.591311 -28.701926) (xy 69.595047 -28.682697) (xy 69.591309 -28.663467)
			(xy 69.586348 -28.65501) (xy 69.41947 -28.39847) (xy 69.380862 -28.339288) (xy 69.380354 -28.338526)
			(xy 69.379846 -28.337764) (xy 69.379592 -28.337256) (xy 69.379084 -28.336494) (xy 69.37248 -28.32608)
			(xy 69.37248 -28.083256) (xy 69.373136 -28.071707) (xy 69.383095 -28.050863) (xy 69.401028 -28.036299)
			(xy 69.412104 -28.032964) (xy 69.424042 -28.03144) (xy 70.160642 -28.03144) (xy 70.171398 -28.031973)
			(xy 70.191088 -28.040629) (xy 70.198742 -28.048204) (xy 70.204957 -28.055591) (xy 70.211862 -28.073607)
			(xy 70.212204 -28.083256) (xy 70.212204 -28.32608) (xy 69.996304 -28.656534) (xy 69.992313 -28.664768)
			(xy 69.989758 -28.68287) (xy 69.99369 -28.700723) (xy 69.998336 -28.708604) (xy 70.030594 -28.758388)
			(xy 70.212204 -29.035502) (xy 70.212204 -29.114242) (xy 70.847204 -29.114242) (xy 70.847204 -28.250642)
			(xy 70.847694 -28.220658) (xy 70.855522 -28.161202) (xy 70.871043 -28.103277) (xy 70.893992 -28.047873)
			(xy 70.923976 -27.995939) (xy 70.960482 -27.948363) (xy 71.002887 -27.905958) (xy 71.050463 -27.869452)
			(xy 71.102397 -27.839468) (xy 71.157801 -27.816519) (xy 71.215726 -27.800998) (xy 71.275182 -27.79317)
			(xy 71.33515 -27.79317) (xy 71.394606 -27.800998) (xy 71.452531 -27.816519) (xy 71.507935 -27.839468)
			(xy 71.559869 -27.869452) (xy 71.607445 -27.905958) (xy 71.64985 -27.948363) (xy 71.686356 -27.995939)
			(xy 71.71634 -28.047873) (xy 71.739289 -28.103277) (xy 71.75481 -28.161202) (xy 71.762638 -28.220658)
			(xy 71.763128 -28.250642) (xy 71.763128 -29.114242) (xy 71.762995 -29.12237) (xy 86.606888 -29.12237)
			(xy 86.606888 -28.25877) (xy 86.607378 -28.228802) (xy 86.615201 -28.16938) (xy 86.630714 -28.111487)
			(xy 86.65365 -28.056114) (xy 86.683617 -28.004208) (xy 86.720104 -27.956658) (xy 86.762484 -27.914278)
			(xy 86.810034 -27.877791) (xy 86.86194 -27.847824) (xy 86.917313 -27.824888) (xy 86.975206 -27.809375)
			(xy 87.034628 -27.801552) (xy 87.094564 -27.801552) (xy 87.153986 -27.809375) (xy 87.211879 -27.824888)
			(xy 87.267252 -27.847824) (xy 87.319158 -27.877791) (xy 87.366708 -27.914278) (xy 87.409088 -27.956658)
			(xy 87.445575 -28.004208) (xy 87.475542 -28.056114) (xy 87.498478 -28.111487) (xy 87.513991 -28.16938)
			(xy 87.521814 -28.228802) (xy 87.522304 -28.25877) (xy 87.522304 -29.12237) (xy 87.521814 -29.152338)
			(xy 87.514758 -29.205936) (xy 88.029288 -29.205936) (xy 88.029288 -28.174188) (xy 88.029775 -28.16408)
			(xy 88.037515 -28.145404) (xy 88.051811 -28.13111) (xy 88.070488 -28.123374) (xy 88.080596 -28.12288)
			(xy 89.312496 -28.12288) (xy 89.322602 -28.123388) (xy 89.341276 -28.131121) (xy 89.35557 -28.14541)
			(xy 89.363309 -28.164082) (xy 89.363804 -28.174188) (xy 89.363804 -29.205936) (xy 92.565728 -29.205936)
			(xy 92.565728 -28.174188) (xy 92.566107 -28.164061) (xy 92.573864 -28.145352) (xy 92.588192 -28.131037)
			(xy 92.606909 -28.123297) (xy 92.617036 -28.12288) (xy 93.848936 -28.12288) (xy 93.859045 -28.123355)
			(xy 93.87772 -28.131101) (xy 93.892013 -28.1454) (xy 93.89975 -28.164079) (xy 93.900244 -28.174188)
			(xy 93.900244 -29.205936) (xy 93.899745 -29.216042) (xy 93.892004 -29.234712) (xy 93.877712 -29.249004)
			(xy 93.859042 -29.256745) (xy 93.848936 -29.257244) (xy 92.617036 -29.257244) (xy 92.606935 -29.256686)
			(xy 92.588266 -29.248969) (xy 92.573972 -29.234694) (xy 92.566228 -29.216036) (xy 92.565728 -29.205936)
			(xy 89.363804 -29.205936) (xy 89.363344 -29.216047) (xy 89.355596 -29.234725) (xy 89.341291 -29.249018)
			(xy 89.322607 -29.256752) (xy 89.312496 -29.257244) (xy 88.080596 -29.257244) (xy 88.070492 -29.256719)
			(xy 88.051823 -29.248988) (xy 88.03753 -29.234704) (xy 88.029787 -29.216039) (xy 88.029288 -29.205936)
			(xy 87.514758 -29.205936) (xy 87.513991 -29.21176) (xy 87.498478 -29.269653) (xy 87.49436 -29.279596)
			(xy 95.372428 -29.279596) (xy 95.372428 -29.036772) (xy 95.517208 -28.816046) (xy 95.566484 -28.740608)
			(xy 95.586296 -28.710382) (xy 95.591256 -28.701925) (xy 95.594987 -28.682697) (xy 95.591253 -28.663468)
			(xy 95.586296 -28.65501) (xy 95.441262 -28.431998) (xy 95.385636 -28.346654) (xy 95.381318 -28.340558)
			(xy 95.378016 -28.33497) (xy 95.377508 -28.333954) (xy 95.372428 -28.32608) (xy 95.372428 -28.083256)
			(xy 95.373056 -28.071737) (xy 95.382932 -28.050922) (xy 95.400765 -28.036334) (xy 95.411798 -28.032964)
			(xy 95.412052 -28.032964) (xy 95.42399 -28.03144) (xy 96.16059 -28.03144) (xy 96.166962 -28.031678)
			(xy 96.179299 -28.034882) (xy 96.184974 -28.03779) (xy 96.192968 -28.042555) (xy 96.20521 -28.056553)
			(xy 96.211755 -28.073959) (xy 96.212152 -28.083256) (xy 96.212152 -28.32608) (xy 95.996252 -28.656534)
			(xy 95.992257 -28.664767) (xy 95.989699 -28.68287) (xy 95.993635 -28.700724) (xy 95.998284 -28.708604)
			(xy 96.030542 -28.758388) (xy 96.046036 -28.78201) (xy 96.212152 -29.035502) (xy 96.212152 -29.114242)
			(xy 96.847152 -29.114242) (xy 96.847152 -28.250642) (xy 96.847642 -28.220658) (xy 96.85547 -28.161202)
			(xy 96.870991 -28.103277) (xy 96.89394 -28.047873) (xy 96.923924 -27.995939) (xy 96.96043 -27.948363)
			(xy 97.002835 -27.905958) (xy 97.050411 -27.869452) (xy 97.102345 -27.839468) (xy 97.157749 -27.816519)
			(xy 97.215674 -27.800998) (xy 97.27513 -27.79317) (xy 97.335098 -27.79317) (xy 97.394554 -27.800998)
			(xy 97.452479 -27.816519) (xy 97.507883 -27.839468) (xy 97.559817 -27.869452) (xy 97.607393 -27.905958)
			(xy 97.649798 -27.948363) (xy 97.686304 -27.995939) (xy 97.716288 -28.047873) (xy 97.739237 -28.103277)
			(xy 97.754758 -28.161202) (xy 97.762586 -28.220658) (xy 97.763076 -28.250642) (xy 97.763076 -29.114242)
			(xy 97.762943 -29.12237) (xy 124.706888 -29.12237) (xy 124.706888 -28.25877) (xy 124.707378 -28.228786)
			(xy 124.715206 -28.16933) (xy 124.730727 -28.111405) (xy 124.753676 -28.056001) (xy 124.78366 -28.004067)
			(xy 124.820166 -27.956491) (xy 124.862571 -27.914086) (xy 124.910147 -27.87758) (xy 124.962081 -27.847596)
			(xy 125.017485 -27.824647) (xy 125.07541 -27.809126) (xy 125.134866 -27.801298) (xy 125.194834 -27.801298)
			(xy 125.25429 -27.809126) (xy 125.312215 -27.824647) (xy 125.367619 -27.847596) (xy 125.419553 -27.87758)
			(xy 125.467129 -27.914086) (xy 125.509534 -27.956491) (xy 125.54604 -28.004067) (xy 125.576024 -28.056001)
			(xy 125.598973 -28.111405) (xy 125.614494 -28.16933) (xy 125.622322 -28.228786) (xy 125.622812 -28.25877)
			(xy 125.622812 -29.12237) (xy 125.622322 -29.152354) (xy 125.615267 -29.205936) (xy 126.129288 -29.205936)
			(xy 126.129288 -28.174188) (xy 126.129775 -28.16408) (xy 126.137515 -28.145404) (xy 126.151811 -28.13111)
			(xy 126.170488 -28.123374) (xy 126.180596 -28.12288) (xy 127.41275 -28.12288) (xy 127.422878 -28.123369)
			(xy 127.441606 -28.131087) (xy 127.455965 -28.145374) (xy 127.463779 -28.164062) (xy 127.464312 -28.174188)
			(xy 127.464312 -29.205936) (xy 130.665728 -29.205936) (xy 130.665728 -28.174188) (xy 130.666112 -28.16403)
			(xy 130.673917 -28.145271) (xy 130.688325 -28.130947) (xy 130.707129 -28.123253) (xy 130.71729 -28.12288)
			(xy 131.94919 -28.12288) (xy 131.959321 -28.123336) (xy 131.97805 -28.131068) (xy 131.992408 -28.145364)
			(xy 132.00022 -28.164059) (xy 132.000752 -28.174188) (xy 132.000752 -29.205936) (xy 132.000309 -29.216086)
			(xy 131.992511 -29.234829) (xy 131.978122 -29.249149) (xy 131.959342 -29.256857) (xy 131.94919 -29.257244)
			(xy 130.71729 -29.257244) (xy 130.707161 -29.256781) (xy 130.688436 -29.249047) (xy 130.67408 -29.234753)
			(xy 130.666264 -29.216063) (xy 130.665728 -29.205936) (xy 127.464312 -29.205936) (xy 127.463845 -29.216046)
			(xy 127.456097 -29.234722) (xy 127.441795 -29.249015) (xy 127.423114 -29.256751) (xy 127.413004 -29.257244)
			(xy 126.18085 -29.257244) (xy 126.170725 -29.256732) (xy 126.152001 -29.249018) (xy 126.137643 -29.234739)
			(xy 126.129825 -29.216059) (xy 126.129288 -29.205936) (xy 125.615267 -29.205936) (xy 125.614494 -29.21181)
			(xy 125.598973 -29.269735) (xy 125.594888 -29.279596) (xy 133.472428 -29.279596) (xy 133.472428 -29.052012)
			(xy 133.472682 -29.047948) (xy 133.472936 -29.045408) (xy 133.472936 -29.036772) (xy 133.478524 -29.028136)
			(xy 133.479794 -29.026104) (xy 133.48081 -29.024072) (xy 133.678168 -28.723082) (xy 133.682057 -28.716765)
			(xy 133.686304 -28.702557) (xy 133.68655 -28.695142) (xy 133.68655 -28.669488) (xy 133.686327 -28.662155)
			(xy 133.682209 -28.648084) (xy 133.678422 -28.641802) (xy 133.480556 -28.33878) (xy 133.47827 -28.33497)
			(xy 133.478016 -28.334462) (xy 133.477 -28.332684) (xy 133.472936 -28.32608) (xy 133.472936 -28.317952)
			(xy 133.472682 -28.315412) (xy 133.472428 -28.311348) (xy 133.472428 -28.083256) (xy 133.472847 -28.07304)
			(xy 133.480682 -28.054169) (xy 133.495143 -28.039733) (xy 133.514027 -28.03193) (xy 133.524244 -28.03144)
			(xy 134.260844 -28.03144) (xy 134.271049 -28.031945) (xy 134.289903 -28.039764) (xy 134.304336 -28.054197)
			(xy 134.312155 -28.073051) (xy 134.31266 -28.083256) (xy 134.31266 -28.31084) (xy 134.312406 -28.314904)
			(xy 134.312152 -28.317444) (xy 134.312152 -28.32608) (xy 134.30631 -28.335478) (xy 134.305548 -28.336748)
			(xy 134.304278 -28.33878) (xy 134.098538 -28.653486) (xy 134.093466 -28.661996) (xy 134.089658 -28.681422)
			(xy 134.093482 -28.700844) (xy 134.098538 -28.709366) (xy 134.304278 -29.022802) (xy 134.305294 -29.024834)
			(xy 134.306564 -29.026866) (xy 134.312152 -29.035502) (xy 134.312152 -29.044138) (xy 134.312406 -29.046678)
			(xy 134.31266 -29.050742) (xy 134.31266 -29.114242) (xy 134.94766 -29.114242) (xy 134.94766 -28.250642)
			(xy 134.94815 -28.220674) (xy 134.955973 -28.161252) (xy 134.971486 -28.103359) (xy 134.994422 -28.047986)
			(xy 135.024389 -27.99608) (xy 135.060876 -27.94853) (xy 135.103256 -27.90615) (xy 135.150806 -27.869663)
			(xy 135.202712 -27.839696) (xy 135.258085 -27.81676) (xy 135.315978 -27.801247) (xy 135.3754 -27.793424)
			(xy 135.435336 -27.793424) (xy 135.494758 -27.801247) (xy 135.552651 -27.81676) (xy 135.608024 -27.839696)
			(xy 135.65993 -27.869663) (xy 135.70748 -27.90615) (xy 135.74986 -27.94853) (xy 135.786347 -27.99608)
			(xy 135.816314 -28.047986) (xy 135.83925 -28.103359) (xy 135.854763 -28.161252) (xy 135.862586 -28.220674)
			(xy 135.863076 -28.250642) (xy 135.863076 -29.114242) (xy 135.862943 -29.12237) (xy 150.706836 -29.12237)
			(xy 150.706836 -28.25877) (xy 150.707326 -28.228786) (xy 150.715154 -28.16933) (xy 150.730675 -28.111405)
			(xy 150.753624 -28.056001) (xy 150.783608 -28.004067) (xy 150.820114 -27.956491) (xy 150.862519 -27.914086)
			(xy 150.910095 -27.87758) (xy 150.962029 -27.847596) (xy 151.017433 -27.824647) (xy 151.075358 -27.809126)
			(xy 151.134814 -27.801298) (xy 151.194782 -27.801298) (xy 151.254238 -27.809126) (xy 151.312163 -27.824647)
			(xy 151.367567 -27.847596) (xy 151.419501 -27.87758) (xy 151.467077 -27.914086) (xy 151.509482 -27.956491)
			(xy 151.545988 -28.004067) (xy 151.575972 -28.056001) (xy 151.598921 -28.111405) (xy 151.614442 -28.16933)
			(xy 151.62227 -28.228786) (xy 151.62276 -28.25877) (xy 151.62276 -29.12237) (xy 151.62227 -29.152354)
			(xy 151.615215 -29.205936) (xy 152.129236 -29.205936) (xy 152.129236 -28.174188) (xy 152.129607 -28.16406)
			(xy 152.137366 -28.145349) (xy 152.151696 -28.131034) (xy 152.170416 -28.123296) (xy 152.180544 -28.12288)
			(xy 153.412698 -28.12288) (xy 153.422829 -28.123329) (xy 153.441558 -28.131064) (xy 153.455916 -28.145362)
			(xy 153.463728 -28.164059) (xy 153.46426 -28.174188) (xy 153.46426 -29.205936) (xy 156.665676 -29.205936)
			(xy 156.665676 -28.174188) (xy 156.666111 -28.164036) (xy 156.673906 -28.145288) (xy 156.688298 -28.130966)
			(xy 156.707084 -28.123262) (xy 156.717238 -28.12288) (xy 157.949138 -28.12288) (xy 157.959272 -28.123297)
			(xy 157.978002 -28.131044) (xy 157.992358 -28.145352) (xy 158.000169 -28.164056) (xy 158.0007 -28.174188)
			(xy 158.0007 -29.205936) (xy 158.000308 -29.216092) (xy 157.9925 -29.234846) (xy 157.978095 -29.249168)
			(xy 157.959297 -29.256866) (xy 157.949138 -29.257244) (xy 156.717238 -29.257244) (xy 156.707112 -29.256742)
			(xy 156.688389 -29.249023) (xy 156.67403 -29.234741) (xy 156.666213 -29.216059) (xy 156.665676 -29.205936)
			(xy 153.46426 -29.205936) (xy 153.463913 -29.216066) (xy 153.456145 -29.234778) (xy 153.441807 -29.249092)
			(xy 153.423082 -29.256829) (xy 153.412952 -29.257244) (xy 152.180798 -29.257244) (xy 152.170669 -29.256774)
			(xy 152.151945 -29.249043) (xy 152.137588 -29.234751) (xy 152.129772 -29.216062) (xy 152.129236 -29.205936)
			(xy 151.615215 -29.205936) (xy 151.614442 -29.21181) (xy 151.598921 -29.269735) (xy 151.594836 -29.279596)
			(xy 159.472376 -29.279596) (xy 159.472376 -29.052012) (xy 159.47263 -29.047948) (xy 159.472884 -29.045408)
			(xy 159.472884 -29.036772) (xy 159.478472 -29.028136) (xy 159.479742 -29.026104) (xy 159.480758 -29.024072)
			(xy 159.678116 -28.723082) (xy 159.682 -28.716763) (xy 159.686251 -28.702556) (xy 159.686498 -28.695142)
			(xy 159.686498 -28.669488) (xy 159.686268 -28.662156) (xy 159.682154 -28.648085) (xy 159.67837 -28.641802)
			(xy 159.480504 -28.33878) (xy 159.478218 -28.33497) (xy 159.477964 -28.334462) (xy 159.476948 -28.332684)
			(xy 159.472884 -28.32608) (xy 159.472884 -28.317952) (xy 159.47263 -28.315412) (xy 159.472376 -28.311348)
			(xy 159.472376 -28.083256) (xy 159.472846 -28.073046) (xy 159.480671 -28.054185) (xy 159.495116 -28.039751)
			(xy 159.513982 -28.031939) (xy 159.524192 -28.03144) (xy 160.260792 -28.03144) (xy 160.270994 -28.031987)
			(xy 160.289847 -28.039789) (xy 160.304282 -28.054209) (xy 160.312102 -28.073055) (xy 160.312608 -28.083256)
			(xy 160.312608 -28.31084) (xy 160.312354 -28.314904) (xy 160.3121 -28.317444) (xy 160.3121 -28.32608)
			(xy 160.306258 -28.335478) (xy 160.305496 -28.336748) (xy 160.304226 -28.33878) (xy 160.098486 -28.653486)
			(xy 160.09341 -28.661995) (xy 160.089599 -28.681422) (xy 160.093427 -28.700845) (xy 160.098486 -28.709366)
			(xy 160.304226 -29.022802) (xy 160.305242 -29.024834) (xy 160.306512 -29.026866) (xy 160.3121 -29.035502)
			(xy 160.3121 -29.044138) (xy 160.312354 -29.046678) (xy 160.312608 -29.050742) (xy 160.312608 -29.114242)
			(xy 160.947608 -29.114242) (xy 160.947608 -28.250642) (xy 160.948098 -28.220674) (xy 160.955921 -28.161252)
			(xy 160.971434 -28.103359) (xy 160.99437 -28.047986) (xy 161.024337 -27.99608) (xy 161.060824 -27.94853)
			(xy 161.103204 -27.90615) (xy 161.150754 -27.869663) (xy 161.20266 -27.839696) (xy 161.258033 -27.81676)
			(xy 161.315926 -27.801247) (xy 161.375348 -27.793424) (xy 161.435284 -27.793424) (xy 161.494706 -27.801247)
			(xy 161.552599 -27.81676) (xy 161.607972 -27.839696) (xy 161.659878 -27.869663) (xy 161.707428 -27.90615)
			(xy 161.749808 -27.94853) (xy 161.786295 -27.99608) (xy 161.816262 -28.047986) (xy 161.839198 -28.103359)
			(xy 161.854711 -28.161252) (xy 161.862534 -28.220674) (xy 161.863024 -28.250642) (xy 161.863024 -29.114242)
			(xy 161.862891 -29.12237) (xy 176.706784 -29.12237) (xy 176.706784 -28.25877) (xy 176.707274 -28.228786)
			(xy 176.715102 -28.16933) (xy 176.730623 -28.111405) (xy 176.753572 -28.056001) (xy 176.783556 -28.004067)
			(xy 176.820062 -27.956491) (xy 176.862467 -27.914086) (xy 176.910043 -27.87758) (xy 176.961977 -27.847596)
			(xy 177.017381 -27.824647) (xy 177.075306 -27.809126) (xy 177.134762 -27.801298) (xy 177.19473 -27.801298)
			(xy 177.254186 -27.809126) (xy 177.312111 -27.824647) (xy 177.367515 -27.847596) (xy 177.419449 -27.87758)
			(xy 177.467025 -27.914086) (xy 177.50943 -27.956491) (xy 177.545936 -28.004067) (xy 177.57592 -28.056001)
			(xy 177.598869 -28.111405) (xy 177.61439 -28.16933) (xy 177.622218 -28.228786) (xy 177.622708 -28.25877)
			(xy 177.622708 -29.12237) (xy 177.622218 -29.152354) (xy 177.615163 -29.205936) (xy 178.129184 -29.205936)
			(xy 178.129184 -28.174188) (xy 178.129675 -28.164081) (xy 178.137414 -28.145405) (xy 178.151709 -28.131111)
			(xy 178.170384 -28.123374) (xy 178.180492 -28.12288) (xy 179.412646 -28.12288) (xy 179.422781 -28.12329)
			(xy 179.44151 -28.13104) (xy 179.455866 -28.14535) (xy 179.463677 -28.164055) (xy 179.464208 -28.174188)
			(xy 179.464208 -29.205936) (xy 182.665624 -29.205936) (xy 182.665624 -28.174188) (xy 182.666012 -28.16403)
			(xy 182.673816 -28.145273) (xy 182.688223 -28.130949) (xy 182.707026 -28.123254) (xy 182.717186 -28.12288)
			(xy 183.949086 -28.12288) (xy 183.959217 -28.123339) (xy 183.977945 -28.13107) (xy 183.992303 -28.145365)
			(xy 184.000116 -28.164059) (xy 184.000648 -28.174188) (xy 184.000648 -29.205936) (xy 184.000209 -29.216086)
			(xy 183.99241 -29.23483) (xy 183.97802 -29.249151) (xy 183.959238 -29.256858) (xy 183.949086 -29.257244)
			(xy 182.717186 -29.257244) (xy 182.707056 -29.256784) (xy 182.688332 -29.249049) (xy 182.673976 -29.234754)
			(xy 182.66616 -29.216063) (xy 182.665624 -29.205936) (xy 179.464208 -29.205936) (xy 179.463745 -29.216046)
			(xy 179.455997 -29.234724) (xy 179.441693 -29.249017) (xy 179.42301 -29.256752) (xy 179.4129 -29.257244)
			(xy 178.180746 -29.257244) (xy 178.17062 -29.256735) (xy 178.151897 -29.24902) (xy 178.137539 -29.23474)
			(xy 178.129721 -29.216059) (xy 178.129184 -29.205936) (xy 177.615163 -29.205936) (xy 177.61439 -29.21181)
			(xy 177.598869 -29.269735) (xy 177.594784 -29.279596) (xy 185.472324 -29.279596) (xy 185.472324 -29.052012)
			(xy 185.472578 -29.047948) (xy 185.472832 -29.045408) (xy 185.472832 -29.036772) (xy 185.47842 -29.028136)
			(xy 185.47969 -29.026104) (xy 185.480706 -29.024072) (xy 185.678064 -28.723082) (xy 185.681952 -28.716765)
			(xy 185.686199 -28.702557) (xy 185.686446 -28.695142) (xy 185.686446 -28.669488) (xy 185.686224 -28.662155)
			(xy 185.682105 -28.648084) (xy 185.678318 -28.641802) (xy 185.480452 -28.33878) (xy 185.478166 -28.33497)
			(xy 185.477912 -28.334462) (xy 185.476896 -28.332684) (xy 185.472832 -28.32608) (xy 185.472832 -28.317952)
			(xy 185.472578 -28.315412) (xy 185.472324 -28.311348) (xy 185.472324 -28.083256) (xy 185.472747 -28.07304)
			(xy 185.480581 -28.05417) (xy 185.495041 -28.039734) (xy 185.513924 -28.03193) (xy 185.52414 -28.03144)
			(xy 186.26074 -28.03144) (xy 186.270945 -28.031948) (xy 186.289799 -28.039766) (xy 186.304232 -28.054198)
			(xy 186.312051 -28.073051) (xy 186.312556 -28.083256) (xy 186.312556 -28.31084) (xy 186.312302 -28.314904)
			(xy 186.312048 -28.317444) (xy 186.312048 -28.32608) (xy 186.306206 -28.335478) (xy 186.305444 -28.336748)
			(xy 186.304174 -28.33878) (xy 186.098434 -28.653486) (xy 186.093362 -28.661996) (xy 186.089555 -28.681422)
			(xy 186.093379 -28.700844) (xy 186.098434 -28.709366) (xy 186.304174 -29.022802) (xy 186.30519 -29.024834)
			(xy 186.30646 -29.026866) (xy 186.312048 -29.035502) (xy 186.312048 -29.044138) (xy 186.312302 -29.046678)
			(xy 186.312556 -29.050742) (xy 186.312556 -29.114242) (xy 186.947556 -29.114242) (xy 186.947556 -28.250642)
			(xy 186.948046 -28.220674) (xy 186.955869 -28.161252) (xy 186.971382 -28.103359) (xy 186.994318 -28.047986)
			(xy 187.024285 -27.99608) (xy 187.060772 -27.94853) (xy 187.103152 -27.90615) (xy 187.150702 -27.869663)
			(xy 187.202608 -27.839696) (xy 187.257981 -27.81676) (xy 187.315874 -27.801247) (xy 187.375296 -27.793424)
			(xy 187.435232 -27.793424) (xy 187.494654 -27.801247) (xy 187.552547 -27.81676) (xy 187.60792 -27.839696)
			(xy 187.659826 -27.869663) (xy 187.707376 -27.90615) (xy 187.749756 -27.94853) (xy 187.786243 -27.99608)
			(xy 187.81621 -28.047986) (xy 187.839146 -28.103359) (xy 187.854659 -28.161252) (xy 187.862482 -28.220674)
			(xy 187.862972 -28.250642) (xy 187.862972 -29.114242) (xy 187.862839 -29.12237) (xy 202.706732 -29.12237)
			(xy 202.706732 -28.25877) (xy 202.707222 -28.228786) (xy 202.71505 -28.16933) (xy 202.730571 -28.111405)
			(xy 202.75352 -28.056001) (xy 202.783504 -28.004067) (xy 202.82001 -27.956491) (xy 202.862415 -27.914086)
			(xy 202.909991 -27.87758) (xy 202.961925 -27.847596) (xy 203.017329 -27.824647) (xy 203.075254 -27.809126)
			(xy 203.13471 -27.801298) (xy 203.194678 -27.801298) (xy 203.254134 -27.809126) (xy 203.312059 -27.824647)
			(xy 203.367463 -27.847596) (xy 203.419397 -27.87758) (xy 203.466973 -27.914086) (xy 203.509378 -27.956491)
			(xy 203.545884 -28.004067) (xy 203.575868 -28.056001) (xy 203.598817 -28.111405) (xy 203.614338 -28.16933)
			(xy 203.622166 -28.228786) (xy 203.622656 -28.25877) (xy 203.622656 -29.12237) (xy 203.622166 -29.152354)
			(xy 203.615111 -29.205936) (xy 204.129132 -29.205936) (xy 204.129132 -28.174188) (xy 204.129507 -28.164061)
			(xy 204.137265 -28.145351) (xy 204.151594 -28.131036) (xy 204.170312 -28.123296) (xy 204.18044 -28.12288)
			(xy 205.412594 -28.12288) (xy 205.422725 -28.123333) (xy 205.441454 -28.131066) (xy 205.455812 -28.145363)
			(xy 205.463624 -28.164059) (xy 205.464156 -28.174188) (xy 205.464156 -29.205936) (xy 208.665572 -29.205936)
			(xy 208.665572 -28.174188) (xy 208.666011 -28.164037) (xy 208.673805 -28.145289) (xy 208.688196 -28.130967)
			(xy 208.706981 -28.123263) (xy 208.717134 -28.12288) (xy 209.949034 -28.12288) (xy 209.959168 -28.1233)
			(xy 209.977897 -28.131046) (xy 209.992254 -28.145353) (xy 210.000065 -28.164056) (xy 210.000596 -28.174188)
			(xy 210.000596 -29.205936) (xy 210.000208 -29.216093) (xy 209.9924 -29.234847) (xy 209.977993 -29.249169)
			(xy 209.959193 -29.256867) (xy 209.949034 -29.257244) (xy 208.717134 -29.257244) (xy 208.707008 -29.256745)
			(xy 208.688284 -29.249025) (xy 208.673926 -29.234742) (xy 208.666109 -29.21606) (xy 208.665572 -29.205936)
			(xy 205.464156 -29.205936) (xy 205.463646 -29.21604) (xy 205.455907 -29.234708) (xy 205.441619 -29.249)
			(xy 205.422952 -29.256743) (xy 205.412848 -29.257244) (xy 204.180694 -29.257244) (xy 204.170565 -29.256778)
			(xy 204.151841 -29.249045) (xy 204.137484 -29.234752) (xy 204.129668 -29.216063) (xy 204.129132 -29.205936)
			(xy 203.615111 -29.205936) (xy 203.614338 -29.21181) (xy 203.598817 -29.269735) (xy 203.594732 -29.279596)
			(xy 211.472272 -29.279596) (xy 211.472272 -29.036772) (xy 211.47786 -29.02839) (xy 211.478114 -29.027882)
			(xy 211.480146 -29.024834) (xy 211.4804 -29.024326) (xy 211.68614 -28.710382) (xy 211.69113 -28.701945)
			(xy 211.694945 -28.682736) (xy 211.691306 -28.663493) (xy 211.686394 -28.65501) (xy 211.600542 -28.52293)
			(xy 211.591144 -28.508452) (xy 211.478876 -28.336494) (xy 211.478368 -28.335478) (xy 211.476336 -28.33243)
			(xy 211.476082 -28.331922) (xy 211.472272 -28.32608) (xy 211.472272 -28.083256) (xy 211.472746 -28.073047)
			(xy 211.480571 -28.054187) (xy 211.495013 -28.039753) (xy 211.513879 -28.031939) (xy 211.524088 -28.03144)
			(xy 212.260688 -28.03144) (xy 212.27089 -28.03199) (xy 212.289743 -28.039791) (xy 212.304177 -28.05421)
			(xy 212.311998 -28.073055) (xy 212.312504 -28.083256) (xy 212.312504 -28.32608) (xy 212.308694 -28.331922)
			(xy 212.30844 -28.33243) (xy 212.304376 -28.338526) (xy 212.304122 -28.33878) (xy 212.1662 -28.549854)
			(xy 212.113114 -28.631134) (xy 212.100668 -28.650184) (xy 212.098636 -28.652978) (xy 212.097366 -28.65501)
			(xy 212.093152 -28.66242) (xy 212.089438 -28.679047) (xy 212.091405 -28.69597) (xy 212.094826 -28.703778)
			(xy 212.282024 -28.989274) (xy 212.284564 -28.993084) (xy 212.304376 -29.023056) (xy 212.30463 -29.023564)
			(xy 212.3059 -29.025596) (xy 212.307678 -29.028136) (xy 212.312504 -29.035502) (xy 212.312504 -29.114242)
			(xy 212.947504 -29.114242) (xy 212.947504 -28.250642) (xy 212.947994 -28.220674) (xy 212.955817 -28.161252)
			(xy 212.97133 -28.103359) (xy 212.994266 -28.047986) (xy 213.024233 -27.99608) (xy 213.06072 -27.94853)
			(xy 213.1031 -27.90615) (xy 213.15065 -27.869663) (xy 213.202556 -27.839696) (xy 213.257929 -27.81676)
			(xy 213.315822 -27.801247) (xy 213.375244 -27.793424) (xy 213.43518 -27.793424) (xy 213.494602 -27.801247)
			(xy 213.552495 -27.81676) (xy 213.607868 -27.839696) (xy 213.659774 -27.869663) (xy 213.707324 -27.90615)
			(xy 213.749704 -27.94853) (xy 213.786191 -27.99608) (xy 213.816158 -28.047986) (xy 213.839094 -28.103359)
			(xy 213.854607 -28.161252) (xy 213.86243 -28.220674) (xy 213.86292 -28.250642) (xy 213.86292 -29.114242)
			(xy 213.862787 -29.12237) (xy 240.806732 -29.12237) (xy 240.806732 -28.25877) (xy 240.807222 -28.228786)
			(xy 240.81505 -28.16933) (xy 240.830571 -28.111405) (xy 240.85352 -28.056001) (xy 240.883504 -28.004067)
			(xy 240.92001 -27.956491) (xy 240.962415 -27.914086) (xy 241.009991 -27.87758) (xy 241.061925 -27.847596)
			(xy 241.117329 -27.824647) (xy 241.175254 -27.809126) (xy 241.23471 -27.801298) (xy 241.294678 -27.801298)
			(xy 241.354134 -27.809126) (xy 241.412059 -27.824647) (xy 241.467463 -27.847596) (xy 241.519397 -27.87758)
			(xy 241.566973 -27.914086) (xy 241.609378 -27.956491) (xy 241.645884 -28.004067) (xy 241.675868 -28.056001)
			(xy 241.698817 -28.111405) (xy 241.714338 -28.16933) (xy 241.722166 -28.228786) (xy 241.722656 -28.25877)
			(xy 241.722656 -29.12237) (xy 241.722166 -29.152354) (xy 241.715111 -29.205936) (xy 242.229132 -29.205936)
			(xy 242.229132 -28.174188) (xy 242.229507 -28.164061) (xy 242.237265 -28.145351) (xy 242.251594 -28.131036)
			(xy 242.270312 -28.123296) (xy 242.28044 -28.12288) (xy 243.512594 -28.12288) (xy 243.522725 -28.123333)
			(xy 243.541454 -28.131066) (xy 243.555812 -28.145363) (xy 243.563624 -28.164059) (xy 243.564156 -28.174188)
			(xy 243.564156 -29.205936) (xy 246.765572 -29.205936) (xy 246.765572 -28.174188) (xy 246.766011 -28.164037)
			(xy 246.773805 -28.145289) (xy 246.788196 -28.130967) (xy 246.806981 -28.123263) (xy 246.817134 -28.12288)
			(xy 248.049034 -28.12288) (xy 248.059168 -28.1233) (xy 248.077897 -28.131046) (xy 248.092254 -28.145353)
			(xy 248.100065 -28.164056) (xy 248.100596 -28.174188) (xy 248.100596 -29.205936) (xy 248.100208 -29.216093)
			(xy 248.0924 -29.234847) (xy 248.077993 -29.249169) (xy 248.059193 -29.256867) (xy 248.049034 -29.257244)
			(xy 246.817134 -29.257244) (xy 246.807008 -29.256745) (xy 246.788284 -29.249025) (xy 246.773926 -29.234742)
			(xy 246.766109 -29.21606) (xy 246.765572 -29.205936) (xy 243.564156 -29.205936) (xy 243.563646 -29.21604)
			(xy 243.555907 -29.234708) (xy 243.541619 -29.249) (xy 243.522952 -29.256743) (xy 243.512848 -29.257244)
			(xy 242.280694 -29.257244) (xy 242.270565 -29.256778) (xy 242.251841 -29.249045) (xy 242.237484 -29.234752)
			(xy 242.229668 -29.216063) (xy 242.229132 -29.205936) (xy 241.715111 -29.205936) (xy 241.714338 -29.21181)
			(xy 241.698817 -29.269735) (xy 241.694732 -29.279596) (xy 249.572272 -29.279596) (xy 249.572272 -29.052012)
			(xy 249.572526 -29.047948) (xy 249.57278 -29.045408) (xy 249.57278 -29.036772) (xy 249.578368 -29.028136)
			(xy 249.579638 -29.026104) (xy 249.580654 -29.024072) (xy 249.778012 -28.723082) (xy 249.781896 -28.716762)
			(xy 249.786147 -28.702556) (xy 249.786394 -28.695142) (xy 249.786394 -28.669488) (xy 249.786165 -28.662156)
			(xy 249.78205 -28.648085) (xy 249.778266 -28.641802) (xy 249.5804 -28.33878) (xy 249.578114 -28.33497)
			(xy 249.57786 -28.334462) (xy 249.576844 -28.332684) (xy 249.57278 -28.32608) (xy 249.57278 -28.317952)
			(xy 249.572526 -28.315412) (xy 249.572272 -28.311348) (xy 249.572272 -28.083256) (xy 249.572746 -28.073047)
			(xy 249.580571 -28.054187) (xy 249.595013 -28.039753) (xy 249.613879 -28.031939) (xy 249.624088 -28.03144)
			(xy 250.360688 -28.03144) (xy 250.37089 -28.03199) (xy 250.389743 -28.039791) (xy 250.404177 -28.05421)
			(xy 250.411998 -28.073055) (xy 250.412504 -28.083256) (xy 250.412504 -28.31084) (xy 250.41225 -28.314904)
			(xy 250.411996 -28.317444) (xy 250.411996 -28.32608) (xy 250.406154 -28.335478) (xy 250.405392 -28.336748)
			(xy 250.404122 -28.33878) (xy 250.198382 -28.653486) (xy 250.193306 -28.661995) (xy 250.189495 -28.681422)
			(xy 250.193323 -28.700845) (xy 250.198382 -28.709366) (xy 250.404122 -29.022802) (xy 250.405138 -29.024834)
			(xy 250.406408 -29.026866) (xy 250.411996 -29.035502) (xy 250.411996 -29.044138) (xy 250.41225 -29.046678)
			(xy 250.412504 -29.050742) (xy 250.412504 -29.114242) (xy 251.047504 -29.114242) (xy 251.047504 -28.250642)
			(xy 251.047994 -28.220674) (xy 251.055817 -28.161252) (xy 251.07133 -28.103359) (xy 251.094266 -28.047986)
			(xy 251.124233 -27.99608) (xy 251.16072 -27.94853) (xy 251.2031 -27.90615) (xy 251.25065 -27.869663)
			(xy 251.302556 -27.839696) (xy 251.357929 -27.81676) (xy 251.415822 -27.801247) (xy 251.475244 -27.793424)
			(xy 251.53518 -27.793424) (xy 251.594602 -27.801247) (xy 251.652495 -27.81676) (xy 251.707868 -27.839696)
			(xy 251.759774 -27.869663) (xy 251.807324 -27.90615) (xy 251.849704 -27.94853) (xy 251.886191 -27.99608)
			(xy 251.916158 -28.047986) (xy 251.939094 -28.103359) (xy 251.954607 -28.161252) (xy 251.96243 -28.220674)
			(xy 251.96292 -28.250642) (xy 251.96292 -29.114242) (xy 251.962787 -29.12237) (xy 266.80668 -29.12237)
			(xy 266.80668 -28.25877) (xy 266.80717 -28.228786) (xy 266.814998 -28.16933) (xy 266.830519 -28.111405)
			(xy 266.853468 -28.056001) (xy 266.883452 -28.004067) (xy 266.919958 -27.956491) (xy 266.962363 -27.914086)
			(xy 267.009939 -27.87758) (xy 267.061873 -27.847596) (xy 267.117277 -27.824647) (xy 267.175202 -27.809126)
			(xy 267.234658 -27.801298) (xy 267.294626 -27.801298) (xy 267.354082 -27.809126) (xy 267.412007 -27.824647)
			(xy 267.467411 -27.847596) (xy 267.519345 -27.87758) (xy 267.566921 -27.914086) (xy 267.609326 -27.956491)
			(xy 267.645832 -28.004067) (xy 267.675816 -28.056001) (xy 267.698765 -28.111405) (xy 267.714286 -28.16933)
			(xy 267.722114 -28.228786) (xy 267.722604 -28.25877) (xy 267.722604 -29.12237) (xy 267.722114 -29.152354)
			(xy 267.715059 -29.205936) (xy 268.22908 -29.205936) (xy 268.22908 -28.174188) (xy 268.229575 -28.164081)
			(xy 268.237313 -28.145406) (xy 268.251606 -28.131113) (xy 268.270281 -28.123375) (xy 268.280388 -28.12288)
			(xy 269.512542 -28.12288) (xy 269.522676 -28.123293) (xy 269.541406 -28.131042) (xy 269.555762 -28.145351)
			(xy 269.563573 -28.164055) (xy 269.564104 -28.174188) (xy 269.564104 -29.205936) (xy 272.76552 -29.205936)
			(xy 272.76552 -28.174188) (xy 272.765912 -28.164031) (xy 272.773715 -28.145274) (xy 272.788121 -28.13095)
			(xy 272.806922 -28.123254) (xy 272.817082 -28.12288) (xy 274.048982 -28.12288) (xy 274.059112 -28.123342)
			(xy 274.077841 -28.131072) (xy 274.092199 -28.145366) (xy 274.100012 -28.16406) (xy 274.100544 -28.174188)
			(xy 274.100544 -29.205936) (xy 274.100109 -29.216087) (xy 274.09231 -29.234832) (xy 274.077918 -29.249152)
			(xy 274.059135 -29.256859) (xy 274.048982 -29.257244) (xy 272.817082 -29.257244) (xy 272.806952 -29.256788)
			(xy 272.788227 -29.249051) (xy 272.773871 -29.234756) (xy 272.766055 -29.216064) (xy 272.76552 -29.205936)
			(xy 269.564104 -29.205936) (xy 269.563644 -29.216047) (xy 269.555896 -29.234725) (xy 269.541591 -29.249018)
			(xy 269.522907 -29.256752) (xy 269.512796 -29.257244) (xy 268.280642 -29.257244) (xy 268.270516 -29.256738)
			(xy 268.251793 -29.249022) (xy 268.237435 -29.23474) (xy 268.229617 -29.216059) (xy 268.22908 -29.205936)
			(xy 267.715059 -29.205936) (xy 267.714286 -29.21181) (xy 267.698765 -29.269735) (xy 267.69468 -29.279596)
			(xy 275.57222 -29.279596) (xy 275.57222 -29.052012) (xy 275.572474 -29.047948) (xy 275.572728 -29.045408)
			(xy 275.572728 -29.036772) (xy 275.578316 -29.028136) (xy 275.579586 -29.026104) (xy 275.580602 -29.024072)
			(xy 275.77796 -28.723082) (xy 275.781848 -28.716765) (xy 275.786095 -28.702557) (xy 275.786342 -28.695142)
			(xy 275.786342 -28.669488) (xy 275.78612 -28.662155) (xy 275.782001 -28.648084) (xy 275.778214 -28.641802)
			(xy 275.580348 -28.33878) (xy 275.578062 -28.33497) (xy 275.577808 -28.334462) (xy 275.576792 -28.332684)
			(xy 275.572728 -28.32608) (xy 275.572728 -28.317952) (xy 275.572474 -28.315412) (xy 275.57222 -28.311348)
			(xy 275.57222 -28.083256) (xy 275.572647 -28.073041) (xy 275.580481 -28.054171) (xy 275.594939 -28.039736)
			(xy 275.61382 -28.031931) (xy 275.624036 -28.03144) (xy 276.360636 -28.03144) (xy 276.370841 -28.031951)
			(xy 276.389695 -28.039768) (xy 276.404128 -28.054199) (xy 276.411947 -28.073051) (xy 276.412452 -28.083256)
			(xy 276.412452 -28.31084) (xy 276.412198 -28.314904) (xy 276.411944 -28.317444) (xy 276.411944 -28.32608)
			(xy 276.406102 -28.335478) (xy 276.40534 -28.336748) (xy 276.40407 -28.33878) (xy 276.19833 -28.653486)
			(xy 276.19325 -28.661994) (xy 276.189435 -28.681422) (xy 276.193267 -28.700847) (xy 276.19833 -28.709366)
			(xy 276.40407 -29.022802) (xy 276.405086 -29.024834) (xy 276.406356 -29.026866) (xy 276.411944 -29.035502)
			(xy 276.411944 -29.044138) (xy 276.412198 -29.046678) (xy 276.412452 -29.050742) (xy 276.412452 -29.114242)
			(xy 277.047452 -29.114242) (xy 277.047452 -28.250642) (xy 277.047942 -28.220674) (xy 277.055765 -28.161252)
			(xy 277.071278 -28.103359) (xy 277.094214 -28.047986) (xy 277.124181 -27.99608) (xy 277.160668 -27.94853)
			(xy 277.203048 -27.90615) (xy 277.250598 -27.869663) (xy 277.302504 -27.839696) (xy 277.357877 -27.81676)
			(xy 277.41577 -27.801247) (xy 277.475192 -27.793424) (xy 277.535128 -27.793424) (xy 277.59455 -27.801247)
			(xy 277.652443 -27.81676) (xy 277.707816 -27.839696) (xy 277.759722 -27.869663) (xy 277.807272 -27.90615)
			(xy 277.849652 -27.94853) (xy 277.886139 -27.99608) (xy 277.916106 -28.047986) (xy 277.939042 -28.103359)
			(xy 277.954555 -28.161252) (xy 277.962378 -28.220674) (xy 277.962868 -28.250642) (xy 277.962868 -29.114242)
			(xy 277.962735 -29.12237) (xy 292.806628 -29.12237) (xy 292.806628 -28.25877) (xy 292.807118 -28.228786)
			(xy 292.814946 -28.16933) (xy 292.830467 -28.111405) (xy 292.853416 -28.056001) (xy 292.8834 -28.004067)
			(xy 292.919906 -27.956491) (xy 292.962311 -27.914086) (xy 293.009887 -27.87758) (xy 293.061821 -27.847596)
			(xy 293.117225 -27.824647) (xy 293.17515 -27.809126) (xy 293.234606 -27.801298) (xy 293.294574 -27.801298)
			(xy 293.35403 -27.809126) (xy 293.411955 -27.824647) (xy 293.467359 -27.847596) (xy 293.519293 -27.87758)
			(xy 293.566869 -27.914086) (xy 293.609274 -27.956491) (xy 293.64578 -28.004067) (xy 293.675764 -28.056001)
			(xy 293.698713 -28.111405) (xy 293.714234 -28.16933) (xy 293.722062 -28.228786) (xy 293.722552 -28.25877)
			(xy 293.722552 -29.12237) (xy 293.722062 -29.152354) (xy 293.715007 -29.205936) (xy 294.229028 -29.205936)
			(xy 294.229028 -28.174188) (xy 294.229407 -28.164061) (xy 294.237164 -28.145352) (xy 294.251492 -28.131037)
			(xy 294.270209 -28.123297) (xy 294.280336 -28.12288) (xy 295.51249 -28.12288) (xy 295.522621 -28.123336)
			(xy 295.54135 -28.131068) (xy 295.555708 -28.145364) (xy 295.56352 -28.164059) (xy 295.564052 -28.174188)
			(xy 295.564052 -29.205936) (xy 298.765468 -29.205936) (xy 298.765468 -28.174188) (xy 298.765911 -28.164037)
			(xy 298.773704 -28.14529) (xy 298.788094 -28.130969) (xy 298.806877 -28.123264) (xy 298.81703 -28.12288)
			(xy 300.04893 -28.12288) (xy 300.059064 -28.123303) (xy 300.077793 -28.131048) (xy 300.09215 -28.145354)
			(xy 300.099961 -28.164056) (xy 300.100492 -28.174188) (xy 300.100492 -29.205936) (xy 300.100108 -29.216093)
			(xy 300.092299 -29.234848) (xy 300.077891 -29.249171) (xy 300.05909 -29.256868) (xy 300.04893 -29.257244)
			(xy 298.81703 -29.257244) (xy 298.806903 -29.256749) (xy 298.78818 -29.249028) (xy 298.773822 -29.234744)
			(xy 298.766004 -29.21606) (xy 298.765468 -29.205936) (xy 295.564052 -29.205936) (xy 295.563546 -29.216041)
			(xy 295.555806 -29.23471) (xy 295.541516 -29.249001) (xy 295.522849 -29.256744) (xy 295.512744 -29.257244)
			(xy 294.28059 -29.257244) (xy 294.270461 -29.256781) (xy 294.251736 -29.249047) (xy 294.23738 -29.234753)
			(xy 294.229564 -29.216063) (xy 294.229028 -29.205936) (xy 293.715007 -29.205936) (xy 293.714234 -29.21181)
			(xy 293.698713 -29.269735) (xy 293.694628 -29.279596) (xy 301.572168 -29.279596) (xy 301.572168 -29.036772)
			(xy 301.577756 -29.02839) (xy 301.57801 -29.027882) (xy 301.580042 -29.024834) (xy 301.580296 -29.024326)
			(xy 301.786036 -28.710382) (xy 301.791026 -28.701945) (xy 301.794842 -28.682736) (xy 301.791202 -28.663493)
			(xy 301.78629 -28.65501) (xy 301.700438 -28.52293) (xy 301.69104 -28.508452) (xy 301.578772 -28.336494)
			(xy 301.578264 -28.335478) (xy 301.576232 -28.33243) (xy 301.575978 -28.331922) (xy 301.572168 -28.32608)
			(xy 301.572168 -28.083256) (xy 301.572645 -28.073047) (xy 301.58047 -28.054188) (xy 301.594911 -28.039754)
			(xy 301.613775 -28.03194) (xy 301.623984 -28.03144) (xy 302.360584 -28.03144) (xy 302.370785 -28.031994)
			(xy 302.389638 -28.039793) (xy 302.404073 -28.054211) (xy 302.411894 -28.073055) (xy 302.4124 -28.083256)
			(xy 302.4124 -28.32608) (xy 302.40859 -28.331922) (xy 302.408336 -28.33243) (xy 302.404272 -28.338526)
			(xy 302.404018 -28.33878) (xy 302.266096 -28.549854) (xy 302.21301 -28.631134) (xy 302.200564 -28.650184)
			(xy 302.198532 -28.652978) (xy 302.197262 -28.65501) (xy 302.193048 -28.66242) (xy 302.189335 -28.679047)
			(xy 302.191301 -28.69597) (xy 302.194722 -28.703778) (xy 302.38192 -28.989274) (xy 302.38446 -28.993084)
			(xy 302.404272 -29.023056) (xy 302.404526 -29.023564) (xy 302.405796 -29.025596) (xy 302.407574 -29.028136)
			(xy 302.4124 -29.035502) (xy 302.4124 -29.114242) (xy 303.0474 -29.114242) (xy 303.0474 -28.250642)
			(xy 303.04789 -28.220674) (xy 303.055713 -28.161252) (xy 303.071226 -28.103359) (xy 303.094162 -28.047986)
			(xy 303.124129 -27.99608) (xy 303.160616 -27.94853) (xy 303.202996 -27.90615) (xy 303.250546 -27.869663)
			(xy 303.302452 -27.839696) (xy 303.357825 -27.81676) (xy 303.415718 -27.801247) (xy 303.47514 -27.793424)
			(xy 303.535076 -27.793424) (xy 303.594498 -27.801247) (xy 303.652391 -27.81676) (xy 303.707764 -27.839696)
			(xy 303.75967 -27.869663) (xy 303.80722 -27.90615) (xy 303.8496 -27.94853) (xy 303.886087 -27.99608)
			(xy 303.916054 -28.047986) (xy 303.93899 -28.103359) (xy 303.954503 -28.161252) (xy 303.962326 -28.220674)
			(xy 303.962816 -28.250642) (xy 303.962816 -29.114242) (xy 303.962683 -29.12237) (xy 318.806576 -29.12237)
			(xy 318.806576 -28.25877) (xy 318.807066 -28.228786) (xy 318.814894 -28.16933) (xy 318.830415 -28.111405)
			(xy 318.853364 -28.056001) (xy 318.883348 -28.004067) (xy 318.919854 -27.956491) (xy 318.962259 -27.914086)
			(xy 319.009835 -27.87758) (xy 319.061769 -27.847596) (xy 319.117173 -27.824647) (xy 319.175098 -27.809126)
			(xy 319.234554 -27.801298) (xy 319.294522 -27.801298) (xy 319.353978 -27.809126) (xy 319.411903 -27.824647)
			(xy 319.467307 -27.847596) (xy 319.519241 -27.87758) (xy 319.566817 -27.914086) (xy 319.609222 -27.956491)
			(xy 319.645728 -28.004067) (xy 319.675712 -28.056001) (xy 319.698661 -28.111405) (xy 319.714182 -28.16933)
			(xy 319.72201 -28.228786) (xy 319.7225 -28.25877) (xy 319.7225 -29.12237) (xy 319.72201 -29.152354)
			(xy 319.714955 -29.205936) (xy 320.228976 -29.205936) (xy 320.228976 -28.174188) (xy 320.229475 -28.164082)
			(xy 320.237212 -28.145408) (xy 320.251504 -28.131114) (xy 320.270178 -28.123376) (xy 320.280284 -28.12288)
			(xy 321.512438 -28.12288) (xy 321.522572 -28.123297) (xy 321.541302 -28.131044) (xy 321.555658 -28.145352)
			(xy 321.563469 -28.164056) (xy 321.564 -28.174188) (xy 321.564 -29.205936) (xy 324.765416 -29.205936)
			(xy 324.765416 -28.174188) (xy 324.765812 -28.164031) (xy 324.773614 -28.145275) (xy 324.788019 -28.130952)
			(xy 324.806819 -28.123255) (xy 324.816978 -28.12288) (xy 326.048878 -28.12288) (xy 326.059008 -28.123346)
			(xy 326.077737 -28.131074) (xy 326.092095 -28.145367) (xy 326.099908 -28.16406) (xy 326.10044 -28.174188)
			(xy 326.10044 -29.205936) (xy 326.100009 -29.216087) (xy 326.092209 -29.234833) (xy 326.077816 -29.249154)
			(xy 326.059032 -29.256859) (xy 326.048878 -29.257244) (xy 324.816978 -29.257244) (xy 324.806848 -29.256791)
			(xy 324.788123 -29.249053) (xy 324.773767 -29.234756) (xy 324.765951 -29.216064) (xy 324.765416 -29.205936)
			(xy 321.564 -29.205936) (xy 321.563544 -29.216047) (xy 321.555795 -29.234726) (xy 321.541489 -29.24902)
			(xy 321.522803 -29.256753) (xy 321.512692 -29.257244) (xy 320.280538 -29.257244) (xy 320.270412 -29.256742)
			(xy 320.251689 -29.249023) (xy 320.23733 -29.234741) (xy 320.229513 -29.216059) (xy 320.228976 -29.205936)
			(xy 319.714955 -29.205936) (xy 319.714182 -29.21181) (xy 319.698661 -29.269735) (xy 319.694576 -29.279596)
			(xy 327.572116 -29.279596) (xy 327.572116 -29.036772) (xy 327.577704 -29.02839) (xy 327.577958 -29.027882)
			(xy 327.57999 -29.024834) (xy 327.580244 -29.024326) (xy 327.785984 -28.710382) (xy 327.790978 -28.701946)
			(xy 327.794798 -28.682736) (xy 327.791154 -28.663491) (xy 327.786238 -28.65501) (xy 327.700386 -28.52293)
			(xy 327.690988 -28.508452) (xy 327.57872 -28.336494) (xy 327.578212 -28.335478) (xy 327.57618 -28.33243)
			(xy 327.575926 -28.331922) (xy 327.572116 -28.32608) (xy 327.572116 -28.083256) (xy 327.572547 -28.073041)
			(xy 327.58038 -28.054173) (xy 327.594837 -28.039737) (xy 327.613717 -28.031932) (xy 327.623932 -28.03144)
			(xy 328.360532 -28.03144) (xy 328.370736 -28.031954) (xy 328.38959 -28.03977) (xy 328.404024 -28.0542)
			(xy 328.411843 -28.073052) (xy 328.412348 -28.083256) (xy 328.412348 -28.32608) (xy 328.408538 -28.331922)
			(xy 328.408284 -28.33243) (xy 328.40422 -28.338526) (xy 328.403966 -28.33878) (xy 328.266044 -28.549854)
			(xy 328.212958 -28.631134) (xy 328.200512 -28.650184) (xy 328.19848 -28.652978) (xy 328.19721 -28.65501)
			(xy 328.192997 -28.66242) (xy 328.189287 -28.679047) (xy 328.191252 -28.695969) (xy 328.19467 -28.703778)
			(xy 328.381868 -28.989274) (xy 328.384408 -28.993084) (xy 328.40422 -29.023056) (xy 328.404474 -29.023564)
			(xy 328.405744 -29.025596) (xy 328.407522 -29.028136) (xy 328.412348 -29.035502) (xy 328.412348 -29.114242)
			(xy 329.047348 -29.114242) (xy 329.047348 -28.250642) (xy 329.047838 -28.220674) (xy 329.055661 -28.161252)
			(xy 329.071174 -28.103359) (xy 329.09411 -28.047986) (xy 329.124077 -27.99608) (xy 329.160564 -27.94853)
			(xy 329.202944 -27.90615) (xy 329.250494 -27.869663) (xy 329.3024 -27.839696) (xy 329.357773 -27.81676)
			(xy 329.415666 -27.801247) (xy 329.475088 -27.793424) (xy 329.535024 -27.793424) (xy 329.594446 -27.801247)
			(xy 329.652339 -27.81676) (xy 329.707712 -27.839696) (xy 329.759618 -27.869663) (xy 329.807168 -27.90615)
			(xy 329.849548 -27.94853) (xy 329.886035 -27.99608) (xy 329.916002 -28.047986) (xy 329.938938 -28.103359)
			(xy 329.954451 -28.161252) (xy 329.962274 -28.220674) (xy 329.962764 -28.250642) (xy 329.962764 -29.114242)
			(xy 329.962631 -29.12237) (xy 356.907084 -29.12237) (xy 356.907084 -28.25877) (xy 356.907574 -28.228802)
			(xy 356.915397 -28.16938) (xy 356.93091 -28.111487) (xy 356.953846 -28.056114) (xy 356.983813 -28.004208)
			(xy 357.0203 -27.956658) (xy 357.06268 -27.914278) (xy 357.11023 -27.877791) (xy 357.162136 -27.847824)
			(xy 357.217509 -27.824888) (xy 357.275402 -27.809375) (xy 357.334824 -27.801552) (xy 357.39476 -27.801552)
			(xy 357.454182 -27.809375) (xy 357.512075 -27.824888) (xy 357.567448 -27.847824) (xy 357.619354 -27.877791)
			(xy 357.666904 -27.914278) (xy 357.709284 -27.956658) (xy 357.745771 -28.004208) (xy 357.775738 -28.056114)
			(xy 357.798674 -28.111487) (xy 357.814187 -28.16938) (xy 357.82201 -28.228802) (xy 357.8225 -28.25877)
			(xy 357.8225 -29.12237) (xy 357.82201 -29.152338) (xy 357.814954 -29.205936) (xy 358.329484 -29.205936)
			(xy 358.329484 -28.174188) (xy 358.329975 -28.164081) (xy 358.337714 -28.145405) (xy 358.352009 -28.131111)
			(xy 358.370684 -28.123374) (xy 358.380792 -28.12288) (xy 359.612692 -28.12288) (xy 359.622798 -28.123391)
			(xy 359.641472 -28.131122) (xy 359.655766 -28.145411) (xy 359.663505 -28.164082) (xy 359.664 -28.174188)
			(xy 359.664 -29.205936) (xy 362.865924 -29.205936) (xy 362.865924 -28.174188) (xy 362.866306 -28.164062)
			(xy 362.874063 -28.145353) (xy 362.88839 -28.131038) (xy 362.907105 -28.123298) (xy 362.917232 -28.12288)
			(xy 364.149132 -28.12288) (xy 364.15924 -28.123358) (xy 364.177915 -28.131103) (xy 364.192208 -28.145401)
			(xy 364.199946 -28.164079) (xy 364.20044 -28.174188) (xy 364.20044 -29.205936) (xy 364.199945 -29.216042)
			(xy 364.192203 -29.234713) (xy 364.17791 -29.249006) (xy 364.159238 -29.256746) (xy 364.149132 -29.257244)
			(xy 362.917232 -29.257244) (xy 362.907131 -29.25669) (xy 362.888462 -29.248971) (xy 362.874167 -29.234696)
			(xy 362.866423 -29.216037) (xy 362.865924 -29.205936) (xy 359.664 -29.205936) (xy 359.663544 -29.216047)
			(xy 359.655795 -29.234726) (xy 359.641489 -29.24902) (xy 359.622803 -29.256753) (xy 359.612692 -29.257244)
			(xy 358.380792 -29.257244) (xy 358.370688 -29.256722) (xy 358.352018 -29.24899) (xy 358.337725 -29.234705)
			(xy 358.329983 -29.216039) (xy 358.329484 -29.205936) (xy 357.814954 -29.205936) (xy 357.814187 -29.21176)
			(xy 357.798674 -29.269653) (xy 357.794556 -29.279596) (xy 365.672624 -29.279596) (xy 365.672624 -29.036772)
			(xy 365.817404 -28.816046) (xy 365.86668 -28.740608) (xy 365.886492 -28.710382) (xy 365.891452 -28.701926)
			(xy 365.895184 -28.682697) (xy 365.891449 -28.663468) (xy 365.886492 -28.65501) (xy 365.741458 -28.431998)
			(xy 365.685832 -28.346654) (xy 365.681514 -28.340558) (xy 365.678212 -28.33497) (xy 365.677704 -28.333954)
			(xy 365.672624 -28.32608) (xy 365.672624 -28.083256) (xy 365.673183 -28.071727) (xy 365.68308 -28.050899)
			(xy 365.700946 -28.03632) (xy 365.711994 -28.032964) (xy 365.712248 -28.032964) (xy 365.724186 -28.03144)
			(xy 366.460786 -28.03144) (xy 366.467158 -28.03168) (xy 366.479495 -28.034883) (xy 366.48517 -28.03779)
			(xy 366.493164 -28.042556) (xy 366.505405 -28.056554) (xy 366.511951 -28.073959) (xy 366.512348 -28.083256)
			(xy 366.512348 -28.32608) (xy 366.296448 -28.656534) (xy 366.292453 -28.664767) (xy 366.289896 -28.68287)
			(xy 366.293831 -28.700724) (xy 366.29848 -28.708604) (xy 366.330738 -28.758388) (xy 366.346232 -28.78201)
			(xy 366.512348 -29.035502) (xy 366.512348 -29.114242) (xy 367.147348 -29.114242) (xy 367.147348 -28.250642)
			(xy 367.147838 -28.220658) (xy 367.155666 -28.161202) (xy 367.171187 -28.103277) (xy 367.194136 -28.047873)
			(xy 367.22412 -27.995939) (xy 367.260626 -27.948363) (xy 367.303031 -27.905958) (xy 367.350607 -27.869452)
			(xy 367.402541 -27.839468) (xy 367.457945 -27.816519) (xy 367.51587 -27.800998) (xy 367.575326 -27.79317)
			(xy 367.635294 -27.79317) (xy 367.69475 -27.800998) (xy 367.752675 -27.816519) (xy 367.808079 -27.839468)
			(xy 367.860013 -27.869452) (xy 367.907589 -27.905958) (xy 367.949994 -27.948363) (xy 367.9865 -27.995939)
			(xy 368.016484 -28.047873) (xy 368.039433 -28.103277) (xy 368.054954 -28.161202) (xy 368.062782 -28.220658)
			(xy 368.063272 -28.250642) (xy 368.063272 -29.114242) (xy 368.063139 -29.12237) (xy 382.907032 -29.12237)
			(xy 382.907032 -28.25877) (xy 382.907522 -28.228802) (xy 382.915345 -28.16938) (xy 382.930858 -28.111487)
			(xy 382.953794 -28.056114) (xy 382.983761 -28.004208) (xy 383.020248 -27.956658) (xy 383.062628 -27.914278)
			(xy 383.110178 -27.877791) (xy 383.162084 -27.847824) (xy 383.217457 -27.824888) (xy 383.27535 -27.809375)
			(xy 383.334772 -27.801552) (xy 383.394708 -27.801552) (xy 383.45413 -27.809375) (xy 383.512023 -27.824888)
			(xy 383.567396 -27.847824) (xy 383.619302 -27.877791) (xy 383.666852 -27.914278) (xy 383.709232 -27.956658)
			(xy 383.745719 -28.004208) (xy 383.775686 -28.056114) (xy 383.798622 -28.111487) (xy 383.814135 -28.16938)
			(xy 383.821958 -28.228802) (xy 383.822448 -28.25877) (xy 383.822448 -29.12237) (xy 383.821958 -29.152338)
			(xy 383.814902 -29.205936) (xy 384.329432 -29.205936) (xy 384.329432 -28.174188) (xy 384.329807 -28.164061)
			(xy 384.337565 -28.145351) (xy 384.351894 -28.131036) (xy 384.370612 -28.123296) (xy 384.38074 -28.12288)
			(xy 385.61264 -28.12288) (xy 385.622749 -28.123352) (xy 385.641424 -28.131099) (xy 385.655717 -28.145399)
			(xy 385.663454 -28.164079) (xy 385.663948 -28.174188) (xy 385.663948 -29.205936) (xy 388.865872 -29.205936)
			(xy 388.865872 -28.174188) (xy 388.866375 -28.164082) (xy 388.874111 -28.145409) (xy 388.888402 -28.131116)
			(xy 388.907074 -28.123376) (xy 388.91718 -28.12288) (xy 390.14908 -28.12288) (xy 390.159199 -28.123332)
			(xy 390.177898 -28.13107) (xy 390.192212 -28.145375) (xy 390.199962 -28.16407) (xy 390.200388 -28.174188)
			(xy 390.200388 -29.205936) (xy 390.199944 -29.216049) (xy 390.192192 -29.23473) (xy 390.177883 -29.249024)
			(xy 390.159193 -29.256755) (xy 390.14908 -29.257244) (xy 388.91718 -29.257244) (xy 388.907075 -29.256733)
			(xy 388.888405 -29.248996) (xy 388.874113 -29.234708) (xy 388.866371 -29.21604) (xy 388.865872 -29.205936)
			(xy 385.663948 -29.205936) (xy 385.663446 -29.216041) (xy 385.655705 -29.234711) (xy 385.641414 -29.249003)
			(xy 385.622745 -29.256745) (xy 385.61264 -29.257244) (xy 384.38074 -29.257244) (xy 384.370626 -29.256752)
			(xy 384.351931 -29.249025) (xy 384.337617 -29.234733) (xy 384.329863 -29.21605) (xy 384.329432 -29.205936)
			(xy 383.814902 -29.205936) (xy 383.814135 -29.21176) (xy 383.798622 -29.269653) (xy 383.794504 -29.279596)
			(xy 391.672572 -29.279596) (xy 391.672572 -29.036772) (xy 391.791444 -28.855416) (xy 391.853928 -28.759912)
			(xy 391.878058 -28.723082) (xy 391.881946 -28.716765) (xy 391.886193 -28.702557) (xy 391.88644 -28.695142)
			(xy 391.88644 -28.669234) (xy 391.886238 -28.663085) (xy 391.883291 -28.651144) (xy 391.880598 -28.645612)
			(xy 391.76706 -28.471622) (xy 391.746994 -28.440634) (xy 391.741406 -28.431998) (xy 391.680954 -28.339288)
			(xy 391.680446 -28.338526) (xy 391.679938 -28.337764) (xy 391.679684 -28.337256) (xy 391.679176 -28.336494)
			(xy 391.672572 -28.32608) (xy 391.672572 -28.083256) (xy 391.673234 -28.071708) (xy 391.683192 -28.050865)
			(xy 391.701121 -28.0363) (xy 391.712196 -28.032964) (xy 391.724134 -28.03144) (xy 392.460734 -28.03144)
			(xy 392.47149 -28.031977) (xy 392.491179 -28.040631) (xy 392.498834 -28.048204) (xy 392.505048 -28.055592)
			(xy 392.511954 -28.073607) (xy 392.512296 -28.083256) (xy 392.512296 -28.32608) (xy 392.296396 -28.656534)
			(xy 392.292406 -28.664768) (xy 392.289851 -28.68287) (xy 392.293783 -28.700723) (xy 392.298428 -28.708604)
			(xy 392.330686 -28.758388) (xy 392.512296 -29.035502) (xy 392.512296 -29.114242) (xy 393.147296 -29.114242)
			(xy 393.147296 -28.250642) (xy 393.147786 -28.220658) (xy 393.155614 -28.161202) (xy 393.171135 -28.103277)
			(xy 393.194084 -28.047873) (xy 393.224068 -27.995939) (xy 393.260574 -27.948363) (xy 393.302979 -27.905958)
			(xy 393.350555 -27.869452) (xy 393.402489 -27.839468) (xy 393.457893 -27.816519) (xy 393.515818 -27.800998)
			(xy 393.575274 -27.79317) (xy 393.635242 -27.79317) (xy 393.694698 -27.800998) (xy 393.752623 -27.816519)
			(xy 393.808027 -27.839468) (xy 393.859961 -27.869452) (xy 393.907537 -27.905958) (xy 393.949942 -27.948363)
			(xy 393.986448 -27.995939) (xy 394.016432 -28.047873) (xy 394.039381 -28.103277) (xy 394.054902 -28.161202)
			(xy 394.06273 -28.220658) (xy 394.06322 -28.250642) (xy 394.06322 -29.114242) (xy 394.063087 -29.12237)
			(xy 408.90698 -29.12237) (xy 408.90698 -28.25877) (xy 408.90747 -28.228802) (xy 408.915293 -28.16938)
			(xy 408.930806 -28.111487) (xy 408.953742 -28.056114) (xy 408.983709 -28.004208) (xy 409.020196 -27.956658)
			(xy 409.062576 -27.914278) (xy 409.110126 -27.877791) (xy 409.162032 -27.847824) (xy 409.217405 -27.824888)
			(xy 409.275298 -27.809375) (xy 409.33472 -27.801552) (xy 409.394656 -27.801552) (xy 409.454078 -27.809375)
			(xy 409.511971 -27.824888) (xy 409.567344 -27.847824) (xy 409.61925 -27.877791) (xy 409.6668 -27.914278)
			(xy 409.70918 -27.956658) (xy 409.745667 -28.004208) (xy 409.775634 -28.056114) (xy 409.79857 -28.111487)
			(xy 409.814083 -28.16938) (xy 409.821906 -28.228802) (xy 409.822396 -28.25877) (xy 409.822396 -29.12237)
			(xy 409.821906 -29.152338) (xy 409.81485 -29.205936) (xy 410.32938 -29.205936) (xy 410.32938 -28.174188)
			(xy 410.329875 -28.164081) (xy 410.337613 -28.145406) (xy 410.351906 -28.131113) (xy 410.370581 -28.123375)
			(xy 410.380688 -28.12288) (xy 411.612588 -28.12288) (xy 411.622694 -28.123394) (xy 411.641368 -28.131124)
			(xy 411.655662 -28.145412) (xy 411.663401 -28.164083) (xy 411.663896 -28.174188) (xy 411.663896 -29.205936)
			(xy 414.86582 -29.205936) (xy 414.86582 -28.174188) (xy 414.866206 -28.164062) (xy 414.873962 -28.145354)
			(xy 414.888288 -28.13104) (xy 414.907002 -28.123298) (xy 414.917128 -28.12288) (xy 416.149028 -28.12288)
			(xy 416.159136 -28.123362) (xy 416.177811 -28.131105) (xy 416.192104 -28.145402) (xy 416.199842 -28.16408)
			(xy 416.200336 -28.174188) (xy 416.200336 -29.205936) (xy 416.199845 -29.216043) (xy 416.192102 -29.234715)
			(xy 416.177808 -29.249007) (xy 416.159135 -29.256747) (xy 416.149028 -29.257244) (xy 414.917128 -29.257244)
			(xy 414.907026 -29.256693) (xy 414.888357 -29.248973) (xy 414.874063 -29.234697) (xy 414.866319 -29.216037)
			(xy 414.86582 -29.205936) (xy 411.663896 -29.205936) (xy 411.663444 -29.216048) (xy 411.655694 -29.234727)
			(xy 411.641387 -29.249021) (xy 411.6227 -29.256754) (xy 411.612588 -29.257244) (xy 410.380688 -29.257244)
			(xy 410.370584 -29.256726) (xy 410.351914 -29.248992) (xy 410.337621 -29.234706) (xy 410.329879 -29.21604)
			(xy 410.32938 -29.205936) (xy 409.81485 -29.205936) (xy 409.814083 -29.21176) (xy 409.79857 -29.269653)
			(xy 409.794452 -29.279596) (xy 417.67252 -29.279596) (xy 417.67252 -29.036772) (xy 417.791392 -28.855416)
			(xy 417.853876 -28.759912) (xy 417.878006 -28.723082) (xy 417.88189 -28.716762) (xy 417.886141 -28.702556)
			(xy 417.886388 -28.695142) (xy 417.886388 -28.669234) (xy 417.886181 -28.663085) (xy 417.883236 -28.651144)
			(xy 417.880546 -28.645612) (xy 417.767008 -28.471622) (xy 417.746942 -28.440634) (xy 417.741354 -28.431998)
			(xy 417.680902 -28.339288) (xy 417.680394 -28.338526) (xy 417.679886 -28.337764) (xy 417.679632 -28.337256)
			(xy 417.679124 -28.336494) (xy 417.67252 -28.32608) (xy 417.67252 -28.083256) (xy 417.673147 -28.071703)
			(xy 417.683115 -28.050853) (xy 417.701062 -28.036293) (xy 417.712144 -28.032964) (xy 417.724082 -28.03144)
			(xy 418.460682 -28.03144) (xy 418.471441 -28.031951) (xy 418.49113 -28.040623) (xy 418.498782 -28.048204)
			(xy 418.505002 -28.055587) (xy 418.511903 -28.073606) (xy 418.512244 -28.083256) (xy 418.512244 -28.32608)
			(xy 418.296344 -28.656534) (xy 418.29235 -28.664767) (xy 418.289792 -28.68287) (xy 418.293727 -28.700724)
			(xy 418.298376 -28.708604) (xy 418.330634 -28.758388) (xy 418.512244 -29.035502) (xy 418.512244 -29.114242)
			(xy 419.147244 -29.114242) (xy 419.147244 -28.250642) (xy 419.147734 -28.220658) (xy 419.155562 -28.161202)
			(xy 419.171083 -28.103277) (xy 419.194032 -28.047873) (xy 419.224016 -27.995939) (xy 419.260522 -27.948363)
			(xy 419.302927 -27.905958) (xy 419.350503 -27.869452) (xy 419.402437 -27.839468) (xy 419.457841 -27.816519)
			(xy 419.515766 -27.800998) (xy 419.575222 -27.79317) (xy 419.63519 -27.79317) (xy 419.694646 -27.800998)
			(xy 419.752571 -27.816519) (xy 419.807975 -27.839468) (xy 419.859909 -27.869452) (xy 419.907485 -27.905958)
			(xy 419.94989 -27.948363) (xy 419.986396 -27.995939) (xy 420.01638 -28.047873) (xy 420.039329 -28.103277)
			(xy 420.05485 -28.161202) (xy 420.062678 -28.220658) (xy 420.063168 -28.250642) (xy 420.063168 -29.114242)
			(xy 420.063035 -29.12237) (xy 434.906928 -29.12237) (xy 434.906928 -28.25877) (xy 434.907418 -28.228802)
			(xy 434.915241 -28.16938) (xy 434.930754 -28.111487) (xy 434.95369 -28.056114) (xy 434.983657 -28.004208)
			(xy 435.020144 -27.956658) (xy 435.062524 -27.914278) (xy 435.110074 -27.877791) (xy 435.16198 -27.847824)
			(xy 435.217353 -27.824888) (xy 435.275246 -27.809375) (xy 435.334668 -27.801552) (xy 435.394604 -27.801552)
			(xy 435.454026 -27.809375) (xy 435.511919 -27.824888) (xy 435.567292 -27.847824) (xy 435.619198 -27.877791)
			(xy 435.666748 -27.914278) (xy 435.709128 -27.956658) (xy 435.745615 -28.004208) (xy 435.775582 -28.056114)
			(xy 435.798518 -28.111487) (xy 435.814031 -28.16938) (xy 435.821854 -28.228802) (xy 435.822344 -28.25877)
			(xy 435.822344 -29.12237) (xy 435.821854 -29.152338) (xy 435.814798 -29.205936) (xy 436.329328 -29.205936)
			(xy 436.329328 -28.174188) (xy 436.329707 -28.164061) (xy 436.337464 -28.145352) (xy 436.351792 -28.131037)
			(xy 436.370509 -28.123297) (xy 436.380636 -28.12288) (xy 437.612536 -28.12288) (xy 437.622645 -28.123355)
			(xy 437.64132 -28.131101) (xy 437.655613 -28.1454) (xy 437.66335 -28.164079) (xy 437.663844 -28.174188)
			(xy 437.663844 -29.205936) (xy 440.865768 -29.205936) (xy 440.865768 -28.174188) (xy 440.866275 -28.164083)
			(xy 440.87401 -28.14541) (xy 440.8883 -28.131117) (xy 440.906971 -28.123377) (xy 440.917076 -28.12288)
			(xy 442.148976 -28.12288) (xy 442.159094 -28.123335) (xy 442.177794 -28.131072) (xy 442.192108 -28.145376)
			(xy 442.199858 -28.16407) (xy 442.200284 -28.174188) (xy 442.200284 -29.205936) (xy 442.199844 -29.216049)
			(xy 442.192092 -29.234731) (xy 442.177781 -29.249025) (xy 442.15909 -29.256756) (xy 442.148976 -29.257244)
			(xy 440.917076 -29.257244) (xy 440.906971 -29.256736) (xy 440.888301 -29.248998) (xy 440.874008 -29.234709)
			(xy 440.866267 -29.216041) (xy 440.865768 -29.205936) (xy 437.663844 -29.205936) (xy 437.663345 -29.216042)
			(xy 437.655604 -29.234712) (xy 437.641312 -29.249004) (xy 437.622642 -29.256745) (xy 437.612536 -29.257244)
			(xy 436.380636 -29.257244) (xy 436.370535 -29.256686) (xy 436.351866 -29.248969) (xy 436.337572 -29.234694)
			(xy 436.329828 -29.216036) (xy 436.329328 -29.205936) (xy 435.814798 -29.205936) (xy 435.814031 -29.21176)
			(xy 435.798518 -29.269653) (xy 435.7944 -29.279596) (xy 443.672468 -29.279596) (xy 443.672468 -29.036772)
			(xy 443.817248 -28.816046) (xy 443.866524 -28.740608) (xy 443.886336 -28.710382) (xy 443.8913 -28.701927)
			(xy 443.895037 -28.682697) (xy 443.891298 -28.663467) (xy 443.886336 -28.65501) (xy 443.741302 -28.431998)
			(xy 443.685676 -28.346654) (xy 443.681358 -28.340558) (xy 443.678056 -28.33497) (xy 443.677548 -28.333954)
			(xy 443.672468 -28.32608) (xy 443.672468 -28.083256) (xy 443.673067 -28.071733) (xy 443.682952 -28.050912)
			(xy 443.700799 -28.036328) (xy 443.711838 -28.032964) (xy 443.712092 -28.032964) (xy 443.72403 -28.03144)
			(xy 444.46063 -28.03144) (xy 444.467003 -28.031664) (xy 444.47934 -28.034878) (xy 444.485014 -28.03779)
			(xy 444.493017 -28.042542) (xy 444.505253 -28.056548) (xy 444.511796 -28.073957) (xy 444.512192 -28.083256)
			(xy 444.512192 -28.32608) (xy 444.296292 -28.656534) (xy 444.292303 -28.664769) (xy 444.289748 -28.68287)
			(xy 444.293679 -28.700723) (xy 444.298324 -28.708604) (xy 444.330582 -28.758388) (xy 444.346076 -28.78201)
			(xy 444.512192 -29.035502) (xy 444.512192 -29.114242) (xy 445.147192 -29.114242) (xy 445.147192 -28.250642)
			(xy 445.147682 -28.220658) (xy 445.15551 -28.161202) (xy 445.171031 -28.103277) (xy 445.19398 -28.047873)
			(xy 445.223964 -27.995939) (xy 445.26047 -27.948363) (xy 445.302875 -27.905958) (xy 445.350451 -27.869452)
			(xy 445.402385 -27.839468) (xy 445.457789 -27.816519) (xy 445.515714 -27.800998) (xy 445.57517 -27.79317)
			(xy 445.635138 -27.79317) (xy 445.694594 -27.800998) (xy 445.752519 -27.816519) (xy 445.807923 -27.839468)
			(xy 445.859857 -27.869452) (xy 445.907433 -27.905958) (xy 445.949838 -27.948363) (xy 445.986344 -27.995939)
			(xy 446.016328 -28.047873) (xy 446.039277 -28.103277) (xy 446.054798 -28.161202) (xy 446.062626 -28.220658)
			(xy 446.063116 -28.250642) (xy 446.063116 -29.114242) (xy 446.062626 -29.144226) (xy 446.054798 -29.203682)
			(xy 446.039277 -29.261607) (xy 446.016328 -29.317011) (xy 445.986344 -29.368945) (xy 445.949838 -29.416521)
			(xy 445.907433 -29.458926) (xy 445.859857 -29.495432) (xy 445.807923 -29.525416) (xy 445.752519 -29.548365)
			(xy 445.694594 -29.563886) (xy 445.635138 -29.571714) (xy 445.57517 -29.571714) (xy 445.515714 -29.563886)
			(xy 445.457789 -29.548365) (xy 445.402385 -29.525416) (xy 445.350451 -29.495432) (xy 445.302875 -29.458926)
			(xy 445.26047 -29.416521) (xy 445.223964 -29.368945) (xy 445.19398 -29.317011) (xy 445.171031 -29.261607)
			(xy 445.15551 -29.203682) (xy 445.147682 -29.144226) (xy 445.147192 -29.114242) (xy 444.512192 -29.114242)
			(xy 444.512192 -29.279596) (xy 444.511585 -29.29112) (xy 444.501709 -29.311944) (xy 444.483862 -29.326527)
			(xy 444.472822 -29.329888) (xy 444.472568 -29.329888) (xy 444.46063 -29.331412) (xy 443.72403 -29.331412)
			(xy 443.717655 -29.331207) (xy 443.705318 -29.327981) (xy 443.699646 -29.325062) (xy 443.691635 -29.320321)
			(xy 443.679394 -29.306313) (xy 443.672858 -29.288897) (xy 443.672468 -29.279596) (xy 435.7944 -29.279596)
			(xy 435.775582 -29.325026) (xy 435.745615 -29.376932) (xy 435.709128 -29.424482) (xy 435.666748 -29.466862)
			(xy 435.619198 -29.503349) (xy 435.567292 -29.533316) (xy 435.511919 -29.556252) (xy 435.454026 -29.571765)
			(xy 435.394604 -29.579588) (xy 435.334668 -29.579588) (xy 435.275246 -29.571765) (xy 435.217353 -29.556252)
			(xy 435.16198 -29.533316) (xy 435.110074 -29.503349) (xy 435.062524 -29.466862) (xy 435.020144 -29.424482)
			(xy 434.983657 -29.376932) (xy 434.95369 -29.325026) (xy 434.930754 -29.269653) (xy 434.915241 -29.21176)
			(xy 434.907418 -29.152338) (xy 434.906928 -29.12237) (xy 420.063035 -29.12237) (xy 420.062678 -29.144226)
			(xy 420.05485 -29.203682) (xy 420.039329 -29.261607) (xy 420.01638 -29.317011) (xy 419.986396 -29.368945)
			(xy 419.94989 -29.416521) (xy 419.907485 -29.458926) (xy 419.859909 -29.495432) (xy 419.807975 -29.525416)
			(xy 419.752571 -29.548365) (xy 419.694646 -29.563886) (xy 419.63519 -29.571714) (xy 419.575222 -29.571714)
			(xy 419.515766 -29.563886) (xy 419.457841 -29.548365) (xy 419.402437 -29.525416) (xy 419.350503 -29.495432)
			(xy 419.302927 -29.458926) (xy 419.260522 -29.416521) (xy 419.224016 -29.368945) (xy 419.194032 -29.317011)
			(xy 419.171083 -29.261607) (xy 419.155562 -29.203682) (xy 419.147734 -29.144226) (xy 419.147244 -29.114242)
			(xy 418.512244 -29.114242) (xy 418.512244 -29.279596) (xy 418.511534 -29.291139) (xy 418.501598 -29.311979)
			(xy 418.483687 -29.326547) (xy 418.47262 -29.329888) (xy 418.460682 -29.331412) (xy 417.724082 -29.331412)
			(xy 417.71333 -29.33085) (xy 417.693641 -29.322212) (xy 417.685982 -29.314648) (xy 417.679793 -29.307242)
			(xy 417.672872 -29.289241) (xy 417.67252 -29.279596) (xy 409.794452 -29.279596) (xy 409.775634 -29.325026)
			(xy 409.745667 -29.376932) (xy 409.70918 -29.424482) (xy 409.6668 -29.466862) (xy 409.61925 -29.503349)
			(xy 409.567344 -29.533316) (xy 409.511971 -29.556252) (xy 409.454078 -29.571765) (xy 409.394656 -29.579588)
			(xy 409.33472 -29.579588) (xy 409.275298 -29.571765) (xy 409.217405 -29.556252) (xy 409.162032 -29.533316)
			(xy 409.110126 -29.503349) (xy 409.062576 -29.466862) (xy 409.020196 -29.424482) (xy 408.983709 -29.376932)
			(xy 408.953742 -29.325026) (xy 408.930806 -29.269653) (xy 408.915293 -29.21176) (xy 408.90747 -29.152338)
			(xy 408.90698 -29.12237) (xy 394.063087 -29.12237) (xy 394.06273 -29.144226) (xy 394.054902 -29.203682)
			(xy 394.039381 -29.261607) (xy 394.016432 -29.317011) (xy 393.986448 -29.368945) (xy 393.949942 -29.416521)
			(xy 393.907537 -29.458926) (xy 393.859961 -29.495432) (xy 393.808027 -29.525416) (xy 393.752623 -29.548365)
			(xy 393.694698 -29.563886) (xy 393.635242 -29.571714) (xy 393.575274 -29.571714) (xy 393.515818 -29.563886)
			(xy 393.457893 -29.548365) (xy 393.402489 -29.525416) (xy 393.350555 -29.495432) (xy 393.302979 -29.458926)
			(xy 393.260574 -29.416521) (xy 393.224068 -29.368945) (xy 393.194084 -29.317011) (xy 393.171135 -29.261607)
			(xy 393.155614 -29.203682) (xy 393.147786 -29.144226) (xy 393.147296 -29.114242) (xy 392.512296 -29.114242)
			(xy 392.512296 -29.279596) (xy 392.511621 -29.291144) (xy 392.501674 -29.31199) (xy 392.483747 -29.326554)
			(xy 392.472672 -29.329888) (xy 392.460734 -29.331412) (xy 391.724134 -29.331412) (xy 391.713379 -29.330877)
			(xy 391.69369 -29.32222) (xy 391.686034 -29.314648) (xy 391.679839 -29.307247) (xy 391.672923 -29.289241)
			(xy 391.672572 -29.279596) (xy 383.794504 -29.279596) (xy 383.775686 -29.325026) (xy 383.745719 -29.376932)
			(xy 383.709232 -29.424482) (xy 383.666852 -29.466862) (xy 383.619302 -29.503349) (xy 383.567396 -29.533316)
			(xy 383.512023 -29.556252) (xy 383.45413 -29.571765) (xy 383.394708 -29.579588) (xy 383.334772 -29.579588)
			(xy 383.27535 -29.571765) (xy 383.217457 -29.556252) (xy 383.162084 -29.533316) (xy 383.110178 -29.503349)
			(xy 383.062628 -29.466862) (xy 383.020248 -29.424482) (xy 382.983761 -29.376932) (xy 382.953794 -29.325026)
			(xy 382.930858 -29.269653) (xy 382.915345 -29.21176) (xy 382.907522 -29.152338) (xy 382.907032 -29.12237)
			(xy 368.063139 -29.12237) (xy 368.062782 -29.144226) (xy 368.054954 -29.203682) (xy 368.039433 -29.261607)
			(xy 368.016484 -29.317011) (xy 367.9865 -29.368945) (xy 367.949994 -29.416521) (xy 367.907589 -29.458926)
			(xy 367.860013 -29.495432) (xy 367.808079 -29.525416) (xy 367.752675 -29.548365) (xy 367.69475 -29.563886)
			(xy 367.635294 -29.571714) (xy 367.575326 -29.571714) (xy 367.51587 -29.563886) (xy 367.457945 -29.548365)
			(xy 367.402541 -29.525416) (xy 367.350607 -29.495432) (xy 367.303031 -29.458926) (xy 367.260626 -29.416521)
			(xy 367.22412 -29.368945) (xy 367.194136 -29.317011) (xy 367.171187 -29.261607) (xy 367.155666 -29.203682)
			(xy 367.147838 -29.144226) (xy 367.147348 -29.114242) (xy 366.512348 -29.114242) (xy 366.512348 -29.279596)
			(xy 366.5117 -29.291114) (xy 366.501837 -29.311931) (xy 366.484009 -29.326519) (xy 366.472978 -29.329888)
			(xy 366.472724 -29.329888) (xy 366.460786 -29.331412) (xy 365.724186 -29.331412) (xy 365.717813 -29.331188)
			(xy 365.705475 -29.327975) (xy 365.699802 -29.325062) (xy 365.691781 -29.320336) (xy 365.679546 -29.306319)
			(xy 365.673013 -29.288899) (xy 365.672624 -29.279596) (xy 357.794556 -29.279596) (xy 357.775738 -29.325026)
			(xy 357.745771 -29.376932) (xy 357.709284 -29.424482) (xy 357.666904 -29.466862) (xy 357.619354 -29.503349)
			(xy 357.567448 -29.533316) (xy 357.512075 -29.556252) (xy 357.454182 -29.571765) (xy 357.39476 -29.579588)
			(xy 357.334824 -29.579588) (xy 357.275402 -29.571765) (xy 357.217509 -29.556252) (xy 357.162136 -29.533316)
			(xy 357.11023 -29.503349) (xy 357.06268 -29.466862) (xy 357.0203 -29.424482) (xy 356.983813 -29.376932)
			(xy 356.953846 -29.325026) (xy 356.93091 -29.269653) (xy 356.915397 -29.21176) (xy 356.907574 -29.152338)
			(xy 356.907084 -29.12237) (xy 329.962631 -29.12237) (xy 329.962274 -29.14421) (xy 329.954451 -29.203632)
			(xy 329.938938 -29.261525) (xy 329.916002 -29.316898) (xy 329.886035 -29.368804) (xy 329.849548 -29.416354)
			(xy 329.807168 -29.458734) (xy 329.759618 -29.495221) (xy 329.707712 -29.525188) (xy 329.652339 -29.548124)
			(xy 329.594446 -29.563637) (xy 329.535024 -29.57146) (xy 329.475088 -29.57146) (xy 329.415666 -29.563637)
			(xy 329.357773 -29.548124) (xy 329.3024 -29.525188) (xy 329.250494 -29.495221) (xy 329.202944 -29.458734)
			(xy 329.160564 -29.416354) (xy 329.124077 -29.368804) (xy 329.09411 -29.316898) (xy 329.071174 -29.261525)
			(xy 329.055661 -29.203632) (xy 329.047838 -29.14421) (xy 329.047348 -29.114242) (xy 328.412348 -29.114242)
			(xy 328.412348 -29.279596) (xy 328.411816 -29.2898) (xy 328.40401 -29.308655) (xy 328.389585 -29.32309)
			(xy 328.370735 -29.330909) (xy 328.360532 -29.331412) (xy 327.623932 -29.331412) (xy 327.613712 -29.330962)
			(xy 327.594825 -29.323148) (xy 327.580368 -29.308699) (xy 327.572544 -29.289816) (xy 327.572116 -29.279596)
			(xy 319.694576 -29.279596) (xy 319.675712 -29.325139) (xy 319.645728 -29.377073) (xy 319.609222 -29.424649)
			(xy 319.566817 -29.467054) (xy 319.519241 -29.50356) (xy 319.467307 -29.533544) (xy 319.411903 -29.556493)
			(xy 319.353978 -29.572014) (xy 319.294522 -29.579842) (xy 319.234554 -29.579842) (xy 319.175098 -29.572014)
			(xy 319.117173 -29.556493) (xy 319.061769 -29.533544) (xy 319.009835 -29.50356) (xy 318.962259 -29.467054)
			(xy 318.919854 -29.424649) (xy 318.883348 -29.377073) (xy 318.853364 -29.325139) (xy 318.830415 -29.269735)
			(xy 318.814894 -29.21181) (xy 318.807066 -29.152354) (xy 318.806576 -29.12237) (xy 303.962683 -29.12237)
			(xy 303.962326 -29.14421) (xy 303.954503 -29.203632) (xy 303.93899 -29.261525) (xy 303.916054 -29.316898)
			(xy 303.886087 -29.368804) (xy 303.8496 -29.416354) (xy 303.80722 -29.458734) (xy 303.75967 -29.495221)
			(xy 303.707764 -29.525188) (xy 303.652391 -29.548124) (xy 303.594498 -29.563637) (xy 303.535076 -29.57146)
			(xy 303.47514 -29.57146) (xy 303.415718 -29.563637) (xy 303.357825 -29.548124) (xy 303.302452 -29.525188)
			(xy 303.250546 -29.495221) (xy 303.202996 -29.458734) (xy 303.160616 -29.416354) (xy 303.124129 -29.368804)
			(xy 303.094162 -29.316898) (xy 303.071226 -29.261525) (xy 303.055713 -29.203632) (xy 303.04789 -29.14421)
			(xy 303.0474 -29.114242) (xy 302.4124 -29.114242) (xy 302.4124 -29.279596) (xy 302.411985 -29.289819)
			(xy 302.40416 -29.30871) (xy 302.3897 -29.323166) (xy 302.370808 -29.330987) (xy 302.360584 -29.331412)
			(xy 301.623984 -29.331412) (xy 301.613775 -29.330931) (xy 301.594912 -29.323112) (xy 301.580477 -29.308671)
			(xy 301.572665 -29.289805) (xy 301.572168 -29.279596) (xy 293.694628 -29.279596) (xy 293.675764 -29.325139)
			(xy 293.64578 -29.377073) (xy 293.609274 -29.424649) (xy 293.566869 -29.467054) (xy 293.519293 -29.50356)
			(xy 293.467359 -29.533544) (xy 293.411955 -29.556493) (xy 293.35403 -29.572014) (xy 293.294574 -29.579842)
			(xy 293.234606 -29.579842) (xy 293.17515 -29.572014) (xy 293.117225 -29.556493) (xy 293.061821 -29.533544)
			(xy 293.009887 -29.50356) (xy 292.962311 -29.467054) (xy 292.919906 -29.424649) (xy 292.8834 -29.377073)
			(xy 292.853416 -29.325139) (xy 292.830467 -29.269735) (xy 292.814946 -29.21181) (xy 292.807118 -29.152354)
			(xy 292.806628 -29.12237) (xy 277.962735 -29.12237) (xy 277.962378 -29.14421) (xy 277.954555 -29.203632)
			(xy 277.939042 -29.261525) (xy 277.916106 -29.316898) (xy 277.886139 -29.368804) (xy 277.849652 -29.416354)
			(xy 277.807272 -29.458734) (xy 277.759722 -29.495221) (xy 277.707816 -29.525188) (xy 277.652443 -29.548124)
			(xy 277.59455 -29.563637) (xy 277.535128 -29.57146) (xy 277.475192 -29.57146) (xy 277.41577 -29.563637)
			(xy 277.357877 -29.548124) (xy 277.302504 -29.525188) (xy 277.250598 -29.495221) (xy 277.203048 -29.458734)
			(xy 277.160668 -29.416354) (xy 277.124181 -29.368804) (xy 277.094214 -29.316898) (xy 277.071278 -29.261525)
			(xy 277.055765 -29.203632) (xy 277.047942 -29.14421) (xy 277.047452 -29.114242) (xy 276.412452 -29.114242)
			(xy 276.412452 -29.279596) (xy 276.411916 -29.289799) (xy 276.404111 -29.308654) (xy 276.389687 -29.323089)
			(xy 276.370839 -29.330908) (xy 276.360636 -29.331412) (xy 275.624036 -29.331412) (xy 275.613816 -29.330959)
			(xy 275.594929 -29.323146) (xy 275.580472 -29.308698) (xy 275.572648 -29.289816) (xy 275.57222 -29.279596)
			(xy 267.69468 -29.279596) (xy 267.675816 -29.325139) (xy 267.645832 -29.377073) (xy 267.609326 -29.424649)
			(xy 267.566921 -29.467054) (xy 267.519345 -29.50356) (xy 267.467411 -29.533544) (xy 267.412007 -29.556493)
			(xy 267.354082 -29.572014) (xy 267.294626 -29.579842) (xy 267.234658 -29.579842) (xy 267.175202 -29.572014)
			(xy 267.117277 -29.556493) (xy 267.061873 -29.533544) (xy 267.009939 -29.50356) (xy 266.962363 -29.467054)
			(xy 266.919958 -29.424649) (xy 266.883452 -29.377073) (xy 266.853468 -29.325139) (xy 266.830519 -29.269735)
			(xy 266.814998 -29.21181) (xy 266.80717 -29.152354) (xy 266.80668 -29.12237) (xy 251.962787 -29.12237)
			(xy 251.96243 -29.14421) (xy 251.954607 -29.203632) (xy 251.939094 -29.261525) (xy 251.916158 -29.316898)
			(xy 251.886191 -29.368804) (xy 251.849704 -29.416354) (xy 251.807324 -29.458734) (xy 251.759774 -29.495221)
			(xy 251.707868 -29.525188) (xy 251.652495 -29.548124) (xy 251.594602 -29.563637) (xy 251.53518 -29.57146)
			(xy 251.475244 -29.57146) (xy 251.415822 -29.563637) (xy 251.357929 -29.548124) (xy 251.302556 -29.525188)
			(xy 251.25065 -29.495221) (xy 251.2031 -29.458734) (xy 251.16072 -29.416354) (xy 251.124233 -29.368804)
			(xy 251.094266 -29.316898) (xy 251.07133 -29.261525) (xy 251.055817 -29.203632) (xy 251.047994 -29.14421)
			(xy 251.047504 -29.114242) (xy 250.412504 -29.114242) (xy 250.412504 -29.279596) (xy 250.412085 -29.289819)
			(xy 250.40426 -29.308709) (xy 250.389802 -29.323165) (xy 250.370911 -29.330986) (xy 250.360688 -29.331412)
			(xy 249.624088 -29.331412) (xy 249.613879 -29.330928) (xy 249.595016 -29.32311) (xy 249.580581 -29.30867)
			(xy 249.572769 -29.289805) (xy 249.572272 -29.279596) (xy 241.694732 -29.279596) (xy 241.675868 -29.325139)
			(xy 241.645884 -29.377073) (xy 241.609378 -29.424649) (xy 241.566973 -29.467054) (xy 241.519397 -29.50356)
			(xy 241.467463 -29.533544) (xy 241.412059 -29.556493) (xy 241.354134 -29.572014) (xy 241.294678 -29.579842)
			(xy 241.23471 -29.579842) (xy 241.175254 -29.572014) (xy 241.117329 -29.556493) (xy 241.061925 -29.533544)
			(xy 241.009991 -29.50356) (xy 240.962415 -29.467054) (xy 240.92001 -29.424649) (xy 240.883504 -29.377073)
			(xy 240.85352 -29.325139) (xy 240.830571 -29.269735) (xy 240.81505 -29.21181) (xy 240.807222 -29.152354)
			(xy 240.806732 -29.12237) (xy 213.862787 -29.12237) (xy 213.86243 -29.14421) (xy 213.854607 -29.203632)
			(xy 213.839094 -29.261525) (xy 213.816158 -29.316898) (xy 213.786191 -29.368804) (xy 213.749704 -29.416354)
			(xy 213.707324 -29.458734) (xy 213.659774 -29.495221) (xy 213.607868 -29.525188) (xy 213.552495 -29.548124)
			(xy 213.494602 -29.563637) (xy 213.43518 -29.57146) (xy 213.375244 -29.57146) (xy 213.315822 -29.563637)
			(xy 213.257929 -29.548124) (xy 213.202556 -29.525188) (xy 213.15065 -29.495221) (xy 213.1031 -29.458734)
			(xy 213.06072 -29.416354) (xy 213.024233 -29.368804) (xy 212.994266 -29.316898) (xy 212.97133 -29.261525)
			(xy 212.955817 -29.203632) (xy 212.947994 -29.14421) (xy 212.947504 -29.114242) (xy 212.312504 -29.114242)
			(xy 212.312504 -29.279596) (xy 212.312085 -29.289819) (xy 212.30426 -29.308709) (xy 212.289802 -29.323165)
			(xy 212.270911 -29.330986) (xy 212.260688 -29.331412) (xy 211.524088 -29.331412) (xy 211.513879 -29.330928)
			(xy 211.495016 -29.32311) (xy 211.480581 -29.30867) (xy 211.472769 -29.289805) (xy 211.472272 -29.279596)
			(xy 203.594732 -29.279596) (xy 203.575868 -29.325139) (xy 203.545884 -29.377073) (xy 203.509378 -29.424649)
			(xy 203.466973 -29.467054) (xy 203.419397 -29.50356) (xy 203.367463 -29.533544) (xy 203.312059 -29.556493)
			(xy 203.254134 -29.572014) (xy 203.194678 -29.579842) (xy 203.13471 -29.579842) (xy 203.075254 -29.572014)
			(xy 203.017329 -29.556493) (xy 202.961925 -29.533544) (xy 202.909991 -29.50356) (xy 202.862415 -29.467054)
			(xy 202.82001 -29.424649) (xy 202.783504 -29.377073) (xy 202.75352 -29.325139) (xy 202.730571 -29.269735)
			(xy 202.71505 -29.21181) (xy 202.707222 -29.152354) (xy 202.706732 -29.12237) (xy 187.862839 -29.12237)
			(xy 187.862482 -29.14421) (xy 187.854659 -29.203632) (xy 187.839146 -29.261525) (xy 187.81621 -29.316898)
			(xy 187.786243 -29.368804) (xy 187.749756 -29.416354) (xy 187.707376 -29.458734) (xy 187.659826 -29.495221)
			(xy 187.60792 -29.525188) (xy 187.552547 -29.548124) (xy 187.494654 -29.563637) (xy 187.435232 -29.57146)
			(xy 187.375296 -29.57146) (xy 187.315874 -29.563637) (xy 187.257981 -29.548124) (xy 187.202608 -29.525188)
			(xy 187.150702 -29.495221) (xy 187.103152 -29.458734) (xy 187.060772 -29.416354) (xy 187.024285 -29.368804)
			(xy 186.994318 -29.316898) (xy 186.971382 -29.261525) (xy 186.955869 -29.203632) (xy 186.948046 -29.14421)
			(xy 186.947556 -29.114242) (xy 186.312556 -29.114242) (xy 186.312556 -29.279596) (xy 186.312016 -29.289799)
			(xy 186.304212 -29.308652) (xy 186.289789 -29.323087) (xy 186.270942 -29.330907) (xy 186.26074 -29.331412)
			(xy 185.52414 -29.331412) (xy 185.51392 -29.330955) (xy 185.495033 -29.323144) (xy 185.480576 -29.308697)
			(xy 185.472752 -29.289815) (xy 185.472324 -29.279596) (xy 177.594784 -29.279596) (xy 177.57592 -29.325139)
			(xy 177.545936 -29.377073) (xy 177.50943 -29.424649) (xy 177.467025 -29.467054) (xy 177.419449 -29.50356)
			(xy 177.367515 -29.533544) (xy 177.312111 -29.556493) (xy 177.254186 -29.572014) (xy 177.19473 -29.579842)
			(xy 177.134762 -29.579842) (xy 177.075306 -29.572014) (xy 177.017381 -29.556493) (xy 176.961977 -29.533544)
			(xy 176.910043 -29.50356) (xy 176.862467 -29.467054) (xy 176.820062 -29.424649) (xy 176.783556 -29.377073)
			(xy 176.753572 -29.325139) (xy 176.730623 -29.269735) (xy 176.715102 -29.21181) (xy 176.707274 -29.152354)
			(xy 176.706784 -29.12237) (xy 161.862891 -29.12237) (xy 161.862534 -29.14421) (xy 161.854711 -29.203632)
			(xy 161.839198 -29.261525) (xy 161.816262 -29.316898) (xy 161.786295 -29.368804) (xy 161.749808 -29.416354)
			(xy 161.707428 -29.458734) (xy 161.659878 -29.495221) (xy 161.607972 -29.525188) (xy 161.552599 -29.548124)
			(xy 161.494706 -29.563637) (xy 161.435284 -29.57146) (xy 161.375348 -29.57146) (xy 161.315926 -29.563637)
			(xy 161.258033 -29.548124) (xy 161.20266 -29.525188) (xy 161.150754 -29.495221) (xy 161.103204 -29.458734)
			(xy 161.060824 -29.416354) (xy 161.024337 -29.368804) (xy 160.99437 -29.316898) (xy 160.971434 -29.261525)
			(xy 160.955921 -29.203632) (xy 160.948098 -29.14421) (xy 160.947608 -29.114242) (xy 160.312608 -29.114242)
			(xy 160.312608 -29.279596) (xy 160.312185 -29.289818) (xy 160.304361 -29.308707) (xy 160.289904 -29.323163)
			(xy 160.271015 -29.330986) (xy 160.260792 -29.331412) (xy 159.524192 -29.331412) (xy 159.513983 -29.330924)
			(xy 159.495121 -29.323108) (xy 159.480685 -29.308669) (xy 159.472873 -29.289805) (xy 159.472376 -29.279596)
			(xy 151.594836 -29.279596) (xy 151.575972 -29.325139) (xy 151.545988 -29.377073) (xy 151.509482 -29.424649)
			(xy 151.467077 -29.467054) (xy 151.419501 -29.50356) (xy 151.367567 -29.533544) (xy 151.312163 -29.556493)
			(xy 151.254238 -29.572014) (xy 151.194782 -29.579842) (xy 151.134814 -29.579842) (xy 151.075358 -29.572014)
			(xy 151.017433 -29.556493) (xy 150.962029 -29.533544) (xy 150.910095 -29.50356) (xy 150.862519 -29.467054)
			(xy 150.820114 -29.424649) (xy 150.783608 -29.377073) (xy 150.753624 -29.325139) (xy 150.730675 -29.269735)
			(xy 150.715154 -29.21181) (xy 150.707326 -29.152354) (xy 150.706836 -29.12237) (xy 135.862943 -29.12237)
			(xy 135.862586 -29.14421) (xy 135.854763 -29.203632) (xy 135.83925 -29.261525) (xy 135.816314 -29.316898)
			(xy 135.786347 -29.368804) (xy 135.74986 -29.416354) (xy 135.70748 -29.458734) (xy 135.65993 -29.495221)
			(xy 135.608024 -29.525188) (xy 135.552651 -29.548124) (xy 135.494758 -29.563637) (xy 135.435336 -29.57146)
			(xy 135.3754 -29.57146) (xy 135.315978 -29.563637) (xy 135.258085 -29.548124) (xy 135.202712 -29.525188)
			(xy 135.150806 -29.495221) (xy 135.103256 -29.458734) (xy 135.060876 -29.416354) (xy 135.024389 -29.368804)
			(xy 134.994422 -29.316898) (xy 134.971486 -29.261525) (xy 134.955973 -29.203632) (xy 134.94815 -29.14421)
			(xy 134.94766 -29.114242) (xy 134.31266 -29.114242) (xy 134.31266 -29.279596) (xy 134.312116 -29.289798)
			(xy 134.304313 -29.308651) (xy 134.289892 -29.323086) (xy 134.271046 -29.330907) (xy 134.260844 -29.331412)
			(xy 133.524244 -29.331412) (xy 133.514025 -29.330952) (xy 133.495137 -29.323142) (xy 133.48068 -29.308696)
			(xy 133.472856 -29.289815) (xy 133.472428 -29.279596) (xy 125.594888 -29.279596) (xy 125.576024 -29.325139)
			(xy 125.54604 -29.377073) (xy 125.509534 -29.424649) (xy 125.467129 -29.467054) (xy 125.419553 -29.50356)
			(xy 125.367619 -29.533544) (xy 125.312215 -29.556493) (xy 125.25429 -29.572014) (xy 125.194834 -29.579842)
			(xy 125.134866 -29.579842) (xy 125.07541 -29.572014) (xy 125.017485 -29.556493) (xy 124.962081 -29.533544)
			(xy 124.910147 -29.50356) (xy 124.862571 -29.467054) (xy 124.820166 -29.424649) (xy 124.78366 -29.377073)
			(xy 124.753676 -29.325139) (xy 124.730727 -29.269735) (xy 124.715206 -29.21181) (xy 124.707378 -29.152354)
			(xy 124.706888 -29.12237) (xy 97.762943 -29.12237) (xy 97.762586 -29.144226) (xy 97.754758 -29.203682)
			(xy 97.739237 -29.261607) (xy 97.716288 -29.317011) (xy 97.686304 -29.368945) (xy 97.649798 -29.416521)
			(xy 97.607393 -29.458926) (xy 97.559817 -29.495432) (xy 97.507883 -29.525416) (xy 97.452479 -29.548365)
			(xy 97.394554 -29.563886) (xy 97.335098 -29.571714) (xy 97.27513 -29.571714) (xy 97.215674 -29.563886)
			(xy 97.157749 -29.548365) (xy 97.102345 -29.525416) (xy 97.050411 -29.495432) (xy 97.002835 -29.458926)
			(xy 96.96043 -29.416521) (xy 96.923924 -29.368945) (xy 96.89394 -29.317011) (xy 96.870991 -29.261607)
			(xy 96.85547 -29.203682) (xy 96.847642 -29.144226) (xy 96.847152 -29.114242) (xy 96.212152 -29.114242)
			(xy 96.212152 -29.279596) (xy 96.211501 -29.291113) (xy 96.201639 -29.31193) (xy 96.183812 -29.326518)
			(xy 96.172782 -29.329888) (xy 96.172528 -29.329888) (xy 96.16059 -29.331412) (xy 95.42399 -29.331412)
			(xy 95.417617 -29.331186) (xy 95.40528 -29.327974) (xy 95.399606 -29.325062) (xy 95.391586 -29.320334)
			(xy 95.37935 -29.306319) (xy 95.372817 -29.288899) (xy 95.372428 -29.279596) (xy 87.49436 -29.279596)
			(xy 87.475542 -29.325026) (xy 87.445575 -29.376932) (xy 87.409088 -29.424482) (xy 87.366708 -29.466862)
			(xy 87.319158 -29.503349) (xy 87.267252 -29.533316) (xy 87.211879 -29.556252) (xy 87.153986 -29.571765)
			(xy 87.094564 -29.579588) (xy 87.034628 -29.579588) (xy 86.975206 -29.571765) (xy 86.917313 -29.556252)
			(xy 86.86194 -29.533316) (xy 86.810034 -29.503349) (xy 86.762484 -29.466862) (xy 86.720104 -29.424482)
			(xy 86.683617 -29.376932) (xy 86.65365 -29.325026) (xy 86.630714 -29.269653) (xy 86.615201 -29.21176)
			(xy 86.607378 -29.152338) (xy 86.606888 -29.12237) (xy 71.762995 -29.12237) (xy 71.762638 -29.144226)
			(xy 71.75481 -29.203682) (xy 71.739289 -29.261607) (xy 71.71634 -29.317011) (xy 71.686356 -29.368945)
			(xy 71.64985 -29.416521) (xy 71.607445 -29.458926) (xy 71.559869 -29.495432) (xy 71.507935 -29.525416)
			(xy 71.452531 -29.548365) (xy 71.394606 -29.563886) (xy 71.33515 -29.571714) (xy 71.275182 -29.571714)
			(xy 71.215726 -29.563886) (xy 71.157801 -29.548365) (xy 71.102397 -29.525416) (xy 71.050463 -29.495432)
			(xy 71.002887 -29.458926) (xy 70.960482 -29.416521) (xy 70.923976 -29.368945) (xy 70.893992 -29.317011)
			(xy 70.871043 -29.261607) (xy 70.855522 -29.203682) (xy 70.847694 -29.144226) (xy 70.847204 -29.114242)
			(xy 70.212204 -29.114242) (xy 70.212204 -29.279596) (xy 70.211523 -29.291143) (xy 70.201578 -29.311988)
			(xy 70.183653 -29.326553) (xy 70.17258 -29.329888) (xy 70.160642 -29.331412) (xy 69.424042 -29.331412)
			(xy 69.413287 -29.330872) (xy 69.393598 -29.322219) (xy 69.385942 -29.314648) (xy 69.379748 -29.307246)
			(xy 69.372831 -29.289241) (xy 69.37248 -29.279596) (xy 61.494412 -29.279596) (xy 61.475594 -29.325026)
			(xy 61.445627 -29.376932) (xy 61.40914 -29.424482) (xy 61.36676 -29.466862) (xy 61.31921 -29.503349)
			(xy 61.267304 -29.533316) (xy 61.211931 -29.556252) (xy 61.154038 -29.571765) (xy 61.094616 -29.579588)
			(xy 61.03468 -29.579588) (xy 60.975258 -29.571765) (xy 60.917365 -29.556252) (xy 60.861992 -29.533316)
			(xy 60.810086 -29.503349) (xy 60.762536 -29.466862) (xy 60.720156 -29.424482) (xy 60.683669 -29.376932)
			(xy 60.653702 -29.325026) (xy 60.630766 -29.269653) (xy 60.615253 -29.21176) (xy 60.60743 -29.152338)
			(xy 60.60694 -29.12237) (xy 45.763047 -29.12237) (xy 45.76269 -29.144226) (xy 45.754862 -29.203682)
			(xy 45.739341 -29.261607) (xy 45.716392 -29.317011) (xy 45.686408 -29.368945) (xy 45.649902 -29.416521)
			(xy 45.607497 -29.458926) (xy 45.559921 -29.495432) (xy 45.507987 -29.525416) (xy 45.452583 -29.548365)
			(xy 45.394658 -29.563886) (xy 45.335202 -29.571714) (xy 45.275234 -29.571714) (xy 45.215778 -29.563886)
			(xy 45.157853 -29.548365) (xy 45.102449 -29.525416) (xy 45.050515 -29.495432) (xy 45.002939 -29.458926)
			(xy 44.960534 -29.416521) (xy 44.924028 -29.368945) (xy 44.894044 -29.317011) (xy 44.871095 -29.261607)
			(xy 44.855574 -29.203682) (xy 44.847746 -29.144226) (xy 44.847256 -29.114242) (xy 44.212256 -29.114242)
			(xy 44.212256 -29.279596) (xy 44.21161 -29.291148) (xy 44.201654 -29.312) (xy 44.183713 -29.32656)
			(xy 44.172632 -29.329888) (xy 44.160694 -29.331412) (xy 43.424094 -29.331412) (xy 43.413336 -29.330898)
			(xy 43.393648 -29.322227) (xy 43.385994 -29.314648) (xy 43.379794 -29.307251) (xy 43.372882 -29.289242)
			(xy 43.372532 -29.279596) (xy 35.494464 -29.279596) (xy 35.475646 -29.325026) (xy 35.445679 -29.376932)
			(xy 35.409192 -29.424482) (xy 35.366812 -29.466862) (xy 35.319262 -29.503349) (xy 35.267356 -29.533316)
			(xy 35.211983 -29.556252) (xy 35.15409 -29.571765) (xy 35.094668 -29.579588) (xy 35.034732 -29.579588)
			(xy 34.97531 -29.571765) (xy 34.917417 -29.556252) (xy 34.862044 -29.533316) (xy 34.810138 -29.503349)
			(xy 34.762588 -29.466862) (xy 34.720208 -29.424482) (xy 34.683721 -29.376932) (xy 34.653754 -29.325026)
			(xy 34.630818 -29.269653) (xy 34.615305 -29.21176) (xy 34.607482 -29.152338) (xy 34.606992 -29.12237)
			(xy 19.763099 -29.12237) (xy 19.762742 -29.144226) (xy 19.754914 -29.203682) (xy 19.739393 -29.261607)
			(xy 19.716444 -29.317011) (xy 19.68646 -29.368945) (xy 19.649954 -29.416521) (xy 19.607549 -29.458926)
			(xy 19.559973 -29.495432) (xy 19.508039 -29.525416) (xy 19.452635 -29.548365) (xy 19.39471 -29.563886)
			(xy 19.335254 -29.571714) (xy 19.275286 -29.571714) (xy 19.21583 -29.563886) (xy 19.157905 -29.548365)
			(xy 19.102501 -29.525416) (xy 19.050567 -29.495432) (xy 19.002991 -29.458926) (xy 18.960586 -29.416521)
			(xy 18.92408 -29.368945) (xy 18.894096 -29.317011) (xy 18.871147 -29.261607) (xy 18.855626 -29.203682)
			(xy 18.847798 -29.144226) (xy 18.847308 -29.114242) (xy 18.212308 -29.114242) (xy 18.212308 -29.279596)
			(xy 18.21169 -29.291118) (xy 18.201817 -29.311941) (xy 18.183975 -29.326525) (xy 18.172938 -29.329888)
			(xy 18.172684 -29.329888) (xy 18.160746 -29.331412) (xy 17.424146 -29.331412) (xy 17.417771 -29.331202)
			(xy 17.405434 -29.327979) (xy 17.399762 -29.325062) (xy 17.391733 -29.320349) (xy 17.379502 -29.306325)
			(xy 17.372972 -29.2889) (xy 17.372584 -29.279596) (xy 9.494516 -29.279596) (xy 9.475698 -29.325026)
			(xy 9.445731 -29.376932) (xy 9.409244 -29.424482) (xy 9.366864 -29.466862) (xy 9.319314 -29.503349)
			(xy 9.267408 -29.533316) (xy 9.212035 -29.556252) (xy 9.154142 -29.571765) (xy 9.09472 -29.579588)
			(xy 9.034784 -29.579588) (xy 8.975362 -29.571765) (xy 8.917469 -29.556252) (xy 8.862096 -29.533316)
			(xy 8.81019 -29.503349) (xy 8.76264 -29.466862) (xy 8.72026 -29.424482) (xy 8.683773 -29.376932)
			(xy 8.653806 -29.325026) (xy 8.63087 -29.269653) (xy 8.615357 -29.21176) (xy 8.607534 -29.152338)
			(xy 8.607044 -29.12237) (xy 0.509016 -29.12237) (xy 0.509016 -30.922468) (xy 6.752844 -30.922468)
			(xy 6.752844 -30.058868) (xy 6.753334 -30.0289) (xy 6.761157 -29.969478) (xy 6.77667 -29.911585)
			(xy 6.799606 -29.856212) (xy 6.829573 -29.804306) (xy 6.86606 -29.756756) (xy 6.90844 -29.714376)
			(xy 6.95599 -29.677889) (xy 7.007896 -29.647922) (xy 7.063269 -29.624986) (xy 7.121162 -29.609473)
			(xy 7.180584 -29.60165) (xy 7.24052 -29.60165) (xy 7.299942 -29.609473) (xy 7.357835 -29.624986)
			(xy 7.413208 -29.647922) (xy 7.465114 -29.677889) (xy 7.512664 -29.714376) (xy 7.555044 -29.756756)
			(xy 7.591531 -29.804306) (xy 7.621498 -29.856212) (xy 7.644434 -29.911585) (xy 7.659947 -29.969478)
			(xy 7.66777 -30.0289) (xy 7.66826 -30.058868) (xy 7.66826 -30.922468) (xy 7.66777 -30.952436) (xy 7.66068 -31.006288)
			(xy 10.029444 -31.006288) (xy 10.029444 -29.974286) (xy 10.029915 -29.964158) (xy 10.037649 -29.945436)
			(xy 10.051939 -29.93108) (xy 10.070626 -29.923262) (xy 10.080752 -29.922724) (xy 11.312652 -29.922724)
			(xy 11.322774 -29.923156) (xy 11.341481 -29.930893) (xy 11.355798 -29.945205) (xy 11.363541 -29.96391)
			(xy 11.36396 -29.974032) (xy 11.36396 -31.006034) (xy 14.565884 -31.006034) (xy 14.565884 -29.974286)
			(xy 14.566317 -29.964153) (xy 14.574057 -29.945423) (xy 14.58836 -29.931066) (xy 14.607061 -29.923255)
			(xy 14.617192 -29.922724) (xy 15.849092 -29.922724) (xy 15.859249 -29.923129) (xy 15.878005 -29.930926)
			(xy 15.89233 -29.945328) (xy 15.900026 -29.964127) (xy 15.9004 -29.974286) (xy 15.9004 -31.006034)
			(xy 15.899903 -31.016158) (xy 15.892171 -31.034872) (xy 15.877889 -31.049226) (xy 15.859213 -31.057051)
			(xy 15.849092 -31.057596) (xy 14.617192 -31.057596) (xy 14.607037 -31.057185) (xy 14.588284 -31.049386)
			(xy 14.57396 -31.034986) (xy 14.566262 -31.016191) (xy 14.565884 -31.006034) (xy 11.36396 -31.006034)
			(xy 11.363501 -31.016163) (xy 11.355762 -31.034885) (xy 11.341468 -31.04924) (xy 11.322779 -31.057058)
			(xy 11.312652 -31.057596) (xy 10.080752 -31.057596) (xy 10.07064 -31.057154) (xy 10.05196 -31.0494)
			(xy 10.037667 -31.03509) (xy 10.029934 -31.016401) (xy 10.029444 -31.006288) (xy 7.66068 -31.006288)
			(xy 7.659947 -31.011858) (xy 7.644434 -31.069751) (xy 7.637685 -31.086044) (xy 20.014692 -31.086044)
			(xy 20.014692 -30.84322) (xy 20.221956 -30.52699) (xy 20.226274 -30.520386) (xy 20.230162 -30.514068)
			(xy 20.234409 -30.499861) (xy 20.234656 -30.492446) (xy 20.234656 -30.485588) (xy 20.234437 -30.478864)
			(xy 20.230964 -30.465871) (xy 20.227798 -30.459934) (xy 20.10283 -30.268164) (xy 20.083526 -30.238446)
			(xy 20.0279 -30.153102) (xy 20.023582 -30.147006) (xy 20.02028 -30.141418) (xy 20.019772 -30.140402)
			(xy 20.014692 -30.132528) (xy 20.014692 -29.889704) (xy 20.01531 -29.878182) (xy 20.025183 -29.857359)
			(xy 20.043025 -29.842775) (xy 20.054062 -29.839412) (xy 20.054316 -29.839412) (xy 20.066254 -29.837888)
			(xy 20.802854 -29.837888) (xy 20.809229 -29.838098) (xy 20.821566 -29.841321) (xy 20.827238 -29.844238)
			(xy 20.835267 -29.848951) (xy 20.847498 -29.862975) (xy 20.854028 -29.8804) (xy 20.854416 -29.889704)
			(xy 20.854416 -30.132528) (xy 20.638516 -30.462982) (xy 20.634486 -30.4712) (xy 20.631944 -30.489312)
			(xy 20.635893 -30.507171) (xy 20.640548 -30.515052) (xy 20.672806 -30.564836) (xy 20.6883 -30.588458)
			(xy 20.854416 -30.84195) (xy 20.854416 -30.92069) (xy 21.489416 -30.92069) (xy 21.489416 -30.05709)
			(xy 21.489906 -30.027106) (xy 21.497734 -29.96765) (xy 21.513255 -29.909725) (xy 21.536204 -29.854321)
			(xy 21.566188 -29.802387) (xy 21.602694 -29.754811) (xy 21.645099 -29.712406) (xy 21.692675 -29.6759)
			(xy 21.744609 -29.645916) (xy 21.800013 -29.622967) (xy 21.857938 -29.607446) (xy 21.917394 -29.599618)
			(xy 21.977362 -29.599618) (xy 22.036818 -29.607446) (xy 22.094743 -29.622967) (xy 22.150147 -29.645916)
			(xy 22.202081 -29.6759) (xy 22.249657 -29.712406) (xy 22.292062 -29.754811) (xy 22.328568 -29.802387)
			(xy 22.358552 -29.854321) (xy 22.381501 -29.909725) (xy 22.397022 -29.96765) (xy 22.40485 -30.027106)
			(xy 22.40534 -30.05709) (xy 22.40534 -30.92069) (xy 22.405311 -30.922468) (xy 32.752792 -30.922468)
			(xy 32.752792 -30.058868) (xy 32.753282 -30.0289) (xy 32.761105 -29.969478) (xy 32.776618 -29.911585)
			(xy 32.799554 -29.856212) (xy 32.829521 -29.804306) (xy 32.866008 -29.756756) (xy 32.908388 -29.714376)
			(xy 32.955938 -29.677889) (xy 33.007844 -29.647922) (xy 33.063217 -29.624986) (xy 33.12111 -29.609473)
			(xy 33.180532 -29.60165) (xy 33.240468 -29.60165) (xy 33.29989 -29.609473) (xy 33.357783 -29.624986)
			(xy 33.413156 -29.647922) (xy 33.465062 -29.677889) (xy 33.512612 -29.714376) (xy 33.554992 -29.756756)
			(xy 33.591479 -29.804306) (xy 33.621446 -29.856212) (xy 33.644382 -29.911585) (xy 33.659895 -29.969478)
			(xy 33.667718 -30.0289) (xy 33.668208 -30.058868) (xy 33.668208 -30.922468) (xy 33.667718 -30.952436)
			(xy 33.660628 -31.006288) (xy 36.029392 -31.006288) (xy 36.029392 -29.974286) (xy 36.029914 -29.964164)
			(xy 36.037637 -29.945452) (xy 36.051912 -29.931098) (xy 36.070581 -29.923271) (xy 36.0807 -29.922724)
			(xy 37.3126 -29.922724) (xy 37.322725 -29.923117) (xy 37.341434 -29.930869) (xy 37.355749 -29.945193)
			(xy 37.36349 -29.963906) (xy 37.363908 -29.974032) (xy 37.363908 -31.006034) (xy 40.565832 -31.006034)
			(xy 40.565832 -29.974286) (xy 40.566315 -29.964159) (xy 40.574046 -29.94544) (xy 40.588333 -29.931084)
			(xy 40.607016 -29.923264) (xy 40.61714 -29.922724) (xy 41.84904 -29.922724) (xy 41.8592 -29.923089)
			(xy 41.877958 -29.930903) (xy 41.89228 -29.945317) (xy 41.899974 -29.964124) (xy 41.900348 -29.974286)
			(xy 41.900348 -31.006034) (xy 41.899901 -31.016164) (xy 41.89216 -31.034889) (xy 41.877861 -31.049244)
			(xy 41.859168 -31.05706) (xy 41.84904 -31.057596) (xy 40.61714 -31.057596) (xy 40.606988 -31.057145)
			(xy 40.588236 -31.049362) (xy 40.573911 -31.034974) (xy 40.56621 -31.016188) (xy 40.565832 -31.006034)
			(xy 37.363908 -31.006034) (xy 37.363403 -31.016157) (xy 37.355673 -31.03487) (xy 37.341393 -31.049223)
			(xy 37.32272 -31.05705) (xy 37.3126 -31.057596) (xy 36.0807 -31.057596) (xy 36.070577 -31.057184)
			(xy 36.051873 -31.049435) (xy 36.037558 -31.035117) (xy 36.029814 -31.016411) (xy 36.029392 -31.006288)
			(xy 33.660628 -31.006288) (xy 33.659895 -31.011858) (xy 33.644382 -31.069751) (xy 33.637633 -31.086044)
			(xy 46.01464 -31.086044) (xy 46.01464 -30.84322) (xy 46.208696 -30.547056) (xy 46.228508 -30.51683)
			(xy 46.233427 -30.508353) (xy 46.237171 -30.489137) (xy 46.233455 -30.469916) (xy 46.228508 -30.461458)
			(xy 46.06163 -30.204918) (xy 46.023022 -30.145736) (xy 46.022514 -30.144974) (xy 46.022006 -30.144212)
			(xy 46.021752 -30.143704) (xy 46.021244 -30.142942) (xy 46.01464 -30.132528) (xy 46.01464 -29.889704)
			(xy 46.015289 -29.878152) (xy 46.025244 -29.857301) (xy 46.043184 -29.842741) (xy 46.054264 -29.839412)
			(xy 46.066202 -29.837888) (xy 46.802802 -29.837888) (xy 46.81356 -29.838404) (xy 46.833248 -29.847074)
			(xy 46.840902 -29.854652) (xy 46.847102 -29.86205) (xy 46.854014 -29.880058) (xy 46.854364 -29.889704)
			(xy 46.854364 -30.132528) (xy 46.638464 -30.462982) (xy 46.634439 -30.471201) (xy 46.6319 -30.489312)
			(xy 46.635845 -30.50717) (xy 46.640496 -30.515052) (xy 46.672754 -30.564836) (xy 46.854364 -30.84195)
			(xy 46.854364 -30.92069) (xy 47.489364 -30.92069) (xy 47.489364 -30.05709) (xy 47.489854 -30.027106)
			(xy 47.497682 -29.96765) (xy 47.513203 -29.909725) (xy 47.536152 -29.854321) (xy 47.566136 -29.802387)
			(xy 47.602642 -29.754811) (xy 47.645047 -29.712406) (xy 47.692623 -29.6759) (xy 47.744557 -29.645916)
			(xy 47.799961 -29.622967) (xy 47.857886 -29.607446) (xy 47.917342 -29.599618) (xy 47.97731 -29.599618)
			(xy 48.036766 -29.607446) (xy 48.094691 -29.622967) (xy 48.150095 -29.645916) (xy 48.202029 -29.6759)
			(xy 48.249605 -29.712406) (xy 48.29201 -29.754811) (xy 48.328516 -29.802387) (xy 48.3585 -29.854321)
			(xy 48.381449 -29.909725) (xy 48.39697 -29.96765) (xy 48.404798 -30.027106) (xy 48.405288 -30.05709)
			(xy 48.405288 -30.92069) (xy 48.405259 -30.922468) (xy 58.75274 -30.922468) (xy 58.75274 -30.058868)
			(xy 58.75323 -30.0289) (xy 58.761053 -29.969478) (xy 58.776566 -29.911585) (xy 58.799502 -29.856212)
			(xy 58.829469 -29.804306) (xy 58.865956 -29.756756) (xy 58.908336 -29.714376) (xy 58.955886 -29.677889)
			(xy 59.007792 -29.647922) (xy 59.063165 -29.624986) (xy 59.121058 -29.609473) (xy 59.18048 -29.60165)
			(xy 59.240416 -29.60165) (xy 59.299838 -29.609473) (xy 59.357731 -29.624986) (xy 59.413104 -29.647922)
			(xy 59.46501 -29.677889) (xy 59.51256 -29.714376) (xy 59.55494 -29.756756) (xy 59.591427 -29.804306)
			(xy 59.621394 -29.856212) (xy 59.64433 -29.911585) (xy 59.659843 -29.969478) (xy 59.667666 -30.0289)
			(xy 59.668156 -30.058868) (xy 59.668156 -30.922468) (xy 59.667666 -30.952436) (xy 59.660576 -31.006288)
			(xy 62.02934 -31.006288) (xy 62.02934 -29.974286) (xy 62.029815 -29.964158) (xy 62.037548 -29.945437)
			(xy 62.051837 -29.931081) (xy 62.070523 -29.923263) (xy 62.080648 -29.922724) (xy 63.312548 -29.922724)
			(xy 63.322663 -29.923147) (xy 63.341347 -29.930904) (xy 63.355641 -29.945221) (xy 63.363369 -29.963916)
			(xy 63.363856 -29.974032) (xy 63.363856 -31.006034) (xy 66.56578 -31.006034) (xy 66.56578 -29.974286)
			(xy 66.566216 -29.964154) (xy 66.573956 -29.945425) (xy 66.588258 -29.931067) (xy 66.606957 -29.923256)
			(xy 66.617088 -29.922724) (xy 67.848988 -29.922724) (xy 67.859144 -29.923132) (xy 67.877901 -29.930928)
			(xy 67.892226 -29.945329) (xy 67.899922 -29.964128) (xy 67.900296 -29.974286) (xy 67.900296 -31.006034)
			(xy 67.899802 -31.016158) (xy 67.89207 -31.034874) (xy 67.877787 -31.049227) (xy 67.85911 -31.057052)
			(xy 67.848988 -31.057596) (xy 66.617088 -31.057596) (xy 66.606933 -31.057188) (xy 66.588179 -31.049388)
			(xy 66.573856 -31.034987) (xy 66.566157 -31.016192) (xy 66.56578 -31.006034) (xy 63.363856 -31.006034)
			(xy 63.363401 -31.016163) (xy 63.355662 -31.034886) (xy 63.341366 -31.049241) (xy 63.322675 -31.057059)
			(xy 63.312548 -31.057596) (xy 62.080648 -31.057596) (xy 62.070528 -31.057145) (xy 62.051825 -31.049411)
			(xy 62.037509 -31.035105) (xy 62.029763 -31.016408) (xy 62.02934 -31.006288) (xy 59.660576 -31.006288)
			(xy 59.659843 -31.011858) (xy 59.64433 -31.069751) (xy 59.637581 -31.086044) (xy 72.014588 -31.086044)
			(xy 72.014588 -30.84322) (xy 72.208644 -30.547056) (xy 72.228456 -30.51683) (xy 72.233379 -30.508354)
			(xy 72.237127 -30.489137) (xy 72.233407 -30.469915) (xy 72.228456 -30.461458) (xy 72.061578 -30.204918)
			(xy 72.02297 -30.145736) (xy 72.022462 -30.144974) (xy 72.021954 -30.144212) (xy 72.0217 -30.143704)
			(xy 72.021192 -30.142942) (xy 72.014588 -30.132528) (xy 72.014588 -29.889704) (xy 72.015275 -29.878158)
			(xy 72.025218 -29.857314) (xy 72.04314 -29.842748) (xy 72.054212 -29.839412) (xy 72.06615 -29.837888)
			(xy 72.80275 -29.837888) (xy 72.813504 -29.838432) (xy 72.833193 -29.847082) (xy 72.84085 -29.854652)
			(xy 72.847043 -29.862055) (xy 72.853961 -29.880059) (xy 72.854312 -29.889704) (xy 72.854312 -30.132528)
			(xy 72.638412 -30.462982) (xy 72.634382 -30.4712) (xy 72.63184 -30.489312) (xy 72.635789 -30.507171)
			(xy 72.640444 -30.515052) (xy 72.672702 -30.564836) (xy 72.854312 -30.84195) (xy 72.854312 -30.92069)
			(xy 73.489312 -30.92069) (xy 73.489312 -30.05709) (xy 73.489802 -30.027106) (xy 73.49763 -29.96765)
			(xy 73.513151 -29.909725) (xy 73.5361 -29.854321) (xy 73.566084 -29.802387) (xy 73.60259 -29.754811)
			(xy 73.644995 -29.712406) (xy 73.692571 -29.6759) (xy 73.744505 -29.645916) (xy 73.799909 -29.622967)
			(xy 73.857834 -29.607446) (xy 73.91729 -29.599618) (xy 73.977258 -29.599618) (xy 74.036714 -29.607446)
			(xy 74.094639 -29.622967) (xy 74.150043 -29.645916) (xy 74.201977 -29.6759) (xy 74.249553 -29.712406)
			(xy 74.291958 -29.754811) (xy 74.328464 -29.802387) (xy 74.358448 -29.854321) (xy 74.381397 -29.909725)
			(xy 74.396918 -29.96765) (xy 74.404746 -30.027106) (xy 74.405236 -30.05709) (xy 74.405236 -30.92069)
			(xy 74.405207 -30.922468) (xy 84.752688 -30.922468) (xy 84.752688 -30.058868) (xy 84.753178 -30.0289)
			(xy 84.761001 -29.969478) (xy 84.776514 -29.911585) (xy 84.79945 -29.856212) (xy 84.829417 -29.804306)
			(xy 84.865904 -29.756756) (xy 84.908284 -29.714376) (xy 84.955834 -29.677889) (xy 85.00774 -29.647922)
			(xy 85.063113 -29.624986) (xy 85.121006 -29.609473) (xy 85.180428 -29.60165) (xy 85.240364 -29.60165)
			(xy 85.299786 -29.609473) (xy 85.357679 -29.624986) (xy 85.413052 -29.647922) (xy 85.464958 -29.677889)
			(xy 85.512508 -29.714376) (xy 85.554888 -29.756756) (xy 85.591375 -29.804306) (xy 85.621342 -29.856212)
			(xy 85.644278 -29.911585) (xy 85.659791 -29.969478) (xy 85.667614 -30.0289) (xy 85.668104 -30.058868)
			(xy 85.668104 -30.922468) (xy 85.667614 -30.952436) (xy 85.660524 -31.006288) (xy 88.029288 -31.006288)
			(xy 88.029288 -29.974286) (xy 88.029814 -29.964165) (xy 88.037537 -29.945453) (xy 88.05181 -29.931099)
			(xy 88.070478 -29.923272) (xy 88.080596 -29.922724) (xy 89.312496 -29.922724) (xy 89.322621 -29.92312)
			(xy 89.341329 -29.930871) (xy 89.355645 -29.945194) (xy 89.363386 -29.963907) (xy 89.363804 -29.974032)
			(xy 89.363804 -31.006034) (xy 92.565728 -31.006034) (xy 92.565728 -29.974286) (xy 92.566215 -29.96416)
			(xy 92.573945 -29.945441) (xy 92.588231 -29.931085) (xy 92.606912 -29.923265) (xy 92.617036 -29.922724)
			(xy 93.848936 -29.922724) (xy 93.859095 -29.923093) (xy 93.877853 -29.930905) (xy 93.892176 -29.945318)
			(xy 93.89987 -29.964124) (xy 93.900244 -29.974286) (xy 93.900244 -31.006034) (xy 93.899801 -31.016165)
			(xy 93.892059 -31.03489) (xy 93.877759 -31.049246) (xy 93.859065 -31.057061) (xy 93.848936 -31.057596)
			(xy 92.617036 -31.057596) (xy 92.606884 -31.057149) (xy 92.588131 -31.049364) (xy 92.573807 -31.034975)
			(xy 92.566106 -31.016188) (xy 92.565728 -31.006034) (xy 89.363804 -31.006034) (xy 89.363303 -31.016157)
			(xy 89.355572 -31.034871) (xy 89.341291 -31.049225) (xy 89.322617 -31.05705) (xy 89.312496 -31.057596)
			(xy 88.080596 -31.057596) (xy 88.070473 -31.057187) (xy 88.051768 -31.049437) (xy 88.037454 -31.035118)
			(xy 88.02971 -31.016411) (xy 88.029288 -31.006288) (xy 85.660524 -31.006288) (xy 85.659791 -31.011858)
			(xy 85.644278 -31.069751) (xy 85.637529 -31.086044) (xy 98.014536 -31.086044) (xy 98.014536 -30.84322)
			(xy 98.133408 -30.661864) (xy 98.195892 -30.56636) (xy 98.220022 -30.52953) (xy 98.223889 -30.523201)
			(xy 98.22815 -30.509002) (xy 98.228404 -30.50159) (xy 98.228404 -30.475682) (xy 98.228224 -30.469531)
			(xy 98.225262 -30.45759) (xy 98.222562 -30.45206) (xy 98.109024 -30.27807) (xy 98.088958 -30.247082)
			(xy 98.08337 -30.238446) (xy 98.022918 -30.145736) (xy 98.02241 -30.144974) (xy 98.021902 -30.144212)
			(xy 98.021648 -30.143704) (xy 98.02114 -30.142942) (xy 98.014536 -30.132528) (xy 98.014536 -29.889704)
			(xy 98.015188 -29.878153) (xy 98.025142 -29.857302) (xy 98.04308 -29.842741) (xy 98.05416 -29.839412)
			(xy 98.066098 -29.837888) (xy 98.802698 -29.837888) (xy 98.813455 -29.838406) (xy 98.833144 -29.847075)
			(xy 98.840798 -29.854652) (xy 98.846998 -29.86205) (xy 98.85391 -29.880058) (xy 98.85426 -29.889704)
			(xy 98.85426 -30.132528) (xy 98.63836 -30.462982) (xy 98.634336 -30.471201) (xy 98.631796 -30.489312)
			(xy 98.635741 -30.50717) (xy 98.640392 -30.515052) (xy 98.67265 -30.564836) (xy 98.85426 -30.84195)
			(xy 98.85426 -30.92069) (xy 99.48926 -30.92069) (xy 99.48926 -30.05709) (xy 99.48975 -30.027106)
			(xy 99.497578 -29.96765) (xy 99.513099 -29.909725) (xy 99.536048 -29.854321) (xy 99.566032 -29.802387)
			(xy 99.602538 -29.754811) (xy 99.644943 -29.712406) (xy 99.692519 -29.6759) (xy 99.744453 -29.645916)
			(xy 99.799857 -29.622967) (xy 99.857782 -29.607446) (xy 99.917238 -29.599618) (xy 99.977206 -29.599618)
			(xy 100.036662 -29.607446) (xy 100.094587 -29.622967) (xy 100.149991 -29.645916) (xy 100.201925 -29.6759)
			(xy 100.249501 -29.712406) (xy 100.291906 -29.754811) (xy 100.328412 -29.802387) (xy 100.358396 -29.854321)
			(xy 100.381345 -29.909725) (xy 100.396866 -29.96765) (xy 100.404694 -30.027106) (xy 100.405184 -30.05709)
			(xy 100.405184 -30.92069) (xy 100.405155 -30.922468) (xy 122.852688 -30.922468) (xy 122.852688 -30.058868)
			(xy 122.853178 -30.028884) (xy 122.861006 -29.969428) (xy 122.876527 -29.911503) (xy 122.899476 -29.856099)
			(xy 122.92946 -29.804165) (xy 122.965966 -29.756589) (xy 123.008371 -29.714184) (xy 123.055947 -29.677678)
			(xy 123.107881 -29.647694) (xy 123.163285 -29.624745) (xy 123.22121 -29.609224) (xy 123.280666 -29.601396)
			(xy 123.340634 -29.601396) (xy 123.40009 -29.609224) (xy 123.458015 -29.624745) (xy 123.513419 -29.647694)
			(xy 123.565353 -29.677678) (xy 123.612929 -29.714184) (xy 123.655334 -29.756589) (xy 123.69184 -29.804165)
			(xy 123.721824 -29.856099) (xy 123.744773 -29.911503) (xy 123.760294 -29.969428) (xy 123.768122 -30.028884)
			(xy 123.768612 -30.058868) (xy 123.768612 -30.922468) (xy 123.768122 -30.952452) (xy 123.761067 -31.006034)
			(xy 126.129288 -31.006034) (xy 126.129288 -29.974286) (xy 126.129654 -29.964107) (xy 126.137453 -29.945303)
			(xy 126.151857 -29.930917) (xy 126.170671 -29.923141) (xy 126.18085 -29.922724) (xy 127.41275 -29.922724)
			(xy 127.422917 -29.923204) (xy 127.441708 -29.93097) (xy 127.456094 -29.945339) (xy 127.463883 -29.96412)
			(xy 127.464312 -29.974286) (xy 127.464312 -31.006034) (xy 130.665728 -31.006034) (xy 130.665728 -29.974286)
			(xy 130.666222 -29.964129) (xy 130.673999 -29.945361) (xy 130.688365 -29.930997) (xy 130.707133 -29.923221)
			(xy 130.71729 -29.922724) (xy 131.94919 -29.922724) (xy 131.959345 -29.923241) (xy 131.978112 -29.93101)
			(xy 131.992477 -29.945368) (xy 132.000254 -29.964131) (xy 132.000752 -29.974286) (xy 132.000752 -31.006034)
			(xy 132.000294 -31.016195) (xy 131.992507 -31.034967) (xy 131.97813 -31.049331) (xy 131.959352 -31.057103)
			(xy 131.94919 -31.057596) (xy 130.71729 -31.057596) (xy 130.707136 -31.057075) (xy 130.688373 -31.049304)
			(xy 130.674009 -31.034947) (xy 130.666229 -31.016188) (xy 130.665728 -31.006034) (xy 127.464312 -31.006034)
			(xy 127.463963 -31.016214) (xy 127.456157 -31.035019) (xy 127.441748 -31.049405) (xy 127.422931 -31.057179)
			(xy 127.41275 -31.057596) (xy 126.18085 -31.057596) (xy 126.170686 -31.057096) (xy 126.151899 -31.049334)
			(xy 126.137513 -31.034972) (xy 126.12972 -31.016197) (xy 126.129288 -31.006034) (xy 123.761067 -31.006034)
			(xy 123.760294 -31.011908) (xy 123.744773 -31.069833) (xy 123.738058 -31.086044) (xy 136.114536 -31.086044)
			(xy 136.114536 -30.84322) (xy 136.120124 -30.834838) (xy 136.120378 -30.83433) (xy 136.12241 -30.831282)
			(xy 136.122664 -30.830774) (xy 136.328404 -30.51683) (xy 136.333357 -30.508373) (xy 136.337189 -30.489176)
			(xy 136.333563 -30.469939) (xy 136.328658 -30.461458) (xy 136.242806 -30.329378) (xy 136.233408 -30.3149)
			(xy 136.12114 -30.142942) (xy 136.120632 -30.141926) (xy 136.1186 -30.138878) (xy 136.118346 -30.13837)
			(xy 136.114536 -30.132528) (xy 136.114536 -29.889704) (xy 136.115084 -29.879502) (xy 136.122886 -29.86065)
			(xy 136.137306 -29.846216) (xy 136.156151 -29.838394) (xy 136.166352 -29.837888) (xy 136.902952 -29.837888)
			(xy 136.913171 -29.838351) (xy 136.932058 -29.846159) (xy 136.946516 -29.860605) (xy 136.95434 -29.879485)
			(xy 136.954768 -29.889704) (xy 136.954768 -30.132528) (xy 136.950958 -30.13837) (xy 136.950704 -30.138878)
			(xy 136.94664 -30.144974) (xy 136.946386 -30.145228) (xy 136.808464 -30.356302) (xy 136.755378 -30.437582)
			(xy 136.742932 -30.456632) (xy 136.7409 -30.459426) (xy 136.73963 -30.461458) (xy 136.735455 -30.468887)
			(xy 136.731731 -30.485502) (xy 136.73368 -30.502418) (xy 136.73709 -30.510226) (xy 136.924288 -30.795722)
			(xy 136.926828 -30.799532) (xy 136.94664 -30.829504) (xy 136.946894 -30.830012) (xy 136.948164 -30.832044)
			(xy 136.949942 -30.834584) (xy 136.954768 -30.84195) (xy 136.954768 -30.92069) (xy 137.589768 -30.92069)
			(xy 137.589768 -30.05709) (xy 137.590258 -30.027122) (xy 137.598081 -29.9677) (xy 137.613594 -29.909807)
			(xy 137.63653 -29.854434) (xy 137.666497 -29.802528) (xy 137.702984 -29.754978) (xy 137.745364 -29.712598)
			(xy 137.792914 -29.676111) (xy 137.84482 -29.646144) (xy 137.900193 -29.623208) (xy 137.958086 -29.607695)
			(xy 138.017508 -29.599872) (xy 138.077444 -29.599872) (xy 138.136866 -29.607695) (xy 138.194759 -29.623208)
			(xy 138.250132 -29.646144) (xy 138.302038 -29.676111) (xy 138.349588 -29.712598) (xy 138.391968 -29.754978)
			(xy 138.428455 -29.802528) (xy 138.458422 -29.854434) (xy 138.481358 -29.909807) (xy 138.496871 -29.9677)
			(xy 138.504694 -30.027122) (xy 138.505184 -30.05709) (xy 138.505184 -30.92069) (xy 138.505155 -30.922468)
			(xy 148.852636 -30.922468) (xy 148.852636 -30.058868) (xy 148.853126 -30.028884) (xy 148.860954 -29.969428)
			(xy 148.876475 -29.911503) (xy 148.899424 -29.856099) (xy 148.929408 -29.804165) (xy 148.965914 -29.756589)
			(xy 149.008319 -29.714184) (xy 149.055895 -29.677678) (xy 149.107829 -29.647694) (xy 149.163233 -29.624745)
			(xy 149.221158 -29.609224) (xy 149.280614 -29.601396) (xy 149.340582 -29.601396) (xy 149.400038 -29.609224)
			(xy 149.457963 -29.624745) (xy 149.513367 -29.647694) (xy 149.565301 -29.677678) (xy 149.612877 -29.714184)
			(xy 149.655282 -29.756589) (xy 149.691788 -29.804165) (xy 149.721772 -29.856099) (xy 149.744721 -29.911503)
			(xy 149.760242 -29.969428) (xy 149.76807 -30.028884) (xy 149.76856 -30.058868) (xy 149.76856 -30.922468)
			(xy 149.76807 -30.952452) (xy 149.761015 -31.006034) (xy 152.129236 -31.006034) (xy 152.129236 -29.974286)
			(xy 152.129722 -29.964128) (xy 152.137501 -29.945359) (xy 152.151869 -29.930994) (xy 152.17064 -29.92322)
			(xy 152.180798 -29.922724) (xy 153.412698 -29.922724) (xy 153.422854 -29.923235) (xy 153.44162 -29.931006)
			(xy 153.455985 -29.945366) (xy 153.463762 -29.96413) (xy 153.46426 -29.974286) (xy 153.46426 -31.006034)
			(xy 156.665676 -31.006034) (xy 156.665676 -29.974286) (xy 156.666053 -29.964109) (xy 156.67385 -29.945307)
			(xy 156.68825 -29.930921) (xy 156.70706 -29.923143) (xy 156.717238 -29.922724) (xy 157.949138 -29.922724)
			(xy 157.959296 -29.923202) (xy 157.978064 -29.930986) (xy 157.992427 -29.945356) (xy 158.000203 -29.964127)
			(xy 158.0007 -29.974286) (xy 158.0007 -31.006034) (xy 158.000195 -31.016189) (xy 157.992417 -31.034952)
			(xy 157.978055 -31.049315) (xy 157.959293 -31.057095) (xy 157.949138 -31.057596) (xy 156.717238 -31.057596)
			(xy 156.707073 -31.057106) (xy 156.688286 -31.04934) (xy 156.673901 -31.034975) (xy 156.666108 -31.016198)
			(xy 156.665676 -31.006034) (xy 153.46426 -31.006034) (xy 153.463794 -31.016194) (xy 153.456008 -31.034965)
			(xy 153.441634 -31.049329) (xy 153.422859 -31.057102) (xy 153.412698 -31.057596) (xy 152.180798 -31.057596)
			(xy 152.170644 -31.057069) (xy 152.151882 -31.0493) (xy 152.137518 -31.034945) (xy 152.129737 -31.016187)
			(xy 152.129236 -31.006034) (xy 149.761015 -31.006034) (xy 149.760242 -31.011908) (xy 149.744721 -31.069833)
			(xy 149.738006 -31.086044) (xy 162.114484 -31.086044) (xy 162.114484 -30.85846) (xy 162.114738 -30.854396)
			(xy 162.114992 -30.851856) (xy 162.114992 -30.84322) (xy 162.12058 -30.834584) (xy 162.12185 -30.832552)
			(xy 162.122866 -30.83052) (xy 162.320224 -30.52953) (xy 162.324091 -30.523201) (xy 162.328352 -30.509002)
			(xy 162.328606 -30.50159) (xy 162.328606 -30.475936) (xy 162.328396 -30.468602) (xy 162.324268 -30.454531)
			(xy 162.320478 -30.44825) (xy 162.122612 -30.145228) (xy 162.120326 -30.141418) (xy 162.120072 -30.14091)
			(xy 162.119056 -30.139132) (xy 162.114992 -30.132528) (xy 162.114992 -30.1244) (xy 162.114738 -30.12186)
			(xy 162.114484 -30.117796) (xy 162.114484 -29.889704) (xy 162.114915 -29.879482) (xy 162.122737 -29.860595)
			(xy 162.137192 -29.846139) (xy 162.156079 -29.838316) (xy 162.1663 -29.837888) (xy 162.9029 -29.837888)
			(xy 162.913122 -29.838312) (xy 162.93201 -29.846136) (xy 162.946466 -29.860593) (xy 162.954289 -29.879482)
			(xy 162.954716 -29.889704) (xy 162.954716 -30.117288) (xy 162.954462 -30.121352) (xy 162.954208 -30.123892)
			(xy 162.954208 -30.132528) (xy 162.948366 -30.141926) (xy 162.947604 -30.143196) (xy 162.946334 -30.145228)
			(xy 162.740594 -30.459934) (xy 162.73556 -30.468465) (xy 162.731734 -30.487878) (xy 162.735544 -30.507294)
			(xy 162.740594 -30.515814) (xy 162.946334 -30.82925) (xy 162.94735 -30.831282) (xy 162.94862 -30.833314)
			(xy 162.954208 -30.84195) (xy 162.954208 -30.850586) (xy 162.954462 -30.853126) (xy 162.954716 -30.85719)
			(xy 162.954716 -30.92069) (xy 163.589716 -30.92069) (xy 163.589716 -30.05709) (xy 163.590206 -30.027122)
			(xy 163.598029 -29.9677) (xy 163.613542 -29.909807) (xy 163.636478 -29.854434) (xy 163.666445 -29.802528)
			(xy 163.702932 -29.754978) (xy 163.745312 -29.712598) (xy 163.792862 -29.676111) (xy 163.844768 -29.646144)
			(xy 163.900141 -29.623208) (xy 163.958034 -29.607695) (xy 164.017456 -29.599872) (xy 164.077392 -29.599872)
			(xy 164.136814 -29.607695) (xy 164.194707 -29.623208) (xy 164.25008 -29.646144) (xy 164.301986 -29.676111)
			(xy 164.349536 -29.712598) (xy 164.391916 -29.754978) (xy 164.428403 -29.802528) (xy 164.45837 -29.854434)
			(xy 164.481306 -29.909807) (xy 164.496819 -29.9677) (xy 164.504642 -30.027122) (xy 164.505132 -30.05709)
			(xy 164.505132 -30.92069) (xy 164.505103 -30.922468) (xy 174.852584 -30.922468) (xy 174.852584 -30.058868)
			(xy 174.853074 -30.028884) (xy 174.860902 -29.969428) (xy 174.876423 -29.911503) (xy 174.899372 -29.856099)
			(xy 174.929356 -29.804165) (xy 174.965862 -29.756589) (xy 175.008267 -29.714184) (xy 175.055843 -29.677678)
			(xy 175.107777 -29.647694) (xy 175.163181 -29.624745) (xy 175.221106 -29.609224) (xy 175.280562 -29.601396)
			(xy 175.34053 -29.601396) (xy 175.399986 -29.609224) (xy 175.457911 -29.624745) (xy 175.513315 -29.647694)
			(xy 175.565249 -29.677678) (xy 175.612825 -29.714184) (xy 175.65523 -29.756589) (xy 175.691736 -29.804165)
			(xy 175.72172 -29.856099) (xy 175.744669 -29.911503) (xy 175.76019 -29.969428) (xy 175.768018 -30.028884)
			(xy 175.768508 -30.058868) (xy 175.768508 -30.922468) (xy 175.768018 -30.952452) (xy 175.760963 -31.006034)
			(xy 178.129184 -31.006034) (xy 178.129184 -29.974286) (xy 178.129554 -29.964108) (xy 178.137352 -29.945304)
			(xy 178.151754 -29.930918) (xy 178.170567 -29.923142) (xy 178.180746 -29.922724) (xy 179.412646 -29.922724)
			(xy 179.422805 -29.923195) (xy 179.441572 -29.930982) (xy 179.455936 -29.945354) (xy 179.463711 -29.964127)
			(xy 179.464208 -29.974286) (xy 179.464208 -31.006034) (xy 182.665624 -31.006034) (xy 182.665624 -29.974286)
			(xy 182.666122 -29.964129) (xy 182.673898 -29.945362) (xy 182.688262 -29.930998) (xy 182.707029 -29.923222)
			(xy 182.717186 -29.922724) (xy 183.949086 -29.922724) (xy 183.959241 -29.923244) (xy 183.978007 -29.931012)
			(xy 183.992373 -29.945369) (xy 184.00015 -29.964131) (xy 184.000648 -29.974286) (xy 184.000648 -31.006034)
			(xy 184.000194 -31.016196) (xy 183.992406 -31.034968) (xy 183.978028 -31.049333) (xy 183.959248 -31.057104)
			(xy 183.949086 -31.057596) (xy 182.717186 -31.057596) (xy 182.707032 -31.057079) (xy 182.688269 -31.049306)
			(xy 182.673905 -31.034948) (xy 182.666125 -31.016188) (xy 182.665624 -31.006034) (xy 179.464208 -31.006034)
			(xy 179.463696 -31.016188) (xy 179.455919 -31.034949) (xy 179.441559 -31.049312) (xy 179.4228 -31.057093)
			(xy 179.412646 -31.057596) (xy 178.180746 -31.057596) (xy 178.170582 -31.057099) (xy 178.151794 -31.049336)
			(xy 178.137409 -31.034973) (xy 178.129616 -31.016198) (xy 178.129184 -31.006034) (xy 175.760963 -31.006034)
			(xy 175.76019 -31.011908) (xy 175.744669 -31.069833) (xy 175.737954 -31.086044) (xy 188.114432 -31.086044)
			(xy 188.114432 -30.84322) (xy 188.12002 -30.834838) (xy 188.120274 -30.83433) (xy 188.122306 -30.831282)
			(xy 188.12256 -30.830774) (xy 188.3283 -30.51683) (xy 188.333253 -30.508373) (xy 188.337085 -30.489176)
			(xy 188.33346 -30.469939) (xy 188.328554 -30.461458) (xy 188.242702 -30.329378) (xy 188.233304 -30.3149)
			(xy 188.121036 -30.142942) (xy 188.120528 -30.141926) (xy 188.118496 -30.138878) (xy 188.118242 -30.13837)
			(xy 188.114432 -30.132528) (xy 188.114432 -29.889704) (xy 188.114816 -29.879477) (xy 188.122647 -29.86058)
			(xy 188.137117 -29.846122) (xy 188.15602 -29.838307) (xy 188.166248 -29.837888) (xy 188.902848 -29.837888)
			(xy 188.913059 -29.838343) (xy 188.931923 -29.846172) (xy 188.946357 -29.860621) (xy 188.954168 -29.879492)
			(xy 188.954664 -29.889704) (xy 188.954664 -30.132528) (xy 188.950854 -30.13837) (xy 188.9506 -30.138878)
			(xy 188.946536 -30.144974) (xy 188.946282 -30.145228) (xy 188.80836 -30.356302) (xy 188.755274 -30.437582)
			(xy 188.742828 -30.456632) (xy 188.740796 -30.459426) (xy 188.739526 -30.461458) (xy 188.735351 -30.468887)
			(xy 188.731627 -30.485502) (xy 188.733576 -30.502418) (xy 188.736986 -30.510226) (xy 188.924184 -30.795722)
			(xy 188.926724 -30.799532) (xy 188.946536 -30.829504) (xy 188.94679 -30.830012) (xy 188.94806 -30.832044)
			(xy 188.949838 -30.834584) (xy 188.954664 -30.84195) (xy 188.954664 -30.92069) (xy 189.589664 -30.92069)
			(xy 189.589664 -30.05709) (xy 189.590154 -30.027122) (xy 189.597977 -29.9677) (xy 189.61349 -29.909807)
			(xy 189.636426 -29.854434) (xy 189.666393 -29.802528) (xy 189.70288 -29.754978) (xy 189.74526 -29.712598)
			(xy 189.79281 -29.676111) (xy 189.844716 -29.646144) (xy 189.900089 -29.623208) (xy 189.957982 -29.607695)
			(xy 190.017404 -29.599872) (xy 190.07734 -29.599872) (xy 190.136762 -29.607695) (xy 190.194655 -29.623208)
			(xy 190.250028 -29.646144) (xy 190.301934 -29.676111) (xy 190.349484 -29.712598) (xy 190.391864 -29.754978)
			(xy 190.428351 -29.802528) (xy 190.458318 -29.854434) (xy 190.481254 -29.909807) (xy 190.496767 -29.9677)
			(xy 190.50459 -30.027122) (xy 190.50508 -30.05709) (xy 190.50508 -30.92069) (xy 190.505051 -30.922468)
			(xy 200.852532 -30.922468) (xy 200.852532 -30.058868) (xy 200.853022 -30.028884) (xy 200.86085 -29.969428)
			(xy 200.876371 -29.911503) (xy 200.89932 -29.856099) (xy 200.929304 -29.804165) (xy 200.96581 -29.756589)
			(xy 201.008215 -29.714184) (xy 201.055791 -29.677678) (xy 201.107725 -29.647694) (xy 201.163129 -29.624745)
			(xy 201.221054 -29.609224) (xy 201.28051 -29.601396) (xy 201.340478 -29.601396) (xy 201.399934 -29.609224)
			(xy 201.457859 -29.624745) (xy 201.513263 -29.647694) (xy 201.565197 -29.677678) (xy 201.612773 -29.714184)
			(xy 201.655178 -29.756589) (xy 201.691684 -29.804165) (xy 201.721668 -29.856099) (xy 201.744617 -29.911503)
			(xy 201.760138 -29.969428) (xy 201.767966 -30.028884) (xy 201.768456 -30.058868) (xy 201.768456 -30.922468)
			(xy 201.767966 -30.952452) (xy 201.760911 -31.006034) (xy 204.129132 -31.006034) (xy 204.129132 -29.974286)
			(xy 204.129622 -29.964128) (xy 204.1374 -29.94536) (xy 204.151767 -29.930995) (xy 204.170536 -29.92322)
			(xy 204.180694 -29.922724) (xy 205.412594 -29.922724) (xy 205.42275 -29.923238) (xy 205.441516 -29.931008)
			(xy 205.455881 -29.945367) (xy 205.463658 -29.964131) (xy 205.464156 -29.974286) (xy 205.464156 -31.006034)
			(xy 208.665572 -31.006034) (xy 208.665572 -29.974286) (xy 208.665953 -29.964109) (xy 208.673749 -29.945308)
			(xy 208.688148 -29.930922) (xy 208.706957 -29.923144) (xy 208.717134 -29.922724) (xy 209.949034 -29.922724)
			(xy 209.959192 -29.923205) (xy 209.977959 -29.930988) (xy 209.992323 -29.945357) (xy 210.000099 -29.964128)
			(xy 210.000596 -29.974286) (xy 210.000596 -31.006034) (xy 210.000095 -31.01619) (xy 209.992316 -31.034953)
			(xy 209.977953 -31.049316) (xy 209.95919 -31.057095) (xy 209.949034 -31.057596) (xy 208.717134 -31.057596)
			(xy 208.706983 -31.057039) (xy 208.688221 -31.049283) (xy 208.673856 -31.034936) (xy 208.666074 -31.016185)
			(xy 208.665572 -31.006034) (xy 205.464156 -31.006034) (xy 205.463694 -31.016195) (xy 205.455908 -31.034966)
			(xy 205.441532 -31.04933) (xy 205.422755 -31.057102) (xy 205.412594 -31.057596) (xy 204.180694 -31.057596)
			(xy 204.17054 -31.057072) (xy 204.151777 -31.049302) (xy 204.137414 -31.034946) (xy 204.129633 -31.016188)
			(xy 204.129132 -31.006034) (xy 201.760911 -31.006034) (xy 201.760138 -31.011908) (xy 201.744617 -31.069833)
			(xy 201.737902 -31.086044) (xy 214.11438 -31.086044) (xy 214.11438 -30.85846) (xy 214.114634 -30.854396)
			(xy 214.114888 -30.851856) (xy 214.114888 -30.84322) (xy 214.120476 -30.834584) (xy 214.121746 -30.832552)
			(xy 214.122762 -30.83052) (xy 214.32012 -30.52953) (xy 214.323987 -30.523201) (xy 214.328248 -30.509002)
			(xy 214.328502 -30.50159) (xy 214.328502 -30.475936) (xy 214.328293 -30.468602) (xy 214.324164 -30.454531)
			(xy 214.320374 -30.44825) (xy 214.122508 -30.145228) (xy 214.120222 -30.141418) (xy 214.119968 -30.14091)
			(xy 214.118952 -30.139132) (xy 214.114888 -30.132528) (xy 214.114888 -30.1244) (xy 214.114634 -30.12186)
			(xy 214.11438 -30.117796) (xy 214.11438 -29.889704) (xy 214.114885 -29.879497) (xy 214.122696 -29.860636)
			(xy 214.137129 -29.8462) (xy 214.155989 -29.838387) (xy 214.166196 -29.837888) (xy 214.902796 -29.837888)
			(xy 214.913018 -29.838315) (xy 214.931906 -29.846138) (xy 214.946362 -29.860594) (xy 214.954185 -29.879482)
			(xy 214.954612 -29.889704) (xy 214.954612 -30.117288) (xy 214.954358 -30.121352) (xy 214.954104 -30.123892)
			(xy 214.954104 -30.132528) (xy 214.948262 -30.141926) (xy 214.9475 -30.143196) (xy 214.94623 -30.145228)
			(xy 214.74049 -30.459934) (xy 214.735457 -30.468465) (xy 214.73163 -30.487878) (xy 214.73544 -30.507294)
			(xy 214.74049 -30.515814) (xy 214.94623 -30.82925) (xy 214.947246 -30.831282) (xy 214.948516 -30.833314)
			(xy 214.954104 -30.84195) (xy 214.954104 -30.850586) (xy 214.954358 -30.853126) (xy 214.954612 -30.85719)
			(xy 214.954612 -30.92069) (xy 215.589612 -30.92069) (xy 215.589612 -30.05709) (xy 215.590102 -30.027122)
			(xy 215.597925 -29.9677) (xy 215.613438 -29.909807) (xy 215.636374 -29.854434) (xy 215.666341 -29.802528)
			(xy 215.702828 -29.754978) (xy 215.745208 -29.712598) (xy 215.792758 -29.676111) (xy 215.844664 -29.646144)
			(xy 215.900037 -29.623208) (xy 215.95793 -29.607695) (xy 216.017352 -29.599872) (xy 216.077288 -29.599872)
			(xy 216.13671 -29.607695) (xy 216.194603 -29.623208) (xy 216.249976 -29.646144) (xy 216.301882 -29.676111)
			(xy 216.349432 -29.712598) (xy 216.391812 -29.754978) (xy 216.428299 -29.802528) (xy 216.458266 -29.854434)
			(xy 216.481202 -29.909807) (xy 216.496715 -29.9677) (xy 216.504538 -30.027122) (xy 216.505028 -30.05709)
			(xy 216.505028 -30.92069) (xy 216.504999 -30.922468) (xy 238.952532 -30.922468) (xy 238.952532 -30.058868)
			(xy 238.953022 -30.028884) (xy 238.96085 -29.969428) (xy 238.976371 -29.911503) (xy 238.99932 -29.856099)
			(xy 239.029304 -29.804165) (xy 239.06581 -29.756589) (xy 239.108215 -29.714184) (xy 239.155791 -29.677678)
			(xy 239.207725 -29.647694) (xy 239.263129 -29.624745) (xy 239.321054 -29.609224) (xy 239.38051 -29.601396)
			(xy 239.440478 -29.601396) (xy 239.499934 -29.609224) (xy 239.557859 -29.624745) (xy 239.613263 -29.647694)
			(xy 239.665197 -29.677678) (xy 239.712773 -29.714184) (xy 239.755178 -29.756589) (xy 239.791684 -29.804165)
			(xy 239.821668 -29.856099) (xy 239.844617 -29.911503) (xy 239.860138 -29.969428) (xy 239.867966 -30.028884)
			(xy 239.868456 -30.058868) (xy 239.868456 -30.922468) (xy 239.867966 -30.952452) (xy 239.860911 -31.006034)
			(xy 242.229132 -31.006034) (xy 242.229132 -29.974286) (xy 242.229622 -29.964128) (xy 242.2374 -29.94536)
			(xy 242.251767 -29.930995) (xy 242.270536 -29.92322) (xy 242.280694 -29.922724) (xy 243.512594 -29.922724)
			(xy 243.52275 -29.923238) (xy 243.541516 -29.931008) (xy 243.555881 -29.945367) (xy 243.563658 -29.964131)
			(xy 243.564156 -29.974286) (xy 243.564156 -31.006034) (xy 246.765572 -31.006034) (xy 246.765572 -29.974286)
			(xy 246.765953 -29.964109) (xy 246.773749 -29.945308) (xy 246.788148 -29.930922) (xy 246.806957 -29.923144)
			(xy 246.817134 -29.922724) (xy 248.049034 -29.922724) (xy 248.059192 -29.923205) (xy 248.077959 -29.930988)
			(xy 248.092323 -29.945357) (xy 248.100099 -29.964128) (xy 248.100596 -29.974286) (xy 248.100596 -31.006034)
			(xy 248.100095 -31.01619) (xy 248.092316 -31.034953) (xy 248.077953 -31.049316) (xy 248.05919 -31.057095)
			(xy 248.049034 -31.057596) (xy 246.817134 -31.057596) (xy 246.806983 -31.057039) (xy 246.788221 -31.049283)
			(xy 246.773856 -31.034936) (xy 246.766074 -31.016185) (xy 246.765572 -31.006034) (xy 243.564156 -31.006034)
			(xy 243.563694 -31.016195) (xy 243.555908 -31.034966) (xy 243.541532 -31.04933) (xy 243.522755 -31.057102)
			(xy 243.512594 -31.057596) (xy 242.280694 -31.057596) (xy 242.27054 -31.057072) (xy 242.251777 -31.049302)
			(xy 242.237414 -31.034946) (xy 242.229633 -31.016188) (xy 242.229132 -31.006034) (xy 239.860911 -31.006034)
			(xy 239.860138 -31.011908) (xy 239.844617 -31.069833) (xy 239.837902 -31.086044) (xy 252.21438 -31.086044)
			(xy 252.21438 -30.85846) (xy 252.214634 -30.854396) (xy 252.214888 -30.851856) (xy 252.214888 -30.84322)
			(xy 252.220476 -30.834584) (xy 252.221746 -30.832552) (xy 252.222762 -30.83052) (xy 252.42012 -30.52953)
			(xy 252.423987 -30.523201) (xy 252.428248 -30.509002) (xy 252.428502 -30.50159) (xy 252.428502 -30.475936)
			(xy 252.428293 -30.468602) (xy 252.424164 -30.454531) (xy 252.420374 -30.44825) (xy 252.222508 -30.145228)
			(xy 252.220222 -30.141418) (xy 252.219968 -30.14091) (xy 252.218952 -30.139132) (xy 252.214888 -30.132528)
			(xy 252.214888 -30.1244) (xy 252.214634 -30.12186) (xy 252.21438 -30.117796) (xy 252.21438 -29.889704)
			(xy 252.214885 -29.879497) (xy 252.222696 -29.860636) (xy 252.237129 -29.8462) (xy 252.255989 -29.838387)
			(xy 252.266196 -29.837888) (xy 253.002796 -29.837888) (xy 253.013018 -29.838315) (xy 253.031906 -29.846138)
			(xy 253.046362 -29.860594) (xy 253.054185 -29.879482) (xy 253.054612 -29.889704) (xy 253.054612 -30.117288)
			(xy 253.054358 -30.121352) (xy 253.054104 -30.123892) (xy 253.054104 -30.132528) (xy 253.048262 -30.141926)
			(xy 253.0475 -30.143196) (xy 253.04623 -30.145228) (xy 252.84049 -30.459934) (xy 252.835457 -30.468465)
			(xy 252.83163 -30.487878) (xy 252.83544 -30.507294) (xy 252.84049 -30.515814) (xy 253.04623 -30.82925)
			(xy 253.047246 -30.831282) (xy 253.048516 -30.833314) (xy 253.054104 -30.84195) (xy 253.054104 -30.850586)
			(xy 253.054358 -30.853126) (xy 253.054612 -30.85719) (xy 253.054612 -30.92069) (xy 253.689612 -30.92069)
			(xy 253.689612 -30.05709) (xy 253.690102 -30.027122) (xy 253.697925 -29.9677) (xy 253.713438 -29.909807)
			(xy 253.736374 -29.854434) (xy 253.766341 -29.802528) (xy 253.802828 -29.754978) (xy 253.845208 -29.712598)
			(xy 253.892758 -29.676111) (xy 253.944664 -29.646144) (xy 254.000037 -29.623208) (xy 254.05793 -29.607695)
			(xy 254.117352 -29.599872) (xy 254.177288 -29.599872) (xy 254.23671 -29.607695) (xy 254.294603 -29.623208)
			(xy 254.349976 -29.646144) (xy 254.401882 -29.676111) (xy 254.449432 -29.712598) (xy 254.491812 -29.754978)
			(xy 254.528299 -29.802528) (xy 254.558266 -29.854434) (xy 254.581202 -29.909807) (xy 254.596715 -29.9677)
			(xy 254.604538 -30.027122) (xy 254.605028 -30.05709) (xy 254.605028 -30.92069) (xy 254.604999 -30.922468)
			(xy 264.95248 -30.922468) (xy 264.95248 -30.058868) (xy 264.95297 -30.028884) (xy 264.960798 -29.969428)
			(xy 264.976319 -29.911503) (xy 264.999268 -29.856099) (xy 265.029252 -29.804165) (xy 265.065758 -29.756589)
			(xy 265.108163 -29.714184) (xy 265.155739 -29.677678) (xy 265.207673 -29.647694) (xy 265.263077 -29.624745)
			(xy 265.321002 -29.609224) (xy 265.380458 -29.601396) (xy 265.440426 -29.601396) (xy 265.499882 -29.609224)
			(xy 265.557807 -29.624745) (xy 265.613211 -29.647694) (xy 265.665145 -29.677678) (xy 265.712721 -29.714184)
			(xy 265.755126 -29.756589) (xy 265.791632 -29.804165) (xy 265.821616 -29.856099) (xy 265.844565 -29.911503)
			(xy 265.860086 -29.969428) (xy 265.867914 -30.028884) (xy 265.868404 -30.058868) (xy 265.868404 -30.922468)
			(xy 265.867914 -30.952452) (xy 265.860859 -31.006034) (xy 268.22908 -31.006034) (xy 268.22908 -29.974286)
			(xy 268.229454 -29.964108) (xy 268.237251 -29.945305) (xy 268.251652 -29.930919) (xy 268.270464 -29.923142)
			(xy 268.280642 -29.922724) (xy 269.512542 -29.922724) (xy 269.522701 -29.923199) (xy 269.541468 -29.930984)
			(xy 269.555831 -29.945355) (xy 269.563607 -29.964127) (xy 269.564104 -29.974286) (xy 269.564104 -31.006034)
			(xy 272.76552 -31.006034) (xy 272.76552 -29.974286) (xy 272.766022 -29.96413) (xy 272.773797 -29.945364)
			(xy 272.78816 -29.931) (xy 272.806926 -29.923222) (xy 272.817082 -29.922724) (xy 274.048982 -29.922724)
			(xy 274.059151 -29.923178) (xy 274.077942 -29.930955) (xy 274.092327 -29.945331) (xy 274.100116 -29.964118)
			(xy 274.100544 -29.974286) (xy 274.100544 -31.006034) (xy 274.100094 -31.016196) (xy 274.092305 -31.03497)
			(xy 274.077926 -31.049334) (xy 274.059145 -31.057104) (xy 274.048982 -31.057596) (xy 272.817082 -31.057596)
			(xy 272.806927 -31.057082) (xy 272.788164 -31.049308) (xy 272.773801 -31.034949) (xy 272.766021 -31.016189)
			(xy 272.76552 -31.006034) (xy 269.564104 -31.006034) (xy 269.563596 -31.016189) (xy 269.555818 -31.034951)
			(xy 269.541457 -31.049313) (xy 269.522697 -31.057094) (xy 269.512542 -31.057596) (xy 268.280642 -31.057596)
			(xy 268.270477 -31.057103) (xy 268.25169 -31.049338) (xy 268.237305 -31.034974) (xy 268.229512 -31.016198)
			(xy 268.22908 -31.006034) (xy 265.860859 -31.006034) (xy 265.860086 -31.011908) (xy 265.844565 -31.069833)
			(xy 265.83785 -31.086044) (xy 278.214328 -31.086044) (xy 278.214328 -30.85846) (xy 278.214582 -30.854396)
			(xy 278.214836 -30.851856) (xy 278.214836 -30.84322) (xy 278.220424 -30.834584) (xy 278.221694 -30.832552)
			(xy 278.22271 -30.83052) (xy 278.420068 -30.52953) (xy 278.423939 -30.523203) (xy 278.428197 -30.509003)
			(xy 278.42845 -30.50159) (xy 278.42845 -30.475936) (xy 278.428248 -30.468602) (xy 278.424116 -30.45453)
			(xy 278.420322 -30.44825) (xy 278.222456 -30.145228) (xy 278.22017 -30.141418) (xy 278.219916 -30.14091)
			(xy 278.2189 -30.139132) (xy 278.214836 -30.132528) (xy 278.214836 -30.1244) (xy 278.214582 -30.12186)
			(xy 278.214328 -30.117796) (xy 278.214328 -29.889704) (xy 278.214716 -29.879477) (xy 278.222546 -29.860581)
			(xy 278.237015 -29.846124) (xy 278.255917 -29.838308) (xy 278.266144 -29.837888) (xy 279.002744 -29.837888)
			(xy 279.012955 -29.838346) (xy 279.031818 -29.846174) (xy 279.046253 -29.860622) (xy 279.054064 -29.879492)
			(xy 279.05456 -29.889704) (xy 279.05456 -30.117288) (xy 279.054306 -30.121352) (xy 279.054052 -30.123892)
			(xy 279.054052 -30.132528) (xy 279.04821 -30.141926) (xy 279.047448 -30.143196) (xy 279.046178 -30.145228)
			(xy 278.840438 -30.459934) (xy 278.835409 -30.468467) (xy 278.831587 -30.487878) (xy 278.835392 -30.507293)
			(xy 278.840438 -30.515814) (xy 279.046178 -30.82925) (xy 279.047194 -30.831282) (xy 279.048464 -30.833314)
			(xy 279.054052 -30.84195) (xy 279.054052 -30.850586) (xy 279.054306 -30.853126) (xy 279.05456 -30.85719)
			(xy 279.05456 -30.92069) (xy 279.68956 -30.92069) (xy 279.68956 -30.05709) (xy 279.69005 -30.027122)
			(xy 279.697873 -29.9677) (xy 279.713386 -29.909807) (xy 279.736322 -29.854434) (xy 279.766289 -29.802528)
			(xy 279.802776 -29.754978) (xy 279.845156 -29.712598) (xy 279.892706 -29.676111) (xy 279.944612 -29.646144)
			(xy 279.999985 -29.623208) (xy 280.057878 -29.607695) (xy 280.1173 -29.599872) (xy 280.177236 -29.599872)
			(xy 280.236658 -29.607695) (xy 280.294551 -29.623208) (xy 280.349924 -29.646144) (xy 280.40183 -29.676111)
			(xy 280.44938 -29.712598) (xy 280.49176 -29.754978) (xy 280.528247 -29.802528) (xy 280.558214 -29.854434)
			(xy 280.58115 -29.909807) (xy 280.596663 -29.9677) (xy 280.604486 -30.027122) (xy 280.604976 -30.05709)
			(xy 280.604976 -30.92069) (xy 280.604947 -30.922468) (xy 290.952428 -30.922468) (xy 290.952428 -30.058868)
			(xy 290.952918 -30.028884) (xy 290.960746 -29.969428) (xy 290.976267 -29.911503) (xy 290.999216 -29.856099)
			(xy 291.0292 -29.804165) (xy 291.065706 -29.756589) (xy 291.108111 -29.714184) (xy 291.155687 -29.677678)
			(xy 291.207621 -29.647694) (xy 291.263025 -29.624745) (xy 291.32095 -29.609224) (xy 291.380406 -29.601396)
			(xy 291.440374 -29.601396) (xy 291.49983 -29.609224) (xy 291.557755 -29.624745) (xy 291.613159 -29.647694)
			(xy 291.665093 -29.677678) (xy 291.712669 -29.714184) (xy 291.755074 -29.756589) (xy 291.79158 -29.804165)
			(xy 291.821564 -29.856099) (xy 291.844513 -29.911503) (xy 291.860034 -29.969428) (xy 291.867862 -30.028884)
			(xy 291.868352 -30.058868) (xy 291.868352 -30.922468) (xy 291.867862 -30.952452) (xy 291.860807 -31.006034)
			(xy 294.229028 -31.006034) (xy 294.229028 -29.974286) (xy 294.229522 -29.964129) (xy 294.237299 -29.945361)
			(xy 294.251665 -29.930997) (xy 294.270433 -29.923221) (xy 294.28059 -29.922724) (xy 295.51249 -29.922724)
			(xy 295.522645 -29.923241) (xy 295.541412 -29.93101) (xy 295.555777 -29.945368) (xy 295.563554 -29.964131)
			(xy 295.564052 -29.974286) (xy 295.564052 -31.006034) (xy 298.765468 -31.006034) (xy 298.765468 -29.974286)
			(xy 298.765853 -29.96411) (xy 298.773648 -29.945309) (xy 298.788046 -29.930924) (xy 298.806853 -29.923145)
			(xy 298.81703 -29.922724) (xy 300.04893 -29.922724) (xy 300.059088 -29.923208) (xy 300.077855 -29.93099)
			(xy 300.092219 -29.945358) (xy 300.099995 -29.964128) (xy 300.100492 -29.974286) (xy 300.100492 -31.006034)
			(xy 300.099995 -31.01619) (xy 300.092215 -31.034954) (xy 300.077851 -31.049317) (xy 300.059086 -31.057096)
			(xy 300.04893 -31.057596) (xy 298.81703 -31.057596) (xy 298.806878 -31.057043) (xy 298.788116 -31.049285)
			(xy 298.773751 -31.034937) (xy 298.765969 -31.016185) (xy 298.765468 -31.006034) (xy 295.564052 -31.006034)
			(xy 295.563594 -31.016195) (xy 295.555807 -31.034967) (xy 295.54143 -31.049331) (xy 295.522652 -31.057103)
			(xy 295.51249 -31.057596) (xy 294.28059 -31.057596) (xy 294.270436 -31.057075) (xy 294.251673 -31.049304)
			(xy 294.237309 -31.034947) (xy 294.229529 -31.016188) (xy 294.229028 -31.006034) (xy 291.860807 -31.006034)
			(xy 291.860034 -31.011908) (xy 291.844513 -31.069833) (xy 291.837798 -31.086044) (xy 304.214276 -31.086044)
			(xy 304.214276 -30.85846) (xy 304.21453 -30.854396) (xy 304.214784 -30.851856) (xy 304.214784 -30.84322)
			(xy 304.220372 -30.834584) (xy 304.221642 -30.832552) (xy 304.222658 -30.83052) (xy 304.420016 -30.52953)
			(xy 304.423882 -30.523201) (xy 304.428144 -30.509002) (xy 304.428398 -30.50159) (xy 304.428398 -30.475936)
			(xy 304.42819 -30.468602) (xy 304.424061 -30.454531) (xy 304.42027 -30.44825) (xy 304.222404 -30.145228)
			(xy 304.220118 -30.141418) (xy 304.219864 -30.14091) (xy 304.218848 -30.139132) (xy 304.214784 -30.132528)
			(xy 304.214784 -30.1244) (xy 304.21453 -30.12186) (xy 304.214276 -30.117796) (xy 304.214276 -29.889704)
			(xy 304.214785 -29.879497) (xy 304.222595 -29.860637) (xy 304.237027 -29.846202) (xy 304.255886 -29.838387)
			(xy 304.266092 -29.837888) (xy 305.002692 -29.837888) (xy 305.012914 -29.838319) (xy 305.031801 -29.84614)
			(xy 305.046258 -29.860595) (xy 305.05408 -29.879482) (xy 305.054508 -29.889704) (xy 305.054508 -30.117288)
			(xy 305.054254 -30.121352) (xy 305.054 -30.123892) (xy 305.054 -30.132528) (xy 305.048158 -30.141926)
			(xy 305.047396 -30.143196) (xy 305.046126 -30.145228) (xy 304.840386 -30.459934) (xy 304.835353 -30.468465)
			(xy 304.831527 -30.487878) (xy 304.835337 -30.507294) (xy 304.840386 -30.515814) (xy 305.046126 -30.82925)
			(xy 305.047142 -30.831282) (xy 305.048412 -30.833314) (xy 305.054 -30.84195) (xy 305.054 -30.850586)
			(xy 305.054254 -30.853126) (xy 305.054508 -30.85719) (xy 305.054508 -30.92069) (xy 305.689508 -30.92069)
			(xy 305.689508 -30.05709) (xy 305.689998 -30.027122) (xy 305.697821 -29.9677) (xy 305.713334 -29.909807)
			(xy 305.73627 -29.854434) (xy 305.766237 -29.802528) (xy 305.802724 -29.754978) (xy 305.845104 -29.712598)
			(xy 305.892654 -29.676111) (xy 305.94456 -29.646144) (xy 305.999933 -29.623208) (xy 306.057826 -29.607695)
			(xy 306.117248 -29.599872) (xy 306.177184 -29.599872) (xy 306.236606 -29.607695) (xy 306.294499 -29.623208)
			(xy 306.349872 -29.646144) (xy 306.401778 -29.676111) (xy 306.449328 -29.712598) (xy 306.491708 -29.754978)
			(xy 306.528195 -29.802528) (xy 306.558162 -29.854434) (xy 306.581098 -29.909807) (xy 306.596611 -29.9677)
			(xy 306.604434 -30.027122) (xy 306.604924 -30.05709) (xy 306.604924 -30.92069) (xy 306.604895 -30.922468)
			(xy 316.952376 -30.922468) (xy 316.952376 -30.058868) (xy 316.952866 -30.028884) (xy 316.960694 -29.969428)
			(xy 316.976215 -29.911503) (xy 316.999164 -29.856099) (xy 317.029148 -29.804165) (xy 317.065654 -29.756589)
			(xy 317.108059 -29.714184) (xy 317.155635 -29.677678) (xy 317.207569 -29.647694) (xy 317.262973 -29.624745)
			(xy 317.320898 -29.609224) (xy 317.380354 -29.601396) (xy 317.440322 -29.601396) (xy 317.499778 -29.609224)
			(xy 317.557703 -29.624745) (xy 317.613107 -29.647694) (xy 317.665041 -29.677678) (xy 317.712617 -29.714184)
			(xy 317.755022 -29.756589) (xy 317.791528 -29.804165) (xy 317.821512 -29.856099) (xy 317.844461 -29.911503)
			(xy 317.859982 -29.969428) (xy 317.86781 -30.028884) (xy 317.8683 -30.058868) (xy 317.8683 -30.922468)
			(xy 317.86781 -30.952452) (xy 317.860755 -31.006034) (xy 320.228976 -31.006034) (xy 320.228976 -29.974286)
			(xy 320.229353 -29.964109) (xy 320.23715 -29.945307) (xy 320.25155 -29.930921) (xy 320.27036 -29.923143)
			(xy 320.280538 -29.922724) (xy 321.512438 -29.922724) (xy 321.522596 -29.923202) (xy 321.541364 -29.930986)
			(xy 321.555727 -29.945356) (xy 321.563503 -29.964127) (xy 321.564 -29.974286) (xy 321.564 -31.006034)
			(xy 324.765416 -31.006034) (xy 324.765416 -29.974286) (xy 324.765922 -29.96413) (xy 324.773697 -29.945365)
			(xy 324.788058 -29.931001) (xy 324.806822 -29.923223) (xy 324.816978 -29.922724) (xy 326.048878 -29.922724)
			(xy 326.059046 -29.923182) (xy 326.077838 -29.930957) (xy 326.092223 -29.945332) (xy 326.100011 -29.964118)
			(xy 326.10044 -29.974286) (xy 326.10044 -31.006034) (xy 326.099994 -31.016197) (xy 326.092204 -31.034971)
			(xy 326.077824 -31.049336) (xy 326.059041 -31.057105) (xy 326.048878 -31.057596) (xy 324.816978 -31.057596)
			(xy 324.806823 -31.057086) (xy 324.78806 -31.04931) (xy 324.773696 -31.03495) (xy 324.765917 -31.016189)
			(xy 324.765416 -31.006034) (xy 321.564 -31.006034) (xy 321.563495 -31.016189) (xy 321.555717 -31.034952)
			(xy 321.541355 -31.049315) (xy 321.522593 -31.057095) (xy 321.512438 -31.057596) (xy 320.280538 -31.057596)
			(xy 320.270373 -31.057106) (xy 320.251586 -31.04934) (xy 320.237201 -31.034975) (xy 320.229408 -31.016198)
			(xy 320.228976 -31.006034) (xy 317.860755 -31.006034) (xy 317.859982 -31.011908) (xy 317.844461 -31.069833)
			(xy 317.837746 -31.086044) (xy 330.214224 -31.086044) (xy 330.214224 -30.85846) (xy 330.214478 -30.854396)
			(xy 330.214732 -30.851856) (xy 330.214732 -30.84322) (xy 330.22032 -30.834584) (xy 330.22159 -30.832552)
			(xy 330.222606 -30.83052) (xy 330.419964 -30.52953) (xy 330.423834 -30.523203) (xy 330.428093 -30.509003)
			(xy 330.428346 -30.50159) (xy 330.428346 -30.475936) (xy 330.428145 -30.468602) (xy 330.424012 -30.45453)
			(xy 330.420218 -30.44825) (xy 330.222352 -30.145228) (xy 330.220066 -30.141418) (xy 330.219812 -30.14091)
			(xy 330.218796 -30.139132) (xy 330.214732 -30.132528) (xy 330.214732 -30.1244) (xy 330.214478 -30.12186)
			(xy 330.214224 -30.117796) (xy 330.214224 -29.889704) (xy 330.214616 -29.879478) (xy 330.222445 -29.860583)
			(xy 330.236913 -29.846125) (xy 330.255813 -29.838309) (xy 330.26604 -29.837888) (xy 331.00264 -29.837888)
			(xy 331.012851 -29.838349) (xy 331.031714 -29.846176) (xy 331.046149 -29.860623) (xy 331.05396 -29.879493)
			(xy 331.054456 -29.889704) (xy 331.054456 -30.117288) (xy 331.054202 -30.121352) (xy 331.053948 -30.123892)
			(xy 331.053948 -30.132528) (xy 331.048106 -30.141926) (xy 331.047344 -30.143196) (xy 331.046074 -30.145228)
			(xy 330.840334 -30.459934) (xy 330.835305 -30.468467) (xy 330.831483 -30.487878) (xy 330.835289 -30.507293)
			(xy 330.840334 -30.515814) (xy 331.046074 -30.82925) (xy 331.04709 -30.831282) (xy 331.04836 -30.833314)
			(xy 331.053948 -30.84195) (xy 331.053948 -30.850586) (xy 331.054202 -30.853126) (xy 331.054456 -30.85719)
			(xy 331.054456 -30.92069) (xy 331.689456 -30.92069) (xy 331.689456 -30.05709) (xy 331.689946 -30.027122)
			(xy 331.697769 -29.9677) (xy 331.713282 -29.909807) (xy 331.736218 -29.854434) (xy 331.766185 -29.802528)
			(xy 331.802672 -29.754978) (xy 331.845052 -29.712598) (xy 331.892602 -29.676111) (xy 331.944508 -29.646144)
			(xy 331.999881 -29.623208) (xy 332.057774 -29.607695) (xy 332.117196 -29.599872) (xy 332.177132 -29.599872)
			(xy 332.236554 -29.607695) (xy 332.294447 -29.623208) (xy 332.34982 -29.646144) (xy 332.401726 -29.676111)
			(xy 332.449276 -29.712598) (xy 332.491656 -29.754978) (xy 332.528143 -29.802528) (xy 332.55811 -29.854434)
			(xy 332.581046 -29.909807) (xy 332.596559 -29.9677) (xy 332.604382 -30.027122) (xy 332.604872 -30.05709)
			(xy 332.604872 -30.92069) (xy 332.604843 -30.922468) (xy 355.052884 -30.922468) (xy 355.052884 -30.058868)
			(xy 355.053374 -30.0289) (xy 355.061197 -29.969478) (xy 355.07671 -29.911585) (xy 355.099646 -29.856212)
			(xy 355.129613 -29.804306) (xy 355.1661 -29.756756) (xy 355.20848 -29.714376) (xy 355.25603 -29.677889)
			(xy 355.307936 -29.647922) (xy 355.363309 -29.624986) (xy 355.421202 -29.609473) (xy 355.480624 -29.60165)
			(xy 355.54056 -29.60165) (xy 355.599982 -29.609473) (xy 355.657875 -29.624986) (xy 355.713248 -29.647922)
			(xy 355.765154 -29.677889) (xy 355.812704 -29.714376) (xy 355.855084 -29.756756) (xy 355.891571 -29.804306)
			(xy 355.921538 -29.856212) (xy 355.944474 -29.911585) (xy 355.959987 -29.969478) (xy 355.96781 -30.0289)
			(xy 355.9683 -30.058868) (xy 355.9683 -30.922468) (xy 355.96781 -30.952436) (xy 355.96072 -31.006288)
			(xy 358.329484 -31.006288) (xy 358.329484 -29.974286) (xy 358.329917 -29.964153) (xy 358.337657 -29.945423)
			(xy 358.35196 -29.931066) (xy 358.370661 -29.923255) (xy 358.380792 -29.922724) (xy 359.612692 -29.922724)
			(xy 359.622817 -29.923123) (xy 359.641525 -29.930873) (xy 359.65584 -29.945195) (xy 359.663582 -29.963907)
			(xy 359.664 -29.974032) (xy 359.664 -31.006034) (xy 362.865924 -31.006034) (xy 362.865924 -29.974286)
			(xy 362.866415 -29.96416) (xy 362.874144 -29.945442) (xy 362.888429 -29.931087) (xy 362.907109 -29.923265)
			(xy 362.917232 -29.922724) (xy 364.149132 -29.922724) (xy 364.159291 -29.923096) (xy 364.178049 -29.930906)
			(xy 364.192372 -29.945319) (xy 364.200066 -29.964124) (xy 364.20044 -29.974286) (xy 364.20044 -31.006034)
			(xy 364.200001 -31.016165) (xy 364.192258 -31.034891) (xy 364.177957 -31.049247) (xy 364.159261 -31.057061)
			(xy 364.149132 -31.057596) (xy 362.917232 -31.057596) (xy 362.907079 -31.057152) (xy 362.888327 -31.049367)
			(xy 362.874002 -31.034976) (xy 362.866302 -31.016188) (xy 362.865924 -31.006034) (xy 359.664 -31.006034)
			(xy 359.663503 -31.016158) (xy 359.655771 -31.034872) (xy 359.641489 -31.049226) (xy 359.622813 -31.057051)
			(xy 359.612692 -31.057596) (xy 358.380792 -31.057596) (xy 358.370669 -31.05719) (xy 358.351964 -31.049439)
			(xy 358.33765 -31.035119) (xy 358.329906 -31.016412) (xy 358.329484 -31.006288) (xy 355.96072 -31.006288)
			(xy 355.959987 -31.011858) (xy 355.944474 -31.069751) (xy 355.937725 -31.086044) (xy 368.314732 -31.086044)
			(xy 368.314732 -30.84322) (xy 368.459512 -30.622494) (xy 368.508788 -30.547056) (xy 368.5286 -30.51683)
			(xy 368.53352 -30.508353) (xy 368.537265 -30.489137) (xy 368.533548 -30.469916) (xy 368.5286 -30.461458)
			(xy 368.383566 -30.238446) (xy 368.32794 -30.153102) (xy 368.323622 -30.147006) (xy 368.32032 -30.141418)
			(xy 368.319812 -30.140402) (xy 368.314732 -30.132528) (xy 368.314732 -29.889704) (xy 368.315394 -29.878188)
			(xy 368.325253 -29.857373) (xy 368.343074 -29.842784) (xy 368.354102 -29.839412) (xy 368.354356 -29.839412)
			(xy 368.366294 -29.837888) (xy 369.102894 -29.837888) (xy 369.109267 -29.838119) (xy 369.121604 -29.841328)
			(xy 369.127278 -29.844238) (xy 369.135295 -29.848971) (xy 369.147532 -29.862983) (xy 369.154067 -29.880402)
			(xy 369.154456 -29.889704) (xy 369.154456 -30.132528) (xy 368.938556 -30.462982) (xy 368.934532 -30.471201)
			(xy 368.931993 -30.489312) (xy 368.935937 -30.50717) (xy 368.940588 -30.515052) (xy 368.972846 -30.564836)
			(xy 368.98834 -30.588458) (xy 369.154456 -30.84195) (xy 369.154456 -30.92069) (xy 369.789456 -30.92069)
			(xy 369.789456 -30.05709) (xy 369.789946 -30.027106) (xy 369.797774 -29.96765) (xy 369.813295 -29.909725)
			(xy 369.836244 -29.854321) (xy 369.866228 -29.802387) (xy 369.902734 -29.754811) (xy 369.945139 -29.712406)
			(xy 369.992715 -29.6759) (xy 370.044649 -29.645916) (xy 370.100053 -29.622967) (xy 370.157978 -29.607446)
			(xy 370.217434 -29.599618) (xy 370.277402 -29.599618) (xy 370.336858 -29.607446) (xy 370.394783 -29.622967)
			(xy 370.450187 -29.645916) (xy 370.502121 -29.6759) (xy 370.549697 -29.712406) (xy 370.592102 -29.754811)
			(xy 370.628608 -29.802387) (xy 370.658592 -29.854321) (xy 370.681541 -29.909725) (xy 370.697062 -29.96765)
			(xy 370.70489 -30.027106) (xy 370.70538 -30.05709) (xy 370.70538 -30.92069) (xy 370.705351 -30.922468)
			(xy 381.052832 -30.922468) (xy 381.052832 -30.058868) (xy 381.053322 -30.0289) (xy 381.061145 -29.969478)
			(xy 381.076658 -29.911585) (xy 381.099594 -29.856212) (xy 381.129561 -29.804306) (xy 381.166048 -29.756756)
			(xy 381.208428 -29.714376) (xy 381.255978 -29.677889) (xy 381.307884 -29.647922) (xy 381.363257 -29.624986)
			(xy 381.42115 -29.609473) (xy 381.480572 -29.60165) (xy 381.540508 -29.60165) (xy 381.59993 -29.609473)
			(xy 381.657823 -29.624986) (xy 381.713196 -29.647922) (xy 381.765102 -29.677889) (xy 381.812652 -29.714376)
			(xy 381.855032 -29.756756) (xy 381.891519 -29.804306) (xy 381.921486 -29.856212) (xy 381.944422 -29.911585)
			(xy 381.959935 -29.969478) (xy 381.967758 -30.0289) (xy 381.968248 -30.058868) (xy 381.968248 -30.922468)
			(xy 381.967758 -30.952436) (xy 381.960668 -31.006288) (xy 384.329432 -31.006288) (xy 384.329432 -29.974286)
			(xy 384.329915 -29.964159) (xy 384.337646 -29.94544) (xy 384.351933 -29.931084) (xy 384.370616 -29.923264)
			(xy 384.38074 -29.922724) (xy 385.61264 -29.922724) (xy 385.622754 -29.923153) (xy 385.641438 -29.930908)
			(xy 385.655732 -29.945223) (xy 385.663461 -29.963917) (xy 385.663948 -29.974032) (xy 385.663948 -31.006034)
			(xy 388.865872 -31.006034) (xy 388.865872 -29.974286) (xy 388.866316 -29.964155) (xy 388.874055 -29.945427)
			(xy 388.888354 -29.93107) (xy 388.907051 -29.923257) (xy 388.91718 -29.922724) (xy 390.14908 -29.922724)
			(xy 390.159236 -29.923138) (xy 390.177992 -29.930932) (xy 390.192317 -29.945331) (xy 390.200014 -29.964128)
			(xy 390.200388 -29.974286) (xy 390.200388 -31.006034) (xy 390.199902 -31.016159) (xy 390.192168 -31.034876)
			(xy 390.177883 -31.04923) (xy 390.159203 -31.057053) (xy 390.14908 -31.057596) (xy 388.91718 -31.057596)
			(xy 388.907024 -31.057195) (xy 388.88827 -31.049392) (xy 388.873948 -31.034989) (xy 388.866249 -31.016192)
			(xy 388.865872 -31.006034) (xy 385.663948 -31.006034) (xy 385.663501 -31.016164) (xy 385.65576 -31.034889)
			(xy 385.641461 -31.049244) (xy 385.622768 -31.05706) (xy 385.61264 -31.057596) (xy 384.38074 -31.057596)
			(xy 384.37062 -31.057151) (xy 384.351916 -31.049415) (xy 384.3376 -31.035107) (xy 384.329855 -31.016408)
			(xy 384.329432 -31.006288) (xy 381.960668 -31.006288) (xy 381.959935 -31.011858) (xy 381.944422 -31.069751)
			(xy 381.937673 -31.086044) (xy 394.31468 -31.086044) (xy 394.31468 -30.84322) (xy 394.433552 -30.661864)
			(xy 394.496036 -30.56636) (xy 394.520166 -30.52953) (xy 394.524037 -30.523203) (xy 394.528295 -30.509003)
			(xy 394.528548 -30.50159) (xy 394.528548 -30.475682) (xy 394.528363 -30.469531) (xy 394.525404 -30.457591)
			(xy 394.522706 -30.45206) (xy 394.409168 -30.27807) (xy 394.389102 -30.247082) (xy 394.383514 -30.238446)
			(xy 394.323062 -30.145736) (xy 394.322554 -30.144974) (xy 394.322046 -30.144212) (xy 394.321792 -30.143704)
			(xy 394.321284 -30.142942) (xy 394.31468 -30.132528) (xy 394.31468 -29.889704) (xy 394.315372 -29.878159)
			(xy 394.325314 -29.857316) (xy 394.343233 -29.842749) (xy 394.354304 -29.839412) (xy 394.366242 -29.837888)
			(xy 395.102842 -29.837888) (xy 395.113596 -29.838436) (xy 395.133285 -29.847084) (xy 395.140942 -29.854652)
			(xy 395.147135 -29.862055) (xy 395.154053 -29.880059) (xy 395.154404 -29.889704) (xy 395.154404 -30.132528)
			(xy 394.938504 -30.462982) (xy 394.934475 -30.4712) (xy 394.931933 -30.489312) (xy 394.935881 -30.507171)
			(xy 394.940536 -30.515052) (xy 394.972794 -30.564836) (xy 395.154404 -30.84195) (xy 395.154404 -30.92069)
			(xy 395.789404 -30.92069) (xy 395.789404 -30.05709) (xy 395.789894 -30.027106) (xy 395.797722 -29.96765)
			(xy 395.813243 -29.909725) (xy 395.836192 -29.854321) (xy 395.866176 -29.802387) (xy 395.902682 -29.754811)
			(xy 395.945087 -29.712406) (xy 395.992663 -29.6759) (xy 396.044597 -29.645916) (xy 396.100001 -29.622967)
			(xy 396.157926 -29.607446) (xy 396.217382 -29.599618) (xy 396.27735 -29.599618) (xy 396.336806 -29.607446)
			(xy 396.394731 -29.622967) (xy 396.450135 -29.645916) (xy 396.502069 -29.6759) (xy 396.549645 -29.712406)
			(xy 396.59205 -29.754811) (xy 396.628556 -29.802387) (xy 396.65854 -29.854321) (xy 396.681489 -29.909725)
			(xy 396.69701 -29.96765) (xy 396.704838 -30.027106) (xy 396.705328 -30.05709) (xy 396.705328 -30.92069)
			(xy 396.705299 -30.922468) (xy 407.05278 -30.922468) (xy 407.05278 -30.058868) (xy 407.05327 -30.0289)
			(xy 407.061093 -29.969478) (xy 407.076606 -29.911585) (xy 407.099542 -29.856212) (xy 407.129509 -29.804306)
			(xy 407.165996 -29.756756) (xy 407.208376 -29.714376) (xy 407.255926 -29.677889) (xy 407.307832 -29.647922)
			(xy 407.363205 -29.624986) (xy 407.421098 -29.609473) (xy 407.48052 -29.60165) (xy 407.540456 -29.60165)
			(xy 407.599878 -29.609473) (xy 407.657771 -29.624986) (xy 407.713144 -29.647922) (xy 407.76505 -29.677889)
			(xy 407.8126 -29.714376) (xy 407.85498 -29.756756) (xy 407.891467 -29.804306) (xy 407.921434 -29.856212)
			(xy 407.94437 -29.911585) (xy 407.959883 -29.969478) (xy 407.967706 -30.0289) (xy 407.968196 -30.058868)
			(xy 407.968196 -30.922468) (xy 407.967706 -30.952436) (xy 407.960616 -31.006288) (xy 410.32938 -31.006288)
			(xy 410.32938 -29.974286) (xy 410.329816 -29.964154) (xy 410.337556 -29.945425) (xy 410.351858 -29.931067)
			(xy 410.370557 -29.923256) (xy 410.380688 -29.922724) (xy 411.612588 -29.922724) (xy 411.622713 -29.923126)
			(xy 411.641421 -29.930875) (xy 411.655736 -29.945196) (xy 411.663478 -29.963907) (xy 411.663896 -29.974032)
			(xy 411.663896 -31.006034) (xy 414.86582 -31.006034) (xy 414.86582 -29.974286) (xy 414.866315 -29.964161)
			(xy 414.874043 -29.945443) (xy 414.888327 -29.931088) (xy 414.907005 -29.923266) (xy 414.917128 -29.922724)
			(xy 416.149028 -29.922724) (xy 416.159187 -29.923099) (xy 416.177945 -29.930908) (xy 416.192268 -29.94532)
			(xy 416.199962 -29.964125) (xy 416.200336 -29.974286) (xy 416.200336 -31.006034) (xy 416.199901 -31.016166)
			(xy 416.192157 -31.034892) (xy 416.177855 -31.049248) (xy 416.159158 -31.057062) (xy 416.149028 -31.057596)
			(xy 414.917128 -31.057596) (xy 414.906975 -31.057156) (xy 414.888223 -31.049369) (xy 414.873898 -31.034977)
			(xy 414.866198 -31.016189) (xy 414.86582 -31.006034) (xy 411.663896 -31.006034) (xy 411.663402 -31.016158)
			(xy 411.65567 -31.034874) (xy 411.641387 -31.049227) (xy 411.62271 -31.057052) (xy 411.612588 -31.057596)
			(xy 410.380688 -31.057596) (xy 410.370578 -31.057124) (xy 410.351899 -31.049382) (xy 410.337604 -31.035081)
			(xy 410.329871 -31.016398) (xy 410.32938 -31.006288) (xy 407.960616 -31.006288) (xy 407.959883 -31.011858)
			(xy 407.94437 -31.069751) (xy 407.937621 -31.086044) (xy 420.314628 -31.086044) (xy 420.314628 -30.84322)
			(xy 420.4335 -30.661864) (xy 420.495984 -30.56636) (xy 420.520114 -30.52953) (xy 420.52398 -30.523201)
			(xy 420.528242 -30.509002) (xy 420.528496 -30.50159) (xy 420.528496 -30.475682) (xy 420.528317 -30.469531)
			(xy 420.525354 -30.45759) (xy 420.522654 -30.45206) (xy 420.409116 -30.27807) (xy 420.38905 -30.247082)
			(xy 420.383462 -30.238446) (xy 420.32301 -30.145736) (xy 420.322502 -30.144974) (xy 420.321994 -30.144212)
			(xy 420.32174 -30.143704) (xy 420.321232 -30.142942) (xy 420.314628 -30.132528) (xy 420.314628 -29.889704)
			(xy 420.315285 -29.878154) (xy 420.325237 -29.857304) (xy 420.343174 -29.842742) (xy 420.354252 -29.839412)
			(xy 420.36619 -29.837888) (xy 421.10279 -29.837888) (xy 421.113547 -29.83841) (xy 421.133236 -29.847076)
			(xy 421.14089 -29.854652) (xy 421.147089 -29.862051) (xy 421.154002 -29.880058) (xy 421.154352 -29.889704)
			(xy 421.154352 -30.132528) (xy 420.938452 -30.462982) (xy 420.934418 -30.471199) (xy 420.931874 -30.489312)
			(xy 420.935826 -30.507172) (xy 420.940484 -30.515052) (xy 420.972742 -30.564836) (xy 421.154352 -30.84195)
			(xy 421.154352 -30.92069) (xy 421.789352 -30.92069) (xy 421.789352 -30.05709) (xy 421.789842 -30.027106)
			(xy 421.79767 -29.96765) (xy 421.813191 -29.909725) (xy 421.83614 -29.854321) (xy 421.866124 -29.802387)
			(xy 421.90263 -29.754811) (xy 421.945035 -29.712406) (xy 421.992611 -29.6759) (xy 422.044545 -29.645916)
			(xy 422.099949 -29.622967) (xy 422.157874 -29.607446) (xy 422.21733 -29.599618) (xy 422.277298 -29.599618)
			(xy 422.336754 -29.607446) (xy 422.394679 -29.622967) (xy 422.450083 -29.645916) (xy 422.502017 -29.6759)
			(xy 422.549593 -29.712406) (xy 422.591998 -29.754811) (xy 422.628504 -29.802387) (xy 422.658488 -29.854321)
			(xy 422.681437 -29.909725) (xy 422.696958 -29.96765) (xy 422.704786 -30.027106) (xy 422.705276 -30.05709)
			(xy 422.705276 -30.92069) (xy 422.705247 -30.922468) (xy 433.052728 -30.922468) (xy 433.052728 -30.058868)
			(xy 433.053218 -30.0289) (xy 433.061041 -29.969478) (xy 433.076554 -29.911585) (xy 433.09949 -29.856212)
			(xy 433.129457 -29.804306) (xy 433.165944 -29.756756) (xy 433.208324 -29.714376) (xy 433.255874 -29.677889)
			(xy 433.30778 -29.647922) (xy 433.363153 -29.624986) (xy 433.421046 -29.609473) (xy 433.480468 -29.60165)
			(xy 433.540404 -29.60165) (xy 433.599826 -29.609473) (xy 433.657719 -29.624986) (xy 433.713092 -29.647922)
			(xy 433.764998 -29.677889) (xy 433.812548 -29.714376) (xy 433.854928 -29.756756) (xy 433.891415 -29.804306)
			(xy 433.921382 -29.856212) (xy 433.944318 -29.911585) (xy 433.959831 -29.969478) (xy 433.967654 -30.0289)
			(xy 433.968144 -30.058868) (xy 433.968144 -30.922468) (xy 433.967654 -30.952436) (xy 433.960564 -31.006288)
			(xy 436.329328 -31.006288) (xy 436.329328 -29.974286) (xy 436.329815 -29.96416) (xy 436.337545 -29.945441)
			(xy 436.351831 -29.931085) (xy 436.370512 -29.923265) (xy 436.380636 -29.922724) (xy 437.612536 -29.922724)
			(xy 437.62265 -29.923156) (xy 437.641334 -29.93091) (xy 437.655628 -29.945223) (xy 437.663357 -29.963917)
			(xy 437.663844 -29.974032) (xy 437.663844 -31.006034) (xy 440.865768 -31.006034) (xy 440.865768 -29.974286)
			(xy 440.866216 -29.964155) (xy 440.873954 -29.945428) (xy 440.888252 -29.931072) (xy 440.906947 -29.923258)
			(xy 440.917076 -29.922724) (xy 442.148976 -29.922724) (xy 442.159132 -29.923142) (xy 442.177888 -29.930934)
			(xy 442.192213 -29.945332) (xy 442.19991 -29.964128) (xy 442.200284 -29.974286) (xy 442.200284 -31.006034)
			(xy 442.199802 -31.01616) (xy 442.192068 -31.034877) (xy 442.17778 -31.049232) (xy 442.1591 -31.057054)
			(xy 442.148976 -31.057596) (xy 440.917076 -31.057596) (xy 440.90692 -31.057198) (xy 440.888166 -31.049394)
			(xy 440.873843 -31.03499) (xy 440.866145 -31.016192) (xy 440.865768 -31.006034) (xy 437.663844 -31.006034)
			(xy 437.663401 -31.016165) (xy 437.655659 -31.03489) (xy 437.641359 -31.049246) (xy 437.622665 -31.057061)
			(xy 437.612536 -31.057596) (xy 436.380636 -31.057596) (xy 436.370515 -31.057154) (xy 436.351812 -31.049417)
			(xy 436.337496 -31.035108) (xy 436.32975 -31.016408) (xy 436.329328 -31.006288) (xy 433.960564 -31.006288)
			(xy 433.959831 -31.011858) (xy 433.944318 -31.069751) (xy 433.937569 -31.086044) (xy 446.314576 -31.086044)
			(xy 446.314576 -30.84322) (xy 446.433448 -30.661864) (xy 446.495932 -30.56636) (xy 446.520062 -30.52953)
			(xy 446.523932 -30.523203) (xy 446.528191 -30.509003) (xy 446.528444 -30.50159) (xy 446.528444 -30.475682)
			(xy 446.52826 -30.469531) (xy 446.5253 -30.457591) (xy 446.522602 -30.45206) (xy 446.409064 -30.27807)
			(xy 446.388998 -30.247082) (xy 446.38341 -30.238446) (xy 446.322958 -30.145736) (xy 446.32245 -30.144974)
			(xy 446.321942 -30.144212) (xy 446.321688 -30.143704) (xy 446.32118 -30.142942) (xy 446.314576 -30.132528)
			(xy 446.314576 -29.889704) (xy 446.315271 -29.878159) (xy 446.325212 -29.857317) (xy 446.34313 -29.84275)
			(xy 446.3542 -29.839412) (xy 446.366138 -29.837888) (xy 447.102738 -29.837888) (xy 447.113492 -29.838438)
			(xy 447.133181 -29.847084) (xy 447.140838 -29.854652) (xy 447.14703 -29.862056) (xy 447.153949 -29.880059)
			(xy 447.1543 -29.889704) (xy 447.1543 -30.132528) (xy 446.9384 -30.462982) (xy 446.934371 -30.4712)
			(xy 446.93183 -30.489312) (xy 446.935778 -30.507171) (xy 446.940432 -30.515052) (xy 446.97269 -30.564836)
			(xy 447.1543 -30.84195) (xy 447.1543 -30.92069) (xy 447.7893 -30.92069) (xy 447.7893 -30.05709) (xy 447.78979 -30.027106)
			(xy 447.797618 -29.96765) (xy 447.813139 -29.909725) (xy 447.836088 -29.854321) (xy 447.866072 -29.802387)
			(xy 447.902578 -29.754811) (xy 447.944983 -29.712406) (xy 447.992559 -29.6759) (xy 448.044493 -29.645916)
			(xy 448.099897 -29.622967) (xy 448.157822 -29.607446) (xy 448.217278 -29.599618) (xy 448.277246 -29.599618)
			(xy 448.336702 -29.607446) (xy 448.394627 -29.622967) (xy 448.450031 -29.645916) (xy 448.501965 -29.6759)
			(xy 448.549541 -29.712406) (xy 448.591946 -29.754811) (xy 448.628452 -29.802387) (xy 448.658436 -29.854321)
			(xy 448.681385 -29.909725) (xy 448.696906 -29.96765) (xy 448.704734 -30.027106) (xy 448.705224 -30.05709)
			(xy 448.705224 -30.745738) (xy 457.614517 -30.745738) (xy 457.614517 -30.616598) (xy 457.622467 -30.487703)
			(xy 457.638337 -30.359543) (xy 457.662066 -30.232602) (xy 457.693565 -30.107363) (xy 457.732714 -29.9843)
			(xy 457.779365 -29.863881) (xy 457.83334 -29.746562) (xy 457.894435 -29.632788) (xy 457.962418 -29.522991)
			(xy 458.037032 -29.417588) (xy 458.117993 -29.316978) (xy 458.204993 -29.221543) (xy 458.297704 -29.131644)
			(xy 458.395774 -29.047623) (xy 458.498829 -28.969799) (xy 458.60648 -28.898467) (xy 458.718319 -28.833897)
			(xy 458.83392 -28.776335) (xy 458.952845 -28.725998) (xy 459.074644 -28.683078) (xy 459.198854 -28.647737)
			(xy 459.325003 -28.62011) (xy 459.452615 -28.600301) (xy 459.581204 -28.588385) (xy 459.710282 -28.584409)
			(xy 459.83936 -28.588385) (xy 459.967949 -28.600301) (xy 460.095561 -28.62011) (xy 460.22171 -28.647737)
			(xy 460.34592 -28.683078) (xy 460.467719 -28.725998) (xy 460.586644 -28.776335) (xy 460.702245 -28.833897)
			(xy 460.814084 -28.898467) (xy 460.921735 -28.969799) (xy 461.02479 -29.047623) (xy 461.12286 -29.131644)
			(xy 461.215571 -29.221543) (xy 461.302571 -29.316978) (xy 461.383532 -29.417588) (xy 461.458146 -29.522991)
			(xy 461.526129 -29.632788) (xy 461.587224 -29.746562) (xy 461.641199 -29.863881) (xy 461.68785 -29.9843)
			(xy 461.726999 -30.107363) (xy 461.758498 -30.232602) (xy 461.782227 -30.359543) (xy 461.798097 -30.487703)
			(xy 461.806047 -30.616598) (xy 461.806544 -30.681168) (xy 461.806047 -30.745738) (xy 461.798097 -30.874633)
			(xy 461.782227 -31.002793) (xy 461.758498 -31.129734) (xy 461.726999 -31.254973) (xy 461.68785 -31.378036)
			(xy 461.641199 -31.498455) (xy 461.587224 -31.615774) (xy 461.526129 -31.729548) (xy 461.458146 -31.839345)
			(xy 461.383532 -31.944748) (xy 461.302571 -32.045358) (xy 461.215571 -32.140793) (xy 461.12286 -32.230692)
			(xy 461.02479 -32.314713) (xy 460.921735 -32.392537) (xy 460.814084 -32.463869) (xy 460.702245 -32.528439)
			(xy 460.586644 -32.586001) (xy 460.467719 -32.636338) (xy 460.34592 -32.679258) (xy 460.22171 -32.714599)
			(xy 460.095561 -32.742226) (xy 459.967949 -32.762035) (xy 459.83936 -32.773951) (xy 459.710282 -32.777928)
			(xy 459.581204 -32.773951) (xy 459.452615 -32.762035) (xy 459.325003 -32.742226) (xy 459.198854 -32.714599)
			(xy 459.074644 -32.679258) (xy 458.952845 -32.636338) (xy 458.83392 -32.586001) (xy 458.718319 -32.528439)
			(xy 458.60648 -32.463869) (xy 458.498829 -32.392537) (xy 458.395774 -32.314713) (xy 458.297704 -32.230692)
			(xy 458.204993 -32.140793) (xy 458.117993 -32.045358) (xy 458.037032 -31.944748) (xy 457.962418 -31.839345)
			(xy 457.894435 -31.729548) (xy 457.83334 -31.615774) (xy 457.779365 -31.498455) (xy 457.732714 -31.378036)
			(xy 457.693565 -31.254973) (xy 457.662066 -31.129734) (xy 457.638337 -31.002793) (xy 457.622467 -30.874633)
			(xy 457.614517 -30.745738) (xy 448.705224 -30.745738) (xy 448.705224 -30.92069) (xy 448.704734 -30.950674)
			(xy 448.696906 -31.01013) (xy 448.681385 -31.068055) (xy 448.658436 -31.123459) (xy 448.628452 -31.175393)
			(xy 448.591946 -31.222969) (xy 448.549541 -31.265374) (xy 448.501965 -31.30188) (xy 448.450031 -31.331864)
			(xy 448.394627 -31.354813) (xy 448.336702 -31.370334) (xy 448.277246 -31.378162) (xy 448.217278 -31.378162)
			(xy 448.157822 -31.370334) (xy 448.099897 -31.354813) (xy 448.044493 -31.331864) (xy 447.992559 -31.30188)
			(xy 447.944983 -31.265374) (xy 447.902578 -31.222969) (xy 447.866072 -31.175393) (xy 447.836088 -31.123459)
			(xy 447.813139 -31.068055) (xy 447.797618 -31.01013) (xy 447.78979 -30.950674) (xy 447.7893 -30.92069)
			(xy 447.1543 -30.92069) (xy 447.1543 -31.086044) (xy 447.153659 -31.097595) (xy 447.143695 -31.118442)
			(xy 447.125755 -31.133004) (xy 447.114676 -31.136336) (xy 447.102738 -31.13786) (xy 446.366138 -31.13786)
			(xy 446.355381 -31.137338) (xy 446.335691 -31.128674) (xy 446.328038 -31.121096) (xy 446.321821 -31.113711)
			(xy 446.314918 -31.095693) (xy 446.314576 -31.086044) (xy 433.937569 -31.086044) (xy 433.921382 -31.125124)
			(xy 433.891415 -31.17703) (xy 433.854928 -31.22458) (xy 433.812548 -31.26696) (xy 433.764998 -31.303447)
			(xy 433.713092 -31.333414) (xy 433.657719 -31.35635) (xy 433.599826 -31.371863) (xy 433.540404 -31.379686)
			(xy 433.480468 -31.379686) (xy 433.421046 -31.371863) (xy 433.363153 -31.35635) (xy 433.30778 -31.333414)
			(xy 433.255874 -31.303447) (xy 433.208324 -31.26696) (xy 433.165944 -31.22458) (xy 433.129457 -31.17703)
			(xy 433.09949 -31.125124) (xy 433.076554 -31.069751) (xy 433.061041 -31.011858) (xy 433.053218 -30.952436)
			(xy 433.052728 -30.922468) (xy 422.705247 -30.922468) (xy 422.704786 -30.950674) (xy 422.696958 -31.01013)
			(xy 422.681437 -31.068055) (xy 422.658488 -31.123459) (xy 422.628504 -31.175393) (xy 422.591998 -31.222969)
			(xy 422.549593 -31.265374) (xy 422.502017 -31.30188) (xy 422.450083 -31.331864) (xy 422.394679 -31.354813)
			(xy 422.336754 -31.370334) (xy 422.277298 -31.378162) (xy 422.21733 -31.378162) (xy 422.157874 -31.370334)
			(xy 422.099949 -31.354813) (xy 422.044545 -31.331864) (xy 421.992611 -31.30188) (xy 421.945035 -31.265374)
			(xy 421.90263 -31.222969) (xy 421.866124 -31.175393) (xy 421.83614 -31.123459) (xy 421.813191 -31.068055)
			(xy 421.79767 -31.01013) (xy 421.789842 -30.950674) (xy 421.789352 -30.92069) (xy 421.154352 -30.92069)
			(xy 421.154352 -31.086044) (xy 421.153673 -31.097589) (xy 421.14372 -31.118429) (xy 421.125799 -31.132996)
			(xy 421.114728 -31.136336) (xy 421.10279 -31.13786) (xy 420.36619 -31.13786) (xy 420.35543 -31.137364)
			(xy 420.33574 -31.128681) (xy 420.32809 -31.121096) (xy 420.321867 -31.113715) (xy 420.314969 -31.095694)
			(xy 420.314628 -31.086044) (xy 407.937621 -31.086044) (xy 407.921434 -31.125124) (xy 407.891467 -31.17703)
			(xy 407.85498 -31.22458) (xy 407.8126 -31.26696) (xy 407.76505 -31.303447) (xy 407.713144 -31.333414)
			(xy 407.657771 -31.35635) (xy 407.599878 -31.371863) (xy 407.540456 -31.379686) (xy 407.48052 -31.379686)
			(xy 407.421098 -31.371863) (xy 407.363205 -31.35635) (xy 407.307832 -31.333414) (xy 407.255926 -31.303447)
			(xy 407.208376 -31.26696) (xy 407.165996 -31.22458) (xy 407.129509 -31.17703) (xy 407.099542 -31.125124)
			(xy 407.076606 -31.069751) (xy 407.061093 -31.011858) (xy 407.05327 -30.952436) (xy 407.05278 -30.922468)
			(xy 396.705299 -30.922468) (xy 396.704838 -30.950674) (xy 396.69701 -31.01013) (xy 396.681489 -31.068055)
			(xy 396.65854 -31.123459) (xy 396.628556 -31.175393) (xy 396.59205 -31.222969) (xy 396.549645 -31.265374)
			(xy 396.502069 -31.30188) (xy 396.450135 -31.331864) (xy 396.394731 -31.354813) (xy 396.336806 -31.370334)
			(xy 396.27735 -31.378162) (xy 396.217382 -31.378162) (xy 396.157926 -31.370334) (xy 396.100001 -31.354813)
			(xy 396.044597 -31.331864) (xy 395.992663 -31.30188) (xy 395.945087 -31.265374) (xy 395.902682 -31.222969)
			(xy 395.866176 -31.175393) (xy 395.836192 -31.123459) (xy 395.813243 -31.068055) (xy 395.797722 -31.01013)
			(xy 395.789894 -30.950674) (xy 395.789404 -30.92069) (xy 395.154404 -30.92069) (xy 395.154404 -31.086044)
			(xy 395.15376 -31.097595) (xy 395.143797 -31.118441) (xy 395.125858 -31.133003) (xy 395.11478 -31.136336)
			(xy 395.102842 -31.13786) (xy 394.366242 -31.13786) (xy 394.355485 -31.137336) (xy 394.335795 -31.128673)
			(xy 394.328142 -31.121096) (xy 394.321925 -31.11371) (xy 394.315022 -31.095693) (xy 394.31468 -31.086044)
			(xy 381.937673 -31.086044) (xy 381.921486 -31.125124) (xy 381.891519 -31.17703) (xy 381.855032 -31.22458)
			(xy 381.812652 -31.26696) (xy 381.765102 -31.303447) (xy 381.713196 -31.333414) (xy 381.657823 -31.35635)
			(xy 381.59993 -31.371863) (xy 381.540508 -31.379686) (xy 381.480572 -31.379686) (xy 381.42115 -31.371863)
			(xy 381.363257 -31.35635) (xy 381.307884 -31.333414) (xy 381.255978 -31.303447) (xy 381.208428 -31.26696)
			(xy 381.166048 -31.22458) (xy 381.129561 -31.17703) (xy 381.099594 -31.125124) (xy 381.076658 -31.069751)
			(xy 381.061145 -31.011858) (xy 381.053322 -30.952436) (xy 381.052832 -30.922468) (xy 370.705351 -30.922468)
			(xy 370.70489 -30.950674) (xy 370.697062 -31.01013) (xy 370.681541 -31.068055) (xy 370.658592 -31.123459)
			(xy 370.628608 -31.175393) (xy 370.592102 -31.222969) (xy 370.549697 -31.265374) (xy 370.502121 -31.30188)
			(xy 370.450187 -31.331864) (xy 370.394783 -31.354813) (xy 370.336858 -31.370334) (xy 370.277402 -31.378162)
			(xy 370.217434 -31.378162) (xy 370.157978 -31.370334) (xy 370.100053 -31.354813) (xy 370.044649 -31.331864)
			(xy 369.992715 -31.30188) (xy 369.945139 -31.265374) (xy 369.902734 -31.222969) (xy 369.866228 -31.175393)
			(xy 369.836244 -31.123459) (xy 369.813295 -31.068055) (xy 369.797774 -31.01013) (xy 369.789946 -30.950674)
			(xy 369.789456 -30.92069) (xy 369.154456 -30.92069) (xy 369.154456 -31.086044) (xy 369.15384 -31.097565)
			(xy 369.14396 -31.118382) (xy 369.126121 -31.132968) (xy 369.115086 -31.136336) (xy 369.114832 -31.136336)
			(xy 369.102894 -31.13786) (xy 368.366294 -31.13786) (xy 368.359921 -31.137627) (xy 368.347584 -31.134419)
			(xy 368.34191 -31.13151) (xy 368.333912 -31.12675) (xy 368.321673 -31.112749) (xy 368.315129 -31.095342)
			(xy 368.314732 -31.086044) (xy 355.937725 -31.086044) (xy 355.921538 -31.125124) (xy 355.891571 -31.17703)
			(xy 355.855084 -31.22458) (xy 355.812704 -31.26696) (xy 355.765154 -31.303447) (xy 355.713248 -31.333414)
			(xy 355.657875 -31.35635) (xy 355.599982 -31.371863) (xy 355.54056 -31.379686) (xy 355.480624 -31.379686)
			(xy 355.421202 -31.371863) (xy 355.363309 -31.35635) (xy 355.307936 -31.333414) (xy 355.25603 -31.303447)
			(xy 355.20848 -31.26696) (xy 355.1661 -31.22458) (xy 355.129613 -31.17703) (xy 355.099646 -31.125124)
			(xy 355.07671 -31.069751) (xy 355.061197 -31.011858) (xy 355.053374 -30.952436) (xy 355.052884 -30.922468)
			(xy 332.604843 -30.922468) (xy 332.604382 -30.950658) (xy 332.596559 -31.01008) (xy 332.581046 -31.067973)
			(xy 332.55811 -31.123346) (xy 332.528143 -31.175252) (xy 332.491656 -31.222802) (xy 332.449276 -31.265182)
			(xy 332.401726 -31.301669) (xy 332.34982 -31.331636) (xy 332.294447 -31.354572) (xy 332.236554 -31.370085)
			(xy 332.177132 -31.377908) (xy 332.117196 -31.377908) (xy 332.057774 -31.370085) (xy 331.999881 -31.354572)
			(xy 331.944508 -31.331636) (xy 331.892602 -31.301669) (xy 331.845052 -31.265182) (xy 331.802672 -31.222802)
			(xy 331.766185 -31.175252) (xy 331.736218 -31.123346) (xy 331.713282 -31.067973) (xy 331.697769 -31.01008)
			(xy 331.689946 -30.950658) (xy 331.689456 -30.92069) (xy 331.054456 -30.92069) (xy 331.054456 -31.086044)
			(xy 331.053955 -31.09625) (xy 331.046135 -31.115105) (xy 331.031701 -31.129538) (xy 331.012846 -31.137356)
			(xy 331.00264 -31.13786) (xy 330.26604 -31.13786) (xy 330.25584 -31.137286) (xy 330.236988 -31.129495)
			(xy 330.222552 -31.115083) (xy 330.21473 -31.096243) (xy 330.214224 -31.086044) (xy 317.837746 -31.086044)
			(xy 317.821512 -31.125237) (xy 317.791528 -31.177171) (xy 317.755022 -31.224747) (xy 317.712617 -31.267152)
			(xy 317.665041 -31.303658) (xy 317.613107 -31.333642) (xy 317.557703 -31.356591) (xy 317.499778 -31.372112)
			(xy 317.440322 -31.37994) (xy 317.380354 -31.37994) (xy 317.320898 -31.372112) (xy 317.262973 -31.356591)
			(xy 317.207569 -31.333642) (xy 317.155635 -31.303658) (xy 317.108059 -31.267152) (xy 317.065654 -31.224747)
			(xy 317.029148 -31.177171) (xy 316.999164 -31.125237) (xy 316.976215 -31.069833) (xy 316.960694 -31.011908)
			(xy 316.952866 -30.952452) (xy 316.952376 -30.922468) (xy 306.604895 -30.922468) (xy 306.604434 -30.950658)
			(xy 306.596611 -31.01008) (xy 306.581098 -31.067973) (xy 306.558162 -31.123346) (xy 306.528195 -31.175252)
			(xy 306.491708 -31.222802) (xy 306.449328 -31.265182) (xy 306.401778 -31.301669) (xy 306.349872 -31.331636)
			(xy 306.294499 -31.354572) (xy 306.236606 -31.370085) (xy 306.177184 -31.377908) (xy 306.117248 -31.377908)
			(xy 306.057826 -31.370085) (xy 305.999933 -31.354572) (xy 305.94456 -31.331636) (xy 305.892654 -31.301669)
			(xy 305.845104 -31.265182) (xy 305.802724 -31.222802) (xy 305.766237 -31.175252) (xy 305.73627 -31.123346)
			(xy 305.713334 -31.067973) (xy 305.697821 -31.01008) (xy 305.689998 -30.950658) (xy 305.689508 -30.92069)
			(xy 305.054508 -30.92069) (xy 305.054508 -31.086044) (xy 305.054054 -31.096256) (xy 305.046225 -31.11512)
			(xy 305.031776 -31.129554) (xy 305.012904 -31.137364) (xy 305.002692 -31.13786) (xy 304.266092 -31.13786)
			(xy 304.255889 -31.137326) (xy 304.237036 -31.129519) (xy 304.222602 -31.115094) (xy 304.214781 -31.096247)
			(xy 304.214276 -31.086044) (xy 291.837798 -31.086044) (xy 291.821564 -31.125237) (xy 291.79158 -31.177171)
			(xy 291.755074 -31.224747) (xy 291.712669 -31.267152) (xy 291.665093 -31.303658) (xy 291.613159 -31.333642)
			(xy 291.557755 -31.356591) (xy 291.49983 -31.372112) (xy 291.440374 -31.37994) (xy 291.380406 -31.37994)
			(xy 291.32095 -31.372112) (xy 291.263025 -31.356591) (xy 291.207621 -31.333642) (xy 291.155687 -31.303658)
			(xy 291.108111 -31.267152) (xy 291.065706 -31.224747) (xy 291.0292 -31.177171) (xy 290.999216 -31.125237)
			(xy 290.976267 -31.069833) (xy 290.960746 -31.011908) (xy 290.952918 -30.952452) (xy 290.952428 -30.922468)
			(xy 280.604947 -30.922468) (xy 280.604486 -30.950658) (xy 280.596663 -31.01008) (xy 280.58115 -31.067973)
			(xy 280.558214 -31.123346) (xy 280.528247 -31.175252) (xy 280.49176 -31.222802) (xy 280.44938 -31.265182)
			(xy 280.40183 -31.301669) (xy 280.349924 -31.331636) (xy 280.294551 -31.354572) (xy 280.236658 -31.370085)
			(xy 280.177236 -31.377908) (xy 280.1173 -31.377908) (xy 280.057878 -31.370085) (xy 279.999985 -31.354572)
			(xy 279.944612 -31.331636) (xy 279.892706 -31.301669) (xy 279.845156 -31.265182) (xy 279.802776 -31.222802)
			(xy 279.766289 -31.175252) (xy 279.736322 -31.123346) (xy 279.713386 -31.067973) (xy 279.697873 -31.01008)
			(xy 279.69005 -30.950658) (xy 279.68956 -30.92069) (xy 279.05456 -30.92069) (xy 279.05456 -31.086044)
			(xy 279.054055 -31.096249) (xy 279.046236 -31.115103) (xy 279.031803 -31.129536) (xy 279.012949 -31.137355)
			(xy 279.002744 -31.13786) (xy 278.266144 -31.13786) (xy 278.255944 -31.137283) (xy 278.237092 -31.129493)
			(xy 278.222656 -31.115082) (xy 278.214834 -31.096243) (xy 278.214328 -31.086044) (xy 265.83785 -31.086044)
			(xy 265.821616 -31.125237) (xy 265.791632 -31.177171) (xy 265.755126 -31.224747) (xy 265.712721 -31.267152)
			(xy 265.665145 -31.303658) (xy 265.613211 -31.333642) (xy 265.557807 -31.356591) (xy 265.499882 -31.372112)
			(xy 265.440426 -31.37994) (xy 265.380458 -31.37994) (xy 265.321002 -31.372112) (xy 265.263077 -31.356591)
			(xy 265.207673 -31.333642) (xy 265.155739 -31.303658) (xy 265.108163 -31.267152) (xy 265.065758 -31.224747)
			(xy 265.029252 -31.177171) (xy 264.999268 -31.125237) (xy 264.976319 -31.069833) (xy 264.960798 -31.011908)
			(xy 264.95297 -30.952452) (xy 264.95248 -30.922468) (xy 254.604999 -30.922468) (xy 254.604538 -30.950658)
			(xy 254.596715 -31.01008) (xy 254.581202 -31.067973) (xy 254.558266 -31.123346) (xy 254.528299 -31.175252)
			(xy 254.491812 -31.222802) (xy 254.449432 -31.265182) (xy 254.401882 -31.301669) (xy 254.349976 -31.331636)
			(xy 254.294603 -31.354572) (xy 254.23671 -31.370085) (xy 254.177288 -31.377908) (xy 254.117352 -31.377908)
			(xy 254.05793 -31.370085) (xy 254.000037 -31.354572) (xy 253.944664 -31.331636) (xy 253.892758 -31.301669)
			(xy 253.845208 -31.265182) (xy 253.802828 -31.222802) (xy 253.766341 -31.175252) (xy 253.736374 -31.123346)
			(xy 253.713438 -31.067973) (xy 253.697925 -31.01008) (xy 253.690102 -30.950658) (xy 253.689612 -30.92069)
			(xy 253.054612 -30.92069) (xy 253.054612 -31.086044) (xy 253.054154 -31.096255) (xy 253.046326 -31.115118)
			(xy 253.031878 -31.129553) (xy 253.013008 -31.137364) (xy 253.002796 -31.13786) (xy 252.266196 -31.13786)
			(xy 252.255993 -31.137322) (xy 252.23714 -31.129517) (xy 252.222706 -31.115093) (xy 252.214885 -31.096246)
			(xy 252.21438 -31.086044) (xy 239.837902 -31.086044) (xy 239.821668 -31.125237) (xy 239.791684 -31.177171)
			(xy 239.755178 -31.224747) (xy 239.712773 -31.267152) (xy 239.665197 -31.303658) (xy 239.613263 -31.333642)
			(xy 239.557859 -31.356591) (xy 239.499934 -31.372112) (xy 239.440478 -31.37994) (xy 239.38051 -31.37994)
			(xy 239.321054 -31.372112) (xy 239.263129 -31.356591) (xy 239.207725 -31.333642) (xy 239.155791 -31.303658)
			(xy 239.108215 -31.267152) (xy 239.06581 -31.224747) (xy 239.029304 -31.177171) (xy 238.99932 -31.125237)
			(xy 238.976371 -31.069833) (xy 238.96085 -31.011908) (xy 238.953022 -30.952452) (xy 238.952532 -30.922468)
			(xy 216.504999 -30.922468) (xy 216.504538 -30.950658) (xy 216.496715 -31.01008) (xy 216.481202 -31.067973)
			(xy 216.458266 -31.123346) (xy 216.428299 -31.175252) (xy 216.391812 -31.222802) (xy 216.349432 -31.265182)
			(xy 216.301882 -31.301669) (xy 216.249976 -31.331636) (xy 216.194603 -31.354572) (xy 216.13671 -31.370085)
			(xy 216.077288 -31.377908) (xy 216.017352 -31.377908) (xy 215.95793 -31.370085) (xy 215.900037 -31.354572)
			(xy 215.844664 -31.331636) (xy 215.792758 -31.301669) (xy 215.745208 -31.265182) (xy 215.702828 -31.222802)
			(xy 215.666341 -31.175252) (xy 215.636374 -31.123346) (xy 215.613438 -31.067973) (xy 215.597925 -31.01008)
			(xy 215.590102 -30.950658) (xy 215.589612 -30.92069) (xy 214.954612 -30.92069) (xy 214.954612 -31.086044)
			(xy 214.954154 -31.096255) (xy 214.946326 -31.115118) (xy 214.931878 -31.129553) (xy 214.913008 -31.137364)
			(xy 214.902796 -31.13786) (xy 214.166196 -31.13786) (xy 214.155993 -31.137322) (xy 214.13714 -31.129517)
			(xy 214.122706 -31.115093) (xy 214.114885 -31.096246) (xy 214.11438 -31.086044) (xy 201.737902 -31.086044)
			(xy 201.721668 -31.125237) (xy 201.691684 -31.177171) (xy 201.655178 -31.224747) (xy 201.612773 -31.267152)
			(xy 201.565197 -31.303658) (xy 201.513263 -31.333642) (xy 201.457859 -31.356591) (xy 201.399934 -31.372112)
			(xy 201.340478 -31.37994) (xy 201.28051 -31.37994) (xy 201.221054 -31.372112) (xy 201.163129 -31.356591)
			(xy 201.107725 -31.333642) (xy 201.055791 -31.303658) (xy 201.008215 -31.267152) (xy 200.96581 -31.224747)
			(xy 200.929304 -31.177171) (xy 200.89932 -31.125237) (xy 200.876371 -31.069833) (xy 200.86085 -31.011908)
			(xy 200.853022 -30.952452) (xy 200.852532 -30.922468) (xy 190.505051 -30.922468) (xy 190.50459 -30.950658)
			(xy 190.496767 -31.01008) (xy 190.481254 -31.067973) (xy 190.458318 -31.123346) (xy 190.428351 -31.175252)
			(xy 190.391864 -31.222802) (xy 190.349484 -31.265182) (xy 190.301934 -31.301669) (xy 190.250028 -31.331636)
			(xy 190.194655 -31.354572) (xy 190.136762 -31.370085) (xy 190.07734 -31.377908) (xy 190.017404 -31.377908)
			(xy 189.957982 -31.370085) (xy 189.900089 -31.354572) (xy 189.844716 -31.331636) (xy 189.79281 -31.301669)
			(xy 189.74526 -31.265182) (xy 189.70288 -31.222802) (xy 189.666393 -31.175252) (xy 189.636426 -31.123346)
			(xy 189.61349 -31.067973) (xy 189.597977 -31.01008) (xy 189.590154 -30.950658) (xy 189.589664 -30.92069)
			(xy 188.954664 -30.92069) (xy 188.954664 -31.086044) (xy 188.954155 -31.096249) (xy 188.946337 -31.115102)
			(xy 188.931905 -31.129535) (xy 188.913053 -31.137355) (xy 188.902848 -31.13786) (xy 188.166248 -31.13786)
			(xy 188.156035 -31.13735) (xy 188.137157 -31.129551) (xy 188.122701 -31.11512) (xy 188.114868 -31.096256)
			(xy 188.114432 -31.086044) (xy 175.737954 -31.086044) (xy 175.72172 -31.125237) (xy 175.691736 -31.177171)
			(xy 175.65523 -31.224747) (xy 175.612825 -31.267152) (xy 175.565249 -31.303658) (xy 175.513315 -31.333642)
			(xy 175.457911 -31.356591) (xy 175.399986 -31.372112) (xy 175.34053 -31.37994) (xy 175.280562 -31.37994)
			(xy 175.221106 -31.372112) (xy 175.163181 -31.356591) (xy 175.107777 -31.333642) (xy 175.055843 -31.303658)
			(xy 175.008267 -31.267152) (xy 174.965862 -31.224747) (xy 174.929356 -31.177171) (xy 174.899372 -31.125237)
			(xy 174.876423 -31.069833) (xy 174.860902 -31.011908) (xy 174.853074 -30.952452) (xy 174.852584 -30.922468)
			(xy 164.505103 -30.922468) (xy 164.504642 -30.950658) (xy 164.496819 -31.01008) (xy 164.481306 -31.067973)
			(xy 164.45837 -31.123346) (xy 164.428403 -31.175252) (xy 164.391916 -31.222802) (xy 164.349536 -31.265182)
			(xy 164.301986 -31.301669) (xy 164.25008 -31.331636) (xy 164.194707 -31.354572) (xy 164.136814 -31.370085)
			(xy 164.077392 -31.377908) (xy 164.017456 -31.377908) (xy 163.958034 -31.370085) (xy 163.900141 -31.354572)
			(xy 163.844768 -31.331636) (xy 163.792862 -31.301669) (xy 163.745312 -31.265182) (xy 163.702932 -31.222802)
			(xy 163.666445 -31.175252) (xy 163.636478 -31.123346) (xy 163.613542 -31.067973) (xy 163.598029 -31.01008)
			(xy 163.590206 -30.950658) (xy 163.589716 -30.92069) (xy 162.954716 -30.92069) (xy 162.954716 -31.086044)
			(xy 162.954254 -31.096255) (xy 162.946427 -31.115117) (xy 162.93198 -31.129552) (xy 162.913111 -31.137363)
			(xy 162.9029 -31.13786) (xy 162.1663 -31.13786) (xy 162.156098 -31.137319) (xy 162.137244 -31.129515)
			(xy 162.12281 -31.115092) (xy 162.114989 -31.096246) (xy 162.114484 -31.086044) (xy 149.738006 -31.086044)
			(xy 149.721772 -31.125237) (xy 149.691788 -31.177171) (xy 149.655282 -31.224747) (xy 149.612877 -31.267152)
			(xy 149.565301 -31.303658) (xy 149.513367 -31.333642) (xy 149.457963 -31.356591) (xy 149.400038 -31.372112)
			(xy 149.340582 -31.37994) (xy 149.280614 -31.37994) (xy 149.221158 -31.372112) (xy 149.163233 -31.356591)
			(xy 149.107829 -31.333642) (xy 149.055895 -31.303658) (xy 149.008319 -31.267152) (xy 148.965914 -31.224747)
			(xy 148.929408 -31.177171) (xy 148.899424 -31.125237) (xy 148.876475 -31.069833) (xy 148.860954 -31.011908)
			(xy 148.853126 -30.952452) (xy 148.852636 -30.922468) (xy 138.505155 -30.922468) (xy 138.504694 -30.950658)
			(xy 138.496871 -31.01008) (xy 138.481358 -31.067973) (xy 138.458422 -31.123346) (xy 138.428455 -31.175252)
			(xy 138.391968 -31.222802) (xy 138.349588 -31.265182) (xy 138.302038 -31.301669) (xy 138.250132 -31.331636)
			(xy 138.194759 -31.354572) (xy 138.136866 -31.370085) (xy 138.077444 -31.377908) (xy 138.017508 -31.377908)
			(xy 137.958086 -31.370085) (xy 137.900193 -31.354572) (xy 137.84482 -31.331636) (xy 137.792914 -31.301669)
			(xy 137.745364 -31.265182) (xy 137.702984 -31.222802) (xy 137.666497 -31.175252) (xy 137.63653 -31.123346)
			(xy 137.613594 -31.067973) (xy 137.598081 -31.01008) (xy 137.590258 -30.950658) (xy 137.589768 -30.92069)
			(xy 136.954768 -30.92069) (xy 136.954768 -31.086044) (xy 136.954423 -31.096275) (xy 136.946576 -31.115172)
			(xy 136.932095 -31.129628) (xy 136.913183 -31.137441) (xy 136.902952 -31.13786) (xy 136.166352 -31.13786)
			(xy 136.156147 -31.137359) (xy 136.137292 -31.129538) (xy 136.12286 -31.115104) (xy 136.115041 -31.096249)
			(xy 136.114536 -31.086044) (xy 123.738058 -31.086044) (xy 123.721824 -31.125237) (xy 123.69184 -31.177171)
			(xy 123.655334 -31.224747) (xy 123.612929 -31.267152) (xy 123.565353 -31.303658) (xy 123.513419 -31.333642)
			(xy 123.458015 -31.356591) (xy 123.40009 -31.372112) (xy 123.340634 -31.37994) (xy 123.280666 -31.37994)
			(xy 123.22121 -31.372112) (xy 123.163285 -31.356591) (xy 123.107881 -31.333642) (xy 123.055947 -31.303658)
			(xy 123.008371 -31.267152) (xy 122.965966 -31.224747) (xy 122.92946 -31.177171) (xy 122.899476 -31.125237)
			(xy 122.876527 -31.069833) (xy 122.861006 -31.011908) (xy 122.853178 -30.952452) (xy 122.852688 -30.922468)
			(xy 100.405155 -30.922468) (xy 100.404694 -30.950674) (xy 100.396866 -31.01013) (xy 100.381345 -31.068055)
			(xy 100.358396 -31.123459) (xy 100.328412 -31.175393) (xy 100.291906 -31.222969) (xy 100.249501 -31.265374)
			(xy 100.201925 -31.30188) (xy 100.149991 -31.331864) (xy 100.094587 -31.354813) (xy 100.036662 -31.370334)
			(xy 99.977206 -31.378162) (xy 99.917238 -31.378162) (xy 99.857782 -31.370334) (xy 99.799857 -31.354813)
			(xy 99.744453 -31.331864) (xy 99.692519 -31.30188) (xy 99.644943 -31.265374) (xy 99.602538 -31.222969)
			(xy 99.566032 -31.175393) (xy 99.536048 -31.123459) (xy 99.513099 -31.068055) (xy 99.497578 -31.01013)
			(xy 99.48975 -30.950674) (xy 99.48926 -30.92069) (xy 98.85426 -30.92069) (xy 98.85426 -31.086044)
			(xy 98.853648 -31.0976) (xy 98.843675 -31.118452) (xy 98.825722 -31.13301) (xy 98.814636 -31.136336)
			(xy 98.802698 -31.13786) (xy 98.066098 -31.13786) (xy 98.055338 -31.13736) (xy 98.035649 -31.12868)
			(xy 98.027998 -31.121096) (xy 98.021776 -31.113715) (xy 98.014877 -31.095694) (xy 98.014536 -31.086044)
			(xy 85.637529 -31.086044) (xy 85.621342 -31.125124) (xy 85.591375 -31.17703) (xy 85.554888 -31.22458)
			(xy 85.512508 -31.26696) (xy 85.464958 -31.303447) (xy 85.413052 -31.333414) (xy 85.357679 -31.35635)
			(xy 85.299786 -31.371863) (xy 85.240364 -31.379686) (xy 85.180428 -31.379686) (xy 85.121006 -31.371863)
			(xy 85.063113 -31.35635) (xy 85.00774 -31.333414) (xy 84.955834 -31.303447) (xy 84.908284 -31.26696)
			(xy 84.865904 -31.22458) (xy 84.829417 -31.17703) (xy 84.79945 -31.125124) (xy 84.776514 -31.069751)
			(xy 84.761001 -31.011858) (xy 84.753178 -30.952436) (xy 84.752688 -30.922468) (xy 74.405207 -30.922468)
			(xy 74.404746 -30.950674) (xy 74.396918 -31.01013) (xy 74.381397 -31.068055) (xy 74.358448 -31.123459)
			(xy 74.328464 -31.175393) (xy 74.291958 -31.222969) (xy 74.249553 -31.265374) (xy 74.201977 -31.30188)
			(xy 74.150043 -31.331864) (xy 74.094639 -31.354813) (xy 74.036714 -31.370334) (xy 73.977258 -31.378162)
			(xy 73.91729 -31.378162) (xy 73.857834 -31.370334) (xy 73.799909 -31.354813) (xy 73.744505 -31.331864)
			(xy 73.692571 -31.30188) (xy 73.644995 -31.265374) (xy 73.60259 -31.222969) (xy 73.566084 -31.175393)
			(xy 73.5361 -31.123459) (xy 73.513151 -31.068055) (xy 73.49763 -31.01013) (xy 73.489802 -30.950674)
			(xy 73.489312 -30.92069) (xy 72.854312 -30.92069) (xy 72.854312 -31.086044) (xy 72.853662 -31.097594)
			(xy 72.843701 -31.118439) (xy 72.825765 -31.133002) (xy 72.814688 -31.136336) (xy 72.80275 -31.13786)
			(xy 72.06615 -31.13786) (xy 72.055394 -31.137331) (xy 72.035704 -31.128672) (xy 72.02805 -31.121096)
			(xy 72.021834 -31.11371) (xy 72.01493 -31.095693) (xy 72.014588 -31.086044) (xy 59.637581 -31.086044)
			(xy 59.621394 -31.125124) (xy 59.591427 -31.17703) (xy 59.55494 -31.22458) (xy 59.51256 -31.26696)
			(xy 59.46501 -31.303447) (xy 59.413104 -31.333414) (xy 59.357731 -31.35635) (xy 59.299838 -31.371863)
			(xy 59.240416 -31.379686) (xy 59.18048 -31.379686) (xy 59.121058 -31.371863) (xy 59.063165 -31.35635)
			(xy 59.007792 -31.333414) (xy 58.955886 -31.303447) (xy 58.908336 -31.26696) (xy 58.865956 -31.22458)
			(xy 58.829469 -31.17703) (xy 58.799502 -31.125124) (xy 58.776566 -31.069751) (xy 58.761053 -31.011858)
			(xy 58.75323 -30.952436) (xy 58.75274 -30.922468) (xy 48.405259 -30.922468) (xy 48.404798 -30.950674)
			(xy 48.39697 -31.01013) (xy 48.381449 -31.068055) (xy 48.3585 -31.123459) (xy 48.328516 -31.175393)
			(xy 48.29201 -31.222969) (xy 48.249605 -31.265374) (xy 48.202029 -31.30188) (xy 48.150095 -31.331864)
			(xy 48.094691 -31.354813) (xy 48.036766 -31.370334) (xy 47.97731 -31.378162) (xy 47.917342 -31.378162)
			(xy 47.857886 -31.370334) (xy 47.799961 -31.354813) (xy 47.744557 -31.331864) (xy 47.692623 -31.30188)
			(xy 47.645047 -31.265374) (xy 47.602642 -31.222969) (xy 47.566136 -31.175393) (xy 47.536152 -31.123459)
			(xy 47.513203 -31.068055) (xy 47.497682 -31.01013) (xy 47.489854 -30.950674) (xy 47.489364 -30.92069)
			(xy 46.854364 -30.92069) (xy 46.854364 -31.086044) (xy 46.853749 -31.097599) (xy 46.843777 -31.118451)
			(xy 46.825825 -31.133009) (xy 46.81474 -31.136336) (xy 46.802802 -31.13786) (xy 46.066202 -31.13786)
			(xy 46.055443 -31.137357) (xy 46.035753 -31.12868) (xy 46.028102 -31.121096) (xy 46.02188 -31.113714)
			(xy 46.014981 -31.095694) (xy 46.01464 -31.086044) (xy 33.637633 -31.086044) (xy 33.621446 -31.125124)
			(xy 33.591479 -31.17703) (xy 33.554992 -31.22458) (xy 33.512612 -31.26696) (xy 33.465062 -31.303447)
			(xy 33.413156 -31.333414) (xy 33.357783 -31.35635) (xy 33.29989 -31.371863) (xy 33.240468 -31.379686)
			(xy 33.180532 -31.379686) (xy 33.12111 -31.371863) (xy 33.063217 -31.35635) (xy 33.007844 -31.333414)
			(xy 32.955938 -31.303447) (xy 32.908388 -31.26696) (xy 32.866008 -31.22458) (xy 32.829521 -31.17703)
			(xy 32.799554 -31.125124) (xy 32.776618 -31.069751) (xy 32.761105 -31.011858) (xy 32.753282 -30.952436)
			(xy 32.752792 -30.922468) (xy 22.405311 -30.922468) (xy 22.40485 -30.950674) (xy 22.397022 -31.01013)
			(xy 22.381501 -31.068055) (xy 22.358552 -31.123459) (xy 22.328568 -31.175393) (xy 22.292062 -31.222969)
			(xy 22.249657 -31.265374) (xy 22.202081 -31.30188) (xy 22.150147 -31.331864) (xy 22.094743 -31.354813)
			(xy 22.036818 -31.370334) (xy 21.977362 -31.378162) (xy 21.917394 -31.378162) (xy 21.857938 -31.370334)
			(xy 21.800013 -31.354813) (xy 21.744609 -31.331864) (xy 21.692675 -31.30188) (xy 21.645099 -31.265374)
			(xy 21.602694 -31.222969) (xy 21.566188 -31.175393) (xy 21.536204 -31.123459) (xy 21.513255 -31.068055)
			(xy 21.497734 -31.01013) (xy 21.489906 -30.950674) (xy 21.489416 -30.92069) (xy 20.854416 -30.92069)
			(xy 20.854416 -31.086044) (xy 20.853828 -31.097569) (xy 20.84394 -31.118391) (xy 20.826087 -31.132974)
			(xy 20.815046 -31.136336) (xy 20.814792 -31.136336) (xy 20.802854 -31.13786) (xy 20.066254 -31.13786)
			(xy 20.05988 -31.137641) (xy 20.047543 -31.134424) (xy 20.04187 -31.13151) (xy 20.033864 -31.126763)
			(xy 20.021629 -31.112755) (xy 20.015088 -31.095343) (xy 20.014692 -31.086044) (xy 7.637685 -31.086044)
			(xy 7.621498 -31.125124) (xy 7.591531 -31.17703) (xy 7.555044 -31.22458) (xy 7.512664 -31.26696)
			(xy 7.465114 -31.303447) (xy 7.413208 -31.333414) (xy 7.357835 -31.35635) (xy 7.299942 -31.371863)
			(xy 7.24052 -31.379686) (xy 7.180584 -31.379686) (xy 7.121162 -31.371863) (xy 7.063269 -31.35635)
			(xy 7.007896 -31.333414) (xy 6.95599 -31.303447) (xy 6.90844 -31.26696) (xy 6.86606 -31.22458) (xy 6.829573 -31.17703)
			(xy 6.799606 -31.125124) (xy 6.77667 -31.069751) (xy 6.761157 -31.011858) (xy 6.753334 -30.952436)
			(xy 6.752844 -30.922468) (xy 0.509016 -30.922468) (xy 0.509016 -32.722312) (xy 8.607044 -32.722312)
			(xy 8.607044 -31.858712) (xy 8.607534 -31.828744) (xy 8.615357 -31.769322) (xy 8.63087 -31.711429)
			(xy 8.653806 -31.656056) (xy 8.683773 -31.60415) (xy 8.72026 -31.5566) (xy 8.76264 -31.51422) (xy 8.81019 -31.477733)
			(xy 8.862096 -31.447766) (xy 8.917469 -31.42483) (xy 8.975362 -31.409317) (xy 9.034784 -31.401494)
			(xy 9.09472 -31.401494) (xy 9.154142 -31.409317) (xy 9.212035 -31.42483) (xy 9.267408 -31.447766)
			(xy 9.319314 -31.477733) (xy 9.366864 -31.51422) (xy 9.409244 -31.5566) (xy 9.445731 -31.60415) (xy 9.475698 -31.656056)
			(xy 9.498634 -31.711429) (xy 9.514147 -31.769322) (xy 9.52197 -31.828744) (xy 9.52246 -31.858712)
			(xy 9.52246 -32.722312) (xy 9.52197 -32.75228) (xy 9.51488 -32.806132) (xy 10.029444 -32.806132)
			(xy 10.029444 -31.77413) (xy 10.029951 -31.764005) (xy 10.03767 -31.745283) (xy 10.05195 -31.730926)
			(xy 10.070629 -31.723106) (xy 10.080752 -31.722568) (xy 11.312652 -31.722568) (xy 11.322767 -31.723055)
			(xy 11.341464 -31.730781) (xy 11.355779 -31.745076) (xy 11.363531 -31.763761) (xy 11.36396 -31.773876)
			(xy 11.36396 -32.805878) (xy 14.565884 -32.805878) (xy 14.565884 -31.77413) (xy 14.566352 -31.764)
			(xy 14.574078 -31.745271) (xy 14.588371 -31.730912) (xy 14.607064 -31.723099) (xy 14.617192 -31.722568)
			(xy 15.849092 -31.722568) (xy 15.859242 -31.723028) (xy 15.877988 -31.730814) (xy 15.89231 -31.745199)
			(xy 15.900016 -31.763979) (xy 15.9004 -31.77413) (xy 15.9004 -32.805878) (xy 15.899857 -32.815998)
			(xy 15.892144 -32.834712) (xy 15.877875 -32.849067) (xy 15.859209 -32.856894) (xy 15.849092 -32.85744)
			(xy 14.617192 -32.85744) (xy 14.607042 -32.856986) (xy 14.588298 -32.849195) (xy 14.573976 -32.834809)
			(xy 14.566269 -32.816029) (xy 14.565884 -32.805878) (xy 11.36396 -32.805878) (xy 11.363456 -32.816003)
			(xy 11.355735 -32.834724) (xy 11.341454 -32.849081) (xy 11.322775 -32.856901) (xy 11.312652 -32.85744)
			(xy 10.080752 -32.85744) (xy 10.070645 -32.856955) (xy 10.051974 -32.849209) (xy 10.037682 -32.834913)
			(xy 10.029942 -32.816239) (xy 10.029444 -32.806132) (xy 9.51488 -32.806132) (xy 9.514147 -32.811702)
			(xy 9.498634 -32.869595) (xy 9.494516 -32.879538) (xy 17.372584 -32.879538) (xy 17.372584 -32.636714)
			(xy 17.56664 -32.34055) (xy 17.586452 -32.310324) (xy 17.59138 -32.301851) (xy 17.595127 -32.282632)
			(xy 17.591404 -32.263409) (xy 17.586452 -32.254952) (xy 17.419574 -31.998412) (xy 17.380966 -31.93923)
			(xy 17.380458 -31.938468) (xy 17.37995 -31.937706) (xy 17.379696 -31.937198) (xy 17.379188 -31.936436)
			(xy 17.372584 -31.926022) (xy 17.372584 -31.683198) (xy 17.372963 -31.673021) (xy 17.380758 -31.654217)
			(xy 17.395157 -31.639831) (xy 17.413968 -31.632054) (xy 17.424146 -31.631636) (xy 18.160746 -31.631636)
			(xy 18.170906 -31.632096) (xy 18.189676 -31.639885) (xy 18.20404 -31.654261) (xy 18.211813 -31.673037)
			(xy 18.212308 -31.683198) (xy 18.212308 -31.926022) (xy 17.996408 -32.256476) (xy 17.992384 -32.264696)
			(xy 17.98984 -32.282807) (xy 17.993787 -32.300665) (xy 17.99844 -32.308546) (xy 18.030698 -32.35833)
			(xy 18.212308 -32.635444) (xy 18.212308 -32.714184) (xy 18.847308 -32.714184) (xy 18.847308 -31.850584)
			(xy 18.847798 -31.8206) (xy 18.855626 -31.761144) (xy 18.871147 -31.703219) (xy 18.894096 -31.647815)
			(xy 18.92408 -31.595881) (xy 18.960586 -31.548305) (xy 19.002991 -31.5059) (xy 19.050567 -31.469394)
			(xy 19.102501 -31.43941) (xy 19.157905 -31.416461) (xy 19.21583 -31.40094) (xy 19.275286 -31.393112)
			(xy 19.335254 -31.393112) (xy 19.39471 -31.40094) (xy 19.452635 -31.416461) (xy 19.508039 -31.43941)
			(xy 19.559973 -31.469394) (xy 19.607549 -31.5059) (xy 19.649954 -31.548305) (xy 19.68646 -31.595881)
			(xy 19.716444 -31.647815) (xy 19.739393 -31.703219) (xy 19.754914 -31.761144) (xy 19.762742 -31.8206)
			(xy 19.763232 -31.850584) (xy 19.763232 -32.714184) (xy 19.763099 -32.722312) (xy 34.606992 -32.722312)
			(xy 34.606992 -31.858712) (xy 34.607482 -31.828744) (xy 34.615305 -31.769322) (xy 34.630818 -31.711429)
			(xy 34.653754 -31.656056) (xy 34.683721 -31.60415) (xy 34.720208 -31.5566) (xy 34.762588 -31.51422)
			(xy 34.810138 -31.477733) (xy 34.862044 -31.447766) (xy 34.917417 -31.42483) (xy 34.97531 -31.409317)
			(xy 35.034732 -31.401494) (xy 35.094668 -31.401494) (xy 35.15409 -31.409317) (xy 35.211983 -31.42483)
			(xy 35.267356 -31.447766) (xy 35.319262 -31.477733) (xy 35.366812 -31.51422) (xy 35.409192 -31.5566)
			(xy 35.445679 -31.60415) (xy 35.475646 -31.656056) (xy 35.498582 -31.711429) (xy 35.514095 -31.769322)
			(xy 35.521918 -31.828744) (xy 35.522408 -31.858712) (xy 35.522408 -32.722312) (xy 35.521918 -32.75228)
			(xy 35.514828 -32.806132) (xy 36.029392 -32.806132) (xy 36.029392 -31.77413) (xy 36.02995 -31.764011)
			(xy 36.037659 -31.7453) (xy 36.051923 -31.730944) (xy 36.070584 -31.723115) (xy 36.0807 -31.722568)
			(xy 37.3126 -31.722568) (xy 37.322705 -31.723084) (xy 37.341377 -31.730816) (xy 37.35567 -31.745103)
			(xy 37.363411 -31.763771) (xy 37.363908 -31.773876) (xy 37.363908 -32.805878) (xy 40.565832 -32.805878)
			(xy 40.565832 -31.77413) (xy 40.566351 -31.764006) (xy 40.574067 -31.745287) (xy 40.588344 -31.73093)
			(xy 40.607019 -31.723108) (xy 40.61714 -31.722568) (xy 41.84904 -31.722568) (xy 41.859193 -31.722988)
			(xy 41.87794 -31.730791) (xy 41.892261 -31.745187) (xy 41.899965 -31.763975) (xy 41.900348 -31.77413)
			(xy 41.900348 -32.805878) (xy 41.899855 -32.816005) (xy 41.892132 -32.834728) (xy 41.877848 -32.849085)
			(xy 41.859164 -32.856903) (xy 41.84904 -32.85744) (xy 40.61714 -32.85744) (xy 40.606993 -32.856946)
			(xy 40.58825 -32.849171) (xy 40.573926 -32.834797) (xy 40.566218 -32.816026) (xy 40.565832 -32.805878)
			(xy 37.363908 -32.805878) (xy 37.363357 -32.815997) (xy 37.355645 -32.834709) (xy 37.341379 -32.849064)
			(xy 37.322716 -32.856893) (xy 37.3126 -32.85744) (xy 36.0807 -32.85744) (xy 36.070596 -32.856916)
			(xy 36.051926 -32.849186) (xy 36.037632 -32.834901) (xy 36.029891 -32.816235) (xy 36.029392 -32.806132)
			(xy 35.514828 -32.806132) (xy 35.514095 -32.811702) (xy 35.498582 -32.869595) (xy 35.494464 -32.879538)
			(xy 43.372532 -32.879538) (xy 43.372532 -32.636714) (xy 43.566588 -32.34055) (xy 43.5864 -32.310324)
			(xy 43.591325 -32.30185) (xy 43.595068 -32.282632) (xy 43.591349 -32.26341) (xy 43.5864 -32.254952)
			(xy 43.419522 -31.998412) (xy 43.380914 -31.93923) (xy 43.380406 -31.938468) (xy 43.379898 -31.937706)
			(xy 43.379644 -31.937198) (xy 43.379136 -31.936436) (xy 43.372532 -31.926022) (xy 43.372532 -31.683198)
			(xy 43.373032 -31.673041) (xy 43.380806 -31.654273) (xy 43.395169 -31.639908) (xy 43.413937 -31.632132)
			(xy 43.424094 -31.631636) (xy 44.160694 -31.631636) (xy 44.170865 -31.632069) (xy 44.189659 -31.639851)
			(xy 44.204044 -31.654234) (xy 44.21183 -31.673027) (xy 44.212256 -31.683198) (xy 44.212256 -31.926022)
			(xy 43.996356 -32.256476) (xy 43.992337 -32.264697) (xy 43.989796 -32.282807) (xy 43.993738 -32.300664)
			(xy 43.998388 -32.308546) (xy 44.030646 -32.35833) (xy 44.212256 -32.635444) (xy 44.212256 -32.714184)
			(xy 44.847256 -32.714184) (xy 44.847256 -31.850584) (xy 44.847746 -31.8206) (xy 44.855574 -31.761144)
			(xy 44.871095 -31.703219) (xy 44.894044 -31.647815) (xy 44.924028 -31.595881) (xy 44.960534 -31.548305)
			(xy 45.002939 -31.5059) (xy 45.050515 -31.469394) (xy 45.102449 -31.43941) (xy 45.157853 -31.416461)
			(xy 45.215778 -31.40094) (xy 45.275234 -31.393112) (xy 45.335202 -31.393112) (xy 45.394658 -31.40094)
			(xy 45.452583 -31.416461) (xy 45.507987 -31.43941) (xy 45.559921 -31.469394) (xy 45.607497 -31.5059)
			(xy 45.649902 -31.548305) (xy 45.686408 -31.595881) (xy 45.716392 -31.647815) (xy 45.739341 -31.703219)
			(xy 45.754862 -31.761144) (xy 45.76269 -31.8206) (xy 45.76318 -31.850584) (xy 45.76318 -32.714184)
			(xy 45.763047 -32.722312) (xy 60.60694 -32.722312) (xy 60.60694 -31.858712) (xy 60.60743 -31.828744)
			(xy 60.615253 -31.769322) (xy 60.630766 -31.711429) (xy 60.653702 -31.656056) (xy 60.683669 -31.60415)
			(xy 60.720156 -31.5566) (xy 60.762536 -31.51422) (xy 60.810086 -31.477733) (xy 60.861992 -31.447766)
			(xy 60.917365 -31.42483) (xy 60.975258 -31.409317) (xy 61.03468 -31.401494) (xy 61.094616 -31.401494)
			(xy 61.154038 -31.409317) (xy 61.211931 -31.42483) (xy 61.267304 -31.447766) (xy 61.31921 -31.477733)
			(xy 61.36676 -31.51422) (xy 61.40914 -31.5566) (xy 61.445627 -31.60415) (xy 61.475594 -31.656056)
			(xy 61.49853 -31.711429) (xy 61.514043 -31.769322) (xy 61.521866 -31.828744) (xy 61.522356 -31.858712)
			(xy 61.522356 -32.722312) (xy 61.521866 -32.75228) (xy 61.514776 -32.806132) (xy 62.02934 -32.806132)
			(xy 62.02934 -31.77413) (xy 62.029851 -31.764005) (xy 62.037569 -31.745285) (xy 62.051848 -31.730927)
			(xy 62.070526 -31.723107) (xy 62.080648 -31.722568) (xy 63.312548 -31.722568) (xy 63.322656 -31.723045)
			(xy 63.341329 -31.730793) (xy 63.355621 -31.745091) (xy 63.36336 -31.763768) (xy 63.363856 -31.773876)
			(xy 63.363856 -32.805878) (xy 66.56578 -32.805878) (xy 66.56578 -31.77413) (xy 66.566252 -31.764)
			(xy 66.573977 -31.745272) (xy 66.588269 -31.730913) (xy 66.606961 -31.7231) (xy 66.617088 -31.722568)
			(xy 67.848988 -31.722568) (xy 67.859137 -31.723031) (xy 67.877883 -31.730816) (xy 67.892206 -31.7452)
			(xy 67.899912 -31.763979) (xy 67.900296 -31.77413) (xy 67.900296 -32.805878) (xy 67.899757 -32.815999)
			(xy 67.892043 -32.834713) (xy 67.877773 -32.849069) (xy 67.859106 -32.856895) (xy 67.848988 -32.85744)
			(xy 66.617088 -32.85744) (xy 66.606938 -32.856989) (xy 66.588193 -32.849197) (xy 66.573871 -32.83481)
			(xy 66.566165 -32.81603) (xy 66.56578 -32.805878) (xy 63.363856 -32.805878) (xy 63.363355 -32.816004)
			(xy 63.355634 -32.834725) (xy 63.341352 -32.849083) (xy 63.322671 -32.856902) (xy 63.312548 -32.85744)
			(xy 62.080648 -32.85744) (xy 62.070534 -32.856946) (xy 62.051839 -32.849221) (xy 62.037524 -32.834929)
			(xy 62.02977 -32.816246) (xy 62.02934 -32.806132) (xy 61.514776 -32.806132) (xy 61.514043 -32.811702)
			(xy 61.49853 -32.869595) (xy 61.494412 -32.879538) (xy 69.37248 -32.879538) (xy 69.37248 -32.636714)
			(xy 69.566536 -32.34055) (xy 69.586348 -32.310324) (xy 69.591277 -32.301851) (xy 69.595024 -32.282632)
			(xy 69.591301 -32.263409) (xy 69.586348 -32.254952) (xy 69.41947 -31.998412) (xy 69.380862 -31.93923)
			(xy 69.380354 -31.938468) (xy 69.379846 -31.937706) (xy 69.379592 -31.937198) (xy 69.379084 -31.936436)
			(xy 69.37248 -31.926022) (xy 69.37248 -31.683198) (xy 69.372863 -31.673021) (xy 69.380657 -31.654218)
			(xy 69.395055 -31.639832) (xy 69.413865 -31.632055) (xy 69.424042 -31.631636) (xy 70.160642 -31.631636)
			(xy 70.170802 -31.632099) (xy 70.189572 -31.639887) (xy 70.203936 -31.654262) (xy 70.211709 -31.673037)
			(xy 70.212204 -31.683198) (xy 70.212204 -31.926022) (xy 69.996304 -32.256476) (xy 69.99228 -32.264696)
			(xy 69.989737 -32.282807) (xy 69.993683 -32.300665) (xy 69.998336 -32.308546) (xy 70.030594 -32.35833)
			(xy 70.212204 -32.635444) (xy 70.212204 -32.714184) (xy 70.847204 -32.714184) (xy 70.847204 -31.850584)
			(xy 70.847694 -31.8206) (xy 70.855522 -31.761144) (xy 70.871043 -31.703219) (xy 70.893992 -31.647815)
			(xy 70.923976 -31.595881) (xy 70.960482 -31.548305) (xy 71.002887 -31.5059) (xy 71.050463 -31.469394)
			(xy 71.102397 -31.43941) (xy 71.157801 -31.416461) (xy 71.215726 -31.40094) (xy 71.275182 -31.393112)
			(xy 71.33515 -31.393112) (xy 71.394606 -31.40094) (xy 71.452531 -31.416461) (xy 71.507935 -31.43941)
			(xy 71.559869 -31.469394) (xy 71.607445 -31.5059) (xy 71.64985 -31.548305) (xy 71.686356 -31.595881)
			(xy 71.71634 -31.647815) (xy 71.739289 -31.703219) (xy 71.75481 -31.761144) (xy 71.762638 -31.8206)
			(xy 71.763128 -31.850584) (xy 71.763128 -32.714184) (xy 71.762995 -32.722312) (xy 86.606888 -32.722312)
			(xy 86.606888 -31.858712) (xy 86.607378 -31.828744) (xy 86.615201 -31.769322) (xy 86.630714 -31.711429)
			(xy 86.65365 -31.656056) (xy 86.683617 -31.60415) (xy 86.720104 -31.5566) (xy 86.762484 -31.51422)
			(xy 86.810034 -31.477733) (xy 86.86194 -31.447766) (xy 86.917313 -31.42483) (xy 86.975206 -31.409317)
			(xy 87.034628 -31.401494) (xy 87.094564 -31.401494) (xy 87.153986 -31.409317) (xy 87.211879 -31.42483)
			(xy 87.267252 -31.447766) (xy 87.319158 -31.477733) (xy 87.366708 -31.51422) (xy 87.409088 -31.5566)
			(xy 87.445575 -31.60415) (xy 87.475542 -31.656056) (xy 87.498478 -31.711429) (xy 87.513991 -31.769322)
			(xy 87.521814 -31.828744) (xy 87.522304 -31.858712) (xy 87.522304 -32.722312) (xy 87.521814 -32.75228)
			(xy 87.514724 -32.806132) (xy 88.029288 -32.806132) (xy 88.029288 -31.77413) (xy 88.029849 -31.764012)
			(xy 88.037558 -31.745301) (xy 88.051821 -31.730945) (xy 88.070481 -31.723116) (xy 88.080596 -31.722568)
			(xy 89.312496 -31.722568) (xy 89.322601 -31.723088) (xy 89.341272 -31.730818) (xy 89.355566 -31.745104)
			(xy 89.363307 -31.763772) (xy 89.363804 -31.773876) (xy 89.363804 -32.805878) (xy 92.565728 -32.805878)
			(xy 92.565728 -31.77413) (xy 92.566251 -31.764007) (xy 92.573966 -31.745288) (xy 92.588242 -31.730931)
			(xy 92.606916 -31.723109) (xy 92.617036 -31.722568) (xy 93.848936 -31.722568) (xy 93.859088 -31.722991)
			(xy 93.877835 -31.730793) (xy 93.892156 -31.745188) (xy 93.899861 -31.763975) (xy 93.900244 -31.77413)
			(xy 93.900244 -32.805878) (xy 93.899755 -32.816005) (xy 93.892032 -32.834729) (xy 93.877746 -32.849087)
			(xy 93.859061 -32.856904) (xy 93.848936 -32.85744) (xy 92.617036 -32.85744) (xy 92.606889 -32.85695)
			(xy 92.588145 -32.849173) (xy 92.573822 -32.834798) (xy 92.566114 -32.816026) (xy 92.565728 -32.805878)
			(xy 89.363804 -32.805878) (xy 89.363257 -32.815998) (xy 89.355544 -32.83471) (xy 89.341277 -32.849066)
			(xy 89.322613 -32.856894) (xy 89.312496 -32.85744) (xy 88.080596 -32.85744) (xy 88.070492 -32.856919)
			(xy 88.051821 -32.849188) (xy 88.037528 -32.834902) (xy 88.029787 -32.816236) (xy 88.029288 -32.806132)
			(xy 87.514724 -32.806132) (xy 87.513991 -32.811702) (xy 87.498478 -32.869595) (xy 87.49436 -32.879538)
			(xy 95.372428 -32.879538) (xy 95.372428 -32.636714) (xy 95.4913 -32.455358) (xy 95.553784 -32.359854)
			(xy 95.577914 -32.323024) (xy 95.581783 -32.316696) (xy 95.586043 -32.302497) (xy 95.586296 -32.295084)
			(xy 95.586296 -32.269176) (xy 95.586119 -32.263025) (xy 95.583155 -32.251084) (xy 95.580454 -32.245554)
			(xy 95.466916 -32.071564) (xy 95.44685 -32.040576) (xy 95.441262 -32.03194) (xy 95.38081 -31.93923)
			(xy 95.380302 -31.938468) (xy 95.379794 -31.937706) (xy 95.37954 -31.937198) (xy 95.379032 -31.936436)
			(xy 95.372428 -31.926022) (xy 95.372428 -31.683198) (xy 95.372932 -31.673041) (xy 95.380705 -31.654274)
			(xy 95.395067 -31.639909) (xy 95.413833 -31.632133) (xy 95.42399 -31.631636) (xy 96.16059 -31.631636)
			(xy 96.170761 -31.632072) (xy 96.189555 -31.639853) (xy 96.20394 -31.654235) (xy 96.211726 -31.673027)
			(xy 96.212152 -31.683198) (xy 96.212152 -31.926022) (xy 95.996252 -32.256476) (xy 95.992223 -32.264695)
			(xy 95.989677 -32.282807) (xy 95.993627 -32.300666) (xy 95.998284 -32.308546) (xy 96.030542 -32.35833)
			(xy 96.212152 -32.635444) (xy 96.212152 -32.714184) (xy 96.847152 -32.714184) (xy 96.847152 -31.850584)
			(xy 96.847642 -31.8206) (xy 96.85547 -31.761144) (xy 96.870991 -31.703219) (xy 96.89394 -31.647815)
			(xy 96.923924 -31.595881) (xy 96.96043 -31.548305) (xy 97.002835 -31.5059) (xy 97.050411 -31.469394)
			(xy 97.102345 -31.43941) (xy 97.157749 -31.416461) (xy 97.215674 -31.40094) (xy 97.27513 -31.393112)
			(xy 97.335098 -31.393112) (xy 97.394554 -31.40094) (xy 97.452479 -31.416461) (xy 97.507883 -31.43941)
			(xy 97.559817 -31.469394) (xy 97.607393 -31.5059) (xy 97.649798 -31.548305) (xy 97.686304 -31.595881)
			(xy 97.716288 -31.647815) (xy 97.739237 -31.703219) (xy 97.754758 -31.761144) (xy 97.762586 -31.8206)
			(xy 97.763076 -31.850584) (xy 97.763076 -32.714184) (xy 97.762943 -32.722312) (xy 124.706888 -32.722312)
			(xy 124.706888 -31.858712) (xy 124.707378 -31.828728) (xy 124.715206 -31.769272) (xy 124.730727 -31.711347)
			(xy 124.753676 -31.655943) (xy 124.78366 -31.604009) (xy 124.820166 -31.556433) (xy 124.862571 -31.514028)
			(xy 124.910147 -31.477522) (xy 124.962081 -31.447538) (xy 125.017485 -31.424589) (xy 125.07541 -31.409068)
			(xy 125.134866 -31.40124) (xy 125.194834 -31.40124) (xy 125.25429 -31.409068) (xy 125.312215 -31.424589)
			(xy 125.367619 -31.447538) (xy 125.419553 -31.477522) (xy 125.467129 -31.514028) (xy 125.509534 -31.556433)
			(xy 125.54604 -31.604009) (xy 125.576024 -31.655943) (xy 125.598973 -31.711347) (xy 125.614494 -31.769272)
			(xy 125.622322 -31.828728) (xy 125.622812 -31.858712) (xy 125.622812 -32.722312) (xy 125.622322 -32.752296)
			(xy 125.615267 -32.805878) (xy 126.129288 -32.805878) (xy 126.129288 -31.77413) (xy 126.12969 -31.763954)
			(xy 126.137474 -31.745151) (xy 126.151867 -31.730763) (xy 126.170674 -31.722986) (xy 126.18085 -31.722568)
			(xy 127.41275 -31.722568) (xy 127.422922 -31.723005) (xy 127.441721 -31.73078) (xy 127.456109 -31.745162)
			(xy 127.463891 -31.763958) (xy 127.464312 -31.77413) (xy 127.464312 -32.805878) (xy 130.665728 -32.805878)
			(xy 130.665728 -31.77413) (xy 130.666188 -31.763962) (xy 130.673962 -31.74517) (xy 130.688336 -31.730784)
			(xy 130.707122 -31.722996) (xy 130.71729 -31.722568) (xy 131.94919 -31.722568) (xy 131.959365 -31.722973)
			(xy 131.978165 -31.73076) (xy 131.992551 -31.745152) (xy 132.000331 -31.763955) (xy 132.000752 -31.77413)
			(xy 132.000752 -32.805878) (xy 132.000318 -32.816049) (xy 131.992538 -32.834845) (xy 131.978156 -32.849231)
			(xy 131.959361 -32.857015) (xy 131.94919 -32.85744) (xy 130.71729 -32.85744) (xy 130.707115 -32.857044)
			(xy 130.688316 -32.849251) (xy 130.673931 -32.834857) (xy 130.66615 -32.816053) (xy 130.665728 -32.805878)
			(xy 127.464312 -32.805878) (xy 127.463917 -32.816054) (xy 127.45613 -32.834858) (xy 127.441734 -32.849245)
			(xy 127.422927 -32.857022) (xy 127.41275 -32.85744) (xy 126.18085 -32.85744) (xy 126.170679 -32.856995)
			(xy 126.151881 -32.849222) (xy 126.137494 -32.834842) (xy 126.129711 -32.816049) (xy 126.129288 -32.805878)
			(xy 125.615267 -32.805878) (xy 125.614494 -32.811752) (xy 125.598973 -32.869677) (xy 125.594888 -32.879538)
			(xy 133.472428 -32.879538) (xy 133.472428 -32.651954) (xy 133.472682 -32.64789) (xy 133.472936 -32.64535)
			(xy 133.472936 -32.636714) (xy 133.478524 -32.628078) (xy 133.479794 -32.626046) (xy 133.48081 -32.624014)
			(xy 133.678168 -32.323024) (xy 133.682041 -32.316699) (xy 133.686298 -32.302497) (xy 133.68655 -32.295084)
			(xy 133.68655 -32.26943) (xy 133.686351 -32.262095) (xy 133.682216 -32.248024) (xy 133.678422 -32.241744)
			(xy 133.480556 -31.938722) (xy 133.47827 -31.934912) (xy 133.478016 -31.934404) (xy 133.477 -31.932626)
			(xy 133.472936 -31.926022) (xy 133.472936 -31.917894) (xy 133.472682 -31.915354) (xy 133.472428 -31.91129)
			(xy 133.472428 -31.683198) (xy 133.472932 -31.673041) (xy 133.480705 -31.654274) (xy 133.495067 -31.639909)
			(xy 133.513833 -31.632133) (xy 133.52399 -31.631636) (xy 134.260844 -31.631636) (xy 134.271017 -31.632138)
			(xy 134.289823 -31.639909) (xy 134.304246 -31.654261) (xy 134.312111 -31.673027) (xy 134.31266 -31.683198)
			(xy 134.31266 -31.910782) (xy 134.312406 -31.914846) (xy 134.312152 -31.917386) (xy 134.312152 -31.926022)
			(xy 134.30631 -31.93542) (xy 134.305548 -31.93669) (xy 134.304278 -31.938722) (xy 134.098538 -32.253428)
			(xy 134.093514 -32.261963) (xy 134.08969 -32.281373) (xy 134.093494 -32.300787) (xy 134.098538 -32.309308)
			(xy 134.304278 -32.622744) (xy 134.305294 -32.624776) (xy 134.306564 -32.626808) (xy 134.312152 -32.635444)
			(xy 134.312152 -32.64408) (xy 134.312406 -32.64662) (xy 134.31266 -32.650684) (xy 134.31266 -32.714184)
			(xy 134.94766 -32.714184) (xy 134.94766 -31.850584) (xy 134.94815 -31.820616) (xy 134.955973 -31.761194)
			(xy 134.971486 -31.703301) (xy 134.994422 -31.647928) (xy 135.024389 -31.596022) (xy 135.060876 -31.548472)
			(xy 135.103256 -31.506092) (xy 135.150806 -31.469605) (xy 135.202712 -31.439638) (xy 135.258085 -31.416702)
			(xy 135.315978 -31.401189) (xy 135.3754 -31.393366) (xy 135.435336 -31.393366) (xy 135.494758 -31.401189)
			(xy 135.552651 -31.416702) (xy 135.608024 -31.439638) (xy 135.65993 -31.469605) (xy 135.70748 -31.506092)
			(xy 135.74986 -31.548472) (xy 135.786347 -31.596022) (xy 135.816314 -31.647928) (xy 135.83925 -31.703301)
			(xy 135.854763 -31.761194) (xy 135.862586 -31.820616) (xy 135.863076 -31.850584) (xy 135.863076 -32.714184)
			(xy 135.862943 -32.722312) (xy 150.706836 -32.722312) (xy 150.706836 -31.858712) (xy 150.707326 -31.828728)
			(xy 150.715154 -31.769272) (xy 150.730675 -31.711347) (xy 150.753624 -31.655943) (xy 150.783608 -31.604009)
			(xy 150.820114 -31.556433) (xy 150.862519 -31.514028) (xy 150.910095 -31.477522) (xy 150.962029 -31.447538)
			(xy 151.017433 -31.424589) (xy 151.075358 -31.409068) (xy 151.134814 -31.40124) (xy 151.194782 -31.40124)
			(xy 151.254238 -31.409068) (xy 151.312163 -31.424589) (xy 151.367567 -31.447538) (xy 151.419501 -31.477522)
			(xy 151.467077 -31.514028) (xy 151.509482 -31.556433) (xy 151.545988 -31.604009) (xy 151.575972 -31.655943)
			(xy 151.598921 -31.711347) (xy 151.614442 -31.769272) (xy 151.62227 -31.828728) (xy 151.62276 -31.858712)
			(xy 151.62276 -32.722312) (xy 151.62227 -32.752296) (xy 151.615215 -32.805878) (xy 152.129236 -32.805878)
			(xy 152.129236 -31.77413) (xy 152.129689 -31.763961) (xy 152.137463 -31.745167) (xy 152.15184 -31.730781)
			(xy 152.170629 -31.722995) (xy 152.180798 -31.722568) (xy 153.412698 -31.722568) (xy 153.422873 -31.722966)
			(xy 153.441674 -31.730756) (xy 153.45606 -31.74515) (xy 153.463839 -31.763955) (xy 153.46426 -31.77413)
			(xy 153.46426 -32.805878) (xy 156.665676 -32.805878) (xy 156.665676 -31.77413) (xy 156.666089 -31.763956)
			(xy 156.673872 -31.745154) (xy 156.688261 -31.730767) (xy 156.707064 -31.722988) (xy 156.717238 -31.722568)
			(xy 157.949138 -31.722568) (xy 157.959302 -31.723003) (xy 157.978078 -31.730796) (xy 157.992443 -31.745179)
			(xy 158.00021 -31.763965) (xy 158.0007 -31.77413) (xy 158.0007 -32.805878) (xy 158.00015 -32.81603)
			(xy 157.99239 -32.834791) (xy 157.978042 -32.849156) (xy 157.959289 -32.856938) (xy 157.949138 -32.85744)
			(xy 156.717238 -32.85744) (xy 156.707066 -32.857004) (xy 156.688268 -32.849228) (xy 156.673881 -32.834845)
			(xy 156.666099 -32.81605) (xy 156.665676 -32.805878) (xy 153.46426 -32.805878) (xy 153.463818 -32.816048)
			(xy 153.45604 -32.834843) (xy 153.44166 -32.849229) (xy 153.422868 -32.857014) (xy 153.412698 -32.85744)
			(xy 152.180798 -32.85744) (xy 152.170624 -32.857037) (xy 152.151825 -32.849247) (xy 152.137439 -32.834855)
			(xy 152.129658 -32.816053) (xy 152.129236 -32.805878) (xy 151.615215 -32.805878) (xy 151.614442 -32.811752)
			(xy 151.598921 -32.869677) (xy 151.594836 -32.879538) (xy 159.472376 -32.879538) (xy 159.472376 -32.651954)
			(xy 159.47263 -32.64789) (xy 159.472884 -32.64535) (xy 159.472884 -32.636714) (xy 159.478472 -32.628078)
			(xy 159.479742 -32.626046) (xy 159.480758 -32.624014) (xy 159.678116 -32.323024) (xy 159.681985 -32.316696)
			(xy 159.686245 -32.302497) (xy 159.686498 -32.295084) (xy 159.686498 -32.26943) (xy 159.686292 -32.262096)
			(xy 159.682162 -32.248025) (xy 159.67837 -32.241744) (xy 159.480504 -31.938722) (xy 159.478218 -31.934912)
			(xy 159.477964 -31.934404) (xy 159.476948 -31.932626) (xy 159.472884 -31.926022) (xy 159.472884 -31.917894)
			(xy 159.47263 -31.915354) (xy 159.472376 -31.91129) (xy 159.472376 -31.683198) (xy 159.472763 -31.673022)
			(xy 159.480556 -31.65422) (xy 159.494953 -31.639833) (xy 159.513761 -31.632055) (xy 159.523938 -31.631636)
			(xy 160.260792 -31.631636) (xy 160.270962 -31.63218) (xy 160.289766 -31.639934) (xy 160.304192 -31.654274)
			(xy 160.312058 -31.673031) (xy 160.312608 -31.683198) (xy 160.312608 -31.910782) (xy 160.312354 -31.914846)
			(xy 160.3121 -31.917386) (xy 160.3121 -31.926022) (xy 160.306258 -31.93542) (xy 160.305496 -31.93669)
			(xy 160.304226 -31.938722) (xy 160.098486 -32.253428) (xy 160.093458 -32.261962) (xy 160.08963 -32.281373)
			(xy 160.093438 -32.300788) (xy 160.098486 -32.309308) (xy 160.304226 -32.622744) (xy 160.305242 -32.624776)
			(xy 160.306512 -32.626808) (xy 160.3121 -32.635444) (xy 160.3121 -32.64408) (xy 160.312354 -32.64662)
			(xy 160.312608 -32.650684) (xy 160.312608 -32.714184) (xy 160.947608 -32.714184) (xy 160.947608 -31.850584)
			(xy 160.948098 -31.820616) (xy 160.955921 -31.761194) (xy 160.971434 -31.703301) (xy 160.99437 -31.647928)
			(xy 161.024337 -31.596022) (xy 161.060824 -31.548472) (xy 161.103204 -31.506092) (xy 161.150754 -31.469605)
			(xy 161.20266 -31.439638) (xy 161.258033 -31.416702) (xy 161.315926 -31.401189) (xy 161.375348 -31.393366)
			(xy 161.435284 -31.393366) (xy 161.494706 -31.401189) (xy 161.552599 -31.416702) (xy 161.607972 -31.439638)
			(xy 161.659878 -31.469605) (xy 161.707428 -31.506092) (xy 161.749808 -31.548472) (xy 161.786295 -31.596022)
			(xy 161.816262 -31.647928) (xy 161.839198 -31.703301) (xy 161.854711 -31.761194) (xy 161.862534 -31.820616)
			(xy 161.863024 -31.850584) (xy 161.863024 -32.714184) (xy 161.862891 -32.722312) (xy 176.706784 -32.722312)
			(xy 176.706784 -31.858712) (xy 176.707274 -31.828728) (xy 176.715102 -31.769272) (xy 176.730623 -31.711347)
			(xy 176.753572 -31.655943) (xy 176.783556 -31.604009) (xy 176.820062 -31.556433) (xy 176.862467 -31.514028)
			(xy 176.910043 -31.477522) (xy 176.961977 -31.447538) (xy 177.017381 -31.424589) (xy 177.075306 -31.409068)
			(xy 177.134762 -31.40124) (xy 177.19473 -31.40124) (xy 177.254186 -31.409068) (xy 177.312111 -31.424589)
			(xy 177.367515 -31.447538) (xy 177.419449 -31.477522) (xy 177.467025 -31.514028) (xy 177.50943 -31.556433)
			(xy 177.545936 -31.604009) (xy 177.57592 -31.655943) (xy 177.598869 -31.711347) (xy 177.61439 -31.769272)
			(xy 177.622218 -31.828728) (xy 177.622708 -31.858712) (xy 177.622708 -32.722312) (xy 177.622218 -32.752296)
			(xy 177.615163 -32.805878) (xy 178.129184 -32.805878) (xy 178.129184 -31.77413) (xy 178.12959 -31.763955)
			(xy 178.137373 -31.745152) (xy 178.151765 -31.730764) (xy 178.170571 -31.722987) (xy 178.180746 -31.722568)
			(xy 179.412646 -31.722568) (xy 179.42281 -31.722997) (xy 179.441586 -31.730792) (xy 179.455951 -31.745178)
			(xy 179.463718 -31.763965) (xy 179.464208 -31.77413) (xy 179.464208 -32.805878) (xy 182.665624 -32.805878)
			(xy 182.665624 -31.77413) (xy 182.666088 -31.763962) (xy 182.673861 -31.745171) (xy 182.688234 -31.730785)
			(xy 182.707018 -31.722997) (xy 182.717186 -31.722568) (xy 183.949086 -31.722568) (xy 183.95926 -31.722976)
			(xy 183.978061 -31.730762) (xy 183.992447 -31.745153) (xy 184.000227 -31.763955) (xy 184.000648 -31.77413)
			(xy 184.000648 -32.805878) (xy 184.000218 -32.81605) (xy 183.992437 -32.834847) (xy 183.978053 -32.849233)
			(xy 183.959258 -32.857016) (xy 183.949086 -32.85744) (xy 182.717186 -32.85744) (xy 182.707011 -32.857047)
			(xy 182.688212 -32.849253) (xy 182.673827 -32.834858) (xy 182.666046 -32.816054) (xy 182.665624 -32.805878)
			(xy 179.464208 -32.805878) (xy 179.46365 -32.816029) (xy 179.455891 -32.834789) (xy 179.441546 -32.849153)
			(xy 179.422796 -32.856937) (xy 179.412646 -32.85744) (xy 178.180746 -32.85744) (xy 178.170575 -32.856998)
			(xy 178.151777 -32.849224) (xy 178.137389 -32.834843) (xy 178.129607 -32.816049) (xy 178.129184 -32.805878)
			(xy 177.615163 -32.805878) (xy 177.61439 -32.811752) (xy 177.598869 -32.869677) (xy 177.594784 -32.879538)
			(xy 185.472324 -32.879538) (xy 185.472324 -32.651954) (xy 185.472578 -32.64789) (xy 185.472832 -32.64535)
			(xy 185.472832 -32.636714) (xy 185.47842 -32.628078) (xy 185.47969 -32.626046) (xy 185.480706 -32.624014)
			(xy 185.678064 -32.323024) (xy 185.681937 -32.316698) (xy 185.686194 -32.302497) (xy 185.686446 -32.295084)
			(xy 185.686446 -32.26943) (xy 185.686247 -32.262095) (xy 185.682113 -32.248024) (xy 185.678318 -32.241744)
			(xy 185.480452 -31.938722) (xy 185.478166 -31.934912) (xy 185.477912 -31.934404) (xy 185.476896 -31.932626)
			(xy 185.472832 -31.926022) (xy 185.472832 -31.917894) (xy 185.472578 -31.915354) (xy 185.472324 -31.91129)
			(xy 185.472324 -31.683198) (xy 185.472831 -31.673042) (xy 185.480604 -31.654275) (xy 185.494965 -31.639911)
			(xy 185.51373 -31.632134) (xy 185.523886 -31.631636) (xy 186.26074 -31.631636) (xy 186.270913 -31.632141)
			(xy 186.289718 -31.639911) (xy 186.304142 -31.654262) (xy 186.312007 -31.673027) (xy 186.312556 -31.683198)
			(xy 186.312556 -31.910782) (xy 186.312302 -31.914846) (xy 186.312048 -31.917386) (xy 186.312048 -31.926022)
			(xy 186.306206 -31.93542) (xy 186.305444 -31.93669) (xy 186.304174 -31.938722) (xy 186.098434 -32.253428)
			(xy 186.09341 -32.261963) (xy 186.089586 -32.281373) (xy 186.09339 -32.300787) (xy 186.098434 -32.309308)
			(xy 186.304174 -32.622744) (xy 186.30519 -32.624776) (xy 186.30646 -32.626808) (xy 186.312048 -32.635444)
			(xy 186.312048 -32.64408) (xy 186.312302 -32.64662) (xy 186.312556 -32.650684) (xy 186.312556 -32.714184)
			(xy 186.947556 -32.714184) (xy 186.947556 -31.850584) (xy 186.948046 -31.820616) (xy 186.955869 -31.761194)
			(xy 186.971382 -31.703301) (xy 186.994318 -31.647928) (xy 187.024285 -31.596022) (xy 187.060772 -31.548472)
			(xy 187.103152 -31.506092) (xy 187.150702 -31.469605) (xy 187.202608 -31.439638) (xy 187.257981 -31.416702)
			(xy 187.315874 -31.401189) (xy 187.375296 -31.393366) (xy 187.435232 -31.393366) (xy 187.494654 -31.401189)
			(xy 187.552547 -31.416702) (xy 187.60792 -31.439638) (xy 187.659826 -31.469605) (xy 187.707376 -31.506092)
			(xy 187.749756 -31.548472) (xy 187.786243 -31.596022) (xy 187.81621 -31.647928) (xy 187.839146 -31.703301)
			(xy 187.854659 -31.761194) (xy 187.862482 -31.820616) (xy 187.862972 -31.850584) (xy 187.862972 -32.714184)
			(xy 187.862839 -32.722312) (xy 202.706732 -32.722312) (xy 202.706732 -31.858712) (xy 202.707222 -31.828728)
			(xy 202.71505 -31.769272) (xy 202.730571 -31.711347) (xy 202.75352 -31.655943) (xy 202.783504 -31.604009)
			(xy 202.82001 -31.556433) (xy 202.862415 -31.514028) (xy 202.909991 -31.477522) (xy 202.961925 -31.447538)
			(xy 203.017329 -31.424589) (xy 203.075254 -31.409068) (xy 203.13471 -31.40124) (xy 203.194678 -31.40124)
			(xy 203.254134 -31.409068) (xy 203.312059 -31.424589) (xy 203.367463 -31.447538) (xy 203.419397 -31.477522)
			(xy 203.466973 -31.514028) (xy 203.509378 -31.556433) (xy 203.545884 -31.604009) (xy 203.575868 -31.655943)
			(xy 203.598817 -31.711347) (xy 203.614338 -31.769272) (xy 203.622166 -31.828728) (xy 203.622656 -31.858712)
			(xy 203.622656 -32.722312) (xy 203.622166 -32.752296) (xy 203.615111 -32.805878) (xy 204.129132 -32.805878)
			(xy 204.129132 -31.77413) (xy 204.129588 -31.763961) (xy 204.137362 -31.745168) (xy 204.151738 -31.730783)
			(xy 204.170525 -31.722996) (xy 204.180694 -31.722568) (xy 205.412594 -31.722568) (xy 205.422769 -31.722969)
			(xy 205.441569 -31.730758) (xy 205.455955 -31.745151) (xy 205.463735 -31.763955) (xy 205.464156 -31.77413)
			(xy 205.464156 -32.805878) (xy 208.665572 -32.805878) (xy 208.665572 -31.77413) (xy 208.665989 -31.763956)
			(xy 208.673771 -31.745156) (xy 208.688159 -31.730769) (xy 208.70696 -31.722989) (xy 208.717134 -31.722568)
			(xy 209.949034 -31.722568) (xy 209.959198 -31.723006) (xy 209.977973 -31.730797) (xy 209.992338 -31.74518)
			(xy 210.000106 -31.763966) (xy 210.000596 -31.77413) (xy 210.000596 -32.805878) (xy 210.00005 -32.81603)
			(xy 209.992289 -32.834792) (xy 209.977939 -32.849157) (xy 209.959186 -32.856939) (xy 209.949034 -32.85744)
			(xy 208.717134 -32.85744) (xy 208.706962 -32.857008) (xy 208.688164 -32.84923) (xy 208.673777 -32.834846)
			(xy 208.665995 -32.81605) (xy 208.665572 -32.805878) (xy 205.464156 -32.805878) (xy 205.463718 -32.816049)
			(xy 205.455939 -32.834844) (xy 205.441558 -32.84923) (xy 205.422765 -32.857015) (xy 205.412594 -32.85744)
			(xy 204.180694 -32.85744) (xy 204.170519 -32.85704) (xy 204.15172 -32.849249) (xy 204.137335 -32.834856)
			(xy 204.129554 -32.816053) (xy 204.129132 -32.805878) (xy 203.615111 -32.805878) (xy 203.614338 -32.811752)
			(xy 203.598817 -32.869677) (xy 203.594732 -32.879538) (xy 211.472272 -32.879538) (xy 211.472272 -32.651954)
			(xy 211.472526 -32.64789) (xy 211.47278 -32.64535) (xy 211.47278 -32.636714) (xy 211.478368 -32.628078)
			(xy 211.479638 -32.626046) (xy 211.480654 -32.624014) (xy 211.678012 -32.323024) (xy 211.68188 -32.316696)
			(xy 211.686141 -32.302496) (xy 211.686394 -32.295084) (xy 211.686394 -32.26943) (xy 211.686189 -32.262096)
			(xy 211.682058 -32.248025) (xy 211.678266 -32.241744) (xy 211.4804 -31.938722) (xy 211.478114 -31.934912)
			(xy 211.47786 -31.934404) (xy 211.476844 -31.932626) (xy 211.47278 -31.926022) (xy 211.47278 -31.917894)
			(xy 211.472526 -31.915354) (xy 211.472272 -31.91129) (xy 211.472272 -31.683198) (xy 211.472663 -31.673022)
			(xy 211.480455 -31.654221) (xy 211.494851 -31.639835) (xy 211.513658 -31.632056) (xy 211.523834 -31.631636)
			(xy 212.260688 -31.631636) (xy 212.270858 -31.632183) (xy 212.289662 -31.639936) (xy 212.304087 -31.654275)
			(xy 212.311954 -31.673031) (xy 212.312504 -31.683198) (xy 212.312504 -31.910782) (xy 212.31225 -31.914846)
			(xy 212.311996 -31.917386) (xy 212.311996 -31.926022) (xy 212.306154 -31.93542) (xy 212.305392 -31.93669)
			(xy 212.304122 -31.938722) (xy 212.098382 -32.253428) (xy 212.093354 -32.261962) (xy 212.089527 -32.281373)
			(xy 212.093334 -32.300788) (xy 212.098382 -32.309308) (xy 212.304122 -32.622744) (xy 212.305138 -32.624776)
			(xy 212.306408 -32.626808) (xy 212.311996 -32.635444) (xy 212.311996 -32.64408) (xy 212.31225 -32.64662)
			(xy 212.312504 -32.650684) (xy 212.312504 -32.714184) (xy 212.947504 -32.714184) (xy 212.947504 -31.850584)
			(xy 212.947994 -31.820616) (xy 212.955817 -31.761194) (xy 212.97133 -31.703301) (xy 212.994266 -31.647928)
			(xy 213.024233 -31.596022) (xy 213.06072 -31.548472) (xy 213.1031 -31.506092) (xy 213.15065 -31.469605)
			(xy 213.202556 -31.439638) (xy 213.257929 -31.416702) (xy 213.315822 -31.401189) (xy 213.375244 -31.393366)
			(xy 213.43518 -31.393366) (xy 213.494602 -31.401189) (xy 213.552495 -31.416702) (xy 213.607868 -31.439638)
			(xy 213.659774 -31.469605) (xy 213.707324 -31.506092) (xy 213.749704 -31.548472) (xy 213.786191 -31.596022)
			(xy 213.816158 -31.647928) (xy 213.839094 -31.703301) (xy 213.854607 -31.761194) (xy 213.86243 -31.820616)
			(xy 213.86292 -31.850584) (xy 213.86292 -32.714184) (xy 213.862787 -32.722312) (xy 240.806732 -32.722312)
			(xy 240.806732 -31.858712) (xy 240.807222 -31.828728) (xy 240.81505 -31.769272) (xy 240.830571 -31.711347)
			(xy 240.85352 -31.655943) (xy 240.883504 -31.604009) (xy 240.92001 -31.556433) (xy 240.962415 -31.514028)
			(xy 241.009991 -31.477522) (xy 241.061925 -31.447538) (xy 241.117329 -31.424589) (xy 241.175254 -31.409068)
			(xy 241.23471 -31.40124) (xy 241.294678 -31.40124) (xy 241.354134 -31.409068) (xy 241.412059 -31.424589)
			(xy 241.467463 -31.447538) (xy 241.519397 -31.477522) (xy 241.566973 -31.514028) (xy 241.609378 -31.556433)
			(xy 241.645884 -31.604009) (xy 241.675868 -31.655943) (xy 241.698817 -31.711347) (xy 241.714338 -31.769272)
			(xy 241.722166 -31.828728) (xy 241.722656 -31.858712) (xy 241.722656 -32.722312) (xy 241.722166 -32.752296)
			(xy 241.715111 -32.805878) (xy 242.229132 -32.805878) (xy 242.229132 -31.77413) (xy 242.229588 -31.763961)
			(xy 242.237362 -31.745168) (xy 242.251738 -31.730783) (xy 242.270525 -31.722996) (xy 242.280694 -31.722568)
			(xy 243.512594 -31.722568) (xy 243.522769 -31.722969) (xy 243.541569 -31.730758) (xy 243.555955 -31.745151)
			(xy 243.563735 -31.763955) (xy 243.564156 -31.77413) (xy 243.564156 -32.805878) (xy 246.765572 -32.805878)
			(xy 246.765572 -31.77413) (xy 246.765989 -31.763956) (xy 246.773771 -31.745156) (xy 246.788159 -31.730769)
			(xy 246.80696 -31.722989) (xy 246.817134 -31.722568) (xy 248.049034 -31.722568) (xy 248.059198 -31.723006)
			(xy 248.077973 -31.730797) (xy 248.092338 -31.74518) (xy 248.100106 -31.763966) (xy 248.100596 -31.77413)
			(xy 248.100596 -32.805878) (xy 248.10005 -32.81603) (xy 248.092289 -32.834792) (xy 248.077939 -32.849157)
			(xy 248.059186 -32.856939) (xy 248.049034 -32.85744) (xy 246.817134 -32.85744) (xy 246.806962 -32.857008)
			(xy 246.788164 -32.84923) (xy 246.773777 -32.834846) (xy 246.765995 -32.81605) (xy 246.765572 -32.805878)
			(xy 243.564156 -32.805878) (xy 243.563718 -32.816049) (xy 243.555939 -32.834844) (xy 243.541558 -32.84923)
			(xy 243.522765 -32.857015) (xy 243.512594 -32.85744) (xy 242.280694 -32.85744) (xy 242.270519 -32.85704)
			(xy 242.25172 -32.849249) (xy 242.237335 -32.834856) (xy 242.229554 -32.816053) (xy 242.229132 -32.805878)
			(xy 241.715111 -32.805878) (xy 241.714338 -32.811752) (xy 241.698817 -32.869677) (xy 241.694732 -32.879538)
			(xy 249.572272 -32.879538) (xy 249.572272 -32.651954) (xy 249.572526 -32.64789) (xy 249.57278 -32.64535)
			(xy 249.57278 -32.636714) (xy 249.578368 -32.628078) (xy 249.579638 -32.626046) (xy 249.580654 -32.624014)
			(xy 249.778012 -32.323024) (xy 249.78188 -32.316696) (xy 249.786141 -32.302496) (xy 249.786394 -32.295084)
			(xy 249.786394 -32.26943) (xy 249.786189 -32.262096) (xy 249.782058 -32.248025) (xy 249.778266 -32.241744)
			(xy 249.5804 -31.938722) (xy 249.578114 -31.934912) (xy 249.57786 -31.934404) (xy 249.576844 -31.932626)
			(xy 249.57278 -31.926022) (xy 249.57278 -31.917894) (xy 249.572526 -31.915354) (xy 249.572272 -31.91129)
			(xy 249.572272 -31.683198) (xy 249.572663 -31.673022) (xy 249.580455 -31.654221) (xy 249.594851 -31.639835)
			(xy 249.613658 -31.632056) (xy 249.623834 -31.631636) (xy 250.360688 -31.631636) (xy 250.370858 -31.632183)
			(xy 250.389662 -31.639936) (xy 250.404087 -31.654275) (xy 250.411954 -31.673031) (xy 250.412504 -31.683198)
			(xy 250.412504 -31.910782) (xy 250.41225 -31.914846) (xy 250.411996 -31.917386) (xy 250.411996 -31.926022)
			(xy 250.406154 -31.93542) (xy 250.405392 -31.93669) (xy 250.404122 -31.938722) (xy 250.198382 -32.253428)
			(xy 250.193354 -32.261962) (xy 250.189527 -32.281373) (xy 250.193334 -32.300788) (xy 250.198382 -32.309308)
			(xy 250.404122 -32.622744) (xy 250.405138 -32.624776) (xy 250.406408 -32.626808) (xy 250.411996 -32.635444)
			(xy 250.411996 -32.64408) (xy 250.41225 -32.64662) (xy 250.412504 -32.650684) (xy 250.412504 -32.714184)
			(xy 251.047504 -32.714184) (xy 251.047504 -31.850584) (xy 251.047994 -31.820616) (xy 251.055817 -31.761194)
			(xy 251.07133 -31.703301) (xy 251.094266 -31.647928) (xy 251.124233 -31.596022) (xy 251.16072 -31.548472)
			(xy 251.2031 -31.506092) (xy 251.25065 -31.469605) (xy 251.302556 -31.439638) (xy 251.357929 -31.416702)
			(xy 251.415822 -31.401189) (xy 251.475244 -31.393366) (xy 251.53518 -31.393366) (xy 251.594602 -31.401189)
			(xy 251.652495 -31.416702) (xy 251.707868 -31.439638) (xy 251.759774 -31.469605) (xy 251.807324 -31.506092)
			(xy 251.849704 -31.548472) (xy 251.886191 -31.596022) (xy 251.916158 -31.647928) (xy 251.939094 -31.703301)
			(xy 251.954607 -31.761194) (xy 251.96243 -31.820616) (xy 251.96292 -31.850584) (xy 251.96292 -32.714184)
			(xy 251.962787 -32.722312) (xy 266.80668 -32.722312) (xy 266.80668 -31.858712) (xy 266.80717 -31.828728)
			(xy 266.814998 -31.769272) (xy 266.830519 -31.711347) (xy 266.853468 -31.655943) (xy 266.883452 -31.604009)
			(xy 266.919958 -31.556433) (xy 266.962363 -31.514028) (xy 267.009939 -31.477522) (xy 267.061873 -31.447538)
			(xy 267.117277 -31.424589) (xy 267.175202 -31.409068) (xy 267.234658 -31.40124) (xy 267.294626 -31.40124)
			(xy 267.354082 -31.409068) (xy 267.412007 -31.424589) (xy 267.467411 -31.447538) (xy 267.519345 -31.477522)
			(xy 267.566921 -31.514028) (xy 267.609326 -31.556433) (xy 267.645832 -31.604009) (xy 267.675816 -31.655943)
			(xy 267.698765 -31.711347) (xy 267.714286 -31.769272) (xy 267.722114 -31.828728) (xy 267.722604 -31.858712)
			(xy 267.722604 -32.722312) (xy 267.722114 -32.752296) (xy 267.715059 -32.805878) (xy 268.22908 -32.805878)
			(xy 268.22908 -31.77413) (xy 268.22949 -31.763955) (xy 268.237272 -31.745153) (xy 268.251663 -31.730766)
			(xy 268.270467 -31.722987) (xy 268.280642 -31.722568) (xy 269.512542 -31.722568) (xy 269.522706 -31.723)
			(xy 269.541482 -31.730794) (xy 269.555847 -31.745178) (xy 269.563614 -31.763965) (xy 269.564104 -31.77413)
			(xy 269.564104 -32.805878) (xy 272.76552 -32.805878) (xy 272.76552 -31.77413) (xy 272.765988 -31.763963)
			(xy 272.77376 -31.745172) (xy 272.788132 -31.730787) (xy 272.806915 -31.722998) (xy 272.817082 -31.722568)
			(xy 274.048982 -31.722568) (xy 274.059156 -31.722979) (xy 274.077956 -31.730764) (xy 274.092343 -31.745154)
			(xy 274.100123 -31.763956) (xy 274.100544 -31.77413) (xy 274.100544 -32.805878) (xy 274.100117 -32.81605)
			(xy 274.092336 -32.834848) (xy 274.077951 -32.849234) (xy 274.059154 -32.857017) (xy 274.048982 -32.85744)
			(xy 272.817082 -32.85744) (xy 272.806907 -32.85705) (xy 272.788107 -32.849255) (xy 272.773722 -32.834859)
			(xy 272.765942 -32.816054) (xy 272.76552 -32.805878) (xy 269.564104 -32.805878) (xy 269.56355 -32.816029)
			(xy 269.55579 -32.83479) (xy 269.541444 -32.849154) (xy 269.522693 -32.856937) (xy 269.512542 -32.85744)
			(xy 268.280642 -32.85744) (xy 268.27047 -32.857001) (xy 268.251672 -32.849226) (xy 268.237285 -32.834844)
			(xy 268.229503 -32.816049) (xy 268.22908 -32.805878) (xy 267.715059 -32.805878) (xy 267.714286 -32.811752)
			(xy 267.698765 -32.869677) (xy 267.69468 -32.879538) (xy 275.57222 -32.879538) (xy 275.57222 -32.651954)
			(xy 275.572474 -32.64789) (xy 275.572728 -32.64535) (xy 275.572728 -32.636714) (xy 275.578316 -32.628078)
			(xy 275.579586 -32.626046) (xy 275.580602 -32.624014) (xy 275.77796 -32.323024) (xy 275.781832 -32.316698)
			(xy 275.78609 -32.302497) (xy 275.786342 -32.295084) (xy 275.786342 -32.26943) (xy 275.786144 -32.262095)
			(xy 275.782009 -32.248024) (xy 275.778214 -32.241744) (xy 275.580348 -31.938722) (xy 275.578062 -31.934912)
			(xy 275.577808 -31.934404) (xy 275.576792 -31.932626) (xy 275.572728 -31.926022) (xy 275.572728 -31.917894)
			(xy 275.572474 -31.915354) (xy 275.57222 -31.91129) (xy 275.57222 -31.683198) (xy 275.572731 -31.673042)
			(xy 275.580503 -31.654277) (xy 275.594863 -31.639912) (xy 275.613626 -31.632135) (xy 275.623782 -31.631636)
			(xy 276.360636 -31.631636) (xy 276.370809 -31.632144) (xy 276.389614 -31.639913) (xy 276.404038 -31.654263)
			(xy 276.411903 -31.673028) (xy 276.412452 -31.683198) (xy 276.412452 -31.910782) (xy 276.412198 -31.914846)
			(xy 276.411944 -31.917386) (xy 276.411944 -31.926022) (xy 276.406102 -31.93542) (xy 276.40534 -31.93669)
			(xy 276.40407 -31.938722) (xy 276.19833 -32.253428) (xy 276.193299 -32.261961) (xy 276.189468 -32.281373)
			(xy 276.193278 -32.300789) (xy 276.19833 -32.309308) (xy 276.40407 -32.622744) (xy 276.405086 -32.624776)
			(xy 276.406356 -32.626808) (xy 276.411944 -32.635444) (xy 276.411944 -32.64408) (xy 276.412198 -32.64662)
			(xy 276.412452 -32.650684) (xy 276.412452 -32.714184) (xy 277.047452 -32.714184) (xy 277.047452 -31.850584)
			(xy 277.047942 -31.820616) (xy 277.055765 -31.761194) (xy 277.071278 -31.703301) (xy 277.094214 -31.647928)
			(xy 277.124181 -31.596022) (xy 277.160668 -31.548472) (xy 277.203048 -31.506092) (xy 277.250598 -31.469605)
			(xy 277.302504 -31.439638) (xy 277.357877 -31.416702) (xy 277.41577 -31.401189) (xy 277.475192 -31.393366)
			(xy 277.535128 -31.393366) (xy 277.59455 -31.401189) (xy 277.652443 -31.416702) (xy 277.707816 -31.439638)
			(xy 277.759722 -31.469605) (xy 277.807272 -31.506092) (xy 277.849652 -31.548472) (xy 277.886139 -31.596022)
			(xy 277.916106 -31.647928) (xy 277.939042 -31.703301) (xy 277.954555 -31.761194) (xy 277.962378 -31.820616)
			(xy 277.962868 -31.850584) (xy 277.962868 -32.714184) (xy 277.962735 -32.722312) (xy 292.806628 -32.722312)
			(xy 292.806628 -31.858712) (xy 292.807118 -31.828728) (xy 292.814946 -31.769272) (xy 292.830467 -31.711347)
			(xy 292.853416 -31.655943) (xy 292.8834 -31.604009) (xy 292.919906 -31.556433) (xy 292.962311 -31.514028)
			(xy 293.009887 -31.477522) (xy 293.061821 -31.447538) (xy 293.117225 -31.424589) (xy 293.17515 -31.409068)
			(xy 293.234606 -31.40124) (xy 293.294574 -31.40124) (xy 293.35403 -31.409068) (xy 293.411955 -31.424589)
			(xy 293.467359 -31.447538) (xy 293.519293 -31.477522) (xy 293.566869 -31.514028) (xy 293.609274 -31.556433)
			(xy 293.64578 -31.604009) (xy 293.675764 -31.655943) (xy 293.698713 -31.711347) (xy 293.714234 -31.769272)
			(xy 293.722062 -31.828728) (xy 293.722552 -31.858712) (xy 293.722552 -32.722312) (xy 293.722062 -32.752296)
			(xy 293.715007 -32.805878) (xy 294.229028 -32.805878) (xy 294.229028 -31.77413) (xy 294.229488 -31.763962)
			(xy 294.237262 -31.74517) (xy 294.251636 -31.730784) (xy 294.270422 -31.722996) (xy 294.28059 -31.722568)
			(xy 295.51249 -31.722568) (xy 295.522665 -31.722973) (xy 295.541465 -31.73076) (xy 295.555851 -31.745152)
			(xy 295.563631 -31.763955) (xy 295.564052 -31.77413) (xy 295.564052 -32.805878) (xy 298.765468 -32.805878)
			(xy 298.765468 -31.77413) (xy 298.765889 -31.763957) (xy 298.77367 -31.745157) (xy 298.788057 -31.73077)
			(xy 298.806857 -31.722989) (xy 298.81703 -31.722568) (xy 300.04893 -31.722568) (xy 300.059093 -31.723009)
			(xy 300.077869 -31.730799) (xy 300.092234 -31.745181) (xy 300.100002 -31.763966) (xy 300.100492 -31.77413)
			(xy 300.100492 -32.805878) (xy 300.09995 -32.816031) (xy 300.092188 -32.834794) (xy 300.077837 -32.849159)
			(xy 300.059082 -32.856939) (xy 300.04893 -32.85744) (xy 298.81703 -32.85744) (xy 298.806858 -32.857011)
			(xy 298.788059 -32.849232) (xy 298.773673 -32.834847) (xy 298.765891 -32.81605) (xy 298.765468 -32.805878)
			(xy 295.564052 -32.805878) (xy 295.563618 -32.816049) (xy 295.555838 -32.834845) (xy 295.541456 -32.849231)
			(xy 295.522661 -32.857015) (xy 295.51249 -32.85744) (xy 294.28059 -32.85744) (xy 294.270415 -32.857044)
			(xy 294.251616 -32.849251) (xy 294.237231 -32.834857) (xy 294.22945 -32.816053) (xy 294.229028 -32.805878)
			(xy 293.715007 -32.805878) (xy 293.714234 -32.811752) (xy 293.698713 -32.869677) (xy 293.694628 -32.879538)
			(xy 301.572168 -32.879538) (xy 301.572168 -32.651954) (xy 301.572422 -32.64789) (xy 301.572676 -32.64535)
			(xy 301.572676 -32.636714) (xy 301.578264 -32.628078) (xy 301.579534 -32.626046) (xy 301.58055 -32.624014)
			(xy 301.777908 -32.323024) (xy 301.781776 -32.316696) (xy 301.786037 -32.302496) (xy 301.78629 -32.295084)
			(xy 301.78629 -32.26943) (xy 301.786085 -32.262096) (xy 301.781954 -32.248025) (xy 301.778162 -32.241744)
			(xy 301.580296 -31.938722) (xy 301.57801 -31.934912) (xy 301.577756 -31.934404) (xy 301.57674 -31.932626)
			(xy 301.572676 -31.926022) (xy 301.572676 -31.917894) (xy 301.572422 -31.915354) (xy 301.572168 -31.91129)
			(xy 301.572168 -31.683198) (xy 301.572563 -31.673023) (xy 301.580354 -31.654222) (xy 301.594749 -31.639836)
			(xy 301.613554 -31.632057) (xy 301.62373 -31.631636) (xy 302.360584 -31.631636) (xy 302.370754 -31.632187)
			(xy 302.389557 -31.639938) (xy 302.403983 -31.654276) (xy 302.41185 -31.673032) (xy 302.4124 -31.683198)
			(xy 302.4124 -31.910782) (xy 302.412146 -31.914846) (xy 302.411892 -31.917386) (xy 302.411892 -31.926022)
			(xy 302.40605 -31.93542) (xy 302.405288 -31.93669) (xy 302.404018 -31.938722) (xy 302.198278 -32.253428)
			(xy 302.193251 -32.261962) (xy 302.189424 -32.281373) (xy 302.19323 -32.300788) (xy 302.198278 -32.309308)
			(xy 302.404018 -32.622744) (xy 302.405034 -32.624776) (xy 302.406304 -32.626808) (xy 302.411892 -32.635444)
			(xy 302.411892 -32.64408) (xy 302.412146 -32.64662) (xy 302.4124 -32.650684) (xy 302.4124 -32.714184)
			(xy 303.0474 -32.714184) (xy 303.0474 -31.850584) (xy 303.04789 -31.820616) (xy 303.055713 -31.761194)
			(xy 303.071226 -31.703301) (xy 303.094162 -31.647928) (xy 303.124129 -31.596022) (xy 303.160616 -31.548472)
			(xy 303.202996 -31.506092) (xy 303.250546 -31.469605) (xy 303.302452 -31.439638) (xy 303.357825 -31.416702)
			(xy 303.415718 -31.401189) (xy 303.47514 -31.393366) (xy 303.535076 -31.393366) (xy 303.594498 -31.401189)
			(xy 303.652391 -31.416702) (xy 303.707764 -31.439638) (xy 303.75967 -31.469605) (xy 303.80722 -31.506092)
			(xy 303.8496 -31.548472) (xy 303.886087 -31.596022) (xy 303.916054 -31.647928) (xy 303.93899 -31.703301)
			(xy 303.954503 -31.761194) (xy 303.962326 -31.820616) (xy 303.962816 -31.850584) (xy 303.962816 -32.714184)
			(xy 303.962683 -32.722312) (xy 318.806576 -32.722312) (xy 318.806576 -31.858712) (xy 318.807066 -31.828728)
			(xy 318.814894 -31.769272) (xy 318.830415 -31.711347) (xy 318.853364 -31.655943) (xy 318.883348 -31.604009)
			(xy 318.919854 -31.556433) (xy 318.962259 -31.514028) (xy 319.009835 -31.477522) (xy 319.061769 -31.447538)
			(xy 319.117173 -31.424589) (xy 319.175098 -31.409068) (xy 319.234554 -31.40124) (xy 319.294522 -31.40124)
			(xy 319.353978 -31.409068) (xy 319.411903 -31.424589) (xy 319.467307 -31.447538) (xy 319.519241 -31.477522)
			(xy 319.566817 -31.514028) (xy 319.609222 -31.556433) (xy 319.645728 -31.604009) (xy 319.675712 -31.655943)
			(xy 319.698661 -31.711347) (xy 319.714182 -31.769272) (xy 319.72201 -31.828728) (xy 319.7225 -31.858712)
			(xy 319.7225 -32.722312) (xy 319.72201 -32.752296) (xy 319.714955 -32.805878) (xy 320.228976 -32.805878)
			(xy 320.228976 -31.77413) (xy 320.229389 -31.763956) (xy 320.237172 -31.745154) (xy 320.251561 -31.730767)
			(xy 320.270364 -31.722988) (xy 320.280538 -31.722568) (xy 321.512438 -31.722568) (xy 321.522602 -31.723003)
			(xy 321.541378 -31.730796) (xy 321.555743 -31.745179) (xy 321.56351 -31.763965) (xy 321.564 -31.77413)
			(xy 321.564 -32.805878) (xy 324.765416 -32.805878) (xy 324.765416 -31.77413) (xy 324.765888 -31.763963)
			(xy 324.773659 -31.745173) (xy 324.78803 -31.730788) (xy 324.806812 -31.722998) (xy 324.816978 -31.722568)
			(xy 326.048878 -31.722568) (xy 326.059052 -31.722983) (xy 326.077852 -31.730766) (xy 326.092238 -31.745155)
			(xy 326.100019 -31.763956) (xy 326.10044 -31.77413) (xy 326.10044 -32.805878) (xy 326.100017 -32.816051)
			(xy 326.092236 -32.834849) (xy 326.077849 -32.849236) (xy 326.059051 -32.857017) (xy 326.048878 -32.85744)
			(xy 324.816978 -32.85744) (xy 324.806816 -32.856984) (xy 324.788042 -32.849198) (xy 324.773677 -32.834821)
			(xy 324.765907 -32.81604) (xy 324.765416 -32.805878) (xy 321.564 -32.805878) (xy 321.56345 -32.81603)
			(xy 321.55569 -32.834791) (xy 321.541342 -32.849156) (xy 321.522589 -32.856938) (xy 321.512438 -32.85744)
			(xy 320.280538 -32.85744) (xy 320.270366 -32.857004) (xy 320.251568 -32.849228) (xy 320.237181 -32.834845)
			(xy 320.229399 -32.81605) (xy 320.228976 -32.805878) (xy 319.714955 -32.805878) (xy 319.714182 -32.811752)
			(xy 319.698661 -32.869677) (xy 319.694576 -32.879538) (xy 327.572116 -32.879538) (xy 327.572116 -32.651954)
			(xy 327.57237 -32.64789) (xy 327.572624 -32.64535) (xy 327.572624 -32.636714) (xy 327.578212 -32.628078)
			(xy 327.579482 -32.626046) (xy 327.580498 -32.624014) (xy 327.777856 -32.323024) (xy 327.781728 -32.316698)
			(xy 327.785986 -32.302497) (xy 327.786238 -32.295084) (xy 327.786238 -32.26943) (xy 327.786041 -32.262095)
			(xy 327.781905 -32.248024) (xy 327.77811 -32.241744) (xy 327.580244 -31.938722) (xy 327.577958 -31.934912)
			(xy 327.577704 -31.934404) (xy 327.576688 -31.932626) (xy 327.572624 -31.926022) (xy 327.572624 -31.917894)
			(xy 327.57237 -31.915354) (xy 327.572116 -31.91129) (xy 327.572116 -31.683198) (xy 327.572631 -31.673043)
			(xy 327.580402 -31.654278) (xy 327.594761 -31.639913) (xy 327.613523 -31.632135) (xy 327.623678 -31.631636)
			(xy 328.360532 -31.631636) (xy 328.370705 -31.632147) (xy 328.38951 -31.639915) (xy 328.403934 -31.654264)
			(xy 328.411799 -31.673028) (xy 328.412348 -31.683198) (xy 328.412348 -31.910782) (xy 328.412094 -31.914846)
			(xy 328.41184 -31.917386) (xy 328.41184 -31.926022) (xy 328.405998 -31.93542) (xy 328.405236 -31.93669)
			(xy 328.403966 -31.938722) (xy 328.198226 -32.253428) (xy 328.193195 -32.261961) (xy 328.189364 -32.281373)
			(xy 328.193175 -32.300789) (xy 328.198226 -32.309308) (xy 328.403966 -32.622744) (xy 328.404982 -32.624776)
			(xy 328.406252 -32.626808) (xy 328.41184 -32.635444) (xy 328.41184 -32.64408) (xy 328.412094 -32.64662)
			(xy 328.412348 -32.650684) (xy 328.412348 -32.714184) (xy 329.047348 -32.714184) (xy 329.047348 -31.850584)
			(xy 329.047838 -31.820616) (xy 329.055661 -31.761194) (xy 329.071174 -31.703301) (xy 329.09411 -31.647928)
			(xy 329.124077 -31.596022) (xy 329.160564 -31.548472) (xy 329.202944 -31.506092) (xy 329.250494 -31.469605)
			(xy 329.3024 -31.439638) (xy 329.357773 -31.416702) (xy 329.415666 -31.401189) (xy 329.475088 -31.393366)
			(xy 329.535024 -31.393366) (xy 329.594446 -31.401189) (xy 329.652339 -31.416702) (xy 329.707712 -31.439638)
			(xy 329.759618 -31.469605) (xy 329.807168 -31.506092) (xy 329.849548 -31.548472) (xy 329.886035 -31.596022)
			(xy 329.916002 -31.647928) (xy 329.938938 -31.703301) (xy 329.954451 -31.761194) (xy 329.962274 -31.820616)
			(xy 329.962764 -31.850584) (xy 329.962764 -32.714184) (xy 329.962631 -32.722312) (xy 356.907084 -32.722312)
			(xy 356.907084 -31.858712) (xy 356.907574 -31.828744) (xy 356.915397 -31.769322) (xy 356.93091 -31.711429)
			(xy 356.953846 -31.656056) (xy 356.983813 -31.60415) (xy 357.0203 -31.5566) (xy 357.06268 -31.51422)
			(xy 357.11023 -31.477733) (xy 357.162136 -31.447766) (xy 357.217509 -31.42483) (xy 357.275402 -31.409317)
			(xy 357.334824 -31.401494) (xy 357.39476 -31.401494) (xy 357.454182 -31.409317) (xy 357.512075 -31.42483)
			(xy 357.567448 -31.447766) (xy 357.619354 -31.477733) (xy 357.666904 -31.51422) (xy 357.709284 -31.5566)
			(xy 357.745771 -31.60415) (xy 357.775738 -31.656056) (xy 357.798674 -31.711429) (xy 357.814187 -31.769322)
			(xy 357.82201 -31.828744) (xy 357.8225 -31.858712) (xy 357.8225 -32.722312) (xy 357.82201 -32.75228)
			(xy 357.81492 -32.806132) (xy 358.329484 -32.806132) (xy 358.329484 -31.77413) (xy 358.329952 -31.764)
			(xy 358.337678 -31.745271) (xy 358.351971 -31.730912) (xy 358.370664 -31.723099) (xy 358.380792 -31.722568)
			(xy 359.612692 -31.722568) (xy 359.622796 -31.723091) (xy 359.641468 -31.73082) (xy 359.655762 -31.745105)
			(xy 359.663503 -31.763772) (xy 359.664 -31.773876) (xy 359.664 -32.805878) (xy 362.865924 -32.805878)
			(xy 362.865924 -31.77413) (xy 362.86645 -31.764007) (xy 362.874165 -31.74529) (xy 362.88844 -31.730933)
			(xy 362.907112 -31.72311) (xy 362.917232 -31.722568) (xy 364.149132 -31.722568) (xy 364.159284 -31.722995)
			(xy 364.178031 -31.730795) (xy 364.192352 -31.745189) (xy 364.200057 -31.763976) (xy 364.20044 -31.77413)
			(xy 364.20044 -32.805878) (xy 364.199955 -32.816006) (xy 364.192231 -32.83473) (xy 364.177943 -32.849088)
			(xy 364.159257 -32.856905) (xy 364.149132 -32.85744) (xy 362.917232 -32.85744) (xy 362.907085 -32.856953)
			(xy 362.888341 -32.849176) (xy 362.874018 -32.834799) (xy 362.86631 -32.816027) (xy 362.865924 -32.805878)
			(xy 359.664 -32.805878) (xy 359.663457 -32.815998) (xy 359.655744 -32.834712) (xy 359.641475 -32.849067)
			(xy 359.622809 -32.856894) (xy 359.612692 -32.85744) (xy 358.380792 -32.85744) (xy 358.370688 -32.856922)
			(xy 358.352017 -32.849189) (xy 358.337724 -32.834903) (xy 358.329982 -32.816236) (xy 358.329484 -32.806132)
			(xy 357.81492 -32.806132) (xy 357.814187 -32.811702) (xy 357.798674 -32.869595) (xy 357.794556 -32.879538)
			(xy 365.672624 -32.879538) (xy 365.672624 -32.636714) (xy 365.791496 -32.455358) (xy 365.85398 -32.359854)
			(xy 365.87811 -32.323024) (xy 365.881978 -32.316696) (xy 365.886239 -32.302496) (xy 365.886492 -32.295084)
			(xy 365.886492 -32.269176) (xy 365.886304 -32.263026) (xy 365.883346 -32.251085) (xy 365.88065 -32.245554)
			(xy 365.767112 -32.071564) (xy 365.747046 -32.040576) (xy 365.741458 -32.03194) (xy 365.681006 -31.93923)
			(xy 365.680498 -31.938468) (xy 365.67999 -31.937706) (xy 365.679736 -31.937198) (xy 365.679228 -31.936436)
			(xy 365.672624 -31.926022) (xy 365.672624 -31.683198) (xy 365.673131 -31.673042) (xy 365.680904 -31.654275)
			(xy 365.695265 -31.639911) (xy 365.71403 -31.632134) (xy 365.724186 -31.631636) (xy 366.460786 -31.631636)
			(xy 366.470956 -31.632075) (xy 366.489751 -31.639855) (xy 366.504136 -31.654236) (xy 366.511922 -31.673028)
			(xy 366.512348 -31.683198) (xy 366.512348 -31.926022) (xy 366.296448 -32.256476) (xy 366.292419 -32.264695)
			(xy 366.289874 -32.282807) (xy 366.293823 -32.300666) (xy 366.29848 -32.308546) (xy 366.330738 -32.35833)
			(xy 366.512348 -32.635444) (xy 366.512348 -32.714184) (xy 367.147348 -32.714184) (xy 367.147348 -31.850584)
			(xy 367.147838 -31.8206) (xy 367.155666 -31.761144) (xy 367.171187 -31.703219) (xy 367.194136 -31.647815)
			(xy 367.22412 -31.595881) (xy 367.260626 -31.548305) (xy 367.303031 -31.5059) (xy 367.350607 -31.469394)
			(xy 367.402541 -31.43941) (xy 367.457945 -31.416461) (xy 367.51587 -31.40094) (xy 367.575326 -31.393112)
			(xy 367.635294 -31.393112) (xy 367.69475 -31.40094) (xy 367.752675 -31.416461) (xy 367.808079 -31.43941)
			(xy 367.860013 -31.469394) (xy 367.907589 -31.5059) (xy 367.949994 -31.548305) (xy 367.9865 -31.595881)
			(xy 368.016484 -31.647815) (xy 368.039433 -31.703219) (xy 368.054954 -31.761144) (xy 368.062782 -31.8206)
			(xy 368.063272 -31.850584) (xy 368.063272 -32.714184) (xy 368.063139 -32.722312) (xy 382.907032 -32.722312)
			(xy 382.907032 -31.858712) (xy 382.907522 -31.828744) (xy 382.915345 -31.769322) (xy 382.930858 -31.711429)
			(xy 382.953794 -31.656056) (xy 382.983761 -31.60415) (xy 383.020248 -31.5566) (xy 383.062628 -31.51422)
			(xy 383.110178 -31.477733) (xy 383.162084 -31.447766) (xy 383.217457 -31.42483) (xy 383.27535 -31.409317)
			(xy 383.334772 -31.401494) (xy 383.394708 -31.401494) (xy 383.45413 -31.409317) (xy 383.512023 -31.42483)
			(xy 383.567396 -31.447766) (xy 383.619302 -31.477733) (xy 383.666852 -31.51422) (xy 383.709232 -31.5566)
			(xy 383.745719 -31.60415) (xy 383.775686 -31.656056) (xy 383.798622 -31.711429) (xy 383.814135 -31.769322)
			(xy 383.821958 -31.828744) (xy 383.822448 -31.858712) (xy 383.822448 -32.722312) (xy 383.821958 -32.75228)
			(xy 383.814868 -32.806132) (xy 384.329432 -32.806132) (xy 384.329432 -31.77413) (xy 384.329951 -31.764006)
			(xy 384.337667 -31.745287) (xy 384.351944 -31.73093) (xy 384.370619 -31.723108) (xy 384.38074 -31.722568)
			(xy 385.61264 -31.722568) (xy 385.622747 -31.723052) (xy 385.64142 -31.730796) (xy 385.655713 -31.745093)
			(xy 385.663452 -31.763769) (xy 385.663948 -31.773876) (xy 385.663948 -32.805878) (xy 388.865872 -32.805878)
			(xy 388.865872 -31.77413) (xy 388.866352 -31.764001) (xy 388.874076 -31.745275) (xy 388.888365 -31.730916)
			(xy 388.907054 -31.723101) (xy 388.91718 -31.722568) (xy 390.14908 -31.722568) (xy 390.159229 -31.723037)
			(xy 390.177975 -31.73082) (xy 390.192298 -31.745202) (xy 390.200004 -31.76398) (xy 390.200388 -31.77413)
			(xy 390.200388 -32.805878) (xy 390.199856 -32.816) (xy 390.192141 -32.834715) (xy 390.177869 -32.849071)
			(xy 390.159199 -32.856896) (xy 390.14908 -32.85744) (xy 388.91718 -32.85744) (xy 388.90703 -32.856996)
			(xy 388.888284 -32.849201) (xy 388.873963 -32.834812) (xy 388.866257 -32.81603) (xy 388.865872 -32.805878)
			(xy 385.663948 -32.805878) (xy 385.663455 -32.816005) (xy 385.655732 -32.834728) (xy 385.641448 -32.849085)
			(xy 385.622764 -32.856903) (xy 385.61264 -32.85744) (xy 384.38074 -32.85744) (xy 384.370625 -32.856952)
			(xy 384.35193 -32.849225) (xy 384.337616 -32.83493) (xy 384.329862 -32.816246) (xy 384.329432 -32.806132)
			(xy 383.814868 -32.806132) (xy 383.814135 -32.811702) (xy 383.798622 -32.869595) (xy 383.794504 -32.879538)
			(xy 391.672572 -32.879538) (xy 391.672572 -32.636714) (xy 391.791444 -32.455358) (xy 391.853928 -32.359854)
			(xy 391.878058 -32.323024) (xy 391.88193 -32.316698) (xy 391.886188 -32.302497) (xy 391.88644 -32.295084)
			(xy 391.88644 -32.269176) (xy 391.886258 -32.263025) (xy 391.883297 -32.251085) (xy 391.880598 -32.245554)
			(xy 391.76706 -32.071564) (xy 391.746994 -32.040576) (xy 391.741406 -32.03194) (xy 391.680954 -31.93923)
			(xy 391.680446 -31.938468) (xy 391.679938 -31.937706) (xy 391.679684 -31.937198) (xy 391.679176 -31.936436)
			(xy 391.672572 -31.926022) (xy 391.672572 -31.683198) (xy 391.672963 -31.673022) (xy 391.680755 -31.654221)
			(xy 391.695151 -31.639835) (xy 391.713958 -31.632056) (xy 391.724134 -31.631636) (xy 392.460734 -31.631636)
			(xy 392.470894 -31.632105) (xy 392.489663 -31.639891) (xy 392.504027 -31.654264) (xy 392.511801 -31.673038)
			(xy 392.512296 -31.683198) (xy 392.512296 -31.926022) (xy 392.296396 -32.256476) (xy 392.292372 -32.264696)
			(xy 392.28983 -32.282807) (xy 392.293775 -32.300665) (xy 392.298428 -32.308546) (xy 392.330686 -32.35833)
			(xy 392.512296 -32.635444) (xy 392.512296 -32.714184) (xy 393.147296 -32.714184) (xy 393.147296 -31.850584)
			(xy 393.147786 -31.8206) (xy 393.155614 -31.761144) (xy 393.171135 -31.703219) (xy 393.194084 -31.647815)
			(xy 393.224068 -31.595881) (xy 393.260574 -31.548305) (xy 393.302979 -31.5059) (xy 393.350555 -31.469394)
			(xy 393.402489 -31.43941) (xy 393.457893 -31.416461) (xy 393.515818 -31.40094) (xy 393.575274 -31.393112)
			(xy 393.635242 -31.393112) (xy 393.694698 -31.40094) (xy 393.752623 -31.416461) (xy 393.808027 -31.43941)
			(xy 393.859961 -31.469394) (xy 393.907537 -31.5059) (xy 393.949942 -31.548305) (xy 393.986448 -31.595881)
			(xy 394.016432 -31.647815) (xy 394.039381 -31.703219) (xy 394.054902 -31.761144) (xy 394.06273 -31.8206)
			(xy 394.06322 -31.850584) (xy 394.06322 -32.714184) (xy 394.063087 -32.722312) (xy 408.90698 -32.722312)
			(xy 408.90698 -31.858712) (xy 408.90747 -31.828744) (xy 408.915293 -31.769322) (xy 408.930806 -31.711429)
			(xy 408.953742 -31.656056) (xy 408.983709 -31.60415) (xy 409.020196 -31.5566) (xy 409.062576 -31.51422)
			(xy 409.110126 -31.477733) (xy 409.162032 -31.447766) (xy 409.217405 -31.42483) (xy 409.275298 -31.409317)
			(xy 409.33472 -31.401494) (xy 409.394656 -31.401494) (xy 409.454078 -31.409317) (xy 409.511971 -31.42483)
			(xy 409.567344 -31.447766) (xy 409.61925 -31.477733) (xy 409.6668 -31.51422) (xy 409.70918 -31.5566)
			(xy 409.745667 -31.60415) (xy 409.775634 -31.656056) (xy 409.79857 -31.711429) (xy 409.814083 -31.769322)
			(xy 409.821906 -31.828744) (xy 409.822396 -31.858712) (xy 409.822396 -32.722312) (xy 409.821906 -32.75228)
			(xy 409.814816 -32.806132) (xy 410.32938 -32.806132) (xy 410.32938 -31.77413) (xy 410.329852 -31.764)
			(xy 410.337577 -31.745272) (xy 410.351869 -31.730913) (xy 410.370561 -31.7231) (xy 410.380688 -31.722568)
			(xy 411.612588 -31.722568) (xy 411.622692 -31.723094) (xy 411.641364 -31.730822) (xy 411.655658 -31.745106)
			(xy 411.663399 -31.763772) (xy 411.663896 -31.773876) (xy 411.663896 -32.805878) (xy 414.86582 -32.805878)
			(xy 414.86582 -31.77413) (xy 414.86635 -31.764008) (xy 414.874065 -31.745291) (xy 414.888337 -31.730934)
			(xy 414.907009 -31.72311) (xy 414.917128 -31.722568) (xy 416.149028 -31.722568) (xy 416.15918 -31.722998)
			(xy 416.177927 -31.730797) (xy 416.192248 -31.74519) (xy 416.199953 -31.763976) (xy 416.200336 -31.77413)
			(xy 416.200336 -32.805878) (xy 416.199855 -32.816006) (xy 416.19213 -32.834732) (xy 416.177841 -32.849089)
			(xy 416.159154 -32.856905) (xy 416.149028 -32.85744) (xy 414.917128 -32.85744) (xy 414.906981 -32.856956)
			(xy 414.888236 -32.849178) (xy 414.873913 -32.8348) (xy 414.866206 -32.816027) (xy 414.86582 -32.805878)
			(xy 411.663896 -32.805878) (xy 411.663357 -32.815999) (xy 411.655643 -32.834713) (xy 411.641373 -32.849069)
			(xy 411.622706 -32.856895) (xy 411.612588 -32.85744) (xy 410.380688 -32.85744) (xy 410.370583 -32.856925)
			(xy 410.351913 -32.849191) (xy 410.33762 -32.834904) (xy 410.329878 -32.816236) (xy 410.32938 -32.806132)
			(xy 409.814816 -32.806132) (xy 409.814083 -32.811702) (xy 409.79857 -32.869595) (xy 409.794452 -32.879538)
			(xy 417.67252 -32.879538) (xy 417.67252 -32.636714) (xy 417.791392 -32.455358) (xy 417.853876 -32.359854)
			(xy 417.878006 -32.323024) (xy 417.881874 -32.316696) (xy 417.886135 -32.302496) (xy 417.886388 -32.295084)
			(xy 417.886388 -32.269176) (xy 417.886201 -32.263026) (xy 417.883243 -32.251085) (xy 417.880546 -32.245554)
			(xy 417.767008 -32.071564) (xy 417.746942 -32.040576) (xy 417.741354 -32.03194) (xy 417.680902 -31.93923)
			(xy 417.680394 -31.938468) (xy 417.679886 -31.937706) (xy 417.679632 -31.937198) (xy 417.679124 -31.936436)
			(xy 417.67252 -31.926022) (xy 417.67252 -31.683198) (xy 417.673031 -31.673042) (xy 417.680803 -31.654277)
			(xy 417.695163 -31.639912) (xy 417.713926 -31.632135) (xy 417.724082 -31.631636) (xy 418.460682 -31.631636)
			(xy 418.470852 -31.632078) (xy 418.489646 -31.639857) (xy 418.504032 -31.654237) (xy 418.511818 -31.673028)
			(xy 418.512244 -31.683198) (xy 418.512244 -31.926022) (xy 418.296344 -32.256476) (xy 418.292316 -32.264695)
			(xy 418.28977 -32.282807) (xy 418.29372 -32.300666) (xy 418.298376 -32.308546) (xy 418.330634 -32.35833)
			(xy 418.512244 -32.635444) (xy 418.512244 -32.714184) (xy 419.147244 -32.714184) (xy 419.147244 -31.850584)
			(xy 419.147734 -31.8206) (xy 419.155562 -31.761144) (xy 419.171083 -31.703219) (xy 419.194032 -31.647815)
			(xy 419.224016 -31.595881) (xy 419.260522 -31.548305) (xy 419.302927 -31.5059) (xy 419.350503 -31.469394)
			(xy 419.402437 -31.43941) (xy 419.457841 -31.416461) (xy 419.515766 -31.40094) (xy 419.575222 -31.393112)
			(xy 419.63519 -31.393112) (xy 419.694646 -31.40094) (xy 419.752571 -31.416461) (xy 419.807975 -31.43941)
			(xy 419.859909 -31.469394) (xy 419.907485 -31.5059) (xy 419.94989 -31.548305) (xy 419.986396 -31.595881)
			(xy 420.01638 -31.647815) (xy 420.039329 -31.703219) (xy 420.05485 -31.761144) (xy 420.062678 -31.8206)
			(xy 420.063168 -31.850584) (xy 420.063168 -32.714184) (xy 420.063035 -32.722312) (xy 434.906928 -32.722312)
			(xy 434.906928 -31.858712) (xy 434.907418 -31.828744) (xy 434.915241 -31.769322) (xy 434.930754 -31.711429)
			(xy 434.95369 -31.656056) (xy 434.983657 -31.60415) (xy 435.020144 -31.5566) (xy 435.062524 -31.51422)
			(xy 435.110074 -31.477733) (xy 435.16198 -31.447766) (xy 435.217353 -31.42483) (xy 435.275246 -31.409317)
			(xy 435.334668 -31.401494) (xy 435.394604 -31.401494) (xy 435.454026 -31.409317) (xy 435.511919 -31.42483)
			(xy 435.567292 -31.447766) (xy 435.619198 -31.477733) (xy 435.666748 -31.51422) (xy 435.709128 -31.5566)
			(xy 435.745615 -31.60415) (xy 435.775582 -31.656056) (xy 435.798518 -31.711429) (xy 435.814031 -31.769322)
			(xy 435.821854 -31.828744) (xy 435.822344 -31.858712) (xy 435.822344 -32.722312) (xy 435.821854 -32.75228)
			(xy 435.814764 -32.806132) (xy 436.329328 -32.806132) (xy 436.329328 -31.77413) (xy 436.329851 -31.764007)
			(xy 436.337566 -31.745288) (xy 436.351842 -31.730931) (xy 436.370516 -31.723109) (xy 436.380636 -31.722568)
			(xy 437.612536 -31.722568) (xy 437.622643 -31.723055) (xy 437.641316 -31.730798) (xy 437.655608 -31.745094)
			(xy 437.663348 -31.763769) (xy 437.663844 -31.773876) (xy 437.663844 -32.805878) (xy 440.865768 -32.805878)
			(xy 440.865768 -31.77413) (xy 440.866252 -31.764002) (xy 440.873975 -31.745276) (xy 440.888263 -31.730917)
			(xy 440.90695 -31.723102) (xy 440.917076 -31.722568) (xy 442.148976 -31.722568) (xy 442.159125 -31.72304)
			(xy 442.17787 -31.730822) (xy 442.192194 -31.745203) (xy 442.1999 -31.76398) (xy 442.200284 -31.77413)
			(xy 442.200284 -32.805878) (xy 442.199756 -32.816) (xy 442.19204 -32.834717) (xy 442.177767 -32.849073)
			(xy 442.159095 -32.856897) (xy 442.148976 -32.85744) (xy 440.917076 -32.85744) (xy 440.906925 -32.856999)
			(xy 440.88818 -32.849203) (xy 440.873859 -32.834813) (xy 440.866153 -32.816031) (xy 440.865768 -32.805878)
			(xy 437.663844 -32.805878) (xy 437.663355 -32.816005) (xy 437.655632 -32.834729) (xy 437.641346 -32.849087)
			(xy 437.622661 -32.856904) (xy 437.612536 -32.85744) (xy 436.380636 -32.85744) (xy 436.370521 -32.856955)
			(xy 436.351826 -32.849226) (xy 436.337512 -32.834931) (xy 436.329758 -32.816247) (xy 436.329328 -32.806132)
			(xy 435.814764 -32.806132) (xy 435.814031 -32.811702) (xy 435.798518 -32.869595) (xy 435.7944 -32.879538)
			(xy 443.672468 -32.879538) (xy 443.672468 -32.636714) (xy 443.79134 -32.455358) (xy 443.853824 -32.359854)
			(xy 443.877954 -32.323024) (xy 443.881826 -32.316698) (xy 443.886083 -32.302497) (xy 443.886336 -32.295084)
			(xy 443.886336 -32.269176) (xy 443.886154 -32.263025) (xy 443.883193 -32.251084) (xy 443.880494 -32.245554)
			(xy 443.766956 -32.071564) (xy 443.74689 -32.040576) (xy 443.741302 -32.03194) (xy 443.68085 -31.93923)
			(xy 443.680342 -31.938468) (xy 443.679834 -31.937706) (xy 443.67958 -31.937198) (xy 443.679072 -31.936436)
			(xy 443.672468 -31.926022) (xy 443.672468 -31.683198) (xy 443.672863 -31.673023) (xy 443.680654 -31.654222)
			(xy 443.695049 -31.639836) (xy 443.713854 -31.632057) (xy 443.72403 -31.631636) (xy 444.46063 -31.631636)
			(xy 444.470789 -31.632109) (xy 444.489559 -31.639893) (xy 444.503923 -31.654265) (xy 444.511697 -31.673038)
			(xy 444.512192 -31.683198) (xy 444.512192 -31.926022) (xy 444.296292 -32.256476) (xy 444.292269 -32.264696)
			(xy 444.289726 -32.282807) (xy 444.293671 -32.300665) (xy 444.298324 -32.308546) (xy 444.330582 -32.35833)
			(xy 444.512192 -32.635444) (xy 444.512192 -32.714184) (xy 445.147192 -32.714184) (xy 445.147192 -31.850584)
			(xy 445.147682 -31.8206) (xy 445.15551 -31.761144) (xy 445.171031 -31.703219) (xy 445.19398 -31.647815)
			(xy 445.223964 -31.595881) (xy 445.26047 -31.548305) (xy 445.302875 -31.5059) (xy 445.350451 -31.469394)
			(xy 445.402385 -31.43941) (xy 445.457789 -31.416461) (xy 445.515714 -31.40094) (xy 445.57517 -31.393112)
			(xy 445.635138 -31.393112) (xy 445.694594 -31.40094) (xy 445.752519 -31.416461) (xy 445.807923 -31.43941)
			(xy 445.859857 -31.469394) (xy 445.907433 -31.5059) (xy 445.949838 -31.548305) (xy 445.986344 -31.595881)
			(xy 446.016328 -31.647815) (xy 446.039277 -31.703219) (xy 446.054798 -31.761144) (xy 446.062626 -31.8206)
			(xy 446.063116 -31.850584) (xy 446.063116 -32.714184) (xy 446.062626 -32.744168) (xy 446.054798 -32.803624)
			(xy 446.039277 -32.861549) (xy 446.016328 -32.916953) (xy 445.986344 -32.968887) (xy 445.949838 -33.016463)
			(xy 445.907433 -33.058868) (xy 445.859857 -33.095374) (xy 445.807923 -33.125358) (xy 445.752519 -33.148307)
			(xy 445.694594 -33.163828) (xy 445.635138 -33.171656) (xy 445.57517 -33.171656) (xy 445.515714 -33.163828)
			(xy 445.457789 -33.148307) (xy 445.402385 -33.125358) (xy 445.350451 -33.095374) (xy 445.302875 -33.058868)
			(xy 445.26047 -33.016463) (xy 445.223964 -32.968887) (xy 445.19398 -32.916953) (xy 445.171031 -32.861549)
			(xy 445.15551 -32.803624) (xy 445.147682 -32.744168) (xy 445.147192 -32.714184) (xy 444.512192 -32.714184)
			(xy 444.512192 -32.879538) (xy 444.511698 -32.889695) (xy 444.503917 -32.908459) (xy 444.489552 -32.922822)
			(xy 444.470787 -32.9306) (xy 444.46063 -32.9311) (xy 443.72403 -32.9311) (xy 443.713879 -32.930543)
			(xy 443.695117 -32.922786) (xy 443.680752 -32.90844) (xy 443.67297 -32.889689) (xy 443.672468 -32.879538)
			(xy 435.7944 -32.879538) (xy 435.775582 -32.924968) (xy 435.745615 -32.976874) (xy 435.709128 -33.024424)
			(xy 435.666748 -33.066804) (xy 435.619198 -33.103291) (xy 435.567292 -33.133258) (xy 435.511919 -33.156194)
			(xy 435.454026 -33.171707) (xy 435.394604 -33.17953) (xy 435.334668 -33.17953) (xy 435.275246 -33.171707)
			(xy 435.217353 -33.156194) (xy 435.16198 -33.133258) (xy 435.110074 -33.103291) (xy 435.062524 -33.066804)
			(xy 435.020144 -33.024424) (xy 434.983657 -32.976874) (xy 434.95369 -32.924968) (xy 434.930754 -32.869595)
			(xy 434.915241 -32.811702) (xy 434.907418 -32.75228) (xy 434.906928 -32.722312) (xy 420.063035 -32.722312)
			(xy 420.062678 -32.744168) (xy 420.05485 -32.803624) (xy 420.039329 -32.861549) (xy 420.01638 -32.916953)
			(xy 419.986396 -32.968887) (xy 419.94989 -33.016463) (xy 419.907485 -33.058868) (xy 419.859909 -33.095374)
			(xy 419.807975 -33.125358) (xy 419.752571 -33.148307) (xy 419.694646 -33.163828) (xy 419.63519 -33.171656)
			(xy 419.575222 -33.171656) (xy 419.515766 -33.163828) (xy 419.457841 -33.148307) (xy 419.402437 -33.125358)
			(xy 419.350503 -33.095374) (xy 419.302927 -33.058868) (xy 419.260522 -33.016463) (xy 419.224016 -32.968887)
			(xy 419.194032 -32.916953) (xy 419.171083 -32.861549) (xy 419.155562 -32.803624) (xy 419.147734 -32.744168)
			(xy 419.147244 -32.714184) (xy 418.512244 -32.714184) (xy 418.512244 -32.879538) (xy 418.511797 -32.8897)
			(xy 418.504007 -32.908474) (xy 418.489627 -32.922838) (xy 418.470845 -32.930608) (xy 418.460682 -32.9311)
			(xy 417.724082 -32.9311) (xy 417.713928 -32.930583) (xy 417.695165 -32.922809) (xy 417.680802 -32.908451)
			(xy 417.673021 -32.889692) (xy 417.67252 -32.879538) (xy 409.794452 -32.879538) (xy 409.775634 -32.924968)
			(xy 409.745667 -32.976874) (xy 409.70918 -33.024424) (xy 409.6668 -33.066804) (xy 409.61925 -33.103291)
			(xy 409.567344 -33.133258) (xy 409.511971 -33.156194) (xy 409.454078 -33.171707) (xy 409.394656 -33.17953)
			(xy 409.33472 -33.17953) (xy 409.275298 -33.171707) (xy 409.217405 -33.156194) (xy 409.162032 -33.133258)
			(xy 409.110126 -33.103291) (xy 409.062576 -33.066804) (xy 409.020196 -33.024424) (xy 408.983709 -32.976874)
			(xy 408.953742 -32.924968) (xy 408.930806 -32.869595) (xy 408.915293 -32.811702) (xy 408.90747 -32.75228)
			(xy 408.90698 -32.722312) (xy 394.063087 -32.722312) (xy 394.06273 -32.744168) (xy 394.054902 -32.803624)
			(xy 394.039381 -32.861549) (xy 394.016432 -32.916953) (xy 393.986448 -32.968887) (xy 393.949942 -33.016463)
			(xy 393.907537 -33.058868) (xy 393.859961 -33.095374) (xy 393.808027 -33.125358) (xy 393.752623 -33.148307)
			(xy 393.694698 -33.163828) (xy 393.635242 -33.171656) (xy 393.575274 -33.171656) (xy 393.515818 -33.163828)
			(xy 393.457893 -33.148307) (xy 393.402489 -33.125358) (xy 393.350555 -33.095374) (xy 393.302979 -33.058868)
			(xy 393.260574 -33.016463) (xy 393.224068 -32.968887) (xy 393.194084 -32.916953) (xy 393.171135 -32.861549)
			(xy 393.155614 -32.803624) (xy 393.147786 -32.744168) (xy 393.147296 -32.714184) (xy 392.512296 -32.714184)
			(xy 392.512296 -32.879538) (xy 392.511799 -32.889694) (xy 392.504018 -32.908458) (xy 392.489654 -32.92282)
			(xy 392.47089 -32.930599) (xy 392.460734 -32.9311) (xy 391.724134 -32.9311) (xy 391.713983 -32.93054)
			(xy 391.695222 -32.922783) (xy 391.680857 -32.908438) (xy 391.673075 -32.889688) (xy 391.672572 -32.879538)
			(xy 383.794504 -32.879538) (xy 383.775686 -32.924968) (xy 383.745719 -32.976874) (xy 383.709232 -33.024424)
			(xy 383.666852 -33.066804) (xy 383.619302 -33.103291) (xy 383.567396 -33.133258) (xy 383.512023 -33.156194)
			(xy 383.45413 -33.171707) (xy 383.394708 -33.17953) (xy 383.334772 -33.17953) (xy 383.27535 -33.171707)
			(xy 383.217457 -33.156194) (xy 383.162084 -33.133258) (xy 383.110178 -33.103291) (xy 383.062628 -33.066804)
			(xy 383.020248 -33.024424) (xy 382.983761 -32.976874) (xy 382.953794 -32.924968) (xy 382.930858 -32.869595)
			(xy 382.915345 -32.811702) (xy 382.907522 -32.75228) (xy 382.907032 -32.722312) (xy 368.063139 -32.722312)
			(xy 368.062782 -32.744168) (xy 368.054954 -32.803624) (xy 368.039433 -32.861549) (xy 368.016484 -32.916953)
			(xy 367.9865 -32.968887) (xy 367.949994 -33.016463) (xy 367.907589 -33.058868) (xy 367.860013 -33.095374)
			(xy 367.808079 -33.125358) (xy 367.752675 -33.148307) (xy 367.69475 -33.163828) (xy 367.635294 -33.171656)
			(xy 367.575326 -33.171656) (xy 367.51587 -33.163828) (xy 367.457945 -33.148307) (xy 367.402541 -33.125358)
			(xy 367.350607 -33.095374) (xy 367.303031 -33.058868) (xy 367.260626 -33.016463) (xy 367.22412 -32.968887)
			(xy 367.194136 -32.916953) (xy 367.171187 -32.861549) (xy 367.155666 -32.803624) (xy 367.147838 -32.744168)
			(xy 367.147348 -32.714184) (xy 366.512348 -32.714184) (xy 366.512348 -32.879538) (xy 366.511897 -32.8897)
			(xy 366.504108 -32.908473) (xy 366.489729 -32.922837) (xy 366.470948 -32.930608) (xy 366.460786 -32.9311)
			(xy 365.724186 -32.9311) (xy 365.714032 -32.930579) (xy 365.69527 -32.922807) (xy 365.680907 -32.90845)
			(xy 365.673126 -32.889692) (xy 365.672624 -32.879538) (xy 357.794556 -32.879538) (xy 357.775738 -32.924968)
			(xy 357.745771 -32.976874) (xy 357.709284 -33.024424) (xy 357.666904 -33.066804) (xy 357.619354 -33.103291)
			(xy 357.567448 -33.133258) (xy 357.512075 -33.156194) (xy 357.454182 -33.171707) (xy 357.39476 -33.17953)
			(xy 357.334824 -33.17953) (xy 357.275402 -33.171707) (xy 357.217509 -33.156194) (xy 357.162136 -33.133258)
			(xy 357.11023 -33.103291) (xy 357.06268 -33.066804) (xy 357.0203 -33.024424) (xy 356.983813 -32.976874)
			(xy 356.953846 -32.924968) (xy 356.93091 -32.869595) (xy 356.915397 -32.811702) (xy 356.907574 -32.75228)
			(xy 356.907084 -32.722312) (xy 329.962631 -32.722312) (xy 329.962274 -32.744152) (xy 329.954451 -32.803574)
			(xy 329.938938 -32.861467) (xy 329.916002 -32.91684) (xy 329.886035 -32.968746) (xy 329.849548 -33.016296)
			(xy 329.807168 -33.058676) (xy 329.759618 -33.095163) (xy 329.707712 -33.12513) (xy 329.652339 -33.148066)
			(xy 329.594446 -33.163579) (xy 329.535024 -33.171402) (xy 329.475088 -33.171402) (xy 329.415666 -33.163579)
			(xy 329.357773 -33.148066) (xy 329.3024 -33.12513) (xy 329.250494 -33.095163) (xy 329.202944 -33.058676)
			(xy 329.160564 -33.016296) (xy 329.124077 -32.968746) (xy 329.09411 -32.91684) (xy 329.071174 -32.861467)
			(xy 329.055661 -32.803574) (xy 329.047838 -32.744152) (xy 329.047348 -32.714184) (xy 328.412348 -32.714184)
			(xy 328.412348 -32.879538) (xy 328.411897 -32.8897) (xy 328.404108 -32.908473) (xy 328.389729 -32.922837)
			(xy 328.370948 -32.930608) (xy 328.360786 -32.9311) (xy 327.623932 -32.9311) (xy 327.613756 -32.930599)
			(xy 327.59494 -32.92284) (xy 327.580511 -32.908487) (xy 327.572655 -32.889712) (xy 327.572116 -32.879538)
			(xy 319.694576 -32.879538) (xy 319.675712 -32.925081) (xy 319.645728 -32.977015) (xy 319.609222 -33.024591)
			(xy 319.566817 -33.066996) (xy 319.519241 -33.103502) (xy 319.467307 -33.133486) (xy 319.411903 -33.156435)
			(xy 319.353978 -33.171956) (xy 319.294522 -33.179784) (xy 319.234554 -33.179784) (xy 319.175098 -33.171956)
			(xy 319.117173 -33.156435) (xy 319.061769 -33.133486) (xy 319.009835 -33.103502) (xy 318.962259 -33.066996)
			(xy 318.919854 -33.024591) (xy 318.883348 -32.977015) (xy 318.853364 -32.925081) (xy 318.830415 -32.869677)
			(xy 318.814894 -32.811752) (xy 318.807066 -32.752296) (xy 318.806576 -32.722312) (xy 303.962683 -32.722312)
			(xy 303.962326 -32.744152) (xy 303.954503 -32.803574) (xy 303.93899 -32.861467) (xy 303.916054 -32.91684)
			(xy 303.886087 -32.968746) (xy 303.8496 -33.016296) (xy 303.80722 -33.058676) (xy 303.75967 -33.095163)
			(xy 303.707764 -33.12513) (xy 303.652391 -33.148066) (xy 303.594498 -33.163579) (xy 303.535076 -33.171402)
			(xy 303.47514 -33.171402) (xy 303.415718 -33.163579) (xy 303.357825 -33.148066) (xy 303.302452 -33.12513)
			(xy 303.250546 -33.095163) (xy 303.202996 -33.058676) (xy 303.160616 -33.016296) (xy 303.124129 -32.968746)
			(xy 303.094162 -32.91684) (xy 303.071226 -32.861467) (xy 303.055713 -32.803574) (xy 303.04789 -32.744152)
			(xy 303.0474 -32.714184) (xy 302.4124 -32.714184) (xy 302.4124 -32.879538) (xy 302.411899 -32.889694)
			(xy 302.404119 -32.908456) (xy 302.389756 -32.922819) (xy 302.370994 -32.930599) (xy 302.360838 -32.9311)
			(xy 301.623984 -32.9311) (xy 301.613805 -32.930637) (xy 301.594988 -32.922864) (xy 301.580561 -32.908498)
			(xy 301.572707 -32.889715) (xy 301.572168 -32.879538) (xy 293.694628 -32.879538) (xy 293.675764 -32.925081)
			(xy 293.64578 -32.977015) (xy 293.609274 -33.024591) (xy 293.566869 -33.066996) (xy 293.519293 -33.103502)
			(xy 293.467359 -33.133486) (xy 293.411955 -33.156435) (xy 293.35403 -33.171956) (xy 293.294574 -33.179784)
			(xy 293.234606 -33.179784) (xy 293.17515 -33.171956) (xy 293.117225 -33.156435) (xy 293.061821 -33.133486)
			(xy 293.009887 -33.103502) (xy 292.962311 -33.066996) (xy 292.919906 -33.024591) (xy 292.8834 -32.977015)
			(xy 292.853416 -32.925081) (xy 292.830467 -32.869677) (xy 292.814946 -32.811752) (xy 292.807118 -32.752296)
			(xy 292.806628 -32.722312) (xy 277.962735 -32.722312) (xy 277.962378 -32.744152) (xy 277.954555 -32.803574)
			(xy 277.939042 -32.861467) (xy 277.916106 -32.91684) (xy 277.886139 -32.968746) (xy 277.849652 -33.016296)
			(xy 277.807272 -33.058676) (xy 277.759722 -33.095163) (xy 277.707816 -33.12513) (xy 277.652443 -33.148066)
			(xy 277.59455 -33.163579) (xy 277.535128 -33.171402) (xy 277.475192 -33.171402) (xy 277.41577 -33.163579)
			(xy 277.357877 -33.148066) (xy 277.302504 -33.12513) (xy 277.250598 -33.095163) (xy 277.203048 -33.058676)
			(xy 277.160668 -33.016296) (xy 277.124181 -32.968746) (xy 277.094214 -32.91684) (xy 277.071278 -32.861467)
			(xy 277.055765 -32.803574) (xy 277.047942 -32.744152) (xy 277.047452 -32.714184) (xy 276.412452 -32.714184)
			(xy 276.412452 -32.879538) (xy 276.411997 -32.889699) (xy 276.404209 -32.908471) (xy 276.389831 -32.922836)
			(xy 276.371052 -32.930607) (xy 276.36089 -32.9311) (xy 275.624036 -32.9311) (xy 275.61386 -32.930595)
			(xy 275.595044 -32.922838) (xy 275.580616 -32.908485) (xy 275.572759 -32.889711) (xy 275.57222 -32.879538)
			(xy 267.69468 -32.879538) (xy 267.675816 -32.925081) (xy 267.645832 -32.977015) (xy 267.609326 -33.024591)
			(xy 267.566921 -33.066996) (xy 267.519345 -33.103502) (xy 267.467411 -33.133486) (xy 267.412007 -33.156435)
			(xy 267.354082 -33.171956) (xy 267.294626 -33.179784) (xy 267.234658 -33.179784) (xy 267.175202 -33.171956)
			(xy 267.117277 -33.156435) (xy 267.061873 -33.133486) (xy 267.009939 -33.103502) (xy 266.962363 -33.066996)
			(xy 266.919958 -33.024591) (xy 266.883452 -32.977015) (xy 266.853468 -32.925081) (xy 266.830519 -32.869677)
			(xy 266.814998 -32.811752) (xy 266.80717 -32.752296) (xy 266.80668 -32.722312) (xy 251.962787 -32.722312)
			(xy 251.96243 -32.744152) (xy 251.954607 -32.803574) (xy 251.939094 -32.861467) (xy 251.916158 -32.91684)
			(xy 251.886191 -32.968746) (xy 251.849704 -33.016296) (xy 251.807324 -33.058676) (xy 251.759774 -33.095163)
			(xy 251.707868 -33.12513) (xy 251.652495 -33.148066) (xy 251.594602 -33.163579) (xy 251.53518 -33.171402)
			(xy 251.475244 -33.171402) (xy 251.415822 -33.163579) (xy 251.357929 -33.148066) (xy 251.302556 -33.12513)
			(xy 251.25065 -33.095163) (xy 251.2031 -33.058676) (xy 251.16072 -33.016296) (xy 251.124233 -32.968746)
			(xy 251.094266 -32.91684) (xy 251.07133 -32.861467) (xy 251.055817 -32.803574) (xy 251.047994 -32.744152)
			(xy 251.047504 -32.714184) (xy 250.412504 -32.714184) (xy 250.412504 -32.879538) (xy 250.411999 -32.889693)
			(xy 250.40422 -32.908455) (xy 250.389858 -32.922817) (xy 250.371097 -32.930598) (xy 250.360942 -32.9311)
			(xy 249.624088 -32.9311) (xy 249.613909 -32.930634) (xy 249.595092 -32.922862) (xy 249.580665 -32.908497)
			(xy 249.572811 -32.889715) (xy 249.572272 -32.879538) (xy 241.694732 -32.879538) (xy 241.675868 -32.925081)
			(xy 241.645884 -32.977015) (xy 241.609378 -33.024591) (xy 241.566973 -33.066996) (xy 241.519397 -33.103502)
			(xy 241.467463 -33.133486) (xy 241.412059 -33.156435) (xy 241.354134 -33.171956) (xy 241.294678 -33.179784)
			(xy 241.23471 -33.179784) (xy 241.175254 -33.171956) (xy 241.117329 -33.156435) (xy 241.061925 -33.133486)
			(xy 241.009991 -33.103502) (xy 240.962415 -33.066996) (xy 240.92001 -33.024591) (xy 240.883504 -32.977015)
			(xy 240.85352 -32.925081) (xy 240.830571 -32.869677) (xy 240.81505 -32.811752) (xy 240.807222 -32.752296)
			(xy 240.806732 -32.722312) (xy 213.862787 -32.722312) (xy 213.86243 -32.744152) (xy 213.854607 -32.803574)
			(xy 213.839094 -32.861467) (xy 213.816158 -32.91684) (xy 213.786191 -32.968746) (xy 213.749704 -33.016296)
			(xy 213.707324 -33.058676) (xy 213.659774 -33.095163) (xy 213.607868 -33.12513) (xy 213.552495 -33.148066)
			(xy 213.494602 -33.163579) (xy 213.43518 -33.171402) (xy 213.375244 -33.171402) (xy 213.315822 -33.163579)
			(xy 213.257929 -33.148066) (xy 213.202556 -33.12513) (xy 213.15065 -33.095163) (xy 213.1031 -33.058676)
			(xy 213.06072 -33.016296) (xy 213.024233 -32.968746) (xy 212.994266 -32.91684) (xy 212.97133 -32.861467)
			(xy 212.955817 -32.803574) (xy 212.947994 -32.744152) (xy 212.947504 -32.714184) (xy 212.312504 -32.714184)
			(xy 212.312504 -32.879538) (xy 212.311999 -32.889693) (xy 212.30422 -32.908455) (xy 212.289858 -32.922817)
			(xy 212.271097 -32.930598) (xy 212.260942 -32.9311) (xy 211.524088 -32.9311) (xy 211.513909 -32.930634)
			(xy 211.495092 -32.922862) (xy 211.480665 -32.908497) (xy 211.472811 -32.889715) (xy 211.472272 -32.879538)
			(xy 203.594732 -32.879538) (xy 203.575868 -32.925081) (xy 203.545884 -32.977015) (xy 203.509378 -33.024591)
			(xy 203.466973 -33.066996) (xy 203.419397 -33.103502) (xy 203.367463 -33.133486) (xy 203.312059 -33.156435)
			(xy 203.254134 -33.171956) (xy 203.194678 -33.179784) (xy 203.13471 -33.179784) (xy 203.075254 -33.171956)
			(xy 203.017329 -33.156435) (xy 202.961925 -33.133486) (xy 202.909991 -33.103502) (xy 202.862415 -33.066996)
			(xy 202.82001 -33.024591) (xy 202.783504 -32.977015) (xy 202.75352 -32.925081) (xy 202.730571 -32.869677)
			(xy 202.71505 -32.811752) (xy 202.707222 -32.752296) (xy 202.706732 -32.722312) (xy 187.862839 -32.722312)
			(xy 187.862482 -32.744152) (xy 187.854659 -32.803574) (xy 187.839146 -32.861467) (xy 187.81621 -32.91684)
			(xy 187.786243 -32.968746) (xy 187.749756 -33.016296) (xy 187.707376 -33.058676) (xy 187.659826 -33.095163)
			(xy 187.60792 -33.12513) (xy 187.552547 -33.148066) (xy 187.494654 -33.163579) (xy 187.435232 -33.171402)
			(xy 187.375296 -33.171402) (xy 187.315874 -33.163579) (xy 187.257981 -33.148066) (xy 187.202608 -33.12513)
			(xy 187.150702 -33.095163) (xy 187.103152 -33.058676) (xy 187.060772 -33.016296) (xy 187.024285 -32.968746)
			(xy 186.994318 -32.91684) (xy 186.971382 -32.861467) (xy 186.955869 -32.803574) (xy 186.948046 -32.744152)
			(xy 186.947556 -32.714184) (xy 186.312556 -32.714184) (xy 186.312556 -32.879538) (xy 186.312098 -32.889699)
			(xy 186.30431 -32.90847) (xy 186.289933 -32.922834) (xy 186.271155 -32.930606) (xy 186.260994 -32.9311)
			(xy 185.52414 -32.9311) (xy 185.513964 -32.930592) (xy 185.495149 -32.922836) (xy 185.48072 -32.908485)
			(xy 185.472864 -32.889711) (xy 185.472324 -32.879538) (xy 177.594784 -32.879538) (xy 177.57592 -32.925081)
			(xy 177.545936 -32.977015) (xy 177.50943 -33.024591) (xy 177.467025 -33.066996) (xy 177.419449 -33.103502)
			(xy 177.367515 -33.133486) (xy 177.312111 -33.156435) (xy 177.254186 -33.171956) (xy 177.19473 -33.179784)
			(xy 177.134762 -33.179784) (xy 177.075306 -33.171956) (xy 177.017381 -33.156435) (xy 176.961977 -33.133486)
			(xy 176.910043 -33.103502) (xy 176.862467 -33.066996) (xy 176.820062 -33.024591) (xy 176.783556 -32.977015)
			(xy 176.753572 -32.925081) (xy 176.730623 -32.869677) (xy 176.715102 -32.811752) (xy 176.707274 -32.752296)
			(xy 176.706784 -32.722312) (xy 161.862891 -32.722312) (xy 161.862534 -32.744152) (xy 161.854711 -32.803574)
			(xy 161.839198 -32.861467) (xy 161.816262 -32.91684) (xy 161.786295 -32.968746) (xy 161.749808 -33.016296)
			(xy 161.707428 -33.058676) (xy 161.659878 -33.095163) (xy 161.607972 -33.12513) (xy 161.552599 -33.148066)
			(xy 161.494706 -33.163579) (xy 161.435284 -33.171402) (xy 161.375348 -33.171402) (xy 161.315926 -33.163579)
			(xy 161.258033 -33.148066) (xy 161.20266 -33.12513) (xy 161.150754 -33.095163) (xy 161.103204 -33.058676)
			(xy 161.060824 -33.016296) (xy 161.024337 -32.968746) (xy 160.99437 -32.91684) (xy 160.971434 -32.861467)
			(xy 160.955921 -32.803574) (xy 160.948098 -32.744152) (xy 160.947608 -32.714184) (xy 160.312608 -32.714184)
			(xy 160.312608 -32.879538) (xy 160.312099 -32.889693) (xy 160.304321 -32.908454) (xy 160.28996 -32.922816)
			(xy 160.2712 -32.930597) (xy 160.261046 -32.9311) (xy 159.524192 -32.9311) (xy 159.514013 -32.930631)
			(xy 159.495197 -32.92286) (xy 159.480769 -32.908496) (xy 159.472915 -32.889715) (xy 159.472376 -32.879538)
			(xy 151.594836 -32.879538) (xy 151.575972 -32.925081) (xy 151.545988 -32.977015) (xy 151.509482 -33.024591)
			(xy 151.467077 -33.066996) (xy 151.419501 -33.103502) (xy 151.367567 -33.133486) (xy 151.312163 -33.156435)
			(xy 151.254238 -33.171956) (xy 151.194782 -33.179784) (xy 151.134814 -33.179784) (xy 151.075358 -33.171956)
			(xy 151.017433 -33.156435) (xy 150.962029 -33.133486) (xy 150.910095 -33.103502) (xy 150.862519 -33.066996)
			(xy 150.820114 -33.024591) (xy 150.783608 -32.977015) (xy 150.753624 -32.925081) (xy 150.730675 -32.869677)
			(xy 150.715154 -32.811752) (xy 150.707326 -32.752296) (xy 150.706836 -32.722312) (xy 135.862943 -32.722312)
			(xy 135.862586 -32.744152) (xy 135.854763 -32.803574) (xy 135.83925 -32.861467) (xy 135.816314 -32.91684)
			(xy 135.786347 -32.968746) (xy 135.74986 -33.016296) (xy 135.70748 -33.058676) (xy 135.65993 -33.095163)
			(xy 135.608024 -33.12513) (xy 135.552651 -33.148066) (xy 135.494758 -33.163579) (xy 135.435336 -33.171402)
			(xy 135.3754 -33.171402) (xy 135.315978 -33.163579) (xy 135.258085 -33.148066) (xy 135.202712 -33.12513)
			(xy 135.150806 -33.095163) (xy 135.103256 -33.058676) (xy 135.060876 -33.016296) (xy 135.024389 -32.968746)
			(xy 134.994422 -32.91684) (xy 134.971486 -32.861467) (xy 134.955973 -32.803574) (xy 134.94815 -32.744152)
			(xy 134.94766 -32.714184) (xy 134.31266 -32.714184) (xy 134.31266 -32.879538) (xy 134.312198 -32.889698)
			(xy 134.30441 -32.908469) (xy 134.290035 -32.922833) (xy 134.271259 -32.930606) (xy 134.261098 -32.9311)
			(xy 133.524244 -32.9311) (xy 133.514068 -32.930588) (xy 133.495253 -32.922834) (xy 133.480824 -32.908484)
			(xy 133.472968 -32.889711) (xy 133.472428 -32.879538) (xy 125.594888 -32.879538) (xy 125.576024 -32.925081)
			(xy 125.54604 -32.977015) (xy 125.509534 -33.024591) (xy 125.467129 -33.066996) (xy 125.419553 -33.103502)
			(xy 125.367619 -33.133486) (xy 125.312215 -33.156435) (xy 125.25429 -33.171956) (xy 125.194834 -33.179784)
			(xy 125.134866 -33.179784) (xy 125.07541 -33.171956) (xy 125.017485 -33.156435) (xy 124.962081 -33.133486)
			(xy 124.910147 -33.103502) (xy 124.862571 -33.066996) (xy 124.820166 -33.024591) (xy 124.78366 -32.977015)
			(xy 124.753676 -32.925081) (xy 124.730727 -32.869677) (xy 124.715206 -32.811752) (xy 124.707378 -32.752296)
			(xy 124.706888 -32.722312) (xy 97.762943 -32.722312) (xy 97.762586 -32.744168) (xy 97.754758 -32.803624)
			(xy 97.739237 -32.861549) (xy 97.716288 -32.916953) (xy 97.686304 -32.968887) (xy 97.649798 -33.016463)
			(xy 97.607393 -33.058868) (xy 97.559817 -33.095374) (xy 97.507883 -33.125358) (xy 97.452479 -33.148307)
			(xy 97.394554 -33.163828) (xy 97.335098 -33.171656) (xy 97.27513 -33.171656) (xy 97.215674 -33.163828)
			(xy 97.157749 -33.148307) (xy 97.102345 -33.125358) (xy 97.050411 -33.095374) (xy 97.002835 -33.058868)
			(xy 96.96043 -33.016463) (xy 96.923924 -32.968887) (xy 96.89394 -32.916953) (xy 96.870991 -32.861549)
			(xy 96.85547 -32.803624) (xy 96.847642 -32.744168) (xy 96.847152 -32.714184) (xy 96.212152 -32.714184)
			(xy 96.212152 -32.879538) (xy 96.211697 -32.889699) (xy 96.203909 -32.908471) (xy 96.189531 -32.922836)
			(xy 96.170752 -32.930607) (xy 96.16059 -32.9311) (xy 95.42399 -32.9311) (xy 95.413836 -32.930576)
			(xy 95.395074 -32.922805) (xy 95.380711 -32.908449) (xy 95.37293 -32.889691) (xy 95.372428 -32.879538)
			(xy 87.49436 -32.879538) (xy 87.475542 -32.924968) (xy 87.445575 -32.976874) (xy 87.409088 -33.024424)
			(xy 87.366708 -33.066804) (xy 87.319158 -33.103291) (xy 87.267252 -33.133258) (xy 87.211879 -33.156194)
			(xy 87.153986 -33.171707) (xy 87.094564 -33.17953) (xy 87.034628 -33.17953) (xy 86.975206 -33.171707)
			(xy 86.917313 -33.156194) (xy 86.86194 -33.133258) (xy 86.810034 -33.103291) (xy 86.762484 -33.066804)
			(xy 86.720104 -33.024424) (xy 86.683617 -32.976874) (xy 86.65365 -32.924968) (xy 86.630714 -32.869595)
			(xy 86.615201 -32.811702) (xy 86.607378 -32.75228) (xy 86.606888 -32.722312) (xy 71.762995 -32.722312)
			(xy 71.762638 -32.744168) (xy 71.75481 -32.803624) (xy 71.739289 -32.861549) (xy 71.71634 -32.916953)
			(xy 71.686356 -32.968887) (xy 71.64985 -33.016463) (xy 71.607445 -33.058868) (xy 71.559869 -33.095374)
			(xy 71.507935 -33.125358) (xy 71.452531 -33.148307) (xy 71.394606 -33.163828) (xy 71.33515 -33.171656)
			(xy 71.275182 -33.171656) (xy 71.215726 -33.163828) (xy 71.157801 -33.148307) (xy 71.102397 -33.125358)
			(xy 71.050463 -33.095374) (xy 71.002887 -33.058868) (xy 70.960482 -33.016463) (xy 70.923976 -32.968887)
			(xy 70.893992 -32.916953) (xy 70.871043 -32.861549) (xy 70.855522 -32.803624) (xy 70.847694 -32.744168)
			(xy 70.847204 -32.714184) (xy 70.212204 -32.714184) (xy 70.212204 -32.879538) (xy 70.211699 -32.889693)
			(xy 70.20392 -32.908455) (xy 70.189558 -32.922817) (xy 70.170797 -32.930598) (xy 70.160642 -32.9311)
			(xy 69.424042 -32.9311) (xy 69.413878 -32.930603) (xy 69.395091 -32.922839) (xy 69.380706 -32.908476)
			(xy 69.372913 -32.889702) (xy 69.37248 -32.879538) (xy 61.494412 -32.879538) (xy 61.475594 -32.924968)
			(xy 61.445627 -32.976874) (xy 61.40914 -33.024424) (xy 61.36676 -33.066804) (xy 61.31921 -33.103291)
			(xy 61.267304 -33.133258) (xy 61.211931 -33.156194) (xy 61.154038 -33.171707) (xy 61.094616 -33.17953)
			(xy 61.03468 -33.17953) (xy 60.975258 -33.171707) (xy 60.917365 -33.156194) (xy 60.861992 -33.133258)
			(xy 60.810086 -33.103291) (xy 60.762536 -33.066804) (xy 60.720156 -33.024424) (xy 60.683669 -32.976874)
			(xy 60.653702 -32.924968) (xy 60.630766 -32.869595) (xy 60.615253 -32.811702) (xy 60.60743 -32.75228)
			(xy 60.60694 -32.722312) (xy 45.763047 -32.722312) (xy 45.76269 -32.744168) (xy 45.754862 -32.803624)
			(xy 45.739341 -32.861549) (xy 45.716392 -32.916953) (xy 45.686408 -32.968887) (xy 45.649902 -33.016463)
			(xy 45.607497 -33.058868) (xy 45.559921 -33.095374) (xy 45.507987 -33.125358) (xy 45.452583 -33.148307)
			(xy 45.394658 -33.163828) (xy 45.335202 -33.171656) (xy 45.275234 -33.171656) (xy 45.215778 -33.163828)
			(xy 45.157853 -33.148307) (xy 45.102449 -33.125358) (xy 45.050515 -33.095374) (xy 45.002939 -33.058868)
			(xy 44.960534 -33.016463) (xy 44.924028 -32.968887) (xy 44.894044 -32.916953) (xy 44.871095 -32.861549)
			(xy 44.855574 -32.803624) (xy 44.847746 -32.744168) (xy 44.847256 -32.714184) (xy 44.212256 -32.714184)
			(xy 44.212256 -32.879538) (xy 44.211798 -32.889699) (xy 44.20401 -32.90847) (xy 44.189633 -32.922834)
			(xy 44.170855 -32.930606) (xy 44.160694 -32.9311) (xy 43.424094 -32.9311) (xy 43.413941 -32.930572)
			(xy 43.395179 -32.922803) (xy 43.380815 -32.908448) (xy 43.373034 -32.889691) (xy 43.372532 -32.879538)
			(xy 35.494464 -32.879538) (xy 35.475646 -32.924968) (xy 35.445679 -32.976874) (xy 35.409192 -33.024424)
			(xy 35.366812 -33.066804) (xy 35.319262 -33.103291) (xy 35.267356 -33.133258) (xy 35.211983 -33.156194)
			(xy 35.15409 -33.171707) (xy 35.094668 -33.17953) (xy 35.034732 -33.17953) (xy 34.97531 -33.171707)
			(xy 34.917417 -33.156194) (xy 34.862044 -33.133258) (xy 34.810138 -33.103291) (xy 34.762588 -33.066804)
			(xy 34.720208 -33.024424) (xy 34.683721 -32.976874) (xy 34.653754 -32.924968) (xy 34.630818 -32.869595)
			(xy 34.615305 -32.811702) (xy 34.607482 -32.75228) (xy 34.606992 -32.722312) (xy 19.763099 -32.722312)
			(xy 19.762742 -32.744168) (xy 19.754914 -32.803624) (xy 19.739393 -32.861549) (xy 19.716444 -32.916953)
			(xy 19.68646 -32.968887) (xy 19.649954 -33.016463) (xy 19.607549 -33.058868) (xy 19.559973 -33.095374)
			(xy 19.508039 -33.125358) (xy 19.452635 -33.148307) (xy 19.39471 -33.163828) (xy 19.335254 -33.171656)
			(xy 19.275286 -33.171656) (xy 19.21583 -33.163828) (xy 19.157905 -33.148307) (xy 19.102501 -33.125358)
			(xy 19.050567 -33.095374) (xy 19.002991 -33.058868) (xy 18.960586 -33.016463) (xy 18.92408 -32.968887)
			(xy 18.894096 -32.916953) (xy 18.871147 -32.861549) (xy 18.855626 -32.803624) (xy 18.847798 -32.744168)
			(xy 18.847308 -32.714184) (xy 18.212308 -32.714184) (xy 18.212308 -32.879538) (xy 18.211799 -32.889693)
			(xy 18.204021 -32.908454) (xy 18.18966 -32.922816) (xy 18.1709 -32.930597) (xy 18.160746 -32.9311)
			(xy 17.424146 -32.9311) (xy 17.413982 -32.930599) (xy 17.395196 -32.922837) (xy 17.380811 -32.908475)
			(xy 17.373017 -32.889701) (xy 17.372584 -32.879538) (xy 9.494516 -32.879538) (xy 9.475698 -32.924968)
			(xy 9.445731 -32.976874) (xy 9.409244 -33.024424) (xy 9.366864 -33.066804) (xy 9.319314 -33.103291)
			(xy 9.267408 -33.133258) (xy 9.212035 -33.156194) (xy 9.154142 -33.171707) (xy 9.09472 -33.17953)
			(xy 9.034784 -33.17953) (xy 8.975362 -33.171707) (xy 8.917469 -33.156194) (xy 8.862096 -33.133258)
			(xy 8.81019 -33.103291) (xy 8.76264 -33.066804) (xy 8.72026 -33.024424) (xy 8.683773 -32.976874)
			(xy 8.653806 -32.924968) (xy 8.63087 -32.869595) (xy 8.615357 -32.811702) (xy 8.607534 -32.75228)
			(xy 8.607044 -32.722312) (xy 0.509016 -32.722312) (xy 0.509016 -34.52241) (xy 6.752844 -34.52241)
			(xy 6.752844 -33.65881) (xy 6.753334 -33.628842) (xy 6.761157 -33.56942) (xy 6.77667 -33.511527)
			(xy 6.799606 -33.456154) (xy 6.829573 -33.404248) (xy 6.86606 -33.356698) (xy 6.90844 -33.314318)
			(xy 6.95599 -33.277831) (xy 7.007896 -33.247864) (xy 7.063269 -33.224928) (xy 7.121162 -33.209415)
			(xy 7.180584 -33.201592) (xy 7.24052 -33.201592) (xy 7.299942 -33.209415) (xy 7.357835 -33.224928)
			(xy 7.413208 -33.247864) (xy 7.465114 -33.277831) (xy 7.512664 -33.314318) (xy 7.555044 -33.356698)
			(xy 7.591531 -33.404248) (xy 7.621498 -33.456154) (xy 7.644434 -33.511527) (xy 7.659947 -33.56942)
			(xy 7.66777 -33.628842) (xy 7.66826 -33.65881) (xy 7.66826 -34.52241) (xy 7.66777 -34.552378) (xy 7.660714 -34.605976)
			(xy 10.029444 -34.605976) (xy 10.029444 -33.574228) (xy 10.030006 -33.564128) (xy 10.037725 -33.545461)
			(xy 10.051997 -33.531167) (xy 10.070653 -33.523421) (xy 10.080752 -33.52292) (xy 11.312652 -33.52292)
			(xy 11.322774 -33.523356) (xy 11.34148 -33.531092) (xy 11.355797 -33.545403) (xy 11.36354 -33.564106)
			(xy 11.36396 -33.574228) (xy 11.36396 -34.605976) (xy 14.565884 -34.605976) (xy 14.565884 -33.574228)
			(xy 14.566338 -33.564109) (xy 14.574074 -33.545409) (xy 14.588379 -33.531095) (xy 14.607074 -33.523345)
			(xy 14.617192 -33.52292) (xy 15.849092 -33.52292) (xy 15.859216 -33.523323) (xy 15.877924 -33.531072)
			(xy 15.892239 -33.545393) (xy 15.899981 -33.564103) (xy 15.9004 -33.574228) (xy 15.9004 -34.605976)
			(xy 15.899965 -34.616097) (xy 15.892224 -34.6348) (xy 15.877914 -34.649115) (xy 15.859213 -34.656861)
			(xy 15.849092 -34.657284) (xy 14.617192 -34.657284) (xy 14.607067 -34.65689) (xy 14.58836 -34.649136)
			(xy 14.574046 -34.634813) (xy 14.566304 -34.616101) (xy 14.565884 -34.605976) (xy 11.36396 -34.605976)
			(xy 11.363564 -34.616102) (xy 11.355816 -34.634813) (xy 11.341493 -34.649129) (xy 11.322778 -34.656868)
			(xy 11.312652 -34.657284) (xy 10.080752 -34.657284) (xy 10.070638 -34.656854) (xy 10.051956 -34.649097)
			(xy 10.037662 -34.634784) (xy 10.029932 -34.61609) (xy 10.029444 -34.605976) (xy 7.660714 -34.605976)
			(xy 7.659947 -34.6118) (xy 7.644434 -34.669693) (xy 7.63758 -34.68624) (xy 20.014692 -34.68624) (xy 20.014692 -34.443416)
			(xy 20.208748 -34.147252) (xy 20.22856 -34.117026) (xy 20.233486 -34.108552) (xy 20.237233 -34.089334)
			(xy 20.233511 -34.070111) (xy 20.22856 -34.061654) (xy 20.061682 -33.805114) (xy 20.023074 -33.745932)
			(xy 20.022566 -33.74517) (xy 20.022058 -33.744408) (xy 20.021804 -33.7439) (xy 20.021296 -33.743138)
			(xy 20.014692 -33.732724) (xy 20.014692 -33.4899) (xy 20.015373 -33.478353) (xy 20.025318 -33.457508)
			(xy 20.043243 -33.442943) (xy 20.054316 -33.439608) (xy 20.066254 -33.438084) (xy 20.802854 -33.438084)
			(xy 20.813608 -33.438627) (xy 20.833297 -33.447278) (xy 20.840954 -33.454848) (xy 20.847146 -33.462251)
			(xy 20.854064 -33.480255) (xy 20.854416 -33.4899) (xy 20.854416 -33.732724) (xy 20.638516 -34.063178)
			(xy 20.634489 -34.071397) (xy 20.631946 -34.089509) (xy 20.635894 -34.107367) (xy 20.640548 -34.115248)
			(xy 20.672806 -34.165032) (xy 20.854416 -34.442146) (xy 20.854416 -34.520886) (xy 21.489416 -34.520886)
			(xy 21.489416 -33.657286) (xy 21.489906 -33.627302) (xy 21.497734 -33.567846) (xy 21.513255 -33.509921)
			(xy 21.536204 -33.454517) (xy 21.566188 -33.402583) (xy 21.602694 -33.355007) (xy 21.645099 -33.312602)
			(xy 21.692675 -33.276096) (xy 21.744609 -33.246112) (xy 21.800013 -33.223163) (xy 21.857938 -33.207642)
			(xy 21.917394 -33.199814) (xy 21.977362 -33.199814) (xy 22.036818 -33.207642) (xy 22.094743 -33.223163)
			(xy 22.150147 -33.246112) (xy 22.202081 -33.276096) (xy 22.249657 -33.312602) (xy 22.292062 -33.355007)
			(xy 22.328568 -33.402583) (xy 22.358552 -33.454517) (xy 22.381501 -33.509921) (xy 22.397022 -33.567846)
			(xy 22.40485 -33.627302) (xy 22.40534 -33.657286) (xy 22.40534 -34.520886) (xy 22.405315 -34.52241)
			(xy 32.752792 -34.52241) (xy 32.752792 -33.65881) (xy 32.753282 -33.628842) (xy 32.761105 -33.56942)
			(xy 32.776618 -33.511527) (xy 32.799554 -33.456154) (xy 32.829521 -33.404248) (xy 32.866008 -33.356698)
			(xy 32.908388 -33.314318) (xy 32.955938 -33.277831) (xy 33.007844 -33.247864) (xy 33.063217 -33.224928)
			(xy 33.12111 -33.209415) (xy 33.180532 -33.201592) (xy 33.240468 -33.201592) (xy 33.29989 -33.209415)
			(xy 33.357783 -33.224928) (xy 33.413156 -33.247864) (xy 33.465062 -33.277831) (xy 33.512612 -33.314318)
			(xy 33.554992 -33.356698) (xy 33.591479 -33.404248) (xy 33.621446 -33.456154) (xy 33.644382 -33.511527)
			(xy 33.659895 -33.56942) (xy 33.667718 -33.628842) (xy 33.668208 -33.65881) (xy 33.668208 -34.52241)
			(xy 33.667718 -34.552378) (xy 33.660662 -34.605976) (xy 36.029392 -34.605976) (xy 36.029392 -33.574228)
			(xy 36.029839 -33.564108) (xy 36.037576 -33.545407) (xy 36.051883 -33.531092) (xy 36.070581 -33.523344)
			(xy 36.0807 -33.52292) (xy 37.3126 -33.52292) (xy 37.322725 -33.523317) (xy 37.341432 -33.531068)
			(xy 37.355747 -33.545391) (xy 37.363489 -33.564103) (xy 37.363908 -33.574228) (xy 37.363908 -34.605976)
			(xy 40.565832 -34.605976) (xy 40.565832 -33.574228) (xy 40.566239 -33.564103) (xy 40.573984 -33.545394)
			(xy 40.588304 -33.531078) (xy 40.607015 -33.523337) (xy 40.61714 -33.52292) (xy 41.84904 -33.52292)
			(xy 41.859154 -33.523353) (xy 41.877837 -33.531107) (xy 41.892131 -33.54542) (xy 41.899861 -33.564114)
			(xy 41.900348 -33.574228) (xy 41.900348 -34.605976) (xy 41.899797 -34.616077) (xy 41.892076 -34.634746)
			(xy 41.8778 -34.64904) (xy 41.859141 -34.656784) (xy 41.84904 -34.657284) (xy 40.61714 -34.657284)
			(xy 40.607018 -34.656851) (xy 40.588312 -34.649113) (xy 40.573996 -34.634801) (xy 40.566252 -34.616098)
			(xy 40.565832 -34.605976) (xy 37.363908 -34.605976) (xy 37.363465 -34.616096) (xy 37.355726 -34.634798)
			(xy 37.341418 -34.649112) (xy 37.32272 -34.65686) (xy 37.3126 -34.657284) (xy 36.0807 -34.657284)
			(xy 36.070576 -34.656884) (xy 36.051869 -34.649132) (xy 36.037554 -34.634811) (xy 36.029812 -34.616101)
			(xy 36.029392 -34.605976) (xy 33.660662 -34.605976) (xy 33.659895 -34.6118) (xy 33.644382 -34.669693)
			(xy 33.637528 -34.68624) (xy 46.01464 -34.68624) (xy 46.01464 -34.443416) (xy 46.208696 -34.147252)
			(xy 46.228508 -34.117026) (xy 46.23343 -34.108551) (xy 46.237174 -34.089334) (xy 46.233456 -34.070112)
			(xy 46.228508 -34.061654) (xy 46.06163 -33.805114) (xy 46.023022 -33.745932) (xy 46.022514 -33.74517)
			(xy 46.022006 -33.744408) (xy 46.021752 -33.7439) (xy 46.021244 -33.743138) (xy 46.01464 -33.732724)
			(xy 46.01464 -33.4899) (xy 46.015285 -33.478348) (xy 46.025242 -33.457497) (xy 46.043183 -33.442936)
			(xy 46.054264 -33.439608) (xy 46.066202 -33.438084) (xy 46.802802 -33.438084) (xy 46.813559 -33.438601)
			(xy 46.833248 -33.44727) (xy 46.840902 -33.454848) (xy 46.8471 -33.462247) (xy 46.854014 -33.480254)
			(xy 46.854364 -33.4899) (xy 46.854364 -33.732724) (xy 46.638464 -34.063178) (xy 46.634442 -34.071399)
			(xy 46.631902 -34.089509) (xy 46.635845 -34.107366) (xy 46.640496 -34.115248) (xy 46.672754 -34.165032)
			(xy 46.854364 -34.442146) (xy 46.854364 -34.520886) (xy 47.489364 -34.520886) (xy 47.489364 -33.657286)
			(xy 47.489854 -33.627302) (xy 47.497682 -33.567846) (xy 47.513203 -33.509921) (xy 47.536152 -33.454517)
			(xy 47.566136 -33.402583) (xy 47.602642 -33.355007) (xy 47.645047 -33.312602) (xy 47.692623 -33.276096)
			(xy 47.744557 -33.246112) (xy 47.799961 -33.223163) (xy 47.857886 -33.207642) (xy 47.917342 -33.199814)
			(xy 47.97731 -33.199814) (xy 48.036766 -33.207642) (xy 48.094691 -33.223163) (xy 48.150095 -33.246112)
			(xy 48.202029 -33.276096) (xy 48.249605 -33.312602) (xy 48.29201 -33.355007) (xy 48.328516 -33.402583)
			(xy 48.3585 -33.454517) (xy 48.381449 -33.509921) (xy 48.39697 -33.567846) (xy 48.404798 -33.627302)
			(xy 48.405288 -33.657286) (xy 48.405288 -34.520886) (xy 48.405263 -34.52241) (xy 58.75274 -34.52241)
			(xy 58.75274 -33.65881) (xy 58.75323 -33.628842) (xy 58.761053 -33.56942) (xy 58.776566 -33.511527)
			(xy 58.799502 -33.456154) (xy 58.829469 -33.404248) (xy 58.865956 -33.356698) (xy 58.908336 -33.314318)
			(xy 58.955886 -33.277831) (xy 59.007792 -33.247864) (xy 59.063165 -33.224928) (xy 59.121058 -33.209415)
			(xy 59.18048 -33.201592) (xy 59.240416 -33.201592) (xy 59.299838 -33.209415) (xy 59.357731 -33.224928)
			(xy 59.413104 -33.247864) (xy 59.46501 -33.277831) (xy 59.51256 -33.314318) (xy 59.55494 -33.356698)
			(xy 59.591427 -33.404248) (xy 59.621394 -33.456154) (xy 59.64433 -33.511527) (xy 59.659843 -33.56942)
			(xy 59.667666 -33.628842) (xy 59.668156 -33.65881) (xy 59.668156 -34.52241) (xy 59.667666 -34.552378)
			(xy 59.66061 -34.605976) (xy 62.02934 -34.605976) (xy 62.02934 -33.574228) (xy 62.02974 -33.564102)
			(xy 62.037486 -33.545392) (xy 62.051808 -33.531075) (xy 62.070522 -33.523336) (xy 62.080648 -33.52292)
			(xy 63.312548 -33.52292) (xy 63.322662 -33.523346) (xy 63.341345 -33.531104) (xy 63.355639 -33.545419)
			(xy 63.363369 -33.564113) (xy 63.363856 -33.574228) (xy 63.363856 -34.605976) (xy 66.56578 -34.605976)
			(xy 66.56578 -33.574228) (xy 66.566238 -33.56411) (xy 66.573973 -33.545411) (xy 66.588277 -33.531096)
			(xy 66.60697 -33.523346) (xy 66.617088 -33.52292) (xy 67.848988 -33.52292) (xy 67.859112 -33.523326)
			(xy 67.877819 -33.531074) (xy 67.892135 -33.545394) (xy 67.899877 -33.564104) (xy 67.900296 -33.574228)
			(xy 67.900296 -34.605976) (xy 67.899864 -34.616097) (xy 67.892123 -34.634801) (xy 67.877811 -34.649117)
			(xy 67.859109 -34.656862) (xy 67.848988 -34.657284) (xy 66.617088 -34.657284) (xy 66.606963 -34.656894)
			(xy 66.588256 -34.649139) (xy 66.573941 -34.634814) (xy 66.566199 -34.616102) (xy 66.56578 -34.605976)
			(xy 63.363856 -34.605976) (xy 63.363297 -34.616076) (xy 63.355577 -34.634743) (xy 63.341304 -34.649037)
			(xy 63.322648 -34.656783) (xy 63.312548 -34.657284) (xy 62.080648 -34.657284) (xy 62.070527 -34.656844)
			(xy 62.051821 -34.649109) (xy 62.037505 -34.634799) (xy 62.02976 -34.616097) (xy 62.02934 -34.605976)
			(xy 59.66061 -34.605976) (xy 59.659843 -34.6118) (xy 59.64433 -34.669693) (xy 59.637476 -34.68624)
			(xy 72.014588 -34.68624) (xy 72.014588 -34.443416) (xy 72.208644 -34.147252) (xy 72.228456 -34.117026)
			(xy 72.233382 -34.108552) (xy 72.237129 -34.089334) (xy 72.233408 -34.070111) (xy 72.228456 -34.061654)
			(xy 72.061578 -33.805114) (xy 72.02297 -33.745932) (xy 72.022462 -33.74517) (xy 72.021954 -33.744408)
			(xy 72.0217 -33.7439) (xy 72.021192 -33.743138) (xy 72.014588 -33.732724) (xy 72.014588 -33.4899)
			(xy 72.015272 -33.478354) (xy 72.025216 -33.457509) (xy 72.043139 -33.442944) (xy 72.054212 -33.439608)
			(xy 72.06615 -33.438084) (xy 72.80275 -33.438084) (xy 72.813504 -33.438629) (xy 72.833193 -33.447279)
			(xy 72.84085 -33.454848) (xy 72.847042 -33.462252) (xy 72.85396 -33.480255) (xy 72.854312 -33.4899)
			(xy 72.854312 -33.732724) (xy 72.638412 -34.063178) (xy 72.634386 -34.071397) (xy 72.631842 -34.089509)
			(xy 72.63579 -34.107367) (xy 72.640444 -34.115248) (xy 72.672702 -34.165032) (xy 72.854312 -34.442146)
			(xy 72.854312 -34.520886) (xy 73.489312 -34.520886) (xy 73.489312 -33.657286) (xy 73.489802 -33.627302)
			(xy 73.49763 -33.567846) (xy 73.513151 -33.509921) (xy 73.5361 -33.454517) (xy 73.566084 -33.402583)
			(xy 73.60259 -33.355007) (xy 73.644995 -33.312602) (xy 73.692571 -33.276096) (xy 73.744505 -33.246112)
			(xy 73.799909 -33.223163) (xy 73.857834 -33.207642) (xy 73.91729 -33.199814) (xy 73.977258 -33.199814)
			(xy 74.036714 -33.207642) (xy 74.094639 -33.223163) (xy 74.150043 -33.246112) (xy 74.201977 -33.276096)
			(xy 74.249553 -33.312602) (xy 74.291958 -33.355007) (xy 74.328464 -33.402583) (xy 74.358448 -33.454517)
			(xy 74.381397 -33.509921) (xy 74.396918 -33.567846) (xy 74.404746 -33.627302) (xy 74.405236 -33.657286)
			(xy 74.405236 -34.520886) (xy 74.405211 -34.52241) (xy 84.752688 -34.52241) (xy 84.752688 -33.65881)
			(xy 84.753178 -33.628842) (xy 84.761001 -33.56942) (xy 84.776514 -33.511527) (xy 84.79945 -33.456154)
			(xy 84.829417 -33.404248) (xy 84.865904 -33.356698) (xy 84.908284 -33.314318) (xy 84.955834 -33.277831)
			(xy 85.00774 -33.247864) (xy 85.063113 -33.224928) (xy 85.121006 -33.209415) (xy 85.180428 -33.201592)
			(xy 85.240364 -33.201592) (xy 85.299786 -33.209415) (xy 85.357679 -33.224928) (xy 85.413052 -33.247864)
			(xy 85.464958 -33.277831) (xy 85.512508 -33.314318) (xy 85.554888 -33.356698) (xy 85.591375 -33.404248)
			(xy 85.621342 -33.456154) (xy 85.644278 -33.511527) (xy 85.659791 -33.56942) (xy 85.667614 -33.628842)
			(xy 85.668104 -33.65881) (xy 85.668104 -34.52241) (xy 85.667614 -34.552378) (xy 85.660558 -34.605976)
			(xy 88.029288 -34.605976) (xy 88.029288 -33.574228) (xy 88.029738 -33.564109) (xy 88.037475 -33.545408)
			(xy 88.051781 -33.531093) (xy 88.070477 -33.523345) (xy 88.080596 -33.52292) (xy 89.312496 -33.52292)
			(xy 89.322621 -33.52332) (xy 89.341328 -33.53107) (xy 89.355643 -33.545392) (xy 89.363385 -33.564103)
			(xy 89.363804 -33.574228) (xy 89.363804 -34.605976) (xy 92.565728 -34.605976) (xy 92.565728 -33.574228)
			(xy 92.566139 -33.564104) (xy 92.573884 -33.545395) (xy 92.588202 -33.531079) (xy 92.606912 -33.523338)
			(xy 92.617036 -33.52292) (xy 93.848936 -33.52292) (xy 93.85905 -33.523356) (xy 93.877732 -33.531109)
			(xy 93.892027 -33.545421) (xy 93.899756 -33.564114) (xy 93.900244 -33.574228) (xy 93.900244 -34.605976)
			(xy 93.899696 -34.616078) (xy 93.891975 -34.634747) (xy 93.877697 -34.649041) (xy 93.859037 -34.656785)
			(xy 93.848936 -34.657284) (xy 92.617036 -34.657284) (xy 92.606914 -34.656854) (xy 92.588208 -34.649115)
			(xy 92.573892 -34.634802) (xy 92.566148 -34.616098) (xy 92.565728 -34.605976) (xy 89.363804 -34.605976)
			(xy 89.363365 -34.616096) (xy 89.355625 -34.634799) (xy 89.341316 -34.649114) (xy 89.322616 -34.656861)
			(xy 89.312496 -34.657284) (xy 88.080596 -34.657284) (xy 88.070471 -34.656887) (xy 88.051765 -34.649134)
			(xy 88.03745 -34.634812) (xy 88.029708 -34.616101) (xy 88.029288 -34.605976) (xy 85.660558 -34.605976)
			(xy 85.659791 -34.6118) (xy 85.644278 -34.669693) (xy 85.637424 -34.68624) (xy 98.014536 -34.68624)
			(xy 98.014536 -34.443416) (xy 98.133408 -34.26206) (xy 98.195892 -34.166556) (xy 98.220022 -34.129726)
			(xy 98.22389 -34.123398) (xy 98.228151 -34.109198) (xy 98.228404 -34.101786) (xy 98.228404 -34.075878)
			(xy 98.228225 -34.069727) (xy 98.225262 -34.057786) (xy 98.222562 -34.052256) (xy 98.109024 -33.878266)
			(xy 98.088958 -33.847278) (xy 98.08337 -33.838642) (xy 98.022918 -33.745932) (xy 98.02241 -33.74517)
			(xy 98.021902 -33.744408) (xy 98.021648 -33.7439) (xy 98.02114 -33.743138) (xy 98.014536 -33.732724)
			(xy 98.014536 -33.4899) (xy 98.015184 -33.478348) (xy 98.02514 -33.457498) (xy 98.04308 -33.442937)
			(xy 98.05416 -33.439608) (xy 98.066098 -33.438084) (xy 98.802698 -33.438084) (xy 98.813455 -33.438603)
			(xy 98.833144 -33.447271) (xy 98.840798 -33.454848) (xy 98.846996 -33.462247) (xy 98.853909 -33.480254)
			(xy 98.85426 -33.4899) (xy 98.85426 -33.732724) (xy 98.63836 -34.063178) (xy 98.634339 -34.071399)
			(xy 98.631798 -34.089509) (xy 98.635742 -34.107366) (xy 98.640392 -34.115248) (xy 98.67265 -34.165032)
			(xy 98.85426 -34.442146) (xy 98.85426 -34.520886) (xy 99.48926 -34.520886) (xy 99.48926 -33.657286)
			(xy 99.48975 -33.627302) (xy 99.497578 -33.567846) (xy 99.513099 -33.509921) (xy 99.536048 -33.454517)
			(xy 99.566032 -33.402583) (xy 99.602538 -33.355007) (xy 99.644943 -33.312602) (xy 99.692519 -33.276096)
			(xy 99.744453 -33.246112) (xy 99.799857 -33.223163) (xy 99.857782 -33.207642) (xy 99.917238 -33.199814)
			(xy 99.977206 -33.199814) (xy 100.036662 -33.207642) (xy 100.094587 -33.223163) (xy 100.149991 -33.246112)
			(xy 100.201925 -33.276096) (xy 100.249501 -33.312602) (xy 100.291906 -33.355007) (xy 100.328412 -33.402583)
			(xy 100.358396 -33.454517) (xy 100.381345 -33.509921) (xy 100.396866 -33.567846) (xy 100.404694 -33.627302)
			(xy 100.405184 -33.657286) (xy 100.405184 -34.520886) (xy 100.405159 -34.52241) (xy 122.852688 -34.52241)
			(xy 122.852688 -33.65881) (xy 122.853178 -33.628826) (xy 122.861006 -33.56937) (xy 122.876527 -33.511445)
			(xy 122.899476 -33.456041) (xy 122.92946 -33.404107) (xy 122.965966 -33.356531) (xy 123.008371 -33.314126)
			(xy 123.055947 -33.27762) (xy 123.107881 -33.247636) (xy 123.163285 -33.224687) (xy 123.22121 -33.209166)
			(xy 123.280666 -33.201338) (xy 123.340634 -33.201338) (xy 123.40009 -33.209166) (xy 123.458015 -33.224687)
			(xy 123.513419 -33.247636) (xy 123.565353 -33.27762) (xy 123.612929 -33.314126) (xy 123.655334 -33.356531)
			(xy 123.69184 -33.404107) (xy 123.721824 -33.456041) (xy 123.744773 -33.511445) (xy 123.760294 -33.56937)
			(xy 123.768122 -33.628826) (xy 123.768612 -33.65881) (xy 123.768612 -34.52241) (xy 123.768122 -34.552394)
			(xy 123.761067 -34.605976) (xy 126.129288 -34.605976) (xy 126.129288 -33.574228) (xy 126.129738 -33.564109)
			(xy 126.137475 -33.545408) (xy 126.151781 -33.531093) (xy 126.170477 -33.523345) (xy 126.180596 -33.52292)
			(xy 127.41275 -33.52292) (xy 127.422871 -33.523467) (xy 127.441587 -33.531175) (xy 127.455945 -33.545443)
			(xy 127.463769 -33.56411) (xy 127.464312 -33.574228) (xy 127.464312 -34.605976) (xy 130.665728 -34.605976)
			(xy 130.665728 -33.574228) (xy 130.666145 -33.564072) (xy 130.673936 -33.545315) (xy 130.688335 -33.530989)
			(xy 130.707132 -33.523294) (xy 130.71729 -33.52292) (xy 131.94919 -33.52292) (xy 131.959314 -33.523434)
			(xy 131.978031 -33.531155) (xy 131.992387 -33.545433) (xy 132.00021 -33.564107) (xy 132.000752 -33.574228)
			(xy 132.000752 -34.605976) (xy 132.00026 -34.616122) (xy 131.992482 -34.634864) (xy 131.978108 -34.649186)
			(xy 131.959338 -34.656896) (xy 131.94919 -34.657284) (xy 130.71729 -34.657284) (xy 130.707166 -34.656782)
			(xy 130.688449 -34.649056) (xy 130.674094 -34.634774) (xy 130.666271 -34.616098) (xy 130.665728 -34.605976)
			(xy 127.464312 -34.605976) (xy 127.463865 -34.616095) (xy 127.456127 -34.634796) (xy 127.44182 -34.649111)
			(xy 127.423123 -34.656859) (xy 127.413004 -34.657284) (xy 126.18085 -34.657284) (xy 126.170729 -34.656733)
			(xy 126.152014 -34.649026) (xy 126.137657 -34.63476) (xy 126.129832 -34.616093) (xy 126.129288 -34.605976)
			(xy 123.761067 -34.605976) (xy 123.760294 -34.61185) (xy 123.744773 -34.669775) (xy 123.737953 -34.68624)
			(xy 136.114536 -34.68624) (xy 136.114536 -34.443416) (xy 136.120124 -34.435034) (xy 136.120378 -34.434526)
			(xy 136.12241 -34.431478) (xy 136.122664 -34.43097) (xy 136.328404 -34.117026) (xy 136.33336 -34.108571)
			(xy 136.337191 -34.089373) (xy 136.333564 -34.070135) (xy 136.328658 -34.061654) (xy 136.242806 -33.929574)
			(xy 136.233408 -33.915096) (xy 136.12114 -33.743138) (xy 136.120632 -33.742122) (xy 136.1186 -33.739074)
			(xy 136.118346 -33.738566) (xy 136.114536 -33.732724) (xy 136.114536 -33.4899) (xy 136.115081 -33.479698)
			(xy 136.122884 -33.460846) (xy 136.137305 -33.446411) (xy 136.156151 -33.43859) (xy 136.166352 -33.438084)
			(xy 136.902952 -33.438084) (xy 136.913171 -33.438551) (xy 136.932057 -33.446359) (xy 136.946514 -33.460803)
			(xy 136.954339 -33.479682) (xy 136.954768 -33.4899) (xy 136.954768 -33.732724) (xy 136.950958 -33.738566)
			(xy 136.950704 -33.739074) (xy 136.94664 -33.74517) (xy 136.946386 -33.745424) (xy 136.808464 -33.956498)
			(xy 136.755378 -34.037778) (xy 136.742932 -34.056828) (xy 136.7409 -34.059622) (xy 136.73963 -34.061654)
			(xy 136.735384 -34.069048) (xy 136.731684 -34.085685) (xy 136.733663 -34.102613) (xy 136.73709 -34.110422)
			(xy 136.924288 -34.395918) (xy 136.926828 -34.399728) (xy 136.94664 -34.4297) (xy 136.946894 -34.430208)
			(xy 136.948164 -34.43224) (xy 136.949942 -34.43478) (xy 136.954768 -34.442146) (xy 136.954768 -34.520886)
			(xy 137.589768 -34.520886) (xy 137.589768 -33.657286) (xy 137.590258 -33.627318) (xy 137.598081 -33.567896)
			(xy 137.613594 -33.510003) (xy 137.63653 -33.45463) (xy 137.666497 -33.402724) (xy 137.702984 -33.355174)
			(xy 137.745364 -33.312794) (xy 137.792914 -33.276307) (xy 137.84482 -33.24634) (xy 137.900193 -33.223404)
			(xy 137.958086 -33.207891) (xy 138.017508 -33.200068) (xy 138.077444 -33.200068) (xy 138.136866 -33.207891)
			(xy 138.194759 -33.223404) (xy 138.250132 -33.24634) (xy 138.302038 -33.276307) (xy 138.349588 -33.312794)
			(xy 138.391968 -33.355174) (xy 138.428455 -33.402724) (xy 138.458422 -33.45463) (xy 138.481358 -33.510003)
			(xy 138.496871 -33.567896) (xy 138.504694 -33.627318) (xy 138.505184 -33.657286) (xy 138.505184 -34.520886)
			(xy 138.505159 -34.52241) (xy 148.852636 -34.52241) (xy 148.852636 -33.65881) (xy 148.853126 -33.628826)
			(xy 148.860954 -33.56937) (xy 148.876475 -33.511445) (xy 148.899424 -33.456041) (xy 148.929408 -33.404107)
			(xy 148.965914 -33.356531) (xy 149.008319 -33.314126) (xy 149.055895 -33.27762) (xy 149.107829 -33.247636)
			(xy 149.163233 -33.224687) (xy 149.221158 -33.209166) (xy 149.280614 -33.201338) (xy 149.340582 -33.201338)
			(xy 149.400038 -33.209166) (xy 149.457963 -33.224687) (xy 149.513367 -33.247636) (xy 149.565301 -33.27762)
			(xy 149.612877 -33.314126) (xy 149.655282 -33.356531) (xy 149.691788 -33.404107) (xy 149.721772 -33.456041)
			(xy 149.744721 -33.511445) (xy 149.760242 -33.56937) (xy 149.76807 -33.628826) (xy 149.76856 -33.65881)
			(xy 149.76856 -34.52241) (xy 149.76807 -34.552394) (xy 149.761015 -34.605976) (xy 152.129236 -34.605976)
			(xy 152.129236 -33.574228) (xy 152.12964 -33.564103) (xy 152.137385 -33.545393) (xy 152.151706 -33.531076)
			(xy 152.170419 -33.523336) (xy 152.180544 -33.52292) (xy 153.412698 -33.52292) (xy 153.422822 -33.523428)
			(xy 153.441539 -33.531151) (xy 153.455895 -33.545431) (xy 153.463718 -33.564107) (xy 153.46426 -33.574228)
			(xy 153.46426 -34.605976) (xy 156.665676 -34.605976) (xy 156.665676 -33.574228) (xy 156.666144 -33.564079)
			(xy 156.673926 -33.545331) (xy 156.688308 -33.531008) (xy 156.707087 -33.523303) (xy 156.717238 -33.52292)
			(xy 157.949138 -33.52292) (xy 157.959265 -33.523395) (xy 157.977983 -33.531131) (xy 157.992337 -33.545421)
			(xy 158.000159 -33.564104) (xy 158.0007 -33.574228) (xy 158.0007 -34.605976) (xy 158.000259 -34.616129)
			(xy 157.992471 -34.634881) (xy 157.97808 -34.649205) (xy 157.959292 -34.656905) (xy 157.949138 -34.657284)
			(xy 156.717238 -34.657284) (xy 156.707117 -34.656743) (xy 156.688401 -34.649032) (xy 156.674044 -34.634762)
			(xy 156.66622 -34.616094) (xy 156.665676 -34.605976) (xy 153.46426 -34.605976) (xy 153.463864 -34.616102)
			(xy 153.456116 -34.634813) (xy 153.441793 -34.649129) (xy 153.423078 -34.656868) (xy 153.412952 -34.657284)
			(xy 152.180798 -34.657284) (xy 152.170674 -34.656776) (xy 152.151958 -34.649052) (xy 152.137602 -34.634772)
			(xy 152.129779 -34.616097) (xy 152.129236 -34.605976) (xy 149.761015 -34.605976) (xy 149.760242 -34.61185)
			(xy 149.744721 -34.669775) (xy 149.737901 -34.68624) (xy 162.114484 -34.68624) (xy 162.114484 -34.458656)
			(xy 162.114738 -34.454592) (xy 162.114992 -34.452052) (xy 162.114992 -34.443416) (xy 162.12058 -34.43478)
			(xy 162.12185 -34.432748) (xy 162.122866 -34.430716) (xy 162.320224 -34.129726) (xy 162.324093 -34.123398)
			(xy 162.328353 -34.109199) (xy 162.328606 -34.101786) (xy 162.328606 -34.076132) (xy 162.328398 -34.068798)
			(xy 162.324269 -34.054727) (xy 162.320478 -34.048446) (xy 162.122612 -33.745424) (xy 162.120326 -33.741614)
			(xy 162.120072 -33.741106) (xy 162.119056 -33.739328) (xy 162.114992 -33.732724) (xy 162.114992 -33.724596)
			(xy 162.114738 -33.722056) (xy 162.114484 -33.717992) (xy 162.114484 -33.4899) (xy 162.114982 -33.479692)
			(xy 162.122795 -33.460831) (xy 162.137231 -33.446395) (xy 162.156092 -33.438582) (xy 162.1663 -33.438084)
			(xy 162.9029 -33.438084) (xy 162.913108 -33.438582) (xy 162.931969 -33.446395) (xy 162.946405 -33.460831)
			(xy 162.954218 -33.479692) (xy 162.954716 -33.4899) (xy 162.954716 -33.717484) (xy 162.954462 -33.721548)
			(xy 162.954208 -33.724088) (xy 162.954208 -33.732724) (xy 162.948366 -33.742122) (xy 162.947604 -33.743392)
			(xy 162.946334 -33.745424) (xy 162.740594 -34.06013) (xy 162.735564 -34.068663) (xy 162.731736 -34.088075)
			(xy 162.735545 -34.10749) (xy 162.740594 -34.11601) (xy 162.946334 -34.429446) (xy 162.94735 -34.431478)
			(xy 162.94862 -34.43351) (xy 162.954208 -34.442146) (xy 162.954208 -34.450782) (xy 162.954462 -34.453322)
			(xy 162.954716 -34.457386) (xy 162.954716 -34.520886) (xy 163.589716 -34.520886) (xy 163.589716 -33.657286)
			(xy 163.590206 -33.627318) (xy 163.598029 -33.567896) (xy 163.613542 -33.510003) (xy 163.636478 -33.45463)
			(xy 163.666445 -33.402724) (xy 163.702932 -33.355174) (xy 163.745312 -33.312794) (xy 163.792862 -33.276307)
			(xy 163.844768 -33.24634) (xy 163.900141 -33.223404) (xy 163.958034 -33.207891) (xy 164.017456 -33.200068)
			(xy 164.077392 -33.200068) (xy 164.136814 -33.207891) (xy 164.194707 -33.223404) (xy 164.25008 -33.24634)
			(xy 164.301986 -33.276307) (xy 164.349536 -33.312794) (xy 164.391916 -33.355174) (xy 164.428403 -33.402724)
			(xy 164.45837 -33.45463) (xy 164.481306 -33.510003) (xy 164.496819 -33.567896) (xy 164.504642 -33.627318)
			(xy 164.505132 -33.657286) (xy 164.505132 -34.520886) (xy 164.505107 -34.52241) (xy 174.852584 -34.52241)
			(xy 174.852584 -33.65881) (xy 174.853074 -33.628826) (xy 174.860902 -33.56937) (xy 174.876423 -33.511445)
			(xy 174.899372 -33.456041) (xy 174.929356 -33.404107) (xy 174.965862 -33.356531) (xy 175.008267 -33.314126)
			(xy 175.055843 -33.27762) (xy 175.107777 -33.247636) (xy 175.163181 -33.224687) (xy 175.221106 -33.209166)
			(xy 175.280562 -33.201338) (xy 175.34053 -33.201338) (xy 175.399986 -33.209166) (xy 175.457911 -33.224687)
			(xy 175.513315 -33.247636) (xy 175.565249 -33.27762) (xy 175.612825 -33.314126) (xy 175.65523 -33.356531)
			(xy 175.691736 -33.404107) (xy 175.72172 -33.456041) (xy 175.744669 -33.511445) (xy 175.76019 -33.56937)
			(xy 175.768018 -33.628826) (xy 175.768508 -33.65881) (xy 175.768508 -34.52241) (xy 175.768018 -34.552394)
			(xy 175.760963 -34.605976) (xy 178.129184 -34.605976) (xy 178.129184 -33.574228) (xy 178.129638 -33.564109)
			(xy 178.137374 -33.545409) (xy 178.151679 -33.531095) (xy 178.170374 -33.523345) (xy 178.180492 -33.52292)
			(xy 179.412646 -33.52292) (xy 179.422773 -33.523388) (xy 179.441492 -33.531128) (xy 179.455846 -33.545419)
			(xy 179.463667 -33.564103) (xy 179.464208 -33.574228) (xy 179.464208 -34.605976) (xy 182.665624 -34.605976)
			(xy 182.665624 -33.574228) (xy 182.666045 -33.564073) (xy 182.673836 -33.545316) (xy 182.688233 -33.530991)
			(xy 182.707029 -33.523294) (xy 182.717186 -33.52292) (xy 183.949086 -33.52292) (xy 183.959209 -33.523437)
			(xy 183.977926 -33.531157) (xy 183.992283 -33.545434) (xy 184.000106 -33.564107) (xy 184.000648 -33.574228)
			(xy 184.000648 -34.605976) (xy 184.00016 -34.616123) (xy 183.992381 -34.634865) (xy 183.978005 -34.649188)
			(xy 183.959234 -34.656897) (xy 183.949086 -34.657284) (xy 182.717186 -34.657284) (xy 182.707061 -34.656785)
			(xy 182.688345 -34.649057) (xy 182.67399 -34.634775) (xy 182.666167 -34.616098) (xy 182.665624 -34.605976)
			(xy 179.464208 -34.605976) (xy 179.463765 -34.616096) (xy 179.456026 -34.634798) (xy 179.441718 -34.649112)
			(xy 179.42302 -34.65686) (xy 179.4129 -34.657284) (xy 178.180746 -34.657284) (xy 178.170625 -34.656736)
			(xy 178.15191 -34.649028) (xy 178.137553 -34.634761) (xy 178.129728 -34.616094) (xy 178.129184 -34.605976)
			(xy 175.760963 -34.605976) (xy 175.76019 -34.61185) (xy 175.744669 -34.669775) (xy 175.737849 -34.68624)
			(xy 188.114432 -34.68624) (xy 188.114432 -34.458656) (xy 188.114686 -34.454592) (xy 188.11494 -34.452052)
			(xy 188.11494 -34.443416) (xy 188.120528 -34.43478) (xy 188.121798 -34.432748) (xy 188.122814 -34.430716)
			(xy 188.320172 -34.129726) (xy 188.324045 -34.1234) (xy 188.328301 -34.109199) (xy 188.328554 -34.101786)
			(xy 188.328554 -34.076132) (xy 188.328353 -34.068798) (xy 188.32422 -34.054726) (xy 188.320426 -34.048446)
			(xy 188.12256 -33.745424) (xy 188.120274 -33.741614) (xy 188.12002 -33.741106) (xy 188.119004 -33.739328)
			(xy 188.11494 -33.732724) (xy 188.11494 -33.724596) (xy 188.114686 -33.722056) (xy 188.114432 -33.717992)
			(xy 188.114432 -33.4899) (xy 188.114813 -33.479672) (xy 188.122645 -33.460776) (xy 188.137116 -33.446318)
			(xy 188.15602 -33.438503) (xy 188.166248 -33.438084) (xy 188.902848 -33.438084) (xy 188.913059 -33.438543)
			(xy 188.931922 -33.446371) (xy 188.946356 -33.460819) (xy 188.954167 -33.479689) (xy 188.954664 -33.4899)
			(xy 188.954664 -33.717484) (xy 188.95441 -33.721548) (xy 188.954156 -33.724088) (xy 188.954156 -33.732724)
			(xy 188.948314 -33.742122) (xy 188.947552 -33.743392) (xy 188.946282 -33.745424) (xy 188.740542 -34.06013)
			(xy 188.735516 -34.068664) (xy 188.731693 -34.088075) (xy 188.735497 -34.107489) (xy 188.740542 -34.11601)
			(xy 188.946282 -34.429446) (xy 188.947298 -34.431478) (xy 188.948568 -34.43351) (xy 188.954156 -34.442146)
			(xy 188.954156 -34.450782) (xy 188.95441 -34.453322) (xy 188.954664 -34.457386) (xy 188.954664 -34.520886)
			(xy 189.589664 -34.520886) (xy 189.589664 -33.657286) (xy 189.590154 -33.627318) (xy 189.597977 -33.567896)
			(xy 189.61349 -33.510003) (xy 189.636426 -33.45463) (xy 189.666393 -33.402724) (xy 189.70288 -33.355174)
			(xy 189.74526 -33.312794) (xy 189.79281 -33.276307) (xy 189.844716 -33.24634) (xy 189.900089 -33.223404)
			(xy 189.957982 -33.207891) (xy 190.017404 -33.200068) (xy 190.07734 -33.200068) (xy 190.136762 -33.207891)
			(xy 190.194655 -33.223404) (xy 190.250028 -33.24634) (xy 190.301934 -33.276307) (xy 190.349484 -33.312794)
			(xy 190.391864 -33.355174) (xy 190.428351 -33.402724) (xy 190.458318 -33.45463) (xy 190.481254 -33.510003)
			(xy 190.496767 -33.567896) (xy 190.50459 -33.627318) (xy 190.50508 -33.657286) (xy 190.50508 -34.520886)
			(xy 190.505055 -34.52241) (xy 200.852532 -34.52241) (xy 200.852532 -33.65881) (xy 200.853022 -33.628826)
			(xy 200.86085 -33.56937) (xy 200.876371 -33.511445) (xy 200.89932 -33.456041) (xy 200.929304 -33.404107)
			(xy 200.96581 -33.356531) (xy 201.008215 -33.314126) (xy 201.055791 -33.27762) (xy 201.107725 -33.247636)
			(xy 201.163129 -33.224687) (xy 201.221054 -33.209166) (xy 201.28051 -33.201338) (xy 201.340478 -33.201338)
			(xy 201.399934 -33.209166) (xy 201.457859 -33.224687) (xy 201.513263 -33.247636) (xy 201.565197 -33.27762)
			(xy 201.612773 -33.314126) (xy 201.655178 -33.356531) (xy 201.691684 -33.404107) (xy 201.721668 -33.456041)
			(xy 201.744617 -33.511445) (xy 201.760138 -33.56937) (xy 201.767966 -33.628826) (xy 201.768456 -33.65881)
			(xy 201.768456 -34.52241) (xy 201.767966 -34.552394) (xy 201.760911 -34.605976) (xy 204.129132 -34.605976)
			(xy 204.129132 -33.574228) (xy 204.129539 -33.564103) (xy 204.137284 -33.545394) (xy 204.151604 -33.531078)
			(xy 204.170315 -33.523337) (xy 204.18044 -33.52292) (xy 205.412594 -33.52292) (xy 205.422718 -33.523431)
			(xy 205.441435 -33.531153) (xy 205.455791 -33.545432) (xy 205.463614 -33.564107) (xy 205.464156 -33.574228)
			(xy 205.464156 -34.605976) (xy 208.665572 -34.605976) (xy 208.665572 -33.574228) (xy 208.666044 -33.564079)
			(xy 208.673825 -33.545333) (xy 208.688206 -33.531009) (xy 208.706984 -33.523304) (xy 208.717134 -33.52292)
			(xy 209.949034 -33.52292) (xy 209.95916 -33.523398) (xy 209.977879 -33.531133) (xy 209.992233 -33.545422)
			(xy 210.000055 -33.564104) (xy 210.000596 -33.574228) (xy 210.000596 -34.605976) (xy 210.000159 -34.616129)
			(xy 209.99237 -34.634882) (xy 209.977978 -34.649206) (xy 209.959189 -34.656906) (xy 209.949034 -34.657284)
			(xy 208.717134 -34.657284) (xy 208.707012 -34.656746) (xy 208.688297 -34.649034) (xy 208.67394 -34.634763)
			(xy 208.666116 -34.616094) (xy 208.665572 -34.605976) (xy 205.464156 -34.605976) (xy 205.463597 -34.616076)
			(xy 205.455877 -34.634743) (xy 205.441604 -34.649037) (xy 205.422948 -34.656783) (xy 205.412848 -34.657284)
			(xy 204.180694 -34.657284) (xy 204.17057 -34.656779) (xy 204.151853 -34.649054) (xy 204.137498 -34.634773)
			(xy 204.129675 -34.616097) (xy 204.129132 -34.605976) (xy 201.760911 -34.605976) (xy 201.760138 -34.61185)
			(xy 201.744617 -34.669775) (xy 201.737797 -34.68624) (xy 214.11438 -34.68624) (xy 214.11438 -34.458656)
			(xy 214.114634 -34.454592) (xy 214.114888 -34.452052) (xy 214.114888 -34.443416) (xy 214.120476 -34.43478)
			(xy 214.121746 -34.432748) (xy 214.122762 -34.430716) (xy 214.32012 -34.129726) (xy 214.323988 -34.123398)
			(xy 214.328249 -34.109198) (xy 214.328502 -34.101786) (xy 214.328502 -34.076132) (xy 214.328295 -34.068798)
			(xy 214.324165 -34.054727) (xy 214.320374 -34.048446) (xy 214.122508 -33.745424) (xy 214.120222 -33.741614)
			(xy 214.119968 -33.741106) (xy 214.118952 -33.739328) (xy 214.114888 -33.732724) (xy 214.114888 -33.724596)
			(xy 214.114634 -33.722056) (xy 214.11438 -33.717992) (xy 214.11438 -33.4899) (xy 214.114882 -33.479693)
			(xy 214.122694 -33.460832) (xy 214.137129 -33.446396) (xy 214.155989 -33.438583) (xy 214.166196 -33.438084)
			(xy 214.902796 -33.438084) (xy 214.913018 -33.438515) (xy 214.931905 -33.446337) (xy 214.946361 -33.460792)
			(xy 214.954184 -33.479679) (xy 214.954612 -33.4899) (xy 214.954612 -33.717484) (xy 214.954358 -33.721548)
			(xy 214.954104 -33.724088) (xy 214.954104 -33.732724) (xy 214.948262 -33.742122) (xy 214.9475 -33.743392)
			(xy 214.94623 -33.745424) (xy 214.74049 -34.06013) (xy 214.73546 -34.068663) (xy 214.731633 -34.088075)
			(xy 214.735441 -34.10749) (xy 214.74049 -34.11601) (xy 214.94623 -34.429446) (xy 214.947246 -34.431478)
			(xy 214.948516 -34.43351) (xy 214.954104 -34.442146) (xy 214.954104 -34.450782) (xy 214.954358 -34.453322)
			(xy 214.954612 -34.457386) (xy 214.954612 -34.520886) (xy 215.589612 -34.520886) (xy 215.589612 -33.657286)
			(xy 215.590102 -33.627318) (xy 215.597925 -33.567896) (xy 215.613438 -33.510003) (xy 215.636374 -33.45463)
			(xy 215.666341 -33.402724) (xy 215.702828 -33.355174) (xy 215.745208 -33.312794) (xy 215.792758 -33.276307)
			(xy 215.844664 -33.24634) (xy 215.900037 -33.223404) (xy 215.95793 -33.207891) (xy 216.017352 -33.200068)
			(xy 216.077288 -33.200068) (xy 216.13671 -33.207891) (xy 216.194603 -33.223404) (xy 216.249976 -33.24634)
			(xy 216.301882 -33.276307) (xy 216.349432 -33.312794) (xy 216.391812 -33.355174) (xy 216.428299 -33.402724)
			(xy 216.458266 -33.45463) (xy 216.481202 -33.510003) (xy 216.496715 -33.567896) (xy 216.504538 -33.627318)
			(xy 216.505028 -33.657286) (xy 216.505028 -34.520886) (xy 216.505003 -34.52241) (xy 238.952532 -34.52241)
			(xy 238.952532 -33.65881) (xy 238.953022 -33.628826) (xy 238.96085 -33.56937) (xy 238.976371 -33.511445)
			(xy 238.99932 -33.456041) (xy 239.029304 -33.404107) (xy 239.06581 -33.356531) (xy 239.108215 -33.314126)
			(xy 239.155791 -33.27762) (xy 239.207725 -33.247636) (xy 239.263129 -33.224687) (xy 239.321054 -33.209166)
			(xy 239.38051 -33.201338) (xy 239.440478 -33.201338) (xy 239.499934 -33.209166) (xy 239.557859 -33.224687)
			(xy 239.613263 -33.247636) (xy 239.665197 -33.27762) (xy 239.712773 -33.314126) (xy 239.755178 -33.356531)
			(xy 239.791684 -33.404107) (xy 239.821668 -33.456041) (xy 239.844617 -33.511445) (xy 239.860138 -33.56937)
			(xy 239.867966 -33.628826) (xy 239.868456 -33.65881) (xy 239.868456 -34.52241) (xy 239.867966 -34.552394)
			(xy 239.860911 -34.605976) (xy 242.229132 -34.605976) (xy 242.229132 -33.574228) (xy 242.229539 -33.564103)
			(xy 242.237284 -33.545394) (xy 242.251604 -33.531078) (xy 242.270315 -33.523337) (xy 242.28044 -33.52292)
			(xy 243.512594 -33.52292) (xy 243.522718 -33.523431) (xy 243.541435 -33.531153) (xy 243.555791 -33.545432)
			(xy 243.563614 -33.564107) (xy 243.564156 -33.574228) (xy 243.564156 -34.605976) (xy 246.765572 -34.605976)
			(xy 246.765572 -33.574228) (xy 246.766044 -33.564079) (xy 246.773825 -33.545333) (xy 246.788206 -33.531009)
			(xy 246.806984 -33.523304) (xy 246.817134 -33.52292) (xy 248.049034 -33.52292) (xy 248.05916 -33.523398)
			(xy 248.077879 -33.531133) (xy 248.092233 -33.545422) (xy 248.100055 -33.564104) (xy 248.100596 -33.574228)
			(xy 248.100596 -34.605976) (xy 248.100159 -34.616129) (xy 248.09237 -34.634882) (xy 248.077978 -34.649206)
			(xy 248.059189 -34.656906) (xy 248.049034 -34.657284) (xy 246.817134 -34.657284) (xy 246.807012 -34.656746)
			(xy 246.788297 -34.649034) (xy 246.77394 -34.634763) (xy 246.766116 -34.616094) (xy 246.765572 -34.605976)
			(xy 243.564156 -34.605976) (xy 243.563597 -34.616076) (xy 243.555877 -34.634743) (xy 243.541604 -34.649037)
			(xy 243.522948 -34.656783) (xy 243.512848 -34.657284) (xy 242.280694 -34.657284) (xy 242.27057 -34.656779)
			(xy 242.251853 -34.649054) (xy 242.237498 -34.634773) (xy 242.229675 -34.616097) (xy 242.229132 -34.605976)
			(xy 239.860911 -34.605976) (xy 239.860138 -34.61185) (xy 239.844617 -34.669775) (xy 239.837797 -34.68624)
			(xy 252.21438 -34.68624) (xy 252.21438 -34.458656) (xy 252.214634 -34.454592) (xy 252.214888 -34.452052)
			(xy 252.214888 -34.443416) (xy 252.220476 -34.43478) (xy 252.221746 -34.432748) (xy 252.222762 -34.430716)
			(xy 252.42012 -34.129726) (xy 252.423988 -34.123398) (xy 252.428249 -34.109198) (xy 252.428502 -34.101786)
			(xy 252.428502 -34.076132) (xy 252.428295 -34.068798) (xy 252.424165 -34.054727) (xy 252.420374 -34.048446)
			(xy 252.222508 -33.745424) (xy 252.220222 -33.741614) (xy 252.219968 -33.741106) (xy 252.218952 -33.739328)
			(xy 252.214888 -33.732724) (xy 252.214888 -33.724596) (xy 252.214634 -33.722056) (xy 252.21438 -33.717992)
			(xy 252.21438 -33.4899) (xy 252.214882 -33.479693) (xy 252.222694 -33.460832) (xy 252.237129 -33.446396)
			(xy 252.255989 -33.438583) (xy 252.266196 -33.438084) (xy 253.002796 -33.438084) (xy 253.013018 -33.438515)
			(xy 253.031905 -33.446337) (xy 253.046361 -33.460792) (xy 253.054184 -33.479679) (xy 253.054612 -33.4899)
			(xy 253.054612 -33.717484) (xy 253.054358 -33.721548) (xy 253.054104 -33.724088) (xy 253.054104 -33.732724)
			(xy 253.048262 -33.742122) (xy 253.0475 -33.743392) (xy 253.04623 -33.745424) (xy 252.84049 -34.06013)
			(xy 252.83546 -34.068663) (xy 252.831633 -34.088075) (xy 252.835441 -34.10749) (xy 252.84049 -34.11601)
			(xy 253.04623 -34.429446) (xy 253.047246 -34.431478) (xy 253.048516 -34.43351) (xy 253.054104 -34.442146)
			(xy 253.054104 -34.450782) (xy 253.054358 -34.453322) (xy 253.054612 -34.457386) (xy 253.054612 -34.520886)
			(xy 253.689612 -34.520886) (xy 253.689612 -33.657286) (xy 253.690102 -33.627318) (xy 253.697925 -33.567896)
			(xy 253.713438 -33.510003) (xy 253.736374 -33.45463) (xy 253.766341 -33.402724) (xy 253.802828 -33.355174)
			(xy 253.845208 -33.312794) (xy 253.892758 -33.276307) (xy 253.944664 -33.24634) (xy 254.000037 -33.223404)
			(xy 254.05793 -33.207891) (xy 254.117352 -33.200068) (xy 254.177288 -33.200068) (xy 254.23671 -33.207891)
			(xy 254.294603 -33.223404) (xy 254.349976 -33.24634) (xy 254.401882 -33.276307) (xy 254.449432 -33.312794)
			(xy 254.491812 -33.355174) (xy 254.528299 -33.402724) (xy 254.558266 -33.45463) (xy 254.581202 -33.510003)
			(xy 254.596715 -33.567896) (xy 254.604538 -33.627318) (xy 254.605028 -33.657286) (xy 254.605028 -34.520886)
			(xy 254.605003 -34.52241) (xy 264.95248 -34.52241) (xy 264.95248 -33.65881) (xy 264.95297 -33.628826)
			(xy 264.960798 -33.56937) (xy 264.976319 -33.511445) (xy 264.999268 -33.456041) (xy 265.029252 -33.404107)
			(xy 265.065758 -33.356531) (xy 265.108163 -33.314126) (xy 265.155739 -33.27762) (xy 265.207673 -33.247636)
			(xy 265.263077 -33.224687) (xy 265.321002 -33.209166) (xy 265.380458 -33.201338) (xy 265.440426 -33.201338)
			(xy 265.499882 -33.209166) (xy 265.557807 -33.224687) (xy 265.613211 -33.247636) (xy 265.665145 -33.27762)
			(xy 265.712721 -33.314126) (xy 265.755126 -33.356531) (xy 265.791632 -33.404107) (xy 265.821616 -33.456041)
			(xy 265.844565 -33.511445) (xy 265.860086 -33.56937) (xy 265.867914 -33.628826) (xy 265.868404 -33.65881)
			(xy 265.868404 -34.52241) (xy 265.867914 -34.552394) (xy 265.860859 -34.605976) (xy 268.22908 -34.605976)
			(xy 268.22908 -33.574228) (xy 268.229538 -33.56411) (xy 268.237273 -33.545411) (xy 268.251577 -33.531096)
			(xy 268.27027 -33.523346) (xy 268.280388 -33.52292) (xy 269.512542 -33.52292) (xy 269.522669 -33.523392)
			(xy 269.541387 -33.531129) (xy 269.555741 -33.54542) (xy 269.563563 -33.564103) (xy 269.564104 -33.574228)
			(xy 269.564104 -34.605976) (xy 272.76552 -34.605976) (xy 272.76552 -33.574228) (xy 272.765945 -33.564073)
			(xy 272.773735 -33.545317) (xy 272.788131 -33.530992) (xy 272.806925 -33.523295) (xy 272.817082 -33.52292)
			(xy 274.048982 -33.52292) (xy 274.059105 -33.523441) (xy 274.077822 -33.531159) (xy 274.092178 -33.545434)
			(xy 274.100002 -33.564108) (xy 274.100544 -33.574228) (xy 274.100544 -34.605976) (xy 274.10006 -34.616123)
			(xy 274.09228 -34.634867) (xy 274.077903 -34.649189) (xy 274.059131 -34.656898) (xy 274.048982 -34.657284)
			(xy 272.817082 -34.657284) (xy 272.806957 -34.656789) (xy 272.78824 -34.64906) (xy 272.773885 -34.634777)
			(xy 272.766062 -34.616098) (xy 272.76552 -34.605976) (xy 269.564104 -34.605976) (xy 269.563665 -34.616096)
			(xy 269.555925 -34.634799) (xy 269.541616 -34.649114) (xy 269.522916 -34.656861) (xy 269.512796 -34.657284)
			(xy 268.280642 -34.657284) (xy 268.270521 -34.65674) (xy 268.251805 -34.64903) (xy 268.237448 -34.634762)
			(xy 268.229624 -34.616094) (xy 268.22908 -34.605976) (xy 265.860859 -34.605976) (xy 265.860086 -34.61185)
			(xy 265.844565 -34.669775) (xy 265.837745 -34.68624) (xy 278.214328 -34.68624) (xy 278.214328 -34.443416)
			(xy 278.219916 -34.435034) (xy 278.22017 -34.434526) (xy 278.222202 -34.431478) (xy 278.222456 -34.43097)
			(xy 278.428196 -34.117026) (xy 278.433153 -34.108571) (xy 278.436984 -34.089373) (xy 278.433357 -34.070135)
			(xy 278.42845 -34.061654) (xy 278.342598 -33.929574) (xy 278.3332 -33.915096) (xy 278.220932 -33.743138)
			(xy 278.220424 -33.742122) (xy 278.218392 -33.739074) (xy 278.218138 -33.738566) (xy 278.214328 -33.732724)
			(xy 278.214328 -33.4899) (xy 278.214713 -33.479673) (xy 278.222544 -33.460777) (xy 278.237014 -33.44632)
			(xy 278.255916 -33.438504) (xy 278.266144 -33.438084) (xy 279.002744 -33.438084) (xy 279.012955 -33.438546)
			(xy 279.031817 -33.446373) (xy 279.046252 -33.46082) (xy 279.054063 -33.479689) (xy 279.05456 -33.4899)
			(xy 279.05456 -33.732724) (xy 279.05075 -33.738566) (xy 279.050496 -33.739074) (xy 279.046432 -33.74517)
			(xy 279.046178 -33.745424) (xy 278.908256 -33.956498) (xy 278.85517 -34.037778) (xy 278.842724 -34.056828)
			(xy 278.840692 -34.059622) (xy 278.839422 -34.061654) (xy 278.835176 -34.069048) (xy 278.831477 -34.085685)
			(xy 278.833456 -34.102613) (xy 278.836882 -34.110422) (xy 279.02408 -34.395918) (xy 279.02662 -34.399728)
			(xy 279.046432 -34.4297) (xy 279.046686 -34.430208) (xy 279.047956 -34.43224) (xy 279.049734 -34.43478)
			(xy 279.05456 -34.442146) (xy 279.05456 -34.520886) (xy 279.68956 -34.520886) (xy 279.68956 -33.657286)
			(xy 279.69005 -33.627318) (xy 279.697873 -33.567896) (xy 279.713386 -33.510003) (xy 279.736322 -33.45463)
			(xy 279.766289 -33.402724) (xy 279.802776 -33.355174) (xy 279.845156 -33.312794) (xy 279.892706 -33.276307)
			(xy 279.944612 -33.24634) (xy 279.999985 -33.223404) (xy 280.057878 -33.207891) (xy 280.1173 -33.200068)
			(xy 280.177236 -33.200068) (xy 280.236658 -33.207891) (xy 280.294551 -33.223404) (xy 280.349924 -33.24634)
			(xy 280.40183 -33.276307) (xy 280.44938 -33.312794) (xy 280.49176 -33.355174) (xy 280.528247 -33.402724)
			(xy 280.558214 -33.45463) (xy 280.58115 -33.510003) (xy 280.596663 -33.567896) (xy 280.604486 -33.627318)
			(xy 280.604976 -33.657286) (xy 280.604976 -34.520886) (xy 280.604951 -34.52241) (xy 290.952428 -34.52241)
			(xy 290.952428 -33.65881) (xy 290.952918 -33.628826) (xy 290.960746 -33.56937) (xy 290.976267 -33.511445)
			(xy 290.999216 -33.456041) (xy 291.0292 -33.404107) (xy 291.065706 -33.356531) (xy 291.108111 -33.314126)
			(xy 291.155687 -33.27762) (xy 291.207621 -33.247636) (xy 291.263025 -33.224687) (xy 291.32095 -33.209166)
			(xy 291.380406 -33.201338) (xy 291.440374 -33.201338) (xy 291.49983 -33.209166) (xy 291.557755 -33.224687)
			(xy 291.613159 -33.247636) (xy 291.665093 -33.27762) (xy 291.712669 -33.314126) (xy 291.755074 -33.356531)
			(xy 291.79158 -33.404107) (xy 291.821564 -33.456041) (xy 291.844513 -33.511445) (xy 291.860034 -33.56937)
			(xy 291.867862 -33.628826) (xy 291.868352 -33.65881) (xy 291.868352 -34.52241) (xy 291.867862 -34.552394)
			(xy 291.860807 -34.605976) (xy 294.229028 -34.605976) (xy 294.229028 -33.574228) (xy 294.229439 -33.564104)
			(xy 294.237184 -33.545395) (xy 294.251502 -33.531079) (xy 294.270212 -33.523338) (xy 294.280336 -33.52292)
			(xy 295.51249 -33.52292) (xy 295.522614 -33.523434) (xy 295.541331 -33.531155) (xy 295.555687 -33.545433)
			(xy 295.56351 -33.564107) (xy 295.564052 -33.574228) (xy 295.564052 -34.605976) (xy 298.765468 -34.605976)
			(xy 298.765468 -33.574228) (xy 298.765944 -33.56408) (xy 298.773724 -33.545334) (xy 298.788104 -33.531011)
			(xy 298.80688 -33.523304) (xy 298.81703 -33.52292) (xy 300.04893 -33.52292) (xy 300.059056 -33.523401)
			(xy 300.077774 -33.531135) (xy 300.092129 -33.545423) (xy 300.09995 -33.564104) (xy 300.100492 -33.574228)
			(xy 300.100492 -34.605976) (xy 300.100059 -34.61613) (xy 300.09227 -34.634883) (xy 300.077876 -34.649208)
			(xy 300.059086 -34.656907) (xy 300.04893 -34.657284) (xy 298.81703 -34.657284) (xy 298.806908 -34.65675)
			(xy 298.788192 -34.649036) (xy 298.773836 -34.634765) (xy 298.766011 -34.616095) (xy 298.765468 -34.605976)
			(xy 295.564052 -34.605976) (xy 295.563497 -34.616077) (xy 295.555777 -34.634745) (xy 295.541502 -34.649038)
			(xy 295.522844 -34.656783) (xy 295.512744 -34.657284) (xy 294.28059 -34.657284) (xy 294.270466 -34.656782)
			(xy 294.251749 -34.649056) (xy 294.237394 -34.634774) (xy 294.229571 -34.616098) (xy 294.229028 -34.605976)
			(xy 291.860807 -34.605976) (xy 291.860034 -34.61185) (xy 291.844513 -34.669775) (xy 291.837693 -34.68624)
			(xy 304.214276 -34.68624) (xy 304.214276 -34.458656) (xy 304.21453 -34.454592) (xy 304.214784 -34.452052)
			(xy 304.214784 -34.443416) (xy 304.220372 -34.43478) (xy 304.221642 -34.432748) (xy 304.222658 -34.430716)
			(xy 304.420016 -34.129726) (xy 304.423884 -34.123398) (xy 304.428145 -34.109198) (xy 304.428398 -34.101786)
			(xy 304.428398 -34.076132) (xy 304.428191 -34.068798) (xy 304.424061 -34.054727) (xy 304.42027 -34.048446)
			(xy 304.222404 -33.745424) (xy 304.220118 -33.741614) (xy 304.219864 -33.741106) (xy 304.218848 -33.739328)
			(xy 304.214784 -33.732724) (xy 304.214784 -33.724596) (xy 304.21453 -33.722056) (xy 304.214276 -33.717992)
			(xy 304.214276 -33.4899) (xy 304.214782 -33.479693) (xy 304.222593 -33.460833) (xy 304.237026 -33.446397)
			(xy 304.255885 -33.438583) (xy 304.266092 -33.438084) (xy 305.002692 -33.438084) (xy 305.012913 -33.438519)
			(xy 305.0318 -33.446339) (xy 305.046256 -33.460793) (xy 305.05408 -33.479679) (xy 305.054508 -33.4899)
			(xy 305.054508 -33.717484) (xy 305.054254 -33.721548) (xy 305.054 -33.724088) (xy 305.054 -33.732724)
			(xy 305.048158 -33.742122) (xy 305.047396 -33.743392) (xy 305.046126 -33.745424) (xy 304.840386 -34.06013)
			(xy 304.835356 -34.068663) (xy 304.831529 -34.088075) (xy 304.835337 -34.10749) (xy 304.840386 -34.11601)
			(xy 305.046126 -34.429446) (xy 305.047142 -34.431478) (xy 305.048412 -34.43351) (xy 305.054 -34.442146)
			(xy 305.054 -34.450782) (xy 305.054254 -34.453322) (xy 305.054508 -34.457386) (xy 305.054508 -34.520886)
			(xy 305.689508 -34.520886) (xy 305.689508 -33.657286) (xy 305.689998 -33.627318) (xy 305.697821 -33.567896)
			(xy 305.713334 -33.510003) (xy 305.73627 -33.45463) (xy 305.766237 -33.402724) (xy 305.802724 -33.355174)
			(xy 305.845104 -33.312794) (xy 305.892654 -33.276307) (xy 305.94456 -33.24634) (xy 305.999933 -33.223404)
			(xy 306.057826 -33.207891) (xy 306.117248 -33.200068) (xy 306.177184 -33.200068) (xy 306.236606 -33.207891)
			(xy 306.294499 -33.223404) (xy 306.349872 -33.24634) (xy 306.401778 -33.276307) (xy 306.449328 -33.312794)
			(xy 306.491708 -33.355174) (xy 306.528195 -33.402724) (xy 306.558162 -33.45463) (xy 306.581098 -33.510003)
			(xy 306.596611 -33.567896) (xy 306.604434 -33.627318) (xy 306.604924 -33.657286) (xy 306.604924 -34.520886)
			(xy 306.604899 -34.52241) (xy 316.952376 -34.52241) (xy 316.952376 -33.65881) (xy 316.952866 -33.628826)
			(xy 316.960694 -33.56937) (xy 316.976215 -33.511445) (xy 316.999164 -33.456041) (xy 317.029148 -33.404107)
			(xy 317.065654 -33.356531) (xy 317.108059 -33.314126) (xy 317.155635 -33.27762) (xy 317.207569 -33.247636)
			(xy 317.262973 -33.224687) (xy 317.320898 -33.209166) (xy 317.380354 -33.201338) (xy 317.440322 -33.201338)
			(xy 317.499778 -33.209166) (xy 317.557703 -33.224687) (xy 317.613107 -33.247636) (xy 317.665041 -33.27762)
			(xy 317.712617 -33.314126) (xy 317.755022 -33.356531) (xy 317.791528 -33.404107) (xy 317.821512 -33.456041)
			(xy 317.844461 -33.511445) (xy 317.859982 -33.56937) (xy 317.86781 -33.628826) (xy 317.8683 -33.65881)
			(xy 317.8683 -34.52241) (xy 317.86781 -34.552394) (xy 317.860755 -34.605976) (xy 320.228976 -34.605976)
			(xy 320.228976 -33.574228) (xy 320.229438 -33.56411) (xy 320.237173 -33.545412) (xy 320.251475 -33.531097)
			(xy 320.270167 -33.523347) (xy 320.280284 -33.52292) (xy 321.512438 -33.52292) (xy 321.522565 -33.523395)
			(xy 321.541283 -33.531131) (xy 321.555637 -33.545421) (xy 321.563459 -33.564104) (xy 321.564 -33.574228)
			(xy 321.564 -34.605976) (xy 324.765416 -34.605976) (xy 324.765416 -33.574228) (xy 324.765845 -33.564074)
			(xy 324.773634 -33.545319) (xy 324.788029 -33.530994) (xy 324.806822 -33.523296) (xy 324.816978 -33.52292)
			(xy 326.048878 -33.52292) (xy 326.059001 -33.523444) (xy 326.077718 -33.531161) (xy 326.092074 -33.545435)
			(xy 326.099898 -33.564108) (xy 326.10044 -33.574228) (xy 326.10044 -34.605976) (xy 326.09996 -34.616124)
			(xy 326.09218 -34.634868) (xy 326.077801 -34.649191) (xy 326.059027 -34.656898) (xy 326.048878 -34.657284)
			(xy 324.816978 -34.657284) (xy 324.806853 -34.656792) (xy 324.788136 -34.649062) (xy 324.773781 -34.634778)
			(xy 324.765958 -34.616099) (xy 324.765416 -34.605976) (xy 321.564 -34.605976) (xy 321.563565 -34.616097)
			(xy 321.555824 -34.6348) (xy 321.541514 -34.649115) (xy 321.522813 -34.656861) (xy 321.512692 -34.657284)
			(xy 320.280538 -34.657284) (xy 320.270417 -34.656743) (xy 320.251701 -34.649032) (xy 320.237344 -34.634762)
			(xy 320.22952 -34.616094) (xy 320.228976 -34.605976) (xy 317.860755 -34.605976) (xy 317.859982 -34.61185)
			(xy 317.844461 -34.669775) (xy 317.837641 -34.68624) (xy 330.214224 -34.68624) (xy 330.214224 -34.458656)
			(xy 330.214478 -34.454592) (xy 330.214732 -34.452052) (xy 330.214732 -34.443416) (xy 330.22032 -34.43478)
			(xy 330.22159 -34.432748) (xy 330.222606 -34.430716) (xy 330.419964 -34.129726) (xy 330.423836 -34.1234)
			(xy 330.428093 -34.109199) (xy 330.428346 -34.101786) (xy 330.428346 -34.076132) (xy 330.428147 -34.068797)
			(xy 330.424012 -34.054726) (xy 330.420218 -34.048446) (xy 330.222352 -33.745424) (xy 330.220066 -33.741614)
			(xy 330.219812 -33.741106) (xy 330.218796 -33.739328) (xy 330.214732 -33.732724) (xy 330.214732 -33.724596)
			(xy 330.214478 -33.722056) (xy 330.214224 -33.717992) (xy 330.214224 -33.4899) (xy 330.214613 -33.479673)
			(xy 330.222444 -33.460778) (xy 330.236912 -33.446321) (xy 330.255813 -33.438505) (xy 330.26604 -33.438084)
			(xy 331.00264 -33.438084) (xy 331.01285 -33.438549) (xy 331.031713 -33.446375) (xy 331.046147 -33.460821)
			(xy 331.053959 -33.479689) (xy 331.054456 -33.4899) (xy 331.054456 -33.717484) (xy 331.054202 -33.721548)
			(xy 331.053948 -33.724088) (xy 331.053948 -33.732724) (xy 331.048106 -33.742122) (xy 331.047344 -33.743392)
			(xy 331.046074 -33.745424) (xy 330.840334 -34.06013) (xy 330.835308 -34.068664) (xy 330.831485 -34.088075)
			(xy 330.835289 -34.107489) (xy 330.840334 -34.11601) (xy 331.046074 -34.429446) (xy 331.04709 -34.431478)
			(xy 331.04836 -34.43351) (xy 331.053948 -34.442146) (xy 331.053948 -34.450782) (xy 331.054202 -34.453322)
			(xy 331.054456 -34.457386) (xy 331.054456 -34.520886) (xy 331.689456 -34.520886) (xy 331.689456 -33.657286)
			(xy 331.689946 -33.627318) (xy 331.697769 -33.567896) (xy 331.713282 -33.510003) (xy 331.736218 -33.45463)
			(xy 331.766185 -33.402724) (xy 331.802672 -33.355174) (xy 331.845052 -33.312794) (xy 331.892602 -33.276307)
			(xy 331.944508 -33.24634) (xy 331.999881 -33.223404) (xy 332.057774 -33.207891) (xy 332.117196 -33.200068)
			(xy 332.177132 -33.200068) (xy 332.236554 -33.207891) (xy 332.294447 -33.223404) (xy 332.34982 -33.24634)
			(xy 332.401726 -33.276307) (xy 332.449276 -33.312794) (xy 332.491656 -33.355174) (xy 332.528143 -33.402724)
			(xy 332.55811 -33.45463) (xy 332.581046 -33.510003) (xy 332.596559 -33.567896) (xy 332.604382 -33.627318)
			(xy 332.604872 -33.657286) (xy 332.604872 -34.520886) (xy 332.604847 -34.52241) (xy 355.052884 -34.52241)
			(xy 355.052884 -33.65881) (xy 355.053374 -33.628842) (xy 355.061197 -33.56942) (xy 355.07671 -33.511527)
			(xy 355.099646 -33.456154) (xy 355.129613 -33.404248) (xy 355.1661 -33.356698) (xy 355.20848 -33.314318)
			(xy 355.25603 -33.277831) (xy 355.307936 -33.247864) (xy 355.363309 -33.224928) (xy 355.421202 -33.209415)
			(xy 355.480624 -33.201592) (xy 355.54056 -33.201592) (xy 355.599982 -33.209415) (xy 355.657875 -33.224928)
			(xy 355.713248 -33.247864) (xy 355.765154 -33.277831) (xy 355.812704 -33.314318) (xy 355.855084 -33.356698)
			(xy 355.891571 -33.404248) (xy 355.921538 -33.456154) (xy 355.944474 -33.511527) (xy 355.959987 -33.56942)
			(xy 355.96781 -33.628842) (xy 355.9683 -33.65881) (xy 355.9683 -34.52241) (xy 355.96781 -34.552378)
			(xy 355.960754 -34.605976) (xy 358.329484 -34.605976) (xy 358.329484 -33.574228) (xy 358.329938 -33.564109)
			(xy 358.337674 -33.545409) (xy 358.351979 -33.531095) (xy 358.370674 -33.523345) (xy 358.380792 -33.52292)
			(xy 359.612692 -33.52292) (xy 359.622816 -33.523323) (xy 359.641524 -33.531072) (xy 359.655839 -33.545393)
			(xy 359.663581 -33.564103) (xy 359.664 -33.574228) (xy 359.664 -34.605976) (xy 362.865924 -34.605976)
			(xy 362.865924 -33.574228) (xy 362.866339 -33.564104) (xy 362.874083 -33.545397) (xy 362.8884 -33.53108)
			(xy 362.907108 -33.523339) (xy 362.917232 -33.52292) (xy 364.149132 -33.52292) (xy 364.159245 -33.523359)
			(xy 364.177928 -33.531111) (xy 364.192222 -33.545422) (xy 364.199952 -33.564114) (xy 364.20044 -33.574228)
			(xy 364.20044 -34.605976) (xy 364.199896 -34.616078) (xy 364.192174 -34.634748) (xy 364.177895 -34.649043)
			(xy 364.159234 -34.656785) (xy 364.149132 -34.657284) (xy 362.917232 -34.657284) (xy 362.90711 -34.656858)
			(xy 362.888403 -34.649117) (xy 362.874087 -34.634803) (xy 362.866344 -34.616098) (xy 362.865924 -34.605976)
			(xy 359.664 -34.605976) (xy 359.663565 -34.616097) (xy 359.655824 -34.6348) (xy 359.641514 -34.649115)
			(xy 359.622813 -34.656861) (xy 359.612692 -34.657284) (xy 358.380792 -34.657284) (xy 358.370667 -34.65689)
			(xy 358.35196 -34.649136) (xy 358.337646 -34.634813) (xy 358.329904 -34.616101) (xy 358.329484 -34.605976)
			(xy 355.960754 -34.605976) (xy 355.959987 -34.6118) (xy 355.944474 -34.669693) (xy 355.93762 -34.68624)
			(xy 368.314732 -34.68624) (xy 368.314732 -34.443416) (xy 368.433604 -34.26206) (xy 368.496088 -34.166556)
			(xy 368.520218 -34.129726) (xy 368.524086 -34.123398) (xy 368.528347 -34.109198) (xy 368.5286 -34.101786)
			(xy 368.5286 -34.075878) (xy 368.528422 -34.069727) (xy 368.525459 -34.057786) (xy 368.522758 -34.052256)
			(xy 368.40922 -33.878266) (xy 368.389154 -33.847278) (xy 368.383566 -33.838642) (xy 368.323114 -33.745932)
			(xy 368.322606 -33.74517) (xy 368.322098 -33.744408) (xy 368.321844 -33.7439) (xy 368.321336 -33.743138)
			(xy 368.314732 -33.732724) (xy 368.314732 -33.4899) (xy 368.315383 -33.478349) (xy 368.325338 -33.457499)
			(xy 368.343276 -33.442937) (xy 368.354356 -33.439608) (xy 368.366294 -33.438084) (xy 369.102894 -33.438084)
			(xy 369.113651 -33.438605) (xy 369.13334 -33.447272) (xy 369.140994 -33.454848) (xy 369.147191 -33.462248)
			(xy 369.154105 -33.480254) (xy 369.154456 -33.4899) (xy 369.154456 -33.732724) (xy 368.938556 -34.063178)
			(xy 368.934535 -34.071399) (xy 368.931995 -34.089509) (xy 368.935938 -34.107366) (xy 368.940588 -34.115248)
			(xy 368.972846 -34.165032) (xy 369.154456 -34.442146) (xy 369.154456 -34.520886) (xy 369.789456 -34.520886)
			(xy 369.789456 -33.657286) (xy 369.789946 -33.627302) (xy 369.797774 -33.567846) (xy 369.813295 -33.509921)
			(xy 369.836244 -33.454517) (xy 369.866228 -33.402583) (xy 369.902734 -33.355007) (xy 369.945139 -33.312602)
			(xy 369.992715 -33.276096) (xy 370.044649 -33.246112) (xy 370.100053 -33.223163) (xy 370.157978 -33.207642)
			(xy 370.217434 -33.199814) (xy 370.277402 -33.199814) (xy 370.336858 -33.207642) (xy 370.394783 -33.223163)
			(xy 370.450187 -33.246112) (xy 370.502121 -33.276096) (xy 370.549697 -33.312602) (xy 370.592102 -33.355007)
			(xy 370.628608 -33.402583) (xy 370.658592 -33.454517) (xy 370.681541 -33.509921) (xy 370.697062 -33.567846)
			(xy 370.70489 -33.627302) (xy 370.70538 -33.657286) (xy 370.70538 -34.520886) (xy 370.705355 -34.52241)
			(xy 381.052832 -34.52241) (xy 381.052832 -33.65881) (xy 381.053322 -33.628842) (xy 381.061145 -33.56942)
			(xy 381.076658 -33.511527) (xy 381.099594 -33.456154) (xy 381.129561 -33.404248) (xy 381.166048 -33.356698)
			(xy 381.208428 -33.314318) (xy 381.255978 -33.277831) (xy 381.307884 -33.247864) (xy 381.363257 -33.224928)
			(xy 381.42115 -33.209415) (xy 381.480572 -33.201592) (xy 381.540508 -33.201592) (xy 381.59993 -33.209415)
			(xy 381.657823 -33.224928) (xy 381.713196 -33.247864) (xy 381.765102 -33.277831) (xy 381.812652 -33.314318)
			(xy 381.855032 -33.356698) (xy 381.891519 -33.404248) (xy 381.921486 -33.456154) (xy 381.944422 -33.511527)
			(xy 381.959935 -33.56942) (xy 381.967758 -33.628842) (xy 381.968248 -33.65881) (xy 381.968248 -34.52241)
			(xy 381.967758 -34.552378) (xy 381.960702 -34.605976) (xy 384.329432 -34.605976) (xy 384.329432 -33.574228)
			(xy 384.329839 -33.564103) (xy 384.337584 -33.545394) (xy 384.351904 -33.531078) (xy 384.370615 -33.523337)
			(xy 384.38074 -33.52292) (xy 385.61264 -33.52292) (xy 385.622754 -33.523353) (xy 385.641437 -33.531107)
			(xy 385.655731 -33.54542) (xy 385.663461 -33.564114) (xy 385.663948 -33.574228) (xy 385.663948 -34.605976)
			(xy 388.865872 -34.605976) (xy 388.865872 -33.574228) (xy 388.866338 -33.564111) (xy 388.874072 -33.545413)
			(xy 388.888373 -33.531099) (xy 388.907063 -33.523347) (xy 388.91718 -33.52292) (xy 390.14908 -33.52292)
			(xy 390.159204 -33.523333) (xy 390.177911 -33.531078) (xy 390.192226 -33.545396) (xy 390.199969 -33.564104)
			(xy 390.200388 -33.574228) (xy 390.200388 -34.605976) (xy 390.199964 -34.616098) (xy 390.192222 -34.634804)
			(xy 390.177907 -34.649119) (xy 390.159202 -34.656863) (xy 390.14908 -34.657284) (xy 388.91718 -34.657284)
			(xy 388.907054 -34.6569) (xy 388.888347 -34.649142) (xy 388.874033 -34.634816) (xy 388.866291 -34.616102)
			(xy 388.865872 -34.605976) (xy 385.663948 -34.605976) (xy 385.663397 -34.616077) (xy 385.655676 -34.634746)
			(xy 385.6414 -34.64904) (xy 385.622741 -34.656784) (xy 385.61264 -34.657284) (xy 384.38074 -34.657284)
			(xy 384.370618 -34.656851) (xy 384.351912 -34.649113) (xy 384.337596 -34.634801) (xy 384.329852 -34.616098)
			(xy 384.329432 -34.605976) (xy 381.960702 -34.605976) (xy 381.959935 -34.6118) (xy 381.944422 -34.669693)
			(xy 381.937568 -34.68624) (xy 394.31468 -34.68624) (xy 394.31468 -34.443416) (xy 394.433552 -34.26206)
			(xy 394.496036 -34.166556) (xy 394.520166 -34.129726) (xy 394.524038 -34.1234) (xy 394.528295 -34.109199)
			(xy 394.528548 -34.101786) (xy 394.528548 -34.075878) (xy 394.528365 -34.069727) (xy 394.525404 -34.057787)
			(xy 394.522706 -34.052256) (xy 394.409168 -33.878266) (xy 394.389102 -33.847278) (xy 394.383514 -33.838642)
			(xy 394.323062 -33.745932) (xy 394.322554 -33.74517) (xy 394.322046 -33.744408) (xy 394.321792 -33.7439)
			(xy 394.321284 -33.743138) (xy 394.31468 -33.732724) (xy 394.31468 -33.4899) (xy 394.315369 -33.478355)
			(xy 394.325312 -33.457511) (xy 394.343233 -33.442945) (xy 394.354304 -33.439608) (xy 394.366242 -33.438084)
			(xy 395.102842 -33.438084) (xy 395.113596 -33.438633) (xy 395.133285 -33.44728) (xy 395.140942 -33.454848)
			(xy 395.147133 -33.462253) (xy 395.154052 -33.480255) (xy 395.154404 -33.4899) (xy 395.154404 -33.732724)
			(xy 394.938504 -34.063178) (xy 394.934478 -34.071397) (xy 394.931936 -34.089509) (xy 394.935883 -34.107367)
			(xy 394.940536 -34.115248) (xy 394.972794 -34.165032) (xy 395.154404 -34.442146) (xy 395.154404 -34.520886)
			(xy 395.789404 -34.520886) (xy 395.789404 -33.657286) (xy 395.789894 -33.627302) (xy 395.797722 -33.567846)
			(xy 395.813243 -33.509921) (xy 395.836192 -33.454517) (xy 395.866176 -33.402583) (xy 395.902682 -33.355007)
			(xy 395.945087 -33.312602) (xy 395.992663 -33.276096) (xy 396.044597 -33.246112) (xy 396.100001 -33.223163)
			(xy 396.157926 -33.207642) (xy 396.217382 -33.199814) (xy 396.27735 -33.199814) (xy 396.336806 -33.207642)
			(xy 396.394731 -33.223163) (xy 396.450135 -33.246112) (xy 396.502069 -33.276096) (xy 396.549645 -33.312602)
			(xy 396.59205 -33.355007) (xy 396.628556 -33.402583) (xy 396.65854 -33.454517) (xy 396.681489 -33.509921)
			(xy 396.69701 -33.567846) (xy 396.704838 -33.627302) (xy 396.705328 -33.657286) (xy 396.705328 -34.520886)
			(xy 396.705303 -34.52241) (xy 407.05278 -34.52241) (xy 407.05278 -33.65881) (xy 407.05327 -33.628842)
			(xy 407.061093 -33.56942) (xy 407.076606 -33.511527) (xy 407.099542 -33.456154) (xy 407.129509 -33.404248)
			(xy 407.165996 -33.356698) (xy 407.208376 -33.314318) (xy 407.255926 -33.277831) (xy 407.307832 -33.247864)
			(xy 407.363205 -33.224928) (xy 407.421098 -33.209415) (xy 407.48052 -33.201592) (xy 407.540456 -33.201592)
			(xy 407.599878 -33.209415) (xy 407.657771 -33.224928) (xy 407.713144 -33.247864) (xy 407.76505 -33.277831)
			(xy 407.8126 -33.314318) (xy 407.85498 -33.356698) (xy 407.891467 -33.404248) (xy 407.921434 -33.456154)
			(xy 407.94437 -33.511527) (xy 407.959883 -33.56942) (xy 407.967706 -33.628842) (xy 407.968196 -33.65881)
			(xy 407.968196 -34.52241) (xy 407.967706 -34.552378) (xy 407.96065 -34.605976) (xy 410.32938 -34.605976)
			(xy 410.32938 -33.574228) (xy 410.329838 -33.56411) (xy 410.337573 -33.545411) (xy 410.351877 -33.531096)
			(xy 410.37057 -33.523346) (xy 410.380688 -33.52292) (xy 411.612588 -33.52292) (xy 411.622712 -33.523326)
			(xy 411.641419 -33.531074) (xy 411.655735 -33.545394) (xy 411.663477 -33.564104) (xy 411.663896 -33.574228)
			(xy 411.663896 -34.605976) (xy 414.86582 -34.605976) (xy 414.86582 -33.574228) (xy 414.866239 -33.564105)
			(xy 414.873982 -33.545398) (xy 414.888298 -33.531082) (xy 414.907005 -33.523339) (xy 414.917128 -33.52292)
			(xy 416.149028 -33.52292) (xy 416.159141 -33.523363) (xy 416.177824 -33.531113) (xy 416.192118 -33.545423)
			(xy 416.199848 -33.564114) (xy 416.200336 -33.574228) (xy 416.200336 -34.605976) (xy 416.199796 -34.616079)
			(xy 416.192073 -34.63475) (xy 416.177793 -34.649044) (xy 416.15913 -34.656786) (xy 416.149028 -34.657284)
			(xy 414.917128 -34.657284) (xy 414.907005 -34.656861) (xy 414.888299 -34.649119) (xy 414.873983 -34.634804)
			(xy 414.86624 -34.616099) (xy 414.86582 -34.605976) (xy 411.663896 -34.605976) (xy 411.663464 -34.616097)
			(xy 411.655723 -34.634801) (xy 411.641411 -34.649117) (xy 411.622709 -34.656862) (xy 411.612588 -34.657284)
			(xy 410.380688 -34.657284) (xy 410.370563 -34.656894) (xy 410.351856 -34.649139) (xy 410.337541 -34.634814)
			(xy 410.329799 -34.616102) (xy 410.32938 -34.605976) (xy 407.96065 -34.605976) (xy 407.959883 -34.6118)
			(xy 407.94437 -34.669693) (xy 407.937516 -34.68624) (xy 420.314628 -34.68624) (xy 420.314628 -34.443416)
			(xy 420.459408 -34.22269) (xy 420.508684 -34.147252) (xy 420.528496 -34.117026) (xy 420.533419 -34.108551)
			(xy 420.537164 -34.089334) (xy 420.533445 -34.070112) (xy 420.528496 -34.061654) (xy 420.383462 -33.838642)
			(xy 420.327836 -33.753298) (xy 420.323518 -33.747202) (xy 420.320216 -33.741614) (xy 420.319708 -33.740598)
			(xy 420.314628 -33.732724) (xy 420.314628 -33.4899) (xy 420.31529 -33.478384) (xy 420.325149 -33.45757)
			(xy 420.34297 -33.44298) (xy 420.353998 -33.439608) (xy 420.354252 -33.439608) (xy 420.36619 -33.438084)
			(xy 421.10279 -33.438084) (xy 421.109163 -33.438317) (xy 421.1215 -33.441524) (xy 421.127174 -33.444434)
			(xy 421.135188 -33.449171) (xy 421.147427 -33.463181) (xy 421.153962 -33.480598) (xy 421.154352 -33.4899)
			(xy 421.154352 -33.732724) (xy 420.938452 -34.063178) (xy 420.934421 -34.071396) (xy 420.931876 -34.089509)
			(xy 420.935827 -34.107368) (xy 420.940484 -34.115248) (xy 420.972742 -34.165032) (xy 420.988236 -34.188654)
			(xy 421.154352 -34.442146) (xy 421.154352 -34.520886) (xy 421.789352 -34.520886) (xy 421.789352 -33.657286)
			(xy 421.789842 -33.627302) (xy 421.79767 -33.567846) (xy 421.813191 -33.509921) (xy 421.83614 -33.454517)
			(xy 421.866124 -33.402583) (xy 421.90263 -33.355007) (xy 421.945035 -33.312602) (xy 421.992611 -33.276096)
			(xy 422.044545 -33.246112) (xy 422.099949 -33.223163) (xy 422.157874 -33.207642) (xy 422.21733 -33.199814)
			(xy 422.277298 -33.199814) (xy 422.336754 -33.207642) (xy 422.394679 -33.223163) (xy 422.450083 -33.246112)
			(xy 422.502017 -33.276096) (xy 422.549593 -33.312602) (xy 422.591998 -33.355007) (xy 422.628504 -33.402583)
			(xy 422.658488 -33.454517) (xy 422.681437 -33.509921) (xy 422.696958 -33.567846) (xy 422.704786 -33.627302)
			(xy 422.705276 -33.657286) (xy 422.705276 -34.520886) (xy 422.705251 -34.52241) (xy 433.052728 -34.52241)
			(xy 433.052728 -33.65881) (xy 433.053218 -33.628842) (xy 433.061041 -33.56942) (xy 433.076554 -33.511527)
			(xy 433.09949 -33.456154) (xy 433.129457 -33.404248) (xy 433.165944 -33.356698) (xy 433.208324 -33.314318)
			(xy 433.255874 -33.277831) (xy 433.30778 -33.247864) (xy 433.363153 -33.224928) (xy 433.421046 -33.209415)
			(xy 433.480468 -33.201592) (xy 433.540404 -33.201592) (xy 433.599826 -33.209415) (xy 433.657719 -33.224928)
			(xy 433.713092 -33.247864) (xy 433.764998 -33.277831) (xy 433.812548 -33.314318) (xy 433.854928 -33.356698)
			(xy 433.891415 -33.404248) (xy 433.921382 -33.456154) (xy 433.944318 -33.511527) (xy 433.959831 -33.56942)
			(xy 433.967654 -33.628842) (xy 433.968144 -33.65881) (xy 433.968144 -34.52241) (xy 433.967654 -34.552378)
			(xy 433.960598 -34.605976) (xy 436.329328 -34.605976) (xy 436.329328 -33.574228) (xy 436.329739 -33.564104)
			(xy 436.337484 -33.545395) (xy 436.351802 -33.531079) (xy 436.370512 -33.523338) (xy 436.380636 -33.52292)
			(xy 437.612536 -33.52292) (xy 437.62265 -33.523356) (xy 437.641332 -33.531109) (xy 437.655627 -33.545421)
			(xy 437.663356 -33.564114) (xy 437.663844 -33.574228) (xy 437.663844 -34.605976) (xy 440.865768 -34.605976)
			(xy 440.865768 -33.574228) (xy 440.866238 -33.564111) (xy 440.873971 -33.545414) (xy 440.888271 -33.5311)
			(xy 440.90696 -33.523348) (xy 440.917076 -33.52292) (xy 442.148976 -33.52292) (xy 442.159099 -33.523336)
			(xy 442.177806 -33.53108) (xy 442.192122 -33.545397) (xy 442.199865 -33.564105) (xy 442.200284 -33.574228)
			(xy 442.200284 -34.605976) (xy 442.199864 -34.616099) (xy 442.192121 -34.634805) (xy 442.177805 -34.649121)
			(xy 442.159099 -34.656864) (xy 442.148976 -34.657284) (xy 440.917076 -34.657284) (xy 440.906964 -34.656834)
			(xy 440.888282 -34.649086) (xy 440.873987 -34.634778) (xy 440.866256 -34.616089) (xy 440.865768 -34.605976)
			(xy 437.663844 -34.605976) (xy 437.663296 -34.616078) (xy 437.655575 -34.634747) (xy 437.641297 -34.649041)
			(xy 437.622637 -34.656785) (xy 437.612536 -34.657284) (xy 436.380636 -34.657284) (xy 436.370514 -34.656854)
			(xy 436.351808 -34.649115) (xy 436.337492 -34.634802) (xy 436.329748 -34.616098) (xy 436.329328 -34.605976)
			(xy 433.960598 -34.605976) (xy 433.959831 -34.6118) (xy 433.944318 -34.669693) (xy 433.937464 -34.68624)
			(xy 446.314576 -34.68624) (xy 446.314576 -34.443416) (xy 446.459356 -34.22269) (xy 446.508632 -34.147252)
			(xy 446.528444 -34.117026) (xy 446.533371 -34.108552) (xy 446.537119 -34.089334) (xy 446.533397 -34.070111)
			(xy 446.528444 -34.061654) (xy 446.38341 -33.838642) (xy 446.327784 -33.753298) (xy 446.323466 -33.747202)
			(xy 446.320164 -33.741614) (xy 446.319656 -33.740598) (xy 446.314576 -33.732724) (xy 446.314576 -33.4899)
			(xy 446.315203 -33.478379) (xy 446.325073 -33.457559) (xy 446.342911 -33.442973) (xy 446.353946 -33.439608)
			(xy 446.3542 -33.439608) (xy 446.366138 -33.438084) (xy 447.102738 -33.438084) (xy 447.109112 -33.4383)
			(xy 447.121449 -33.441519) (xy 447.127122 -33.444434) (xy 447.135146 -33.449155) (xy 447.147379 -33.463175)
			(xy 447.153911 -33.480597) (xy 447.1543 -33.4899) (xy 447.1543 -33.732724) (xy 446.9384 -34.063178)
			(xy 446.934374 -34.071397) (xy 446.931832 -34.089509) (xy 446.935778 -34.107367) (xy 446.940432 -34.115248)
			(xy 446.97269 -34.165032) (xy 446.988184 -34.188654) (xy 447.1543 -34.442146) (xy 447.1543 -34.520886)
			(xy 447.7893 -34.520886) (xy 447.7893 -33.657286) (xy 447.78979 -33.627302) (xy 447.797618 -33.567846)
			(xy 447.813139 -33.509921) (xy 447.836088 -33.454517) (xy 447.866072 -33.402583) (xy 447.902578 -33.355007)
			(xy 447.944983 -33.312602) (xy 447.992559 -33.276096) (xy 448.044493 -33.246112) (xy 448.099897 -33.223163)
			(xy 448.157822 -33.207642) (xy 448.217278 -33.199814) (xy 448.277246 -33.199814) (xy 448.336702 -33.207642)
			(xy 448.394627 -33.223163) (xy 448.450031 -33.246112) (xy 448.501965 -33.276096) (xy 448.549541 -33.312602)
			(xy 448.591946 -33.355007) (xy 448.628452 -33.402583) (xy 448.658436 -33.454517) (xy 448.681385 -33.509921)
			(xy 448.696906 -33.567846) (xy 448.704734 -33.627302) (xy 448.705224 -33.657286) (xy 448.705224 -34.520886)
			(xy 448.704734 -34.55087) (xy 448.696906 -34.610326) (xy 448.681385 -34.668251) (xy 448.658436 -34.723655)
			(xy 448.628452 -34.775589) (xy 448.591946 -34.823165) (xy 448.549541 -34.86557) (xy 448.501965 -34.902076)
			(xy 448.450031 -34.93206) (xy 448.394627 -34.955009) (xy 448.336702 -34.97053) (xy 448.277246 -34.978358)
			(xy 448.217278 -34.978358) (xy 448.157822 -34.97053) (xy 448.099897 -34.955009) (xy 448.044493 -34.93206)
			(xy 447.992559 -34.902076) (xy 447.944983 -34.86557) (xy 447.902578 -34.823165) (xy 447.866072 -34.775589)
			(xy 447.836088 -34.723655) (xy 447.813139 -34.668251) (xy 447.797618 -34.610326) (xy 447.78979 -34.55087)
			(xy 447.7893 -34.520886) (xy 447.1543 -34.520886) (xy 447.1543 -34.68624) (xy 447.153721 -34.697766)
			(xy 447.14383 -34.718591) (xy 447.125973 -34.733172) (xy 447.11493 -34.736532) (xy 447.114676 -34.736532)
			(xy 447.102738 -34.738056) (xy 446.366138 -34.738056) (xy 446.359764 -34.737843) (xy 446.347427 -34.734622)
			(xy 446.341754 -34.731706) (xy 446.333764 -34.726934) (xy 446.32152 -34.71294) (xy 446.314973 -34.695537)
			(xy 446.314576 -34.68624) (xy 433.937464 -34.68624) (xy 433.921382 -34.725066) (xy 433.891415 -34.776972)
			(xy 433.854928 -34.824522) (xy 433.812548 -34.866902) (xy 433.764998 -34.903389) (xy 433.713092 -34.933356)
			(xy 433.657719 -34.956292) (xy 433.599826 -34.971805) (xy 433.540404 -34.979628) (xy 433.480468 -34.979628)
			(xy 433.421046 -34.971805) (xy 433.363153 -34.956292) (xy 433.30778 -34.933356) (xy 433.255874 -34.903389)
			(xy 433.208324 -34.866902) (xy 433.165944 -34.824522) (xy 433.129457 -34.776972) (xy 433.09949 -34.725066)
			(xy 433.076554 -34.669693) (xy 433.061041 -34.6118) (xy 433.053218 -34.552378) (xy 433.052728 -34.52241)
			(xy 422.705251 -34.52241) (xy 422.704786 -34.55087) (xy 422.696958 -34.610326) (xy 422.681437 -34.668251)
			(xy 422.658488 -34.723655) (xy 422.628504 -34.775589) (xy 422.591998 -34.823165) (xy 422.549593 -34.86557)
			(xy 422.502017 -34.902076) (xy 422.450083 -34.93206) (xy 422.394679 -34.955009) (xy 422.336754 -34.97053)
			(xy 422.277298 -34.978358) (xy 422.21733 -34.978358) (xy 422.157874 -34.97053) (xy 422.099949 -34.955009)
			(xy 422.044545 -34.93206) (xy 421.992611 -34.902076) (xy 421.945035 -34.86557) (xy 421.90263 -34.823165)
			(xy 421.866124 -34.775589) (xy 421.83614 -34.723655) (xy 421.813191 -34.668251) (xy 421.79767 -34.610326)
			(xy 421.789842 -34.55087) (xy 421.789352 -34.520886) (xy 421.154352 -34.520886) (xy 421.154352 -34.68624)
			(xy 421.153735 -34.697761) (xy 421.143856 -34.718579) (xy 421.126017 -34.733165) (xy 421.114982 -34.736532)
			(xy 421.114728 -34.736532) (xy 421.10279 -34.738056) (xy 420.36619 -34.738056) (xy 420.359817 -34.737825)
			(xy 420.34748 -34.734616) (xy 420.341806 -34.731706) (xy 420.333806 -34.72695) (xy 420.321567 -34.712947)
			(xy 420.315024 -34.695538) (xy 420.314628 -34.68624) (xy 407.937516 -34.68624) (xy 407.921434 -34.725066)
			(xy 407.891467 -34.776972) (xy 407.85498 -34.824522) (xy 407.8126 -34.866902) (xy 407.76505 -34.903389)
			(xy 407.713144 -34.933356) (xy 407.657771 -34.956292) (xy 407.599878 -34.971805) (xy 407.540456 -34.979628)
			(xy 407.48052 -34.979628) (xy 407.421098 -34.971805) (xy 407.363205 -34.956292) (xy 407.307832 -34.933356)
			(xy 407.255926 -34.903389) (xy 407.208376 -34.866902) (xy 407.165996 -34.824522) (xy 407.129509 -34.776972)
			(xy 407.099542 -34.725066) (xy 407.076606 -34.669693) (xy 407.061093 -34.6118) (xy 407.05327 -34.552378)
			(xy 407.05278 -34.52241) (xy 396.705303 -34.52241) (xy 396.704838 -34.55087) (xy 396.69701 -34.610326)
			(xy 396.681489 -34.668251) (xy 396.65854 -34.723655) (xy 396.628556 -34.775589) (xy 396.59205 -34.823165)
			(xy 396.549645 -34.86557) (xy 396.502069 -34.902076) (xy 396.450135 -34.93206) (xy 396.394731 -34.955009)
			(xy 396.336806 -34.97053) (xy 396.27735 -34.978358) (xy 396.217382 -34.978358) (xy 396.157926 -34.97053)
			(xy 396.100001 -34.955009) (xy 396.044597 -34.93206) (xy 395.992663 -34.902076) (xy 395.945087 -34.86557)
			(xy 395.902682 -34.823165) (xy 395.866176 -34.775589) (xy 395.836192 -34.723655) (xy 395.813243 -34.668251)
			(xy 395.797722 -34.610326) (xy 395.789894 -34.55087) (xy 395.789404 -34.520886) (xy 395.154404 -34.520886)
			(xy 395.154404 -34.68624) (xy 395.153757 -34.69779) (xy 395.143795 -34.718637) (xy 395.125858 -34.733199)
			(xy 395.11478 -34.736532) (xy 395.102842 -34.738056) (xy 394.366242 -34.738056) (xy 394.355485 -34.737533)
			(xy 394.335795 -34.72887) (xy 394.328142 -34.721292) (xy 394.321966 -34.713877) (xy 394.315039 -34.695882)
			(xy 394.31468 -34.68624) (xy 381.937568 -34.68624) (xy 381.921486 -34.725066) (xy 381.891519 -34.776972)
			(xy 381.855032 -34.824522) (xy 381.812652 -34.866902) (xy 381.765102 -34.903389) (xy 381.713196 -34.933356)
			(xy 381.657823 -34.956292) (xy 381.59993 -34.971805) (xy 381.540508 -34.979628) (xy 381.480572 -34.979628)
			(xy 381.42115 -34.971805) (xy 381.363257 -34.956292) (xy 381.307884 -34.933356) (xy 381.255978 -34.903389)
			(xy 381.208428 -34.866902) (xy 381.166048 -34.824522) (xy 381.129561 -34.776972) (xy 381.099594 -34.725066)
			(xy 381.076658 -34.669693) (xy 381.061145 -34.6118) (xy 381.053322 -34.552378) (xy 381.052832 -34.52241)
			(xy 370.705355 -34.52241) (xy 370.70489 -34.55087) (xy 370.697062 -34.610326) (xy 370.681541 -34.668251)
			(xy 370.658592 -34.723655) (xy 370.628608 -34.775589) (xy 370.592102 -34.823165) (xy 370.549697 -34.86557)
			(xy 370.502121 -34.902076) (xy 370.450187 -34.93206) (xy 370.394783 -34.955009) (xy 370.336858 -34.97053)
			(xy 370.277402 -34.978358) (xy 370.217434 -34.978358) (xy 370.157978 -34.97053) (xy 370.100053 -34.955009)
			(xy 370.044649 -34.93206) (xy 369.992715 -34.902076) (xy 369.945139 -34.86557) (xy 369.902734 -34.823165)
			(xy 369.866228 -34.775589) (xy 369.836244 -34.723655) (xy 369.813295 -34.668251) (xy 369.797774 -34.610326)
			(xy 369.789946 -34.55087) (xy 369.789456 -34.520886) (xy 369.154456 -34.520886) (xy 369.154456 -34.68624)
			(xy 369.153844 -34.697796) (xy 369.143872 -34.718648) (xy 369.125918 -34.733206) (xy 369.114832 -34.736532)
			(xy 369.102894 -34.738056) (xy 368.366294 -34.738056) (xy 368.355534 -34.737559) (xy 368.335844 -34.728877)
			(xy 368.328194 -34.721292) (xy 368.322012 -34.713881) (xy 368.315089 -34.695883) (xy 368.314732 -34.68624)
			(xy 355.93762 -34.68624) (xy 355.921538 -34.725066) (xy 355.891571 -34.776972) (xy 355.855084 -34.824522)
			(xy 355.812704 -34.866902) (xy 355.765154 -34.903389) (xy 355.713248 -34.933356) (xy 355.657875 -34.956292)
			(xy 355.599982 -34.971805) (xy 355.54056 -34.979628) (xy 355.480624 -34.979628) (xy 355.421202 -34.971805)
			(xy 355.363309 -34.956292) (xy 355.307936 -34.933356) (xy 355.25603 -34.903389) (xy 355.20848 -34.866902)
			(xy 355.1661 -34.824522) (xy 355.129613 -34.776972) (xy 355.099646 -34.725066) (xy 355.07671 -34.669693)
			(xy 355.061197 -34.6118) (xy 355.053374 -34.552378) (xy 355.052884 -34.52241) (xy 332.604847 -34.52241)
			(xy 332.604382 -34.550854) (xy 332.596559 -34.610276) (xy 332.581046 -34.668169) (xy 332.55811 -34.723542)
			(xy 332.528143 -34.775448) (xy 332.491656 -34.822998) (xy 332.449276 -34.865378) (xy 332.401726 -34.901865)
			(xy 332.34982 -34.931832) (xy 332.294447 -34.954768) (xy 332.236554 -34.970281) (xy 332.177132 -34.978104)
			(xy 332.117196 -34.978104) (xy 332.057774 -34.970281) (xy 331.999881 -34.954768) (xy 331.944508 -34.931832)
			(xy 331.892602 -34.901865) (xy 331.845052 -34.865378) (xy 331.802672 -34.822998) (xy 331.766185 -34.775448)
			(xy 331.736218 -34.723542) (xy 331.713282 -34.668169) (xy 331.697769 -34.610276) (xy 331.689946 -34.550854)
			(xy 331.689456 -34.520886) (xy 331.054456 -34.520886) (xy 331.054456 -34.68624) (xy 331.053952 -34.696445)
			(xy 331.046133 -34.7153) (xy 331.0317 -34.729733) (xy 331.012845 -34.737552) (xy 331.00264 -34.738056)
			(xy 330.26604 -34.738056) (xy 330.25584 -34.737486) (xy 330.236987 -34.729694) (xy 330.222551 -34.71528)
			(xy 330.214729 -34.69644) (xy 330.214224 -34.68624) (xy 317.837641 -34.68624) (xy 317.821512 -34.725179)
			(xy 317.791528 -34.777113) (xy 317.755022 -34.824689) (xy 317.712617 -34.867094) (xy 317.665041 -34.9036)
			(xy 317.613107 -34.933584) (xy 317.557703 -34.956533) (xy 317.499778 -34.972054) (xy 317.440322 -34.979882)
			(xy 317.380354 -34.979882) (xy 317.320898 -34.972054) (xy 317.262973 -34.956533) (xy 317.207569 -34.933584)
			(xy 317.155635 -34.9036) (xy 317.108059 -34.867094) (xy 317.065654 -34.824689) (xy 317.029148 -34.777113)
			(xy 316.999164 -34.725179) (xy 316.976215 -34.669775) (xy 316.960694 -34.61185) (xy 316.952866 -34.552394)
			(xy 316.952376 -34.52241) (xy 306.604899 -34.52241) (xy 306.604434 -34.550854) (xy 306.596611 -34.610276)
			(xy 306.581098 -34.668169) (xy 306.558162 -34.723542) (xy 306.528195 -34.775448) (xy 306.491708 -34.822998)
			(xy 306.449328 -34.865378) (xy 306.401778 -34.901865) (xy 306.349872 -34.931832) (xy 306.294499 -34.954768)
			(xy 306.236606 -34.970281) (xy 306.177184 -34.978104) (xy 306.117248 -34.978104) (xy 306.057826 -34.970281)
			(xy 305.999933 -34.954768) (xy 305.94456 -34.931832) (xy 305.892654 -34.901865) (xy 305.845104 -34.865378)
			(xy 305.802724 -34.822998) (xy 305.766237 -34.775448) (xy 305.73627 -34.723542) (xy 305.713334 -34.668169)
			(xy 305.697821 -34.610276) (xy 305.689998 -34.550854) (xy 305.689508 -34.520886) (xy 305.054508 -34.520886)
			(xy 305.054508 -34.68624) (xy 305.054051 -34.696451) (xy 305.046223 -34.715315) (xy 305.031775 -34.72975)
			(xy 305.012904 -34.73756) (xy 305.002692 -34.738056) (xy 304.266092 -34.738056) (xy 304.255889 -34.737526)
			(xy 304.237035 -34.729718) (xy 304.2226 -34.715292) (xy 304.214781 -34.696443) (xy 304.214276 -34.68624)
			(xy 291.837693 -34.68624) (xy 291.821564 -34.725179) (xy 291.79158 -34.777113) (xy 291.755074 -34.824689)
			(xy 291.712669 -34.867094) (xy 291.665093 -34.9036) (xy 291.613159 -34.933584) (xy 291.557755 -34.956533)
			(xy 291.49983 -34.972054) (xy 291.440374 -34.979882) (xy 291.380406 -34.979882) (xy 291.32095 -34.972054)
			(xy 291.263025 -34.956533) (xy 291.207621 -34.933584) (xy 291.155687 -34.9036) (xy 291.108111 -34.867094)
			(xy 291.065706 -34.824689) (xy 291.0292 -34.777113) (xy 290.999216 -34.725179) (xy 290.976267 -34.669775)
			(xy 290.960746 -34.61185) (xy 290.952918 -34.552394) (xy 290.952428 -34.52241) (xy 280.604951 -34.52241)
			(xy 280.604486 -34.550854) (xy 280.596663 -34.610276) (xy 280.58115 -34.668169) (xy 280.558214 -34.723542)
			(xy 280.528247 -34.775448) (xy 280.49176 -34.822998) (xy 280.44938 -34.865378) (xy 280.40183 -34.901865)
			(xy 280.349924 -34.931832) (xy 280.294551 -34.954768) (xy 280.236658 -34.970281) (xy 280.177236 -34.978104)
			(xy 280.1173 -34.978104) (xy 280.057878 -34.970281) (xy 279.999985 -34.954768) (xy 279.944612 -34.931832)
			(xy 279.892706 -34.901865) (xy 279.845156 -34.865378) (xy 279.802776 -34.822998) (xy 279.766289 -34.775448)
			(xy 279.736322 -34.723542) (xy 279.713386 -34.668169) (xy 279.697873 -34.610276) (xy 279.69005 -34.550854)
			(xy 279.68956 -34.520886) (xy 279.05456 -34.520886) (xy 279.05456 -34.68624) (xy 279.054052 -34.696445)
			(xy 279.046234 -34.715299) (xy 279.031802 -34.729732) (xy 279.012949 -34.737551) (xy 279.002744 -34.738056)
			(xy 278.266144 -34.738056) (xy 278.25593 -34.737553) (xy 278.237051 -34.729752) (xy 278.222595 -34.715319)
			(xy 278.214763 -34.696453) (xy 278.214328 -34.68624) (xy 265.837745 -34.68624) (xy 265.821616 -34.725179)
			(xy 265.791632 -34.777113) (xy 265.755126 -34.824689) (xy 265.712721 -34.867094) (xy 265.665145 -34.9036)
			(xy 265.613211 -34.933584) (xy 265.557807 -34.956533) (xy 265.499882 -34.972054) (xy 265.440426 -34.979882)
			(xy 265.380458 -34.979882) (xy 265.321002 -34.972054) (xy 265.263077 -34.956533) (xy 265.207673 -34.933584)
			(xy 265.155739 -34.9036) (xy 265.108163 -34.867094) (xy 265.065758 -34.824689) (xy 265.029252 -34.777113)
			(xy 264.999268 -34.725179) (xy 264.976319 -34.669775) (xy 264.960798 -34.61185) (xy 264.95297 -34.552394)
			(xy 264.95248 -34.52241) (xy 254.605003 -34.52241) (xy 254.604538 -34.550854) (xy 254.596715 -34.610276)
			(xy 254.581202 -34.668169) (xy 254.558266 -34.723542) (xy 254.528299 -34.775448) (xy 254.491812 -34.822998)
			(xy 254.449432 -34.865378) (xy 254.401882 -34.901865) (xy 254.349976 -34.931832) (xy 254.294603 -34.954768)
			(xy 254.23671 -34.970281) (xy 254.177288 -34.978104) (xy 254.117352 -34.978104) (xy 254.05793 -34.970281)
			(xy 254.000037 -34.954768) (xy 253.944664 -34.931832) (xy 253.892758 -34.901865) (xy 253.845208 -34.865378)
			(xy 253.802828 -34.822998) (xy 253.766341 -34.775448) (xy 253.736374 -34.723542) (xy 253.713438 -34.668169)
			(xy 253.697925 -34.610276) (xy 253.690102 -34.550854) (xy 253.689612 -34.520886) (xy 253.054612 -34.520886)
			(xy 253.054612 -34.68624) (xy 253.054151 -34.696451) (xy 253.046324 -34.715314) (xy 253.031877 -34.729749)
			(xy 253.013007 -34.73756) (xy 253.002796 -34.738056) (xy 252.266196 -34.738056) (xy 252.255993 -34.737522)
			(xy 252.237139 -34.729716) (xy 252.222704 -34.715291) (xy 252.214885 -34.696443) (xy 252.21438 -34.68624)
			(xy 239.837797 -34.68624) (xy 239.821668 -34.725179) (xy 239.791684 -34.777113) (xy 239.755178 -34.824689)
			(xy 239.712773 -34.867094) (xy 239.665197 -34.9036) (xy 239.613263 -34.933584) (xy 239.557859 -34.956533)
			(xy 239.499934 -34.972054) (xy 239.440478 -34.979882) (xy 239.38051 -34.979882) (xy 239.321054 -34.972054)
			(xy 239.263129 -34.956533) (xy 239.207725 -34.933584) (xy 239.155791 -34.9036) (xy 239.108215 -34.867094)
			(xy 239.06581 -34.824689) (xy 239.029304 -34.777113) (xy 238.99932 -34.725179) (xy 238.976371 -34.669775)
			(xy 238.96085 -34.61185) (xy 238.953022 -34.552394) (xy 238.952532 -34.52241) (xy 216.505003 -34.52241)
			(xy 216.504538 -34.550854) (xy 216.496715 -34.610276) (xy 216.481202 -34.668169) (xy 216.458266 -34.723542)
			(xy 216.428299 -34.775448) (xy 216.391812 -34.822998) (xy 216.349432 -34.865378) (xy 216.301882 -34.901865)
			(xy 216.249976 -34.931832) (xy 216.194603 -34.954768) (xy 216.13671 -34.970281) (xy 216.077288 -34.978104)
			(xy 216.017352 -34.978104) (xy 215.95793 -34.970281) (xy 215.900037 -34.954768) (xy 215.844664 -34.931832)
			(xy 215.792758 -34.901865) (xy 215.745208 -34.865378) (xy 215.702828 -34.822998) (xy 215.666341 -34.775448)
			(xy 215.636374 -34.723542) (xy 215.613438 -34.668169) (xy 215.597925 -34.610276) (xy 215.590102 -34.550854)
			(xy 215.589612 -34.520886) (xy 214.954612 -34.520886) (xy 214.954612 -34.68624) (xy 214.954151 -34.696451)
			(xy 214.946324 -34.715314) (xy 214.931877 -34.729749) (xy 214.913007 -34.73756) (xy 214.902796 -34.738056)
			(xy 214.166196 -34.738056) (xy 214.155993 -34.737522) (xy 214.137139 -34.729716) (xy 214.122704 -34.715291)
			(xy 214.114885 -34.696443) (xy 214.11438 -34.68624) (xy 201.737797 -34.68624) (xy 201.721668 -34.725179)
			(xy 201.691684 -34.777113) (xy 201.655178 -34.824689) (xy 201.612773 -34.867094) (xy 201.565197 -34.9036)
			(xy 201.513263 -34.933584) (xy 201.457859 -34.956533) (xy 201.399934 -34.972054) (xy 201.340478 -34.979882)
			(xy 201.28051 -34.979882) (xy 201.221054 -34.972054) (xy 201.163129 -34.956533) (xy 201.107725 -34.933584)
			(xy 201.055791 -34.9036) (xy 201.008215 -34.867094) (xy 200.96581 -34.824689) (xy 200.929304 -34.777113)
			(xy 200.89932 -34.725179) (xy 200.876371 -34.669775) (xy 200.86085 -34.61185) (xy 200.853022 -34.552394)
			(xy 200.852532 -34.52241) (xy 190.505055 -34.52241) (xy 190.50459 -34.550854) (xy 190.496767 -34.610276)
			(xy 190.481254 -34.668169) (xy 190.458318 -34.723542) (xy 190.428351 -34.775448) (xy 190.391864 -34.822998)
			(xy 190.349484 -34.865378) (xy 190.301934 -34.901865) (xy 190.250028 -34.931832) (xy 190.194655 -34.954768)
			(xy 190.136762 -34.970281) (xy 190.07734 -34.978104) (xy 190.017404 -34.978104) (xy 189.957982 -34.970281)
			(xy 189.900089 -34.954768) (xy 189.844716 -34.931832) (xy 189.79281 -34.901865) (xy 189.74526 -34.865378)
			(xy 189.70288 -34.822998) (xy 189.666393 -34.775448) (xy 189.636426 -34.723542) (xy 189.61349 -34.668169)
			(xy 189.597977 -34.610276) (xy 189.590154 -34.550854) (xy 189.589664 -34.520886) (xy 188.954664 -34.520886)
			(xy 188.954664 -34.68624) (xy 188.954152 -34.696444) (xy 188.946335 -34.715298) (xy 188.931904 -34.729731)
			(xy 188.913052 -34.737551) (xy 188.902848 -34.738056) (xy 188.166248 -34.738056) (xy 188.156034 -34.73755)
			(xy 188.137156 -34.72975) (xy 188.1227 -34.715318) (xy 188.114867 -34.696453) (xy 188.114432 -34.68624)
			(xy 175.737849 -34.68624) (xy 175.72172 -34.725179) (xy 175.691736 -34.777113) (xy 175.65523 -34.824689)
			(xy 175.612825 -34.867094) (xy 175.565249 -34.9036) (xy 175.513315 -34.933584) (xy 175.457911 -34.956533)
			(xy 175.399986 -34.972054) (xy 175.34053 -34.979882) (xy 175.280562 -34.979882) (xy 175.221106 -34.972054)
			(xy 175.163181 -34.956533) (xy 175.107777 -34.933584) (xy 175.055843 -34.9036) (xy 175.008267 -34.867094)
			(xy 174.965862 -34.824689) (xy 174.929356 -34.777113) (xy 174.899372 -34.725179) (xy 174.876423 -34.669775)
			(xy 174.860902 -34.61185) (xy 174.853074 -34.552394) (xy 174.852584 -34.52241) (xy 164.505107 -34.52241)
			(xy 164.504642 -34.550854) (xy 164.496819 -34.610276) (xy 164.481306 -34.668169) (xy 164.45837 -34.723542)
			(xy 164.428403 -34.775448) (xy 164.391916 -34.822998) (xy 164.349536 -34.865378) (xy 164.301986 -34.901865)
			(xy 164.25008 -34.931832) (xy 164.194707 -34.954768) (xy 164.136814 -34.970281) (xy 164.077392 -34.978104)
			(xy 164.017456 -34.978104) (xy 163.958034 -34.970281) (xy 163.900141 -34.954768) (xy 163.844768 -34.931832)
			(xy 163.792862 -34.901865) (xy 163.745312 -34.865378) (xy 163.702932 -34.822998) (xy 163.666445 -34.775448)
			(xy 163.636478 -34.723542) (xy 163.613542 -34.668169) (xy 163.598029 -34.610276) (xy 163.590206 -34.550854)
			(xy 163.589716 -34.520886) (xy 162.954716 -34.520886) (xy 162.954716 -34.68624) (xy 162.954251 -34.69645)
			(xy 162.946425 -34.715313) (xy 162.931979 -34.729747) (xy 162.913111 -34.737559) (xy 162.9029 -34.738056)
			(xy 162.1663 -34.738056) (xy 162.156097 -34.737519) (xy 162.137243 -34.729714) (xy 162.122809 -34.71529)
			(xy 162.114989 -34.696442) (xy 162.114484 -34.68624) (xy 149.737901 -34.68624) (xy 149.721772 -34.725179)
			(xy 149.691788 -34.777113) (xy 149.655282 -34.824689) (xy 149.612877 -34.867094) (xy 149.565301 -34.9036)
			(xy 149.513367 -34.933584) (xy 149.457963 -34.956533) (xy 149.400038 -34.972054) (xy 149.340582 -34.979882)
			(xy 149.280614 -34.979882) (xy 149.221158 -34.972054) (xy 149.163233 -34.956533) (xy 149.107829 -34.933584)
			(xy 149.055895 -34.9036) (xy 149.008319 -34.867094) (xy 148.965914 -34.824689) (xy 148.929408 -34.777113)
			(xy 148.899424 -34.725179) (xy 148.876475 -34.669775) (xy 148.860954 -34.61185) (xy 148.853126 -34.552394)
			(xy 148.852636 -34.52241) (xy 138.505159 -34.52241) (xy 138.504694 -34.550854) (xy 138.496871 -34.610276)
			(xy 138.481358 -34.668169) (xy 138.458422 -34.723542) (xy 138.428455 -34.775448) (xy 138.391968 -34.822998)
			(xy 138.349588 -34.865378) (xy 138.302038 -34.901865) (xy 138.250132 -34.931832) (xy 138.194759 -34.954768)
			(xy 138.136866 -34.970281) (xy 138.077444 -34.978104) (xy 138.017508 -34.978104) (xy 137.958086 -34.970281)
			(xy 137.900193 -34.954768) (xy 137.84482 -34.931832) (xy 137.792914 -34.901865) (xy 137.745364 -34.865378)
			(xy 137.702984 -34.822998) (xy 137.666497 -34.775448) (xy 137.63653 -34.723542) (xy 137.613594 -34.668169)
			(xy 137.598081 -34.610276) (xy 137.590258 -34.550854) (xy 137.589768 -34.520886) (xy 136.954768 -34.520886)
			(xy 136.954768 -34.68624) (xy 136.954419 -34.69647) (xy 136.946574 -34.715368) (xy 136.932093 -34.729823)
			(xy 136.913183 -34.737637) (xy 136.902952 -34.738056) (xy 136.166352 -34.738056) (xy 136.156146 -34.737558)
			(xy 136.137291 -34.729737) (xy 136.122858 -34.715302) (xy 136.11504 -34.696446) (xy 136.114536 -34.68624)
			(xy 123.737953 -34.68624) (xy 123.721824 -34.725179) (xy 123.69184 -34.777113) (xy 123.655334 -34.824689)
			(xy 123.612929 -34.867094) (xy 123.565353 -34.9036) (xy 123.513419 -34.933584) (xy 123.458015 -34.956533)
			(xy 123.40009 -34.972054) (xy 123.340634 -34.979882) (xy 123.280666 -34.979882) (xy 123.22121 -34.972054)
			(xy 123.163285 -34.956533) (xy 123.107881 -34.933584) (xy 123.055947 -34.9036) (xy 123.008371 -34.867094)
			(xy 122.965966 -34.824689) (xy 122.92946 -34.777113) (xy 122.899476 -34.725179) (xy 122.876527 -34.669775)
			(xy 122.861006 -34.61185) (xy 122.853178 -34.552394) (xy 122.852688 -34.52241) (xy 100.405159 -34.52241)
			(xy 100.404694 -34.55087) (xy 100.396866 -34.610326) (xy 100.381345 -34.668251) (xy 100.358396 -34.723655)
			(xy 100.328412 -34.775589) (xy 100.291906 -34.823165) (xy 100.249501 -34.86557) (xy 100.201925 -34.902076)
			(xy 100.149991 -34.93206) (xy 100.094587 -34.955009) (xy 100.036662 -34.97053) (xy 99.977206 -34.978358)
			(xy 99.917238 -34.978358) (xy 99.857782 -34.97053) (xy 99.799857 -34.955009) (xy 99.744453 -34.93206)
			(xy 99.692519 -34.902076) (xy 99.644943 -34.86557) (xy 99.602538 -34.823165) (xy 99.566032 -34.775589)
			(xy 99.536048 -34.723655) (xy 99.513099 -34.668251) (xy 99.497578 -34.610326) (xy 99.48975 -34.55087)
			(xy 99.48926 -34.520886) (xy 98.85426 -34.520886) (xy 98.85426 -34.68624) (xy 98.853645 -34.697795)
			(xy 98.843674 -34.718647) (xy 98.825721 -34.733206) (xy 98.814636 -34.736532) (xy 98.802698 -34.738056)
			(xy 98.066098 -34.738056) (xy 98.055338 -34.737557) (xy 98.035649 -34.728877) (xy 98.027998 -34.721292)
			(xy 98.021817 -34.713881) (xy 98.014893 -34.695883) (xy 98.014536 -34.68624) (xy 85.637424 -34.68624)
			(xy 85.621342 -34.725066) (xy 85.591375 -34.776972) (xy 85.554888 -34.824522) (xy 85.512508 -34.866902)
			(xy 85.464958 -34.903389) (xy 85.413052 -34.933356) (xy 85.357679 -34.956292) (xy 85.299786 -34.971805)
			(xy 85.240364 -34.979628) (xy 85.180428 -34.979628) (xy 85.121006 -34.971805) (xy 85.063113 -34.956292)
			(xy 85.00774 -34.933356) (xy 84.955834 -34.903389) (xy 84.908284 -34.866902) (xy 84.865904 -34.824522)
			(xy 84.829417 -34.776972) (xy 84.79945 -34.725066) (xy 84.776514 -34.669693) (xy 84.761001 -34.6118)
			(xy 84.753178 -34.552378) (xy 84.752688 -34.52241) (xy 74.405211 -34.52241) (xy 74.404746 -34.55087)
			(xy 74.396918 -34.610326) (xy 74.381397 -34.668251) (xy 74.358448 -34.723655) (xy 74.328464 -34.775589)
			(xy 74.291958 -34.823165) (xy 74.249553 -34.86557) (xy 74.201977 -34.902076) (xy 74.150043 -34.93206)
			(xy 74.094639 -34.955009) (xy 74.036714 -34.97053) (xy 73.977258 -34.978358) (xy 73.91729 -34.978358)
			(xy 73.857834 -34.97053) (xy 73.799909 -34.955009) (xy 73.744505 -34.93206) (xy 73.692571 -34.902076)
			(xy 73.644995 -34.86557) (xy 73.60259 -34.823165) (xy 73.566084 -34.775589) (xy 73.5361 -34.723655)
			(xy 73.513151 -34.668251) (xy 73.49763 -34.610326) (xy 73.489802 -34.55087) (xy 73.489312 -34.520886)
			(xy 72.854312 -34.520886) (xy 72.854312 -34.68624) (xy 72.853659 -34.69779) (xy 72.843699 -34.718635)
			(xy 72.825765 -34.733198) (xy 72.814688 -34.736532) (xy 72.80275 -34.738056) (xy 72.06615 -34.738056)
			(xy 72.055393 -34.737528) (xy 72.035704 -34.728868) (xy 72.02805 -34.721292) (xy 72.021875 -34.713876)
			(xy 72.014947 -34.695882) (xy 72.014588 -34.68624) (xy 59.637476 -34.68624) (xy 59.621394 -34.725066)
			(xy 59.591427 -34.776972) (xy 59.55494 -34.824522) (xy 59.51256 -34.866902) (xy 59.46501 -34.903389)
			(xy 59.413104 -34.933356) (xy 59.357731 -34.956292) (xy 59.299838 -34.971805) (xy 59.240416 -34.979628)
			(xy 59.18048 -34.979628) (xy 59.121058 -34.971805) (xy 59.063165 -34.956292) (xy 59.007792 -34.933356)
			(xy 58.955886 -34.903389) (xy 58.908336 -34.866902) (xy 58.865956 -34.824522) (xy 58.829469 -34.776972)
			(xy 58.799502 -34.725066) (xy 58.776566 -34.669693) (xy 58.761053 -34.6118) (xy 58.75323 -34.552378)
			(xy 58.75274 -34.52241) (xy 48.405263 -34.52241) (xy 48.404798 -34.55087) (xy 48.39697 -34.610326)
			(xy 48.381449 -34.668251) (xy 48.3585 -34.723655) (xy 48.328516 -34.775589) (xy 48.29201 -34.823165)
			(xy 48.249605 -34.86557) (xy 48.202029 -34.902076) (xy 48.150095 -34.93206) (xy 48.094691 -34.955009)
			(xy 48.036766 -34.97053) (xy 47.97731 -34.978358) (xy 47.917342 -34.978358) (xy 47.857886 -34.97053)
			(xy 47.799961 -34.955009) (xy 47.744557 -34.93206) (xy 47.692623 -34.902076) (xy 47.645047 -34.86557)
			(xy 47.602642 -34.823165) (xy 47.566136 -34.775589) (xy 47.536152 -34.723655) (xy 47.513203 -34.668251)
			(xy 47.497682 -34.610326) (xy 47.489854 -34.55087) (xy 47.489364 -34.520886) (xy 46.854364 -34.520886)
			(xy 46.854364 -34.68624) (xy 46.853746 -34.697795) (xy 46.843776 -34.718646) (xy 46.825824 -34.733205)
			(xy 46.81474 -34.736532) (xy 46.802802 -34.738056) (xy 46.066202 -34.738056) (xy 46.055442 -34.737555)
			(xy 46.035753 -34.728876) (xy 46.028102 -34.721292) (xy 46.021921 -34.71388) (xy 46.014997 -34.695883)
			(xy 46.01464 -34.68624) (xy 33.637528 -34.68624) (xy 33.621446 -34.725066) (xy 33.591479 -34.776972)
			(xy 33.554992 -34.824522) (xy 33.512612 -34.866902) (xy 33.465062 -34.903389) (xy 33.413156 -34.933356)
			(xy 33.357783 -34.956292) (xy 33.29989 -34.971805) (xy 33.240468 -34.979628) (xy 33.180532 -34.979628)
			(xy 33.12111 -34.971805) (xy 33.063217 -34.956292) (xy 33.007844 -34.933356) (xy 32.955938 -34.903389)
			(xy 32.908388 -34.866902) (xy 32.866008 -34.824522) (xy 32.829521 -34.776972) (xy 32.799554 -34.725066)
			(xy 32.776618 -34.669693) (xy 32.761105 -34.6118) (xy 32.753282 -34.552378) (xy 32.752792 -34.52241)
			(xy 22.405315 -34.52241) (xy 22.40485 -34.55087) (xy 22.397022 -34.610326) (xy 22.381501 -34.668251)
			(xy 22.358552 -34.723655) (xy 22.328568 -34.775589) (xy 22.292062 -34.823165) (xy 22.249657 -34.86557)
			(xy 22.202081 -34.902076) (xy 22.150147 -34.93206) (xy 22.094743 -34.955009) (xy 22.036818 -34.97053)
			(xy 21.977362 -34.978358) (xy 21.917394 -34.978358) (xy 21.857938 -34.97053) (xy 21.800013 -34.955009)
			(xy 21.744609 -34.93206) (xy 21.692675 -34.902076) (xy 21.645099 -34.86557) (xy 21.602694 -34.823165)
			(xy 21.566188 -34.775589) (xy 21.536204 -34.723655) (xy 21.513255 -34.668251) (xy 21.497734 -34.610326)
			(xy 21.489906 -34.55087) (xy 21.489416 -34.520886) (xy 20.854416 -34.520886) (xy 20.854416 -34.68624)
			(xy 20.85376 -34.697789) (xy 20.843801 -34.718634) (xy 20.825868 -34.733197) (xy 20.814792 -34.736532)
			(xy 20.802854 -34.738056) (xy 20.066254 -34.738056) (xy 20.055498 -34.737526) (xy 20.035808 -34.728868)
			(xy 20.028154 -34.721292) (xy 20.02198 -34.713875) (xy 20.015051 -34.695882) (xy 20.014692 -34.68624)
			(xy 7.63758 -34.68624) (xy 7.621498 -34.725066) (xy 7.591531 -34.776972) (xy 7.555044 -34.824522)
			(xy 7.512664 -34.866902) (xy 7.465114 -34.903389) (xy 7.413208 -34.933356) (xy 7.357835 -34.956292)
			(xy 7.299942 -34.971805) (xy 7.24052 -34.979628) (xy 7.180584 -34.979628) (xy 7.121162 -34.971805)
			(xy 7.063269 -34.956292) (xy 7.007896 -34.933356) (xy 6.95599 -34.903389) (xy 6.90844 -34.866902)
			(xy 6.86606 -34.824522) (xy 6.829573 -34.776972) (xy 6.799606 -34.725066) (xy 6.77667 -34.669693)
			(xy 6.761157 -34.6118) (xy 6.753334 -34.552378) (xy 6.752844 -34.52241) (xy 0.509016 -34.52241) (xy 0.509016 -36.60013)
			(xy 11.998205 -36.60013) (xy 12.00221 -36.512222) (xy 12.014193 -36.425042) (xy 12.034053 -36.339313)
			(xy 12.061628 -36.255745) (xy 12.096687 -36.175031) (xy 12.13894 -36.097839) (xy 12.188038 -36.02481)
			(xy 12.243574 -35.956548) (xy 12.305086 -35.893618) (xy 12.372067 -35.836544) (xy 12.44396 -35.785796)
			(xy 12.520169 -35.741796) (xy 12.600064 -35.704909) (xy 12.682983 -35.67544) (xy 12.768238 -35.653633)
			(xy 12.855122 -35.639669) (xy 12.942916 -35.633663) (xy 13.030893 -35.635667) (xy 13.118323 -35.645662)
			(xy 13.204482 -35.663566) (xy 13.288656 -35.68923) (xy 13.370147 -35.722443) (xy 13.448281 -35.762929)
			(xy 13.522409 -35.810351) (xy 13.591917 -35.864318) (xy 13.656231 -35.924383) (xy 13.714815 -35.990047)
			(xy 13.767186 -36.060766) (xy 13.812909 -36.135954) (xy 13.851606 -36.214989) (xy 13.882955 -36.297215)
			(xy 13.906697 -36.381951) (xy 13.922635 -36.468495) (xy 13.930637 -36.55613) (xy 13.931138 -36.60013)
			(xy 37.998153 -36.60013) (xy 38.002158 -36.512222) (xy 38.014141 -36.425042) (xy 38.034001 -36.339313)
			(xy 38.061576 -36.255745) (xy 38.096635 -36.175031) (xy 38.138888 -36.097839) (xy 38.187986 -36.02481)
			(xy 38.243522 -35.956548) (xy 38.305034 -35.893618) (xy 38.372015 -35.836544) (xy 38.443908 -35.785796)
			(xy 38.520117 -35.741796) (xy 38.600012 -35.704909) (xy 38.682931 -35.67544) (xy 38.768186 -35.653633)
			(xy 38.85507 -35.639669) (xy 38.942864 -35.633663) (xy 39.030841 -35.635667) (xy 39.118271 -35.645662)
			(xy 39.20443 -35.663566) (xy 39.288604 -35.68923) (xy 39.370095 -35.722443) (xy 39.448229 -35.762929)
			(xy 39.522357 -35.810351) (xy 39.591865 -35.864318) (xy 39.656179 -35.924383) (xy 39.714763 -35.990047)
			(xy 39.767134 -36.060766) (xy 39.812857 -36.135954) (xy 39.851554 -36.214989) (xy 39.882903 -36.297215)
			(xy 39.906645 -36.381951) (xy 39.922583 -36.468495) (xy 39.930585 -36.55613) (xy 39.931086 -36.60013)
			(xy 63.998101 -36.60013) (xy 64.002106 -36.512222) (xy 64.014089 -36.425042) (xy 64.033949 -36.339313)
			(xy 64.061524 -36.255745) (xy 64.096583 -36.175031) (xy 64.138836 -36.097839) (xy 64.187934 -36.02481)
			(xy 64.24347 -35.956548) (xy 64.304982 -35.893618) (xy 64.371963 -35.836544) (xy 64.443856 -35.785796)
			(xy 64.520065 -35.741796) (xy 64.59996 -35.704909) (xy 64.682879 -35.67544) (xy 64.768134 -35.653633)
			(xy 64.855018 -35.639669) (xy 64.942812 -35.633663) (xy 65.030789 -35.635667) (xy 65.118219 -35.645662)
			(xy 65.204378 -35.663566) (xy 65.288552 -35.68923) (xy 65.370043 -35.722443) (xy 65.448177 -35.762929)
			(xy 65.522305 -35.810351) (xy 65.591813 -35.864318) (xy 65.656127 -35.924383) (xy 65.714711 -35.990047)
			(xy 65.767082 -36.060766) (xy 65.812805 -36.135954) (xy 65.851502 -36.214989) (xy 65.882851 -36.297215)
			(xy 65.906593 -36.381951) (xy 65.922531 -36.468495) (xy 65.930533 -36.55613) (xy 65.931034 -36.60013)
			(xy 89.998049 -36.60013) (xy 90.002054 -36.512222) (xy 90.014037 -36.425042) (xy 90.033897 -36.339313)
			(xy 90.061472 -36.255745) (xy 90.096531 -36.175031) (xy 90.138784 -36.097839) (xy 90.187882 -36.02481)
			(xy 90.243418 -35.956548) (xy 90.30493 -35.893618) (xy 90.371911 -35.836544) (xy 90.443804 -35.785796)
			(xy 90.520013 -35.741796) (xy 90.599908 -35.704909) (xy 90.682827 -35.67544) (xy 90.768082 -35.653633)
			(xy 90.854966 -35.639669) (xy 90.94276 -35.633663) (xy 91.030737 -35.635667) (xy 91.118167 -35.645662)
			(xy 91.204326 -35.663566) (xy 91.2885 -35.68923) (xy 91.369991 -35.722443) (xy 91.448125 -35.762929)
			(xy 91.522253 -35.810351) (xy 91.591761 -35.864318) (xy 91.656075 -35.924383) (xy 91.714659 -35.990047)
			(xy 91.76703 -36.060766) (xy 91.812753 -36.135954) (xy 91.85145 -36.214989) (xy 91.882799 -36.297215)
			(xy 91.906541 -36.381951) (xy 91.922479 -36.468495) (xy 91.930481 -36.55613) (xy 91.930982 -36.60013)
			(xy 128.098303 -36.60013) (xy 128.102308 -36.512222) (xy 128.114291 -36.425042) (xy 128.134151 -36.339313)
			(xy 128.161726 -36.255745) (xy 128.196785 -36.175031) (xy 128.239038 -36.097839) (xy 128.288136 -36.02481)
			(xy 128.343672 -35.956548) (xy 128.405184 -35.893618) (xy 128.472165 -35.836544) (xy 128.544058 -35.785796)
			(xy 128.620267 -35.741796) (xy 128.700162 -35.704909) (xy 128.783081 -35.67544) (xy 128.868336 -35.653633)
			(xy 128.95522 -35.639669) (xy 129.043014 -35.633663) (xy 129.130991 -35.635667) (xy 129.218421 -35.645662)
			(xy 129.30458 -35.663566) (xy 129.388754 -35.68923) (xy 129.470245 -35.722443) (xy 129.548379 -35.762929)
			(xy 129.622507 -35.810351) (xy 129.692015 -35.864318) (xy 129.756329 -35.924383) (xy 129.814913 -35.990047)
			(xy 129.867284 -36.060766) (xy 129.913007 -36.135954) (xy 129.951704 -36.214989) (xy 129.983053 -36.297215)
			(xy 130.006795 -36.381951) (xy 130.022733 -36.468495) (xy 130.030735 -36.55613) (xy 130.031236 -36.60013)
			(xy 154.098251 -36.60013) (xy 154.102256 -36.512222) (xy 154.114239 -36.425042) (xy 154.134099 -36.339313)
			(xy 154.161674 -36.255745) (xy 154.196733 -36.175031) (xy 154.238986 -36.097839) (xy 154.288084 -36.02481)
			(xy 154.34362 -35.956548) (xy 154.405132 -35.893618) (xy 154.472113 -35.836544) (xy 154.544006 -35.785796)
			(xy 154.620215 -35.741796) (xy 154.70011 -35.704909) (xy 154.783029 -35.67544) (xy 154.868284 -35.653633)
			(xy 154.955168 -35.639669) (xy 155.042962 -35.633663) (xy 155.130939 -35.635667) (xy 155.218369 -35.645662)
			(xy 155.304528 -35.663566) (xy 155.388702 -35.68923) (xy 155.470193 -35.722443) (xy 155.548327 -35.762929)
			(xy 155.622455 -35.810351) (xy 155.691963 -35.864318) (xy 155.756277 -35.924383) (xy 155.814861 -35.990047)
			(xy 155.867232 -36.060766) (xy 155.912955 -36.135954) (xy 155.951652 -36.214989) (xy 155.983001 -36.297215)
			(xy 156.006743 -36.381951) (xy 156.022681 -36.468495) (xy 156.030683 -36.55613) (xy 156.031184 -36.60013)
			(xy 180.098199 -36.60013) (xy 180.102204 -36.512222) (xy 180.114187 -36.425042) (xy 180.134047 -36.339313)
			(xy 180.161622 -36.255745) (xy 180.196681 -36.175031) (xy 180.238934 -36.097839) (xy 180.288032 -36.02481)
			(xy 180.343568 -35.956548) (xy 180.40508 -35.893618) (xy 180.472061 -35.836544) (xy 180.543954 -35.785796)
			(xy 180.620163 -35.741796) (xy 180.700058 -35.704909) (xy 180.782977 -35.67544) (xy 180.868232 -35.653633)
			(xy 180.955116 -35.639669) (xy 181.04291 -35.633663) (xy 181.130887 -35.635667) (xy 181.218317 -35.645662)
			(xy 181.304476 -35.663566) (xy 181.38865 -35.68923) (xy 181.470141 -35.722443) (xy 181.548275 -35.762929)
			(xy 181.622403 -35.810351) (xy 181.691911 -35.864318) (xy 181.756225 -35.924383) (xy 181.814809 -35.990047)
			(xy 181.86718 -36.060766) (xy 181.912903 -36.135954) (xy 181.9516 -36.214989) (xy 181.982949 -36.297215)
			(xy 182.006691 -36.381951) (xy 182.022629 -36.468495) (xy 182.030631 -36.55613) (xy 182.031132 -36.60013)
			(xy 206.098655 -36.60013) (xy 206.102659 -36.512245) (xy 206.114639 -36.425088) (xy 206.134494 -36.339381)
			(xy 206.162061 -36.255836) (xy 206.197111 -36.175143) (xy 206.239353 -36.097971) (xy 206.288438 -36.024961)
			(xy 206.343959 -35.956717) (xy 206.405456 -35.893804) (xy 206.472418 -35.836744) (xy 206.544292 -35.78601)
			(xy 206.620482 -35.742022) (xy 206.700356 -35.705144) (xy 206.783253 -35.675683) (xy 206.868485 -35.653881)
			(xy 206.955347 -35.639921) (xy 207.043118 -35.633917) (xy 207.131072 -35.63592) (xy 207.218479 -35.645912)
			(xy 207.304615 -35.663812) (xy 207.388767 -35.68947) (xy 207.470237 -35.722674) (xy 207.54835 -35.763148)
			(xy 207.622458 -35.810559) (xy 207.691949 -35.864512) (xy 207.756245 -35.92456) (xy 207.814814 -35.990207)
			(xy 207.867171 -36.060907) (xy 207.912883 -36.136076) (xy 207.951569 -36.21509) (xy 207.98291 -36.297295)
			(xy 208.006645 -36.382009) (xy 208.022579 -36.46853) (xy 208.030579 -36.556142) (xy 208.03108 -36.60013)
			(xy 244.198655 -36.60013) (xy 244.202659 -36.512245) (xy 244.214639 -36.425088) (xy 244.234494 -36.339381)
			(xy 244.262061 -36.255836) (xy 244.297111 -36.175143) (xy 244.339353 -36.097971) (xy 244.388438 -36.024961)
			(xy 244.443959 -35.956717) (xy 244.505456 -35.893804) (xy 244.572418 -35.836744) (xy 244.644292 -35.78601)
			(xy 244.720482 -35.742022) (xy 244.800356 -35.705144) (xy 244.883253 -35.675683) (xy 244.968485 -35.653881)
			(xy 245.055347 -35.639921) (xy 245.143118 -35.633917) (xy 245.231072 -35.63592) (xy 245.318479 -35.645912)
			(xy 245.404615 -35.663812) (xy 245.488767 -35.68947) (xy 245.570237 -35.722674) (xy 245.64835 -35.763148)
			(xy 245.722458 -35.810559) (xy 245.791949 -35.864512) (xy 245.856245 -35.92456) (xy 245.914814 -35.990207)
			(xy 245.967171 -36.060907) (xy 246.012883 -36.136076) (xy 246.051569 -36.21509) (xy 246.08291 -36.297295)
			(xy 246.106645 -36.382009) (xy 246.122579 -36.46853) (xy 246.130579 -36.556142) (xy 246.13108 -36.60013)
			(xy 270.198603 -36.60013) (xy 270.202607 -36.512245) (xy 270.214587 -36.425088) (xy 270.234442 -36.339381)
			(xy 270.262009 -36.255836) (xy 270.297059 -36.175143) (xy 270.339301 -36.097971) (xy 270.388386 -36.024961)
			(xy 270.443907 -35.956717) (xy 270.505404 -35.893804) (xy 270.572366 -35.836744) (xy 270.64424 -35.78601)
			(xy 270.72043 -35.742022) (xy 270.800304 -35.705144) (xy 270.883201 -35.675683) (xy 270.968433 -35.653881)
			(xy 271.055295 -35.639921) (xy 271.143066 -35.633917) (xy 271.23102 -35.63592) (xy 271.318427 -35.645912)
			(xy 271.404563 -35.663812) (xy 271.488715 -35.68947) (xy 271.570185 -35.722674) (xy 271.648298 -35.763148)
			(xy 271.722406 -35.810559) (xy 271.791897 -35.864512) (xy 271.856193 -35.92456) (xy 271.914762 -35.990207)
			(xy 271.967119 -36.060907) (xy 272.012831 -36.136076) (xy 272.051517 -36.21509) (xy 272.082858 -36.297295)
			(xy 272.106593 -36.382009) (xy 272.122527 -36.46853) (xy 272.130527 -36.556142) (xy 272.131028 -36.60013)
			(xy 296.198551 -36.60013) (xy 296.202555 -36.512245) (xy 296.214535 -36.425088) (xy 296.23439 -36.339381)
			(xy 296.261957 -36.255836) (xy 296.297007 -36.175143) (xy 296.339249 -36.097971) (xy 296.388334 -36.024961)
			(xy 296.443855 -35.956717) (xy 296.505352 -35.893804) (xy 296.572314 -35.836744) (xy 296.644188 -35.78601)
			(xy 296.720378 -35.742022) (xy 296.800252 -35.705144) (xy 296.883149 -35.675683) (xy 296.968381 -35.653881)
			(xy 297.055243 -35.639921) (xy 297.143014 -35.633917) (xy 297.230968 -35.63592) (xy 297.318375 -35.645912)
			(xy 297.404511 -35.663812) (xy 297.488663 -35.68947) (xy 297.570133 -35.722674) (xy 297.648246 -35.763148)
			(xy 297.722354 -35.810559) (xy 297.791845 -35.864512) (xy 297.856141 -35.92456) (xy 297.91471 -35.990207)
			(xy 297.967067 -36.060907) (xy 298.012779 -36.136076) (xy 298.051465 -36.21509) (xy 298.082806 -36.297295)
			(xy 298.106541 -36.382009) (xy 298.122475 -36.46853) (xy 298.130475 -36.556142) (xy 298.130976 -36.60013)
			(xy 322.197991 -36.60013) (xy 322.201996 -36.512222) (xy 322.213979 -36.425042) (xy 322.233839 -36.339313)
			(xy 322.261414 -36.255745) (xy 322.296473 -36.175031) (xy 322.338726 -36.097839) (xy 322.387824 -36.02481)
			(xy 322.44336 -35.956548) (xy 322.504872 -35.893618) (xy 322.571853 -35.836544) (xy 322.643746 -35.785796)
			(xy 322.719955 -35.741796) (xy 322.79985 -35.704909) (xy 322.882769 -35.67544) (xy 322.968024 -35.653633)
			(xy 323.054908 -35.639669) (xy 323.142702 -35.633663) (xy 323.230679 -35.635667) (xy 323.318109 -35.645662)
			(xy 323.404268 -35.663566) (xy 323.488442 -35.68923) (xy 323.569933 -35.722443) (xy 323.648067 -35.762929)
			(xy 323.722195 -35.810351) (xy 323.791703 -35.864318) (xy 323.856017 -35.924383) (xy 323.914601 -35.990047)
			(xy 323.966972 -36.060766) (xy 324.012695 -36.135954) (xy 324.051392 -36.214989) (xy 324.082741 -36.297215)
			(xy 324.106483 -36.381951) (xy 324.122421 -36.468495) (xy 324.130423 -36.55613) (xy 324.130924 -36.60013)
			(xy 360.298245 -36.60013) (xy 360.30225 -36.512222) (xy 360.314233 -36.425042) (xy 360.334093 -36.339313)
			(xy 360.361668 -36.255745) (xy 360.396727 -36.175031) (xy 360.43898 -36.097839) (xy 360.488078 -36.02481)
			(xy 360.543614 -35.956548) (xy 360.605126 -35.893618) (xy 360.672107 -35.836544) (xy 360.744 -35.785796)
			(xy 360.820209 -35.741796) (xy 360.900104 -35.704909) (xy 360.983023 -35.67544) (xy 361.068278 -35.653633)
			(xy 361.155162 -35.639669) (xy 361.242956 -35.633663) (xy 361.330933 -35.635667) (xy 361.418363 -35.645662)
			(xy 361.504522 -35.663566) (xy 361.588696 -35.68923) (xy 361.670187 -35.722443) (xy 361.748321 -35.762929)
			(xy 361.822449 -35.810351) (xy 361.891957 -35.864318) (xy 361.956271 -35.924383) (xy 362.014855 -35.990047)
			(xy 362.067226 -36.060766) (xy 362.112949 -36.135954) (xy 362.151646 -36.214989) (xy 362.182995 -36.297215)
			(xy 362.206737 -36.381951) (xy 362.222675 -36.468495) (xy 362.230677 -36.55613) (xy 362.231178 -36.60013)
			(xy 386.298193 -36.60013) (xy 386.302198 -36.512222) (xy 386.314181 -36.425042) (xy 386.334041 -36.339313)
			(xy 386.361616 -36.255745) (xy 386.396675 -36.175031) (xy 386.438928 -36.097839) (xy 386.488026 -36.02481)
			(xy 386.543562 -35.956548) (xy 386.605074 -35.893618) (xy 386.672055 -35.836544) (xy 386.743948 -35.785796)
			(xy 386.820157 -35.741796) (xy 386.900052 -35.704909) (xy 386.982971 -35.67544) (xy 387.068226 -35.653633)
			(xy 387.15511 -35.639669) (xy 387.242904 -35.633663) (xy 387.330881 -35.635667) (xy 387.418311 -35.645662)
			(xy 387.50447 -35.663566) (xy 387.588644 -35.68923) (xy 387.670135 -35.722443) (xy 387.748269 -35.762929)
			(xy 387.822397 -35.810351) (xy 387.891905 -35.864318) (xy 387.956219 -35.924383) (xy 388.014803 -35.990047)
			(xy 388.067174 -36.060766) (xy 388.112897 -36.135954) (xy 388.151594 -36.214989) (xy 388.182943 -36.297215)
			(xy 388.206685 -36.381951) (xy 388.222623 -36.468495) (xy 388.230625 -36.55613) (xy 388.231126 -36.60013)
			(xy 412.298649 -36.60013) (xy 412.302653 -36.512245) (xy 412.314633 -36.425088) (xy 412.334488 -36.339381)
			(xy 412.362055 -36.255836) (xy 412.397105 -36.175143) (xy 412.439347 -36.097971) (xy 412.488432 -36.024961)
			(xy 412.543953 -35.956717) (xy 412.60545 -35.893804) (xy 412.672412 -35.836744) (xy 412.744286 -35.78601)
			(xy 412.820476 -35.742022) (xy 412.90035 -35.705144) (xy 412.983247 -35.675683) (xy 413.068479 -35.653881)
			(xy 413.155341 -35.639921) (xy 413.243112 -35.633917) (xy 413.331066 -35.63592) (xy 413.418473 -35.645912)
			(xy 413.504609 -35.663812) (xy 413.588761 -35.68947) (xy 413.670231 -35.722674) (xy 413.748344 -35.763148)
			(xy 413.822452 -35.810559) (xy 413.891943 -35.864512) (xy 413.956239 -35.92456) (xy 414.014808 -35.990207)
			(xy 414.067165 -36.060907) (xy 414.112877 -36.136076) (xy 414.151563 -36.21509) (xy 414.182904 -36.297295)
			(xy 414.206639 -36.382009) (xy 414.222573 -36.46853) (xy 414.230573 -36.556142) (xy 414.231074 -36.60013)
			(xy 438.298597 -36.60013) (xy 438.302601 -36.512245) (xy 438.314581 -36.425088) (xy 438.334436 -36.339381)
			(xy 438.362003 -36.255836) (xy 438.397053 -36.175143) (xy 438.439295 -36.097971) (xy 438.48838 -36.024961)
			(xy 438.543901 -35.956717) (xy 438.605398 -35.893804) (xy 438.67236 -35.836744) (xy 438.744234 -35.78601)
			(xy 438.820424 -35.742022) (xy 438.900298 -35.705144) (xy 438.983195 -35.675683) (xy 439.068427 -35.653881)
			(xy 439.155289 -35.639921) (xy 439.24306 -35.633917) (xy 439.331014 -35.63592) (xy 439.418421 -35.645912)
			(xy 439.504557 -35.663812) (xy 439.588709 -35.68947) (xy 439.670179 -35.722674) (xy 439.748292 -35.763148)
			(xy 439.8224 -35.810559) (xy 439.891891 -35.864512) (xy 439.956187 -35.92456) (xy 440.014756 -35.990207)
			(xy 440.067113 -36.060907) (xy 440.112825 -36.136076) (xy 440.151511 -36.21509) (xy 440.182852 -36.297295)
			(xy 440.206587 -36.382009) (xy 440.222521 -36.46853) (xy 440.230521 -36.556142) (xy 440.231022 -36.60013)
			(xy 440.230521 -36.644118) (xy 440.222521 -36.73173) (xy 440.206587 -36.818251) (xy 440.182852 -36.902965)
			(xy 440.151511 -36.98517) (xy 440.112825 -37.064184) (xy 440.067113 -37.139353) (xy 440.014756 -37.210053)
			(xy 439.956187 -37.2757) (xy 439.891891 -37.335748) (xy 439.8224 -37.389701) (xy 439.748292 -37.437112)
			(xy 439.670179 -37.477586) (xy 439.588709 -37.51079) (xy 439.504557 -37.536448) (xy 439.418421 -37.554348)
			(xy 439.331014 -37.56434) (xy 439.24306 -37.566343) (xy 439.155289 -37.560339) (xy 439.068427 -37.546379)
			(xy 438.983195 -37.524577) (xy 438.900298 -37.495116) (xy 438.820424 -37.458238) (xy 438.744234 -37.41425)
			(xy 438.67236 -37.363516) (xy 438.605398 -37.306456) (xy 438.543901 -37.243543) (xy 438.48838 -37.175299)
			(xy 438.439295 -37.102289) (xy 438.397053 -37.025117) (xy 438.362003 -36.944424) (xy 438.334436 -36.860879)
			(xy 438.314581 -36.775172) (xy 438.302601 -36.688015) (xy 438.298597 -36.60013) (xy 414.231074 -36.60013)
			(xy 414.230573 -36.644118) (xy 414.222573 -36.73173) (xy 414.206639 -36.818251) (xy 414.182904 -36.902965)
			(xy 414.151563 -36.98517) (xy 414.112877 -37.064184) (xy 414.067165 -37.139353) (xy 414.014808 -37.210053)
			(xy 413.956239 -37.2757) (xy 413.891943 -37.335748) (xy 413.822452 -37.389701) (xy 413.748344 -37.437112)
			(xy 413.670231 -37.477586) (xy 413.588761 -37.51079) (xy 413.504609 -37.536448) (xy 413.418473 -37.554348)
			(xy 413.331066 -37.56434) (xy 413.243112 -37.566343) (xy 413.155341 -37.560339) (xy 413.068479 -37.546379)
			(xy 412.983247 -37.524577) (xy 412.90035 -37.495116) (xy 412.820476 -37.458238) (xy 412.744286 -37.41425)
			(xy 412.672412 -37.363516) (xy 412.60545 -37.306456) (xy 412.543953 -37.243543) (xy 412.488432 -37.175299)
			(xy 412.439347 -37.102289) (xy 412.397105 -37.025117) (xy 412.362055 -36.944424) (xy 412.334488 -36.860879)
			(xy 412.314633 -36.775172) (xy 412.302653 -36.688015) (xy 412.298649 -36.60013) (xy 388.231126 -36.60013)
			(xy 388.230625 -36.64413) (xy 388.222623 -36.731765) (xy 388.206685 -36.818309) (xy 388.182943 -36.903045)
			(xy 388.151594 -36.985271) (xy 388.112897 -37.064306) (xy 388.067174 -37.139494) (xy 388.014803 -37.210213)
			(xy 387.956219 -37.275877) (xy 387.891905 -37.335942) (xy 387.822397 -37.389909) (xy 387.748269 -37.437331)
			(xy 387.670135 -37.477817) (xy 387.588644 -37.51103) (xy 387.50447 -37.536694) (xy 387.418311 -37.554598)
			(xy 387.330881 -37.564593) (xy 387.242904 -37.566597) (xy 387.15511 -37.560591) (xy 387.068226 -37.546627)
			(xy 386.982971 -37.52482) (xy 386.900052 -37.495351) (xy 386.820157 -37.458464) (xy 386.743948 -37.414464)
			(xy 386.672055 -37.363716) (xy 386.605074 -37.306642) (xy 386.543562 -37.243712) (xy 386.488026 -37.17545)
			(xy 386.438928 -37.102421) (xy 386.396675 -37.025229) (xy 386.361616 -36.944515) (xy 386.334041 -36.860947)
			(xy 386.314181 -36.775218) (xy 386.302198 -36.688038) (xy 386.298193 -36.60013) (xy 362.231178 -36.60013)
			(xy 362.230677 -36.64413) (xy 362.222675 -36.731765) (xy 362.206737 -36.818309) (xy 362.182995 -36.903045)
			(xy 362.151646 -36.985271) (xy 362.112949 -37.064306) (xy 362.067226 -37.139494) (xy 362.014855 -37.210213)
			(xy 361.956271 -37.275877) (xy 361.891957 -37.335942) (xy 361.822449 -37.389909) (xy 361.748321 -37.437331)
			(xy 361.670187 -37.477817) (xy 361.588696 -37.51103) (xy 361.504522 -37.536694) (xy 361.418363 -37.554598)
			(xy 361.330933 -37.564593) (xy 361.242956 -37.566597) (xy 361.155162 -37.560591) (xy 361.068278 -37.546627)
			(xy 360.983023 -37.52482) (xy 360.900104 -37.495351) (xy 360.820209 -37.458464) (xy 360.744 -37.414464)
			(xy 360.672107 -37.363716) (xy 360.605126 -37.306642) (xy 360.543614 -37.243712) (xy 360.488078 -37.17545)
			(xy 360.43898 -37.102421) (xy 360.396727 -37.025229) (xy 360.361668 -36.944515) (xy 360.334093 -36.860947)
			(xy 360.314233 -36.775218) (xy 360.30225 -36.688038) (xy 360.298245 -36.60013) (xy 324.130924 -36.60013)
			(xy 324.130423 -36.64413) (xy 324.122421 -36.731765) (xy 324.106483 -36.818309) (xy 324.082741 -36.903045)
			(xy 324.051392 -36.985271) (xy 324.012695 -37.064306) (xy 323.966972 -37.139494) (xy 323.914601 -37.210213)
			(xy 323.856017 -37.275877) (xy 323.791703 -37.335942) (xy 323.722195 -37.389909) (xy 323.648067 -37.437331)
			(xy 323.569933 -37.477817) (xy 323.488442 -37.51103) (xy 323.404268 -37.536694) (xy 323.318109 -37.554598)
			(xy 323.230679 -37.564593) (xy 323.142702 -37.566597) (xy 323.054908 -37.560591) (xy 322.968024 -37.546627)
			(xy 322.882769 -37.52482) (xy 322.79985 -37.495351) (xy 322.719955 -37.458464) (xy 322.643746 -37.414464)
			(xy 322.571853 -37.363716) (xy 322.504872 -37.306642) (xy 322.44336 -37.243712) (xy 322.387824 -37.17545)
			(xy 322.338726 -37.102421) (xy 322.296473 -37.025229) (xy 322.261414 -36.944515) (xy 322.233839 -36.860947)
			(xy 322.213979 -36.775218) (xy 322.201996 -36.688038) (xy 322.197991 -36.60013) (xy 298.130976 -36.60013)
			(xy 298.130475 -36.644118) (xy 298.122475 -36.73173) (xy 298.106541 -36.818251) (xy 298.082806 -36.902965)
			(xy 298.051465 -36.98517) (xy 298.012779 -37.064184) (xy 297.967067 -37.139353) (xy 297.91471 -37.210053)
			(xy 297.856141 -37.2757) (xy 297.791845 -37.335748) (xy 297.722354 -37.389701) (xy 297.648246 -37.437112)
			(xy 297.570133 -37.477586) (xy 297.488663 -37.51079) (xy 297.404511 -37.536448) (xy 297.318375 -37.554348)
			(xy 297.230968 -37.56434) (xy 297.143014 -37.566343) (xy 297.055243 -37.560339) (xy 296.968381 -37.546379)
			(xy 296.883149 -37.524577) (xy 296.800252 -37.495116) (xy 296.720378 -37.458238) (xy 296.644188 -37.41425)
			(xy 296.572314 -37.363516) (xy 296.505352 -37.306456) (xy 296.443855 -37.243543) (xy 296.388334 -37.175299)
			(xy 296.339249 -37.102289) (xy 296.297007 -37.025117) (xy 296.261957 -36.944424) (xy 296.23439 -36.860879)
			(xy 296.214535 -36.775172) (xy 296.202555 -36.688015) (xy 296.198551 -36.60013) (xy 272.131028 -36.60013)
			(xy 272.130527 -36.644118) (xy 272.122527 -36.73173) (xy 272.106593 -36.818251) (xy 272.082858 -36.902965)
			(xy 272.051517 -36.98517) (xy 272.012831 -37.064184) (xy 271.967119 -37.139353) (xy 271.914762 -37.210053)
			(xy 271.856193 -37.2757) (xy 271.791897 -37.335748) (xy 271.722406 -37.389701) (xy 271.648298 -37.437112)
			(xy 271.570185 -37.477586) (xy 271.488715 -37.51079) (xy 271.404563 -37.536448) (xy 271.318427 -37.554348)
			(xy 271.23102 -37.56434) (xy 271.143066 -37.566343) (xy 271.055295 -37.560339) (xy 270.968433 -37.546379)
			(xy 270.883201 -37.524577) (xy 270.800304 -37.495116) (xy 270.72043 -37.458238) (xy 270.64424 -37.41425)
			(xy 270.572366 -37.363516) (xy 270.505404 -37.306456) (xy 270.443907 -37.243543) (xy 270.388386 -37.175299)
			(xy 270.339301 -37.102289) (xy 270.297059 -37.025117) (xy 270.262009 -36.944424) (xy 270.234442 -36.860879)
			(xy 270.214587 -36.775172) (xy 270.202607 -36.688015) (xy 270.198603 -36.60013) (xy 246.13108 -36.60013)
			(xy 246.130579 -36.644118) (xy 246.122579 -36.73173) (xy 246.106645 -36.818251) (xy 246.08291 -36.902965)
			(xy 246.051569 -36.98517) (xy 246.012883 -37.064184) (xy 245.967171 -37.139353) (xy 245.914814 -37.210053)
			(xy 245.856245 -37.2757) (xy 245.791949 -37.335748) (xy 245.722458 -37.389701) (xy 245.64835 -37.437112)
			(xy 245.570237 -37.477586) (xy 245.488767 -37.51079) (xy 245.404615 -37.536448) (xy 245.318479 -37.554348)
			(xy 245.231072 -37.56434) (xy 245.143118 -37.566343) (xy 245.055347 -37.560339) (xy 244.968485 -37.546379)
			(xy 244.883253 -37.524577) (xy 244.800356 -37.495116) (xy 244.720482 -37.458238) (xy 244.644292 -37.41425)
			(xy 244.572418 -37.363516) (xy 244.505456 -37.306456) (xy 244.443959 -37.243543) (xy 244.388438 -37.175299)
			(xy 244.339353 -37.102289) (xy 244.297111 -37.025117) (xy 244.262061 -36.944424) (xy 244.234494 -36.860879)
			(xy 244.214639 -36.775172) (xy 244.202659 -36.688015) (xy 244.198655 -36.60013) (xy 208.03108 -36.60013)
			(xy 208.030579 -36.644118) (xy 208.022579 -36.73173) (xy 208.006645 -36.818251) (xy 207.98291 -36.902965)
			(xy 207.951569 -36.98517) (xy 207.912883 -37.064184) (xy 207.867171 -37.139353) (xy 207.814814 -37.210053)
			(xy 207.756245 -37.2757) (xy 207.691949 -37.335748) (xy 207.622458 -37.389701) (xy 207.54835 -37.437112)
			(xy 207.470237 -37.477586) (xy 207.388767 -37.51079) (xy 207.304615 -37.536448) (xy 207.218479 -37.554348)
			(xy 207.131072 -37.56434) (xy 207.043118 -37.566343) (xy 206.955347 -37.560339) (xy 206.868485 -37.546379)
			(xy 206.783253 -37.524577) (xy 206.700356 -37.495116) (xy 206.620482 -37.458238) (xy 206.544292 -37.41425)
			(xy 206.472418 -37.363516) (xy 206.405456 -37.306456) (xy 206.343959 -37.243543) (xy 206.288438 -37.175299)
			(xy 206.239353 -37.102289) (xy 206.197111 -37.025117) (xy 206.162061 -36.944424) (xy 206.134494 -36.860879)
			(xy 206.114639 -36.775172) (xy 206.102659 -36.688015) (xy 206.098655 -36.60013) (xy 182.031132 -36.60013)
			(xy 182.030631 -36.64413) (xy 182.022629 -36.731765) (xy 182.006691 -36.818309) (xy 181.982949 -36.903045)
			(xy 181.9516 -36.985271) (xy 181.912903 -37.064306) (xy 181.86718 -37.139494) (xy 181.814809 -37.210213)
			(xy 181.756225 -37.275877) (xy 181.691911 -37.335942) (xy 181.622403 -37.389909) (xy 181.548275 -37.437331)
			(xy 181.470141 -37.477817) (xy 181.38865 -37.51103) (xy 181.304476 -37.536694) (xy 181.218317 -37.554598)
			(xy 181.130887 -37.564593) (xy 181.04291 -37.566597) (xy 180.955116 -37.560591) (xy 180.868232 -37.546627)
			(xy 180.782977 -37.52482) (xy 180.700058 -37.495351) (xy 180.620163 -37.458464) (xy 180.543954 -37.414464)
			(xy 180.472061 -37.363716) (xy 180.40508 -37.306642) (xy 180.343568 -37.243712) (xy 180.288032 -37.17545)
			(xy 180.238934 -37.102421) (xy 180.196681 -37.025229) (xy 180.161622 -36.944515) (xy 180.134047 -36.860947)
			(xy 180.114187 -36.775218) (xy 180.102204 -36.688038) (xy 180.098199 -36.60013) (xy 156.031184 -36.60013)
			(xy 156.030683 -36.64413) (xy 156.022681 -36.731765) (xy 156.006743 -36.818309) (xy 155.983001 -36.903045)
			(xy 155.951652 -36.985271) (xy 155.912955 -37.064306) (xy 155.867232 -37.139494) (xy 155.814861 -37.210213)
			(xy 155.756277 -37.275877) (xy 155.691963 -37.335942) (xy 155.622455 -37.389909) (xy 155.548327 -37.437331)
			(xy 155.470193 -37.477817) (xy 155.388702 -37.51103) (xy 155.304528 -37.536694) (xy 155.218369 -37.554598)
			(xy 155.130939 -37.564593) (xy 155.042962 -37.566597) (xy 154.955168 -37.560591) (xy 154.868284 -37.546627)
			(xy 154.783029 -37.52482) (xy 154.70011 -37.495351) (xy 154.620215 -37.458464) (xy 154.544006 -37.414464)
			(xy 154.472113 -37.363716) (xy 154.405132 -37.306642) (xy 154.34362 -37.243712) (xy 154.288084 -37.17545)
			(xy 154.238986 -37.102421) (xy 154.196733 -37.025229) (xy 154.161674 -36.944515) (xy 154.134099 -36.860947)
			(xy 154.114239 -36.775218) (xy 154.102256 -36.688038) (xy 154.098251 -36.60013) (xy 130.031236 -36.60013)
			(xy 130.030735 -36.64413) (xy 130.022733 -36.731765) (xy 130.006795 -36.818309) (xy 129.983053 -36.903045)
			(xy 129.951704 -36.985271) (xy 129.913007 -37.064306) (xy 129.867284 -37.139494) (xy 129.814913 -37.210213)
			(xy 129.756329 -37.275877) (xy 129.692015 -37.335942) (xy 129.622507 -37.389909) (xy 129.548379 -37.437331)
			(xy 129.470245 -37.477817) (xy 129.388754 -37.51103) (xy 129.30458 -37.536694) (xy 129.218421 -37.554598)
			(xy 129.130991 -37.564593) (xy 129.043014 -37.566597) (xy 128.95522 -37.560591) (xy 128.868336 -37.546627)
			(xy 128.783081 -37.52482) (xy 128.700162 -37.495351) (xy 128.620267 -37.458464) (xy 128.544058 -37.414464)
			(xy 128.472165 -37.363716) (xy 128.405184 -37.306642) (xy 128.343672 -37.243712) (xy 128.288136 -37.17545)
			(xy 128.239038 -37.102421) (xy 128.196785 -37.025229) (xy 128.161726 -36.944515) (xy 128.134151 -36.860947)
			(xy 128.114291 -36.775218) (xy 128.102308 -36.688038) (xy 128.098303 -36.60013) (xy 91.930982 -36.60013)
			(xy 91.930481 -36.64413) (xy 91.922479 -36.731765) (xy 91.906541 -36.818309) (xy 91.882799 -36.903045)
			(xy 91.85145 -36.985271) (xy 91.812753 -37.064306) (xy 91.76703 -37.139494) (xy 91.714659 -37.210213)
			(xy 91.656075 -37.275877) (xy 91.591761 -37.335942) (xy 91.522253 -37.389909) (xy 91.448125 -37.437331)
			(xy 91.369991 -37.477817) (xy 91.2885 -37.51103) (xy 91.204326 -37.536694) (xy 91.118167 -37.554598)
			(xy 91.030737 -37.564593) (xy 90.94276 -37.566597) (xy 90.854966 -37.560591) (xy 90.768082 -37.546627)
			(xy 90.682827 -37.52482) (xy 90.599908 -37.495351) (xy 90.520013 -37.458464) (xy 90.443804 -37.414464)
			(xy 90.371911 -37.363716) (xy 90.30493 -37.306642) (xy 90.243418 -37.243712) (xy 90.187882 -37.17545)
			(xy 90.138784 -37.102421) (xy 90.096531 -37.025229) (xy 90.061472 -36.944515) (xy 90.033897 -36.860947)
			(xy 90.014037 -36.775218) (xy 90.002054 -36.688038) (xy 89.998049 -36.60013) (xy 65.931034 -36.60013)
			(xy 65.930533 -36.64413) (xy 65.922531 -36.731765) (xy 65.906593 -36.818309) (xy 65.882851 -36.903045)
			(xy 65.851502 -36.985271) (xy 65.812805 -37.064306) (xy 65.767082 -37.139494) (xy 65.714711 -37.210213)
			(xy 65.656127 -37.275877) (xy 65.591813 -37.335942) (xy 65.522305 -37.389909) (xy 65.448177 -37.437331)
			(xy 65.370043 -37.477817) (xy 65.288552 -37.51103) (xy 65.204378 -37.536694) (xy 65.118219 -37.554598)
			(xy 65.030789 -37.564593) (xy 64.942812 -37.566597) (xy 64.855018 -37.560591) (xy 64.768134 -37.546627)
			(xy 64.682879 -37.52482) (xy 64.59996 -37.495351) (xy 64.520065 -37.458464) (xy 64.443856 -37.414464)
			(xy 64.371963 -37.363716) (xy 64.304982 -37.306642) (xy 64.24347 -37.243712) (xy 64.187934 -37.17545)
			(xy 64.138836 -37.102421) (xy 64.096583 -37.025229) (xy 64.061524 -36.944515) (xy 64.033949 -36.860947)
			(xy 64.014089 -36.775218) (xy 64.002106 -36.688038) (xy 63.998101 -36.60013) (xy 39.931086 -36.60013)
			(xy 39.930585 -36.64413) (xy 39.922583 -36.731765) (xy 39.906645 -36.818309) (xy 39.882903 -36.903045)
			(xy 39.851554 -36.985271) (xy 39.812857 -37.064306) (xy 39.767134 -37.139494) (xy 39.714763 -37.210213)
			(xy 39.656179 -37.275877) (xy 39.591865 -37.335942) (xy 39.522357 -37.389909) (xy 39.448229 -37.437331)
			(xy 39.370095 -37.477817) (xy 39.288604 -37.51103) (xy 39.20443 -37.536694) (xy 39.118271 -37.554598)
			(xy 39.030841 -37.564593) (xy 38.942864 -37.566597) (xy 38.85507 -37.560591) (xy 38.768186 -37.546627)
			(xy 38.682931 -37.52482) (xy 38.600012 -37.495351) (xy 38.520117 -37.458464) (xy 38.443908 -37.414464)
			(xy 38.372015 -37.363716) (xy 38.305034 -37.306642) (xy 38.243522 -37.243712) (xy 38.187986 -37.17545)
			(xy 38.138888 -37.102421) (xy 38.096635 -37.025229) (xy 38.061576 -36.944515) (xy 38.034001 -36.860947)
			(xy 38.014141 -36.775218) (xy 38.002158 -36.688038) (xy 37.998153 -36.60013) (xy 13.931138 -36.60013)
			(xy 13.930637 -36.64413) (xy 13.922635 -36.731765) (xy 13.906697 -36.818309) (xy 13.882955 -36.903045)
			(xy 13.851606 -36.985271) (xy 13.812909 -37.064306) (xy 13.767186 -37.139494) (xy 13.714815 -37.210213)
			(xy 13.656231 -37.275877) (xy 13.591917 -37.335942) (xy 13.522409 -37.389909) (xy 13.448281 -37.437331)
			(xy 13.370147 -37.477817) (xy 13.288656 -37.51103) (xy 13.204482 -37.536694) (xy 13.118323 -37.554598)
			(xy 13.030893 -37.564593) (xy 12.942916 -37.566597) (xy 12.855122 -37.560591) (xy 12.768238 -37.546627)
			(xy 12.682983 -37.52482) (xy 12.600064 -37.495351) (xy 12.520169 -37.458464) (xy 12.44396 -37.414464)
			(xy 12.372067 -37.363716) (xy 12.305086 -37.306642) (xy 12.243574 -37.243712) (xy 12.188038 -37.17545)
			(xy 12.13894 -37.102421) (xy 12.096687 -37.025229) (xy 12.061628 -36.944515) (xy 12.034053 -36.860947)
			(xy 12.014193 -36.775218) (xy 12.00221 -36.688038) (xy 11.998205 -36.60013) (xy 0.509016 -36.60013)
			(xy 0.509016 -60.13196) (xy 226.436428 -60.13196) (xy 226.436428 -59.26836) (xy 226.436918 -59.238392)
			(xy 226.444741 -59.17897) (xy 226.460254 -59.121077) (xy 226.48319 -59.065704) (xy 226.513157 -59.013798)
			(xy 226.549644 -58.966248) (xy 226.592024 -58.923868) (xy 226.639574 -58.887381) (xy 226.69148 -58.857414)
			(xy 226.746853 -58.834478) (xy 226.804746 -58.818965) (xy 226.864168 -58.811142) (xy 226.924104 -58.811142)
			(xy 226.983526 -58.818965) (xy 227.041419 -58.834478) (xy 227.096792 -58.857414) (xy 227.148698 -58.887381)
			(xy 227.196248 -58.923868) (xy 227.238628 -58.966248) (xy 227.275115 -59.013798) (xy 227.305082 -59.065704)
			(xy 227.328018 -59.121077) (xy 227.343531 -59.17897) (xy 227.351354 -59.238392) (xy 227.351844 -59.26836)
			(xy 227.351844 -60.13196) (xy 227.351707 -60.140342) (xy 228.763068 -60.140342) (xy 228.763068 -59.260232)
			(xy 228.763547 -59.250084) (xy 228.771326 -59.231338) (xy 228.785705 -59.217015) (xy 228.80448 -59.209308)
			(xy 228.81463 -59.208924) (xy 229.792022 -59.208924) (xy 229.804439 -59.208306) (xy 229.826406 -59.196722)
			(xy 229.833932 -59.186826) (xy 229.888288 -59.107324) (xy 229.891336 -59.082432) (xy 229.886764 -59.070748)
			(xy 229.869758 -59.025304) (xy 229.84245 -58.932188) (xy 229.822955 -58.837128) (xy 229.811407 -58.740779)
			(xy 229.807887 -58.643805) (xy 229.812418 -58.546873) (xy 229.824969 -58.45065) (xy 229.845454 -58.355798)
			(xy 229.873731 -58.262972) (xy 229.909607 -58.172809) (xy 229.952833 -58.08593) (xy 230.003114 -58.002934)
			(xy 230.060101 -57.924392) (xy 230.123404 -57.850845) (xy 230.192585 -57.782799) (xy 230.26717 -57.720722)
			(xy 230.346644 -57.665042) (xy 230.43046 -57.616142) (xy 230.518042 -57.574359) (xy 230.608786 -57.53998)
			(xy 230.702068 -57.513242) (xy 230.797246 -57.49433) (xy 230.893663 -57.483372) (xy 230.990657 -57.480446)
			(xy 231.08756 -57.48557) (xy 231.183704 -57.498711) (xy 231.278429 -57.519776) (xy 231.37108 -57.548621)
			(xy 231.461022 -57.585049) (xy 231.547634 -57.628806) (xy 231.63032 -57.679594) (xy 231.708512 -57.737061)
			(xy 231.78167 -57.800813) (xy 231.849291 -57.87041) (xy 231.91091 -57.945374) (xy 231.966103 -58.025187)
			(xy 232.014488 -58.109302) (xy 232.055734 -58.197138) (xy 232.089557 -58.288091) (xy 232.115723 -58.381535)
			(xy 232.134052 -58.476826) (xy 232.144419 -58.573309) (xy 232.146751 -58.670319) (xy 232.141033 -58.767189)
			(xy 232.127304 -58.863251) (xy 232.105659 -58.957844) (xy 232.076247 -59.050317) (xy 232.03927 -59.140034)
			(xy 231.994982 -59.226377) (xy 231.943689 -59.30875) (xy 231.885744 -59.386588) (xy 231.821545 -59.459355)
			(xy 231.751535 -59.526549) (xy 231.676196 -59.587707) (xy 231.596046 -59.64241) (xy 231.511637 -59.69028)
			(xy 231.42355 -59.730987) (xy 231.332391 -59.764252) (xy 231.238789 -59.789845) (xy 231.143387 -59.80759)
			(xy 231.046843 -59.817366) (xy 230.94982 -59.819104) (xy 230.852987 -59.812793) (xy 230.757011 -59.798476)
			(xy 230.662552 -59.776252) (xy 230.570261 -59.746274) (xy 230.480772 -59.708748) (xy 230.394702 -59.663933)
			(xy 230.312644 -59.612136) (xy 230.273606 -59.58332) (xy 230.265822 -59.578073) (xy 230.247778 -59.572974)
			(xy 230.229107 -59.574707) (xy 230.22052 -59.578494) (xy 230.138986 -59.619134) (xy 230.130718 -59.623681)
			(xy 230.117995 -59.637596) (xy 230.111171 -59.655173) (xy 230.110792 -59.6646) (xy 230.110792 -60.140342)
			(xy 230.110309 -60.150467) (xy 230.102573 -60.169184) (xy 230.088287 -60.183537) (xy 230.069607 -60.191361)
			(xy 230.059484 -60.191904) (xy 228.81463 -60.191904) (xy 228.804479 -60.191343) (xy 228.785719 -60.183587)
			(xy 228.771354 -60.169242) (xy 228.763571 -60.150492) (xy 228.763068 -60.140342) (xy 227.351707 -60.140342)
			(xy 227.351354 -60.161928) (xy 227.343531 -60.22135) (xy 227.328018 -60.279243) (xy 227.305082 -60.334616)
			(xy 227.275115 -60.386522) (xy 227.238628 -60.434072) (xy 227.196248 -60.476452) (xy 227.148698 -60.512939)
			(xy 227.096792 -60.542906) (xy 227.041419 -60.565842) (xy 226.983526 -60.581355) (xy 226.924104 -60.589178)
			(xy 226.864168 -60.589178) (xy 226.804746 -60.581355) (xy 226.746853 -60.565842) (xy 226.69148 -60.542906)
			(xy 226.639574 -60.512939) (xy 226.592024 -60.476452) (xy 226.549644 -60.434072) (xy 226.513157 -60.386522)
			(xy 226.48319 -60.334616) (xy 226.460254 -60.279243) (xy 226.444741 -60.22135) (xy 226.436918 -60.161928)
			(xy 226.436428 -60.13196) (xy 0.509016 -60.13196) (xy 0.509016 -69.798271) (xy 229.808523 -69.798271)
			(xy 229.808523 -69.701577) (xy 229.816508 -69.605214) (xy 229.832424 -69.509839) (xy 229.85616 -69.416105)
			(xy 229.887557 -69.32465) (xy 229.926398 -69.236101) (xy 229.972419 -69.151061) (xy 230.025305 -69.070113)
			(xy 230.084696 -68.993808) (xy 230.150184 -68.922668) (xy 230.221324 -68.85718) (xy 230.297629 -68.797789)
			(xy 230.378577 -68.744903) (xy 230.463617 -68.698882) (xy 230.552166 -68.660041) (xy 230.643621 -68.628644)
			(xy 230.737355 -68.604908) (xy 230.83273 -68.588992) (xy 230.929093 -68.581007) (xy 231.025787 -68.581007)
			(xy 231.12215 -68.588992) (xy 231.217525 -68.604908) (xy 231.311259 -68.628644) (xy 231.402714 -68.660041)
			(xy 231.491263 -68.698882) (xy 231.576303 -68.744903) (xy 231.657251 -68.797789) (xy 231.733556 -68.85718)
			(xy 231.804696 -68.922668) (xy 231.870184 -68.993808) (xy 231.929575 -69.070113) (xy 231.982461 -69.151061)
			(xy 232.028482 -69.236101) (xy 232.067323 -69.32465) (xy 232.09872 -69.416105) (xy 232.122456 -69.509839)
			(xy 232.138372 -69.605214) (xy 232.146357 -69.701577) (xy 232.146856 -69.749924) (xy 232.146357 -69.798271)
			(xy 232.138372 -69.894634) (xy 232.122456 -69.990009) (xy 232.09872 -70.083743) (xy 232.067323 -70.175198)
			(xy 232.028482 -70.263747) (xy 231.982461 -70.348787) (xy 231.929575 -70.429735) (xy 231.870184 -70.50604)
			(xy 231.804696 -70.57718) (xy 231.733556 -70.642668) (xy 231.657251 -70.702059) (xy 231.576303 -70.754945)
			(xy 231.491263 -70.800966) (xy 231.402714 -70.839807) (xy 231.311259 -70.871204) (xy 231.217525 -70.89494)
			(xy 231.12215 -70.910856) (xy 231.025787 -70.918841) (xy 230.929093 -70.918841) (xy 230.83273 -70.910856)
			(xy 230.737355 -70.89494) (xy 230.643621 -70.871204) (xy 230.552166 -70.839807) (xy 230.463617 -70.800966)
			(xy 230.378577 -70.754945) (xy 230.297629 -70.702059) (xy 230.221324 -70.642668) (xy 230.150184 -70.57718)
			(xy 230.084696 -70.50604) (xy 230.025305 -70.429735) (xy 229.972419 -70.348787) (xy 229.926398 -70.263747)
			(xy 229.887557 -70.175198) (xy 229.85616 -70.083743) (xy 229.832424 -69.990009) (xy 229.816508 -69.894634)
			(xy 229.808523 -69.798271) (xy 0.509016 -69.798271) (xy 0.509016 -75.288385) (xy 262.150829 -75.288385)
			(xy 262.150829 -75.228415) (xy 262.158657 -75.168959) (xy 262.174178 -75.111033) (xy 262.197128 -75.055628)
			(xy 262.227114 -75.003693) (xy 262.263621 -74.956116) (xy 262.306027 -74.913712) (xy 262.353605 -74.877206)
			(xy 262.405541 -74.847222) (xy 262.460946 -74.824274) (xy 262.518872 -74.808754) (xy 262.578329 -74.800928)
			(xy 262.608314 -74.80046) (xy 263.471914 -74.80046) (xy 263.501899 -74.800907) (xy 263.561356 -74.808736)
			(xy 263.619283 -74.824259) (xy 263.674687 -74.84721) (xy 263.726623 -74.877196) (xy 263.7742 -74.913705)
			(xy 263.816604 -74.956111) (xy 263.853111 -75.003689) (xy 263.883096 -75.055625) (xy 263.906045 -75.111031)
			(xy 263.921566 -75.168958) (xy 263.929394 -75.228415) (xy 263.929394 -75.288385) (xy 263.921566 -75.347842)
			(xy 263.906045 -75.405769) (xy 263.883096 -75.461175) (xy 263.853111 -75.513111) (xy 263.816604 -75.560689)
			(xy 263.7742 -75.603095) (xy 263.726623 -75.639604) (xy 263.674687 -75.66959) (xy 263.619283 -75.692541)
			(xy 263.561356 -75.708064) (xy 263.501899 -75.715893) (xy 263.471914 -75.716384) (xy 262.608314 -75.716384)
			(xy 262.578329 -75.715872) (xy 262.518872 -75.708046) (xy 262.460946 -75.692526) (xy 262.405541 -75.669578)
			(xy 262.353605 -75.639594) (xy 262.306027 -75.603088) (xy 262.263621 -75.560684) (xy 262.227114 -75.513107)
			(xy 262.197128 -75.461172) (xy 262.174178 -75.405767) (xy 262.158657 -75.347841) (xy 262.150829 -75.288385)
			(xy 0.509016 -75.288385) (xy 0.509016 -76.826085) (xy 229.640845 -76.826085) (xy 229.640845 -76.766115)
			(xy 229.648673 -76.706658) (xy 229.664196 -76.648731) (xy 229.687147 -76.593327) (xy 229.717134 -76.541392)
			(xy 229.753643 -76.493816) (xy 229.796051 -76.451413) (xy 229.84363 -76.414908) (xy 229.895568 -76.384926)
			(xy 229.950975 -76.361981) (xy 230.008903 -76.346464) (xy 230.068361 -76.338642) (xy 230.098346 -76.338176)
			(xy 230.961946 -76.338176) (xy 230.991931 -76.338593) (xy 231.051387 -76.346426) (xy 231.109312 -76.361952)
			(xy 231.164715 -76.384906) (xy 231.216648 -76.414894) (xy 231.264223 -76.451404) (xy 231.306626 -76.493811)
			(xy 231.343131 -76.54139) (xy 231.373114 -76.593326) (xy 231.396063 -76.648732) (xy 231.411583 -76.706658)
			(xy 231.41941 -76.766115) (xy 231.41941 -76.826085) (xy 231.411583 -76.885542) (xy 231.396063 -76.943468)
			(xy 231.373114 -76.998874) (xy 231.343131 -77.05081) (xy 231.306626 -77.098389) (xy 231.264223 -77.140796)
			(xy 231.216648 -77.177306) (xy 231.164715 -77.207294) (xy 231.109312 -77.230248) (xy 231.051387 -77.245774)
			(xy 230.991931 -77.253607) (xy 230.961946 -77.2541) (xy 230.098346 -77.2541) (xy 230.068361 -77.253558)
			(xy 230.008903 -77.245736) (xy 229.950975 -77.230219) (xy 229.895568 -77.207274) (xy 229.84363 -77.177292)
			(xy 229.796051 -77.140787) (xy 229.753643 -77.098384) (xy 229.717134 -77.050808) (xy 229.687147 -76.998873)
			(xy 229.664196 -76.943469) (xy 229.648673 -76.885542) (xy 229.640845 -76.826085) (xy 0.509016 -76.826085)
			(xy 0.509016 -77.365367) (xy 105.150162 -77.365367) (xy 105.150162 -77.305433) (xy 105.157985 -77.246011)
			(xy 105.173496 -77.188119) (xy 105.19643 -77.132746) (xy 105.226396 -77.08084) (xy 105.26288 -77.03329)
			(xy 105.305258 -76.990908) (xy 105.352805 -76.954419) (xy 105.404708 -76.924449) (xy 105.460079 -76.901509)
			(xy 105.51797 -76.885993) (xy 105.577391 -76.878165) (xy 105.607358 -76.877672) (xy 106.470958 -76.877672)
			(xy 106.500928 -76.878178) (xy 106.560354 -76.885997) (xy 106.618252 -76.901506) (xy 106.67363 -76.92444)
			(xy 106.72554 -76.954406) (xy 106.773095 -76.990892) (xy 106.81548 -77.033273) (xy 106.851971 -77.080825)
			(xy 106.881942 -77.132732) (xy 106.904881 -77.188108) (xy 106.920395 -77.246004) (xy 106.928219 -77.305431)
			(xy 106.928219 -77.365367) (xy 109.150162 -77.365367) (xy 109.150162 -77.305433) (xy 109.157984 -77.246012)
			(xy 109.173495 -77.18812) (xy 109.196429 -77.132748) (xy 109.226394 -77.080843) (xy 109.262878 -77.033292)
			(xy 109.305255 -76.990911) (xy 109.352801 -76.954422) (xy 109.404703 -76.924452) (xy 109.460073 -76.901511)
			(xy 109.517963 -76.885994) (xy 109.577383 -76.878165) (xy 109.60735 -76.877672) (xy 110.47095 -76.877672)
			(xy 110.50092 -76.878178) (xy 110.560347 -76.885996) (xy 110.618246 -76.901504) (xy 110.673625 -76.924437)
			(xy 110.725536 -76.954403) (xy 110.773092 -76.990889) (xy 110.815478 -77.03327) (xy 110.851969 -77.080822)
			(xy 110.881941 -77.13273) (xy 110.90488 -77.188107) (xy 110.920395 -77.246003) (xy 110.928219 -77.30543)
			(xy 110.928219 -77.36537) (xy 110.920395 -77.424797) (xy 110.90488 -77.482693) (xy 110.881941 -77.53807)
			(xy 110.851969 -77.589978) (xy 110.815478 -77.63753) (xy 110.773092 -77.679911) (xy 110.725536 -77.716397)
			(xy 110.673625 -77.746363) (xy 110.618246 -77.769296) (xy 110.560347 -77.784804) (xy 110.50092 -77.792622)
			(xy 110.47095 -77.793088) (xy 109.60735 -77.793088) (xy 109.577383 -77.792635) (xy 109.517963 -77.784806)
			(xy 109.460073 -77.769289) (xy 109.404703 -77.746348) (xy 109.352801 -77.716378) (xy 109.305255 -77.679889)
			(xy 109.262878 -77.637508) (xy 109.226394 -77.589957) (xy 109.196429 -77.538052) (xy 109.173495 -77.48268)
			(xy 109.157984 -77.424788) (xy 109.150162 -77.365367) (xy 106.928219 -77.365367) (xy 106.928219 -77.365369)
			(xy 106.920395 -77.424796) (xy 106.904881 -77.482692) (xy 106.881942 -77.538068) (xy 106.851971 -77.589975)
			(xy 106.81548 -77.637527) (xy 106.773095 -77.679908) (xy 106.72554 -77.716394) (xy 106.67363 -77.74636)
			(xy 106.618252 -77.769294) (xy 106.560354 -77.784803) (xy 106.500928 -77.792622) (xy 106.470958 -77.793088)
			(xy 105.607358 -77.793088) (xy 105.577391 -77.792635) (xy 105.51797 -77.784807) (xy 105.460079 -77.769291)
			(xy 105.404708 -77.746351) (xy 105.352805 -77.716381) (xy 105.305258 -77.679892) (xy 105.26288 -77.63751)
			(xy 105.226396 -77.58996) (xy 105.19643 -77.538054) (xy 105.173496 -77.482681) (xy 105.157985 -77.424789)
			(xy 105.150162 -77.365367) (xy 0.509016 -77.365367) (xy 0.509016 -78.127367) (xy 107.150162 -78.127367)
			(xy 107.150162 -78.067433) (xy 107.157984 -78.008012) (xy 107.173496 -77.950119) (xy 107.19643 -77.894747)
			(xy 107.226395 -77.842842) (xy 107.262879 -77.795291) (xy 107.305256 -77.752909) (xy 107.352803 -77.716421)
			(xy 107.404706 -77.68645) (xy 107.460076 -77.66351) (xy 107.517966 -77.647993) (xy 107.577387 -77.640165)
			(xy 107.607354 -77.639672) (xy 108.470954 -77.639672) (xy 108.500924 -77.640178) (xy 108.560351 -77.647996)
			(xy 108.618249 -77.663505) (xy 108.673627 -77.686438) (xy 108.725538 -77.716405) (xy 108.773094 -77.752891)
			(xy 108.815479 -77.795272) (xy 108.85197 -77.842823) (xy 108.881941 -77.894731) (xy 108.90488 -77.950107)
			(xy 108.920395 -78.008004) (xy 108.928219 -78.06743) (xy 108.928219 -78.12737) (xy 108.920395 -78.186796)
			(xy 108.90488 -78.244693) (xy 108.881941 -78.300069) (xy 108.85197 -78.351977) (xy 108.815479 -78.399528)
			(xy 108.773093 -78.441909) (xy 108.725538 -78.478395) (xy 108.673627 -78.508362) (xy 108.618249 -78.531295)
			(xy 108.560351 -78.546804) (xy 108.500924 -78.554622) (xy 108.470954 -78.555088) (xy 107.607354 -78.555088)
			(xy 107.577387 -78.554635) (xy 107.517966 -78.546807) (xy 107.460076 -78.53129) (xy 107.404706 -78.50835)
			(xy 107.352803 -78.478379) (xy 107.305256 -78.441891) (xy 107.262879 -78.399509) (xy 107.226395 -78.351958)
			(xy 107.19643 -78.300053) (xy 107.173496 -78.244681) (xy 107.157984 -78.186788) (xy 107.150162 -78.127367)
			(xy 0.509016 -78.127367) (xy 0.509016 -79.238094) (xy 227.9777 -79.238094) (xy 227.9777 -78.374494)
			(xy 227.97819 -78.344526) (xy 227.986013 -78.285104) (xy 228.001526 -78.227211) (xy 228.024462 -78.171838)
			(xy 228.054429 -78.119932) (xy 228.090916 -78.072382) (xy 228.133296 -78.030002) (xy 228.180846 -77.993515)
			(xy 228.232752 -77.963548) (xy 228.288125 -77.940612) (xy 228.346018 -77.925099) (xy 228.40544 -77.917276)
			(xy 228.465376 -77.917276) (xy 228.524798 -77.925099) (xy 228.582691 -77.940612) (xy 228.638064 -77.963548)
			(xy 228.68997 -77.993515) (xy 228.73752 -78.030002) (xy 228.7799 -78.072382) (xy 228.816387 -78.119932)
			(xy 228.83413 -78.150664) (xy 336.40703 -78.150664) (xy 336.40703 -78.090736) (xy 336.414852 -78.031319)
			(xy 336.430363 -77.973433) (xy 336.453297 -77.918066) (xy 336.483261 -77.866166) (xy 336.519743 -77.818621)
			(xy 336.562119 -77.776245) (xy 336.609664 -77.739762) (xy 336.661564 -77.709797) (xy 336.716931 -77.686864)
			(xy 336.774817 -77.671353) (xy 336.834234 -77.66353) (xy 336.864198 -77.66304) (xy 337.727798 -77.66304)
			(xy 337.75777 -77.663413) (xy 337.817202 -77.671237) (xy 337.875104 -77.686751) (xy 337.930486 -77.709691)
			(xy 337.982399 -77.739663) (xy 338.029957 -77.776155) (xy 338.072344 -77.818542) (xy 338.108836 -77.866099)
			(xy 338.138808 -77.918013) (xy 338.161748 -77.973394) (xy 338.177263 -78.031296) (xy 338.185087 -78.090728)
			(xy 338.185087 -78.150672) (xy 338.177263 -78.210104) (xy 338.161748 -78.268006) (xy 338.138808 -78.323387)
			(xy 338.108836 -78.375301) (xy 338.072344 -78.422858) (xy 338.029957 -78.465245) (xy 337.982399 -78.501737)
			(xy 337.930486 -78.531709) (xy 337.875104 -78.554649) (xy 337.817202 -78.570163) (xy 337.75777 -78.577987)
			(xy 337.727798 -78.578456) (xy 336.864198 -78.578456) (xy 336.834234 -78.57787) (xy 336.774817 -78.570047)
			(xy 336.716931 -78.554536) (xy 336.661564 -78.531603) (xy 336.609664 -78.501638) (xy 336.562119 -78.465155)
			(xy 336.519743 -78.422779) (xy 336.483261 -78.375234) (xy 336.453297 -78.323334) (xy 336.430363 -78.267967)
			(xy 336.414852 -78.210081) (xy 336.40703 -78.150664) (xy 228.83413 -78.150664) (xy 228.846354 -78.171838)
			(xy 228.86929 -78.227211) (xy 228.884803 -78.285104) (xy 228.892626 -78.344526) (xy 228.893116 -78.374494)
			(xy 228.893116 -79.0448) (xy 229.538276 -79.0448) (xy 229.538276 -78.567534) (xy 229.538693 -78.55736)
			(xy 229.546474 -78.538559) (xy 229.560862 -78.524171) (xy 229.579664 -78.516392) (xy 229.589838 -78.515972)
			(xy 229.998016 -78.515972) (xy 230.008168 -78.516408) (xy 230.026915 -78.524203) (xy 230.041237 -78.538595)
			(xy 230.048941 -78.55738) (xy 230.049324 -78.567534) (xy 230.049324 -78.85176) (xy 230.251508 -78.85176)
			(xy 230.251508 -78.239874) (xy 230.252011 -78.229718) (xy 230.259789 -78.210954) (xy 230.274151 -78.196591)
			(xy 230.292914 -78.188812) (xy 230.30307 -78.188312) (xy 230.35641 -78.188312) (xy 230.366565 -78.188825)
			(xy 230.385329 -78.196598) (xy 230.399693 -78.210957) (xy 230.407472 -78.229719) (xy 230.407972 -78.239874)
			(xy 230.407972 -78.85176) (xy 230.651304 -78.85176) (xy 230.651304 -78.239874) (xy 230.651811 -78.229719)
			(xy 230.659588 -78.210955) (xy 230.673949 -78.196592) (xy 230.692711 -78.188813) (xy 230.702866 -78.188312)
			(xy 230.756206 -78.188312) (xy 230.766361 -78.188828) (xy 230.785125 -78.1966) (xy 230.799489 -78.210958)
			(xy 230.807268 -78.229719) (xy 230.807768 -78.239874) (xy 230.807768 -78.85176) (xy 230.807345 -78.861915)
			(xy 230.799557 -78.880673) (xy 230.785159 -78.894999) (xy 230.766363 -78.902694) (xy 230.756206 -78.903068)
			(xy 230.702866 -78.903068) (xy 230.692738 -78.902602) (xy 230.674018 -78.894864) (xy 230.659663 -78.880572)
			(xy 230.651843 -78.861886) (xy 230.651304 -78.85176) (xy 230.407972 -78.85176) (xy 230.407545 -78.861915)
			(xy 230.399757 -78.880672) (xy 230.385362 -78.894998) (xy 230.366567 -78.902694) (xy 230.35641 -78.903068)
			(xy 230.30307 -78.903068) (xy 230.292942 -78.902598) (xy 230.274222 -78.894862) (xy 230.259867 -78.880571)
			(xy 230.252047 -78.861885) (xy 230.251508 -78.85176) (xy 230.049324 -78.85176) (xy 230.049324 -79.0448)
			(xy 230.048815 -79.054906) (xy 230.041082 -79.073579) (xy 230.026793 -79.087873) (xy 230.008122 -79.095612)
			(xy 229.998016 -79.096108) (xy 229.589838 -79.096108) (xy 229.57972 -79.095544) (xy 229.561008 -79.087837)
			(xy 229.546653 -79.073575) (xy 229.538824 -79.054915) (xy 229.538276 -79.0448) (xy 228.893116 -79.0448)
			(xy 228.893116 -79.238094) (xy 228.892626 -79.268062) (xy 228.884803 -79.327484) (xy 228.86929 -79.385377)
			(xy 228.846354 -79.44075) (xy 228.816387 -79.492656) (xy 228.7799 -79.540206) (xy 228.73752 -79.582586)
			(xy 228.68997 -79.619073) (xy 228.638064 -79.64904) (xy 228.582691 -79.671976) (xy 228.524798 -79.687489)
			(xy 228.465376 -79.695312) (xy 228.40544 -79.695312) (xy 228.346018 -79.687489) (xy 228.288125 -79.671976)
			(xy 228.232752 -79.64904) (xy 228.180846 -79.619073) (xy 228.133296 -79.582586) (xy 228.090916 -79.540206)
			(xy 228.054429 -79.492656) (xy 228.024462 -79.44075) (xy 228.001526 -79.385377) (xy 227.986013 -79.327484)
			(xy 227.97819 -79.268062) (xy 227.9777 -79.238094) (xy 0.509016 -79.238094) (xy 0.509016 -79.771494)
			(xy 230.252016 -79.771494) (xy 230.252016 -79.159608) (xy 230.252428 -79.149452) (xy 230.260224 -79.130697)
			(xy 230.274624 -79.116373) (xy 230.29342 -79.108676) (xy 230.303578 -79.1083) (xy 230.356918 -79.1083)
			(xy 230.367041 -79.10881) (xy 230.385755 -79.116537) (xy 230.400109 -79.130815) (xy 230.407935 -79.149488)
			(xy 230.40848 -79.159608) (xy 230.40848 -79.771494) (xy 230.651812 -79.771494) (xy 230.651812 -79.159608)
			(xy 230.652228 -79.149453) (xy 230.660024 -79.130698) (xy 230.674422 -79.116374) (xy 230.693217 -79.108676)
			(xy 230.703374 -79.1083) (xy 230.756714 -79.1083) (xy 230.766837 -79.108814) (xy 230.78555 -79.116539)
			(xy 230.799905 -79.130816) (xy 230.80773 -79.149488) (xy 230.808276 -79.159608) (xy 230.808276 -79.771494)
			(xy 230.807762 -79.78165) (xy 230.799992 -79.800416) (xy 230.785633 -79.814781) (xy 230.766869 -79.822558)
			(xy 230.756714 -79.823056) (xy 230.703374 -79.823056) (xy 230.693214 -79.822588) (xy 230.674443 -79.814804)
			(xy 230.660078 -79.80043) (xy 230.652306 -79.781655) (xy 230.651812 -79.771494) (xy 230.40848 -79.771494)
			(xy 230.407962 -79.781649) (xy 230.400193 -79.800415) (xy 230.385835 -79.81478) (xy 230.367073 -79.822557)
			(xy 230.356918 -79.823056) (xy 230.303578 -79.823056) (xy 230.293418 -79.822585) (xy 230.274647 -79.814802)
			(xy 230.260282 -79.800429) (xy 230.25251 -79.781654) (xy 230.252016 -79.771494) (xy 0.509016 -79.771494)
			(xy 0.509016 -80.183482) (xy 237.540292 -80.183482) (xy 237.540292 -79.319882) (xy 237.540782 -79.289914)
			(xy 237.548605 -79.230492) (xy 237.564118 -79.172599) (xy 237.587054 -79.117226) (xy 237.617021 -79.06532)
			(xy 237.653508 -79.01777) (xy 237.695888 -78.97539) (xy 237.743438 -78.938903) (xy 237.795344 -78.908936)
			(xy 237.850717 -78.886) (xy 237.90861 -78.870487) (xy 237.968032 -78.862664) (xy 238.027968 -78.862664)
			(xy 238.08739 -78.870487) (xy 238.145283 -78.886) (xy 238.200656 -78.908936) (xy 238.207117 -78.912666)
			(xy 334.407009 -78.912666) (xy 334.407009 -78.852734) (xy 334.414832 -78.793315) (xy 334.430343 -78.735425)
			(xy 334.453278 -78.680055) (xy 334.483244 -78.628153) (xy 334.519729 -78.580606) (xy 334.562107 -78.538227)
			(xy 334.609654 -78.501743) (xy 334.661557 -78.471777) (xy 334.716927 -78.448843) (xy 334.774817 -78.433331)
			(xy 334.834236 -78.425509) (xy 334.864202 -78.42504) (xy 335.727802 -78.42504) (xy 335.757773 -78.425434)
			(xy 335.817201 -78.433258) (xy 335.8751 -78.448773) (xy 335.930479 -78.471711) (xy 335.982389 -78.501682)
			(xy 336.029944 -78.538172) (xy 336.072329 -78.580557) (xy 336.108819 -78.628112) (xy 336.13879 -78.680023)
			(xy 336.161728 -78.735402) (xy 336.177242 -78.793301) (xy 336.185066 -78.852729) (xy 336.185066 -78.912664)
			(xy 338.40703 -78.912664) (xy 338.40703 -78.852736) (xy 338.414852 -78.79332) (xy 338.430363 -78.735433)
			(xy 338.453296 -78.680067) (xy 338.48326 -78.628167) (xy 338.519742 -78.580622) (xy 338.562118 -78.538246)
			(xy 338.609662 -78.501763) (xy 338.661561 -78.471799) (xy 338.716928 -78.448865) (xy 338.774814 -78.433353)
			(xy 338.83423 -78.42553) (xy 338.864194 -78.42504) (xy 339.727794 -78.42504) (xy 339.757766 -78.425412)
			(xy 339.817199 -78.433236) (xy 339.875101 -78.44875) (xy 339.930483 -78.47169) (xy 339.982397 -78.501662)
			(xy 340.029955 -78.538153) (xy 340.072343 -78.580541) (xy 340.108835 -78.628098) (xy 340.138808 -78.680011)
			(xy 340.161748 -78.735393) (xy 340.177263 -78.793296) (xy 340.185087 -78.852728) (xy 340.185087 -78.912672)
			(xy 340.177263 -78.972104) (xy 340.161748 -79.030007) (xy 340.138808 -79.085389) (xy 340.108835 -79.137302)
			(xy 340.072343 -79.184859) (xy 340.029955 -79.227247) (xy 339.982397 -79.263738) (xy 339.930483 -79.29371)
			(xy 339.875101 -79.31665) (xy 339.817199 -79.332164) (xy 339.757766 -79.339988) (xy 339.727794 -79.340456)
			(xy 338.864194 -79.340456) (xy 338.83423 -79.33987) (xy 338.774814 -79.332047) (xy 338.716928 -79.316535)
			(xy 338.661561 -79.293601) (xy 338.609662 -79.263637) (xy 338.562118 -79.227154) (xy 338.519742 -79.184778)
			(xy 338.48326 -79.137233) (xy 338.453296 -79.085333) (xy 338.430363 -79.029967) (xy 338.414852 -78.97208)
			(xy 338.40703 -78.912664) (xy 336.185066 -78.912664) (xy 336.185066 -78.912671) (xy 336.177242 -78.972099)
			(xy 336.161728 -79.029998) (xy 336.13879 -79.085377) (xy 336.108819 -79.137288) (xy 336.072329 -79.184843)
			(xy 336.029944 -79.227228) (xy 335.982389 -79.263718) (xy 335.930479 -79.293689) (xy 335.8751 -79.316627)
			(xy 335.817201 -79.332142) (xy 335.757773 -79.339966) (xy 335.727802 -79.340456) (xy 334.864202 -79.340456)
			(xy 334.834236 -79.339891) (xy 334.774817 -79.332069) (xy 334.716927 -79.316557) (xy 334.661557 -79.293623)
			(xy 334.609654 -79.263657) (xy 334.562107 -79.227173) (xy 334.519729 -79.184794) (xy 334.483244 -79.137247)
			(xy 334.453278 -79.085345) (xy 334.430343 -79.029975) (xy 334.414832 -78.972085) (xy 334.407009 -78.912666)
			(xy 238.207117 -78.912666) (xy 238.252562 -78.938903) (xy 238.300112 -78.97539) (xy 238.342492 -79.01777)
			(xy 238.378979 -79.06532) (xy 238.408946 -79.117226) (xy 238.431882 -79.172599) (xy 238.447395 -79.230492)
			(xy 238.455218 -79.289914) (xy 238.455708 -79.319882) (xy 238.455708 -80.183482) (xy 238.455218 -80.21345)
			(xy 238.447395 -80.272872) (xy 238.431882 -80.330765) (xy 238.408946 -80.386138) (xy 238.378979 -80.438044)
			(xy 238.342492 -80.485594) (xy 238.300112 -80.527974) (xy 238.252562 -80.564461) (xy 238.200656 -80.594428)
			(xy 238.145283 -80.617364) (xy 238.08739 -80.632877) (xy 238.027968 -80.6407) (xy 237.968032 -80.6407)
			(xy 237.90861 -80.632877) (xy 237.850717 -80.617364) (xy 237.795344 -80.594428) (xy 237.743438 -80.564461)
			(xy 237.695888 -80.527974) (xy 237.653508 -80.485594) (xy 237.617021 -80.438044) (xy 237.587054 -80.386138)
			(xy 237.564118 -80.330765) (xy 237.548605 -80.272872) (xy 237.540782 -80.21345) (xy 237.540292 -80.183482)
			(xy 0.509016 -80.183482) (xy 0.509016 -82.131916) (xy 0.5095 -82.185129) (xy 0.517108 -82.291282)
			(xy 0.532268 -82.396623) (xy 0.554903 -82.500614) (xy 0.584898 -82.602726) (xy 0.622099 -82.702438)
			(xy 0.666318 -82.799243) (xy 0.717328 -82.892647) (xy 0.774871 -82.982175) (xy 0.838652 -83.067371)
			(xy 0.908348 -83.147801) (xy 0.945642 -83.185762) (xy 2.78524 -85.025538) (xy 44.856389 -85.025538)
			(xy 44.856389 -84.896398) (xy 44.864339 -84.767503) (xy 44.880209 -84.639343) (xy 44.903938 -84.512402)
			(xy 44.935437 -84.387163) (xy 44.974586 -84.2641) (xy 45.021237 -84.143681) (xy 45.075212 -84.026362)
			(xy 45.136307 -83.912588) (xy 45.20429 -83.802791) (xy 45.278904 -83.697388) (xy 45.359865 -83.596778)
			(xy 45.446865 -83.501343) (xy 45.539576 -83.411444) (xy 45.637646 -83.327423) (xy 45.740701 -83.249599)
			(xy 45.848352 -83.178267) (xy 45.960191 -83.113697) (xy 46.075792 -83.056135) (xy 46.194717 -83.005798)
			(xy 46.316516 -82.962878) (xy 46.440726 -82.927537) (xy 46.566875 -82.89991) (xy 46.694487 -82.880101)
			(xy 46.823076 -82.868185) (xy 46.952154 -82.864209) (xy 47.081232 -82.868185) (xy 47.209821 -82.880101)
			(xy 47.337433 -82.89991) (xy 47.463582 -82.927537) (xy 47.587792 -82.962878) (xy 47.709591 -83.005798)
			(xy 47.828516 -83.056135) (xy 47.944117 -83.113697) (xy 48.055956 -83.178267) (xy 48.163607 -83.249599)
			(xy 48.266662 -83.327423) (xy 48.303507 -83.35899) (xy 116.623592 -83.35899) (xy 116.623592 -82.49539)
			(xy 116.624082 -82.465422) (xy 116.631905 -82.406) (xy 116.647418 -82.348107) (xy 116.670354 -82.292734)
			(xy 116.700321 -82.240828) (xy 116.736808 -82.193278) (xy 116.779188 -82.150898) (xy 116.826738 -82.114411)
			(xy 116.878644 -82.084444) (xy 116.934017 -82.061508) (xy 116.99191 -82.045995) (xy 117.051332 -82.038172)
			(xy 117.111268 -82.038172) (xy 117.17069 -82.045995) (xy 117.228583 -82.061508) (xy 117.283956 -82.084444)
			(xy 117.335862 -82.114411) (xy 117.383412 -82.150898) (xy 117.425792 -82.193278) (xy 117.462279 -82.240828)
			(xy 117.492246 -82.292734) (xy 117.515182 -82.348107) (xy 117.530695 -82.406) (xy 117.538518 -82.465422)
			(xy 117.539008 -82.49539) (xy 117.539008 -83.35899) (xy 117.538518 -83.388958) (xy 117.530695 -83.44838)
			(xy 117.515182 -83.506273) (xy 117.492246 -83.561646) (xy 117.462279 -83.613552) (xy 117.425792 -83.661102)
			(xy 117.383412 -83.703482) (xy 117.335862 -83.739969) (xy 117.283956 -83.769936) (xy 117.228583 -83.792872)
			(xy 117.17069 -83.808385) (xy 117.111268 -83.816208) (xy 117.051332 -83.816208) (xy 116.99191 -83.808385)
			(xy 116.934017 -83.792872) (xy 116.878644 -83.769936) (xy 116.826738 -83.739969) (xy 116.779188 -83.703482)
			(xy 116.736808 -83.661102) (xy 116.700321 -83.613552) (xy 116.670354 -83.561646) (xy 116.647418 -83.506273)
			(xy 116.631905 -83.44838) (xy 116.624082 -83.388958) (xy 116.623592 -83.35899) (xy 48.303507 -83.35899)
			(xy 48.364732 -83.411444) (xy 48.457443 -83.501343) (xy 48.544443 -83.596778) (xy 48.625404 -83.697388)
			(xy 48.700018 -83.802791) (xy 48.710988 -83.820508) (xy 232.214928 -83.820508) (xy 232.214928 -83.617308)
			(xy 232.215342 -83.603132) (xy 232.221577 -83.575474) (xy 232.233723 -83.549855) (xy 232.251189 -83.527522)
			(xy 232.261918 -83.518248) (xy 232.26903 -83.511136) (xy 232.278278 -83.500485) (xy 232.3005 -83.483124)
			(xy 232.325979 -83.471037) (xy 232.353483 -83.464808) (xy 232.367582 -83.4644) (xy 232.571798 -83.4644)
			(xy 232.583707 -83.464691) (xy 232.607102 -83.46917) (xy 232.61828 -83.47329) (xy 232.619804 -83.473798)
			(xy 232.62976 -83.47678) (xy 232.650475 -83.475531) (xy 232.668993 -83.466164) (xy 232.682274 -83.450217)
			(xy 232.688135 -83.43031) (xy 232.687368 -83.41995) (xy 232.68595 -83.406852) (xy 232.684425 -83.380547)
			(xy 232.68432 -83.367372) (xy 232.68432 -83.194906) (xy 232.683807 -83.184901) (xy 232.676154 -83.166413)
			(xy 232.662008 -83.152261) (xy 232.643525 -83.144598) (xy 232.63352 -83.144106) (xy 232.628186 -83.144106)
			(xy 232.622852 -83.145376) (xy 232.616381 -83.146596) (xy 232.603275 -83.147869) (xy 232.59669 -83.147916)
			(xy 232.596436 -83.147916) (xy 232.34269 -83.147916) (xy 232.325959 -83.147427) (xy 232.293634 -83.138773)
			(xy 232.264646 -83.122055) (xy 232.240966 -83.098412) (xy 232.224203 -83.06945) (xy 232.215499 -83.037139)
			(xy 232.214928 -83.020408) (xy 232.214928 -82.817208) (xy 232.215442 -82.800511) (xy 232.224074 -82.768253)
			(xy 232.240753 -82.739324) (xy 232.264344 -82.715691) (xy 232.293244 -82.698961) (xy 232.325486 -82.690272)
			(xy 232.342182 -82.6897) (xy 232.59669 -82.6897) (xy 232.603275 -82.689733) (xy 232.616383 -82.691008)
			(xy 232.622852 -82.69224) (xy 232.628186 -82.69351) (xy 232.63352 -82.69351) (xy 232.643528 -82.693029)
			(xy 232.662018 -82.685364) (xy 232.67617 -82.67121) (xy 232.683831 -82.652718) (xy 232.68432 -82.64271)
			(xy 232.68432 -82.503518) (xy 232.684828 -82.479896) (xy 232.685336 -82.468974) (xy 232.677716 -82.449162)
			(xy 232.608882 -82.380074) (xy 232.588816 -82.372708) (xy 232.579418 -82.373216) (xy 232.57637 -82.373216)
			(xy 232.367582 -82.373216) (xy 232.35348 -82.372825) (xy 232.325968 -82.366606) (xy 232.300484 -82.354519)
			(xy 232.278261 -82.337148) (xy 232.26903 -82.32648) (xy 232.261918 -82.319368) (xy 232.251161 -82.31012)
			(xy 232.23367 -82.287791) (xy 232.221519 -82.262163) (xy 232.215301 -82.23449) (xy 232.214928 -82.220308)
			(xy 232.214928 -82.017108) (xy 232.215342 -82.002932) (xy 232.221577 -81.975274) (xy 232.233723 -81.949655)
			(xy 232.251189 -81.927322) (xy 232.261918 -81.918048) (xy 232.26903 -81.910936) (xy 232.278278 -81.900285)
			(xy 232.3005 -81.882924) (xy 232.325979 -81.870837) (xy 232.353483 -81.864608) (xy 232.367582 -81.8642)
			(xy 232.571798 -81.8642) (xy 232.5859 -81.864599) (xy 232.613412 -81.870814) (xy 232.638896 -81.882899)
			(xy 232.661119 -81.900268) (xy 232.67035 -81.910936) (xy 232.677462 -81.918048) (xy 232.688195 -81.927322)
			(xy 232.705685 -81.949644) (xy 232.717841 -81.975264) (xy 232.724071 -82.002929) (xy 232.724452 -82.017108)
			(xy 232.724452 -82.042) (xy 232.724889 -82.051227) (xy 232.731425 -82.068484) (xy 232.743651 -82.082308)
			(xy 232.75163 -82.086958) (xy 232.843324 -82.135472) (xy 232.871772 -82.133694) (xy 232.883202 -82.12582)
			(xy 232.906142 -82.110617) (xy 232.954938 -82.085166) (xy 233.00643 -82.06574) (xy 233.059877 -82.052617)
			(xy 233.114511 -82.045985) (xy 233.142028 -82.045556) (xy 233.174228 -82.046112) (xy 233.237991 -82.055143)
			(xy 233.299859 -82.073022) (xy 233.358611 -82.099395) (xy 233.413086 -82.133744) (xy 233.462208 -82.175389)
			(xy 233.505009 -82.223508) (xy 233.523282 -82.250026) (xy 233.529746 -82.258849) (xy 233.548315 -82.270373)
			(xy 233.569989 -82.27317) (xy 233.590875 -82.266737) (xy 233.607219 -82.25223) (xy 233.616085 -82.232255)
			(xy 233.6165 -82.221324) (xy 233.6165 -82.0166) (xy 233.616898 -82.002498) (xy 233.623113 -81.974986)
			(xy 233.635198 -81.949501) (xy 233.652568 -81.927279) (xy 233.663236 -81.918048) (xy 233.670348 -81.910936)
			(xy 233.679587 -81.900276) (xy 233.701812 -81.882917) (xy 233.727294 -81.870832) (xy 233.7548 -81.864606)
			(xy 233.7689 -81.8642) (xy 233.973116 -81.8642) (xy 233.987219 -81.864587) (xy 234.014731 -81.870806)
			(xy 234.040216 -81.882894) (xy 234.062437 -81.900267) (xy 234.071668 -81.910936) (xy 234.07878 -81.918048)
			(xy 234.089424 -81.927304) (xy 234.106791 -81.949522) (xy 234.118881 -81.974998) (xy 234.12511 -82.002501)
			(xy 234.125516 -82.0166) (xy 234.125516 -82.220816) (xy 234.125123 -82.234918) (xy 234.118905 -82.26243)
			(xy 234.106818 -82.287914) (xy 234.089448 -82.310137) (xy 234.07878 -82.319368) (xy 234.071668 -82.32648)
			(xy 234.062403 -82.337116) (xy 234.062333 -82.337171) (xy 238.132537 -82.337171) (xy 238.132537 -82.277229)
			(xy 238.140362 -82.217799) (xy 238.155876 -82.159898) (xy 238.178816 -82.104519) (xy 238.208788 -82.052607)
			(xy 238.24528 -82.005052) (xy 238.287667 -81.962667) (xy 238.335224 -81.926177) (xy 238.387137 -81.896207)
			(xy 238.442517 -81.87327) (xy 238.500418 -81.857758) (xy 238.559849 -81.849936) (xy 238.58982 -81.849468)
			(xy 239.45342 -81.849468) (xy 239.483385 -81.850007) (xy 239.542803 -81.857832) (xy 239.600691 -81.873345)
			(xy 239.656058 -81.896282) (xy 239.707959 -81.926248) (xy 239.755504 -81.962733) (xy 239.769238 -81.976468)
			(xy 273.798284 -81.976468) (xy 273.798284 -81.112868) (xy 273.798774 -81.0829) (xy 273.806597 -81.023478)
			(xy 273.82211 -80.965585) (xy 273.845046 -80.910212) (xy 273.875013 -80.858306) (xy 273.9115 -80.810756)
			(xy 273.95388 -80.768376) (xy 274.00143 -80.731889) (xy 274.053336 -80.701922) (xy 274.108709 -80.678986)
			(xy 274.166602 -80.663473) (xy 274.226024 -80.65565) (xy 274.28596 -80.65565) (xy 274.345382 -80.663473)
			(xy 274.403275 -80.678986) (xy 274.458648 -80.701922) (xy 274.510554 -80.731889) (xy 274.558104 -80.768376)
			(xy 274.600484 -80.810756) (xy 274.636971 -80.858306) (xy 274.666938 -80.910212) (xy 274.689874 -80.965585)
			(xy 274.705387 -81.023478) (xy 274.71321 -81.0829) (xy 274.7137 -81.112868) (xy 274.7137 -81.976468)
			(xy 274.71321 -82.006436) (xy 274.705387 -82.065858) (xy 274.689874 -82.123751) (xy 274.666938 -82.179124)
			(xy 274.636971 -82.23103) (xy 274.600484 -82.27858) (xy 274.558104 -82.32096) (xy 274.510554 -82.357447)
			(xy 274.458648 -82.387414) (xy 274.403275 -82.41035) (xy 274.345382 -82.425863) (xy 274.28596 -82.433686)
			(xy 274.226024 -82.433686) (xy 274.166602 -82.425863) (xy 274.108709 -82.41035) (xy 274.053336 -82.387414)
			(xy 274.00143 -82.357447) (xy 273.95388 -82.32096) (xy 273.9115 -82.27858) (xy 273.875013 -82.23103)
			(xy 273.845046 -82.179124) (xy 273.82211 -82.123751) (xy 273.806597 -82.065858) (xy 273.798774 -82.006436)
			(xy 273.798284 -81.976468) (xy 239.769238 -81.976468) (xy 239.79788 -82.005111) (xy 239.834363 -82.052658)
			(xy 239.864327 -82.10456) (xy 239.887261 -82.159928) (xy 239.902772 -82.217817) (xy 239.910594 -82.277235)
			(xy 239.910594 -82.337165) (xy 239.902772 -82.396583) (xy 239.887261 -82.454472) (xy 239.864327 -82.50984)
			(xy 239.834363 -82.561742) (xy 239.79788 -82.609289) (xy 239.755504 -82.651667) (xy 239.707959 -82.688152)
			(xy 239.656058 -82.718118) (xy 239.600691 -82.741055) (xy 239.542803 -82.756568) (xy 239.483385 -82.764393)
			(xy 239.45342 -82.764884) (xy 238.58982 -82.764884) (xy 238.559849 -82.764464) (xy 238.500418 -82.756642)
			(xy 238.442517 -82.74113) (xy 238.387137 -82.718193) (xy 238.335224 -82.688223) (xy 238.287667 -82.651733)
			(xy 238.24528 -82.609348) (xy 238.208788 -82.561793) (xy 238.178816 -82.509881) (xy 238.155876 -82.454502)
			(xy 238.140362 -82.396601) (xy 238.132537 -82.337171) (xy 234.062333 -82.337171) (xy 234.040189 -82.354484)
			(xy 234.014715 -82.366576) (xy 233.987214 -82.372808) (xy 233.973116 -82.373216) (xy 233.7689 -82.373216)
			(xy 233.754784 -82.372782) (xy 233.727256 -82.366512) (xy 233.70177 -82.354363) (xy 233.679563 -82.336927)
			(xy 233.670348 -82.326226) (xy 233.66349 -82.319368) (xy 233.661712 -82.317844) (xy 233.653096 -82.311127)
			(xy 233.632059 -82.30528) (xy 233.610489 -82.308675) (xy 233.592265 -82.320702) (xy 233.58066 -82.339198)
			(xy 233.577762 -82.360839) (xy 233.580432 -82.371438) (xy 233.589487 -82.403703) (xy 233.599184 -82.470011)
			(xy 233.599736 -82.503518) (xy 233.599736 -82.59191) (xy 233.600283 -82.603118) (xy 233.609775 -82.623419)
			(xy 233.618024 -82.631026) (xy 233.678222 -82.681064) (xy 233.687312 -82.68779) (xy 233.709196 -82.693342)
			(xy 233.720386 -82.691732) (xy 233.726177 -82.690745) (xy 233.73788 -82.689728) (xy 233.743754 -82.6897)
			(xy 233.744262 -82.6897) (xy 233.998008 -82.6897) (xy 234.014724 -82.690231) (xy 234.047016 -82.698886)
			(xy 234.075968 -82.715603) (xy 234.099606 -82.739245) (xy 234.116321 -82.768199) (xy 234.124971 -82.800492)
			(xy 234.125516 -82.817208) (xy 234.125516 -83.020408) (xy 234.12497 -83.037123) (xy 234.116316 -83.069412)
			(xy 234.099601 -83.098363) (xy 234.075963 -83.122001) (xy 234.047012 -83.138716) (xy 234.014723 -83.14737)
			(xy 233.998008 -83.147916) (xy 233.743754 -83.147916) (xy 233.737881 -83.14787) (xy 233.726179 -83.146855)
			(xy 233.720386 -83.145884) (xy 233.709195 -83.144307) (xy 233.687314 -83.14984) (xy 233.678222 -83.156552)
			(xy 233.618024 -83.20659) (xy 233.60981 -83.214222) (xy 233.600323 -83.234509) (xy 233.599736 -83.245706)
			(xy 233.599736 -83.371944) (xy 233.600274 -83.384018) (xy 233.611006 -83.405633) (xy 233.62031 -83.413346)
			(xy 233.68635 -83.462368) (xy 233.696385 -83.468892) (xy 233.71995 -83.472883) (xy 233.731562 -83.469988)
			(xy 233.740797 -83.467342) (xy 233.759802 -83.464536) (xy 233.769408 -83.4644) (xy 233.973116 -83.4644)
			(xy 233.987219 -83.464787) (xy 234.014731 -83.471006) (xy 234.040216 -83.483094) (xy 234.062437 -83.500467)
			(xy 234.071668 -83.511136) (xy 234.07878 -83.518248) (xy 234.089424 -83.527504) (xy 234.106791 -83.549722)
			(xy 234.118881 -83.575198) (xy 234.12511 -83.602701) (xy 234.125516 -83.6168) (xy 234.125516 -83.821016)
			(xy 234.125123 -83.835118) (xy 234.118905 -83.86263) (xy 234.106818 -83.888114) (xy 234.089448 -83.910337)
			(xy 234.07878 -83.919568) (xy 234.071668 -83.92668) (xy 234.062403 -83.937316) (xy 234.040189 -83.954684)
			(xy 234.014715 -83.966776) (xy 233.987214 -83.973008) (xy 233.973116 -83.973416) (xy 233.7689 -83.973416)
			(xy 233.754798 -83.973013) (xy 233.727287 -83.966798) (xy 233.701803 -83.954714) (xy 233.67958 -83.937347)
			(xy 233.670348 -83.92668) (xy 233.663236 -83.919568) (xy 233.652584 -83.910321) (xy 233.635223 -83.888098)
			(xy 233.623136 -83.862619) (xy 233.616907 -83.835115) (xy 233.6165 -83.821016) (xy 233.6165 -83.78444)
			(xy 233.616051 -83.774663) (xy 233.608774 -83.756515) (xy 233.595254 -83.742389) (xy 233.586528 -83.737958)
			(xy 233.501692 -83.700112) (xy 233.492592 -83.696524) (xy 233.473067 -83.695734) (xy 233.45467 -83.702323)
			(xy 233.447082 -83.708494) (xy 233.426046 -83.726727) (xy 233.380353 -83.758529) (xy 233.331144 -83.784559)
			(xy 233.279143 -83.804436) (xy 233.225118 -83.817865) (xy 233.169863 -83.82465) (xy 233.142028 -83.82508)
			(xy 233.111271 -83.824592) (xy 233.050318 -83.816299) (xy 232.991023 -83.799926) (xy 232.934451 -83.775767)
			(xy 232.881619 -83.744257) (xy 232.833479 -83.705962) (xy 232.811828 -83.68411) (xy 232.804358 -83.677084)
			(xy 232.785496 -83.669085) (xy 232.775252 -83.668616) (xy 232.765239 -83.669049) (xy 232.746743 -83.676728)
			(xy 232.732592 -83.690897) (xy 232.724937 -83.709403) (xy 232.724452 -83.719416) (xy 232.724452 -83.820508)
			(xy 232.724056 -83.834685) (xy 232.717817 -83.862345) (xy 232.705665 -83.887964) (xy 232.688193 -83.910296)
			(xy 232.677462 -83.919568) (xy 232.67035 -83.92668) (xy 232.661095 -83.937325) (xy 232.638877 -83.954691)
			(xy 232.6134 -83.966781) (xy 232.585897 -83.97301) (xy 232.571798 -83.973416) (xy 232.367582 -83.973416)
			(xy 232.35348 -83.973025) (xy 232.325968 -83.966806) (xy 232.300484 -83.954719) (xy 232.278261 -83.937348)
			(xy 232.26903 -83.92668) (xy 232.261918 -83.919568) (xy 232.251161 -83.91032) (xy 232.23367 -83.887991)
			(xy 232.221519 -83.862363) (xy 232.215301 -83.83469) (xy 232.214928 -83.820508) (xy 48.710988 -83.820508)
			(xy 48.768001 -83.912588) (xy 48.829096 -84.026362) (xy 48.883071 -84.143681) (xy 48.929722 -84.2641)
			(xy 48.968871 -84.387163) (xy 49.00037 -84.512402) (xy 49.024099 -84.639343) (xy 49.039969 -84.767503)
			(xy 49.047919 -84.896398) (xy 49.048416 -84.960968) (xy 49.047919 -85.025538) (xy 49.039969 -85.154433)
			(xy 49.024099 -85.282593) (xy 49.009819 -85.358986) (xy 117.385592 -85.358986) (xy 117.385592 -84.495386)
			(xy 117.386082 -84.465418) (xy 117.393905 -84.405996) (xy 117.409418 -84.348103) (xy 117.432354 -84.29273)
			(xy 117.462321 -84.240824) (xy 117.498808 -84.193274) (xy 117.541188 -84.150894) (xy 117.588738 -84.114407)
			(xy 117.640644 -84.08444) (xy 117.696017 -84.061504) (xy 117.75391 -84.045991) (xy 117.813332 -84.038168)
			(xy 117.873268 -84.038168) (xy 117.93269 -84.045991) (xy 117.990583 -84.061504) (xy 118.045956 -84.08444)
			(xy 118.097862 -84.114407) (xy 118.145412 -84.150894) (xy 118.187792 -84.193274) (xy 118.224279 -84.240824)
			(xy 118.254246 -84.29273) (xy 118.277182 -84.348103) (xy 118.292695 -84.405996) (xy 118.300518 -84.465418)
			(xy 118.301008 -84.495386) (xy 118.301008 -85.358986) (xy 118.300518 -85.388954) (xy 118.292695 -85.448376)
			(xy 118.289959 -85.458587) (xy 232.264389 -85.458587) (xy 232.264389 -85.398613) (xy 232.272218 -85.339151)
			(xy 232.28774 -85.28122) (xy 232.310692 -85.225811) (xy 232.34068 -85.173871) (xy 232.377191 -85.126291)
			(xy 232.4196 -85.083883) (xy 232.467181 -85.047373) (xy 232.519122 -85.017387) (xy 232.574531 -84.994437)
			(xy 232.632463 -84.978915) (xy 232.691925 -84.971088) (xy 232.721912 -84.97062) (xy 233.585512 -84.97062)
			(xy 233.615495 -84.971147) (xy 233.674947 -84.978975) (xy 233.732868 -84.994497) (xy 233.788268 -85.017445)
			(xy 233.840199 -85.047429) (xy 233.887772 -85.083934) (xy 233.930174 -85.126337) (xy 233.966678 -85.173911)
			(xy 233.99666 -85.225842) (xy 234.019607 -85.281243) (xy 234.035127 -85.339165) (xy 234.042954 -85.398617)
			(xy 234.042954 -85.458583) (xy 234.035127 -85.518035) (xy 234.019607 -85.575957) (xy 233.99666 -85.631358)
			(xy 233.984097 -85.653118) (xy 238.070136 -85.653118) (xy 238.070136 -85.449918) (xy 238.070486 -85.435762)
			(xy 238.076708 -85.408144) (xy 238.088872 -85.38258) (xy 238.106377 -85.360331) (xy 238.117126 -85.351112)
			(xy 238.124492 -85.343746) (xy 238.133706 -85.332998) (xy 238.15597 -85.315519) (xy 238.181534 -85.303368)
			(xy 238.209145 -85.297139) (xy 238.223298 -85.296756) (xy 238.426498 -85.296756) (xy 238.441992 -85.297772)
			(xy 238.453168 -85.299296) (xy 238.474758 -85.292438) (xy 238.548164 -85.224112) (xy 238.556546 -85.203538)
			(xy 238.556038 -85.192362) (xy 238.556038 -85.191854) (xy 238.555276 -85.169502) (xy 238.555276 -85.082126)
			(xy 238.554843 -85.072057) (xy 238.547129 -85.053459) (xy 238.54029 -85.046058) (xy 238.489236 -84.995258)
			(xy 238.481821 -84.988584) (xy 238.463387 -84.981005) (xy 238.453422 -84.980526) (xy 238.452914 -84.980526)
			(xy 238.451898 -84.98078) (xy 238.197898 -84.98078) (xy 238.181151 -84.980217) (xy 238.148799 -84.971549)
			(xy 238.119792 -84.954803) (xy 238.096107 -84.931121) (xy 238.079357 -84.902116) (xy 238.070685 -84.869765)
			(xy 238.070136 -84.853018) (xy 238.070136 -84.649818) (xy 238.070651 -84.633064) (xy 238.07932 -84.600698)
			(xy 238.096071 -84.571678) (xy 238.119762 -84.547983) (xy 238.148779 -84.531227) (xy 238.181144 -84.522554)
			(xy 238.197898 -84.522056) (xy 238.451898 -84.522056) (xy 238.452914 -84.52231) (xy 238.453422 -84.52231)
			(xy 238.463393 -84.521869) (xy 238.481829 -84.51427) (xy 238.489236 -84.507578) (xy 238.54029 -84.456778)
			(xy 238.547131 -84.449378) (xy 238.554851 -84.430779) (xy 238.555276 -84.42071) (xy 238.555276 -84.305902)
			(xy 238.555411 -84.290166) (xy 238.557571 -84.25877) (xy 238.559594 -84.243164) (xy 238.560464 -84.2339)
			(xy 238.556235 -84.215793) (xy 238.545822 -84.200389) (xy 238.530596 -84.189717) (xy 238.512564 -84.185184)
			(xy 238.494101 -84.187387) (xy 238.48568 -84.191348) (xy 238.471853 -84.198192) (xy 238.44192 -84.205634)
			(xy 238.426498 -84.20608) (xy 238.223298 -84.20608) (xy 238.209142 -84.205738) (xy 238.181524 -84.199512)
			(xy 238.15596 -84.187346) (xy 238.133711 -84.169839) (xy 238.124492 -84.15909) (xy 238.117126 -84.151724)
			(xy 238.106381 -84.142506) (xy 238.088903 -84.120243) (xy 238.076751 -84.09468) (xy 238.07052 -84.06707)
			(xy 238.070136 -84.052918) (xy 238.070136 -83.849718) (xy 238.070486 -83.835562) (xy 238.076708 -83.807944)
			(xy 238.088872 -83.78238) (xy 238.106377 -83.760131) (xy 238.117126 -83.750912) (xy 238.124492 -83.743546)
			(xy 238.133706 -83.732798) (xy 238.15597 -83.715319) (xy 238.181534 -83.703168) (xy 238.209145 -83.696939)
			(xy 238.223298 -83.696556) (xy 238.426498 -83.696556) (xy 238.440655 -83.696888) (xy 238.468274 -83.703115)
			(xy 238.493839 -83.715284) (xy 238.516087 -83.732795) (xy 238.525304 -83.743546) (xy 238.53267 -83.750912)
			(xy 238.543383 -83.760164) (xy 238.560866 -83.782415) (xy 238.573027 -83.807968) (xy 238.579269 -83.835569)
			(xy 238.57966 -83.849718) (xy 238.57966 -83.855814) (xy 238.580173 -83.865151) (xy 238.586938 -83.882563)
			(xy 238.599465 -83.896419) (xy 238.6076 -83.901026) (xy 238.701326 -83.948524) (xy 238.729774 -83.946238)
			(xy 238.741458 -83.937602) (xy 238.765122 -83.920628) (xy 238.81596 -83.892215) (xy 238.869995 -83.870491)
			(xy 238.926353 -83.855807) (xy 238.984119 -83.848401) (xy 239.013238 -83.84794) (xy 239.044467 -83.848458)
			(xy 239.106345 -83.856961) (xy 239.166494 -83.873791) (xy 239.223799 -83.898637) (xy 239.277198 -83.931036)
			(xy 239.301782 -83.950302) (xy 239.313212 -83.9597) (xy 239.342168 -83.963256) (xy 239.43818 -83.917282)
			(xy 239.446653 -83.912839) (xy 239.459737 -83.898904) (xy 239.466749 -83.881121) (xy 239.467136 -83.871562)
			(xy 239.467136 -83.849718) (xy 239.467486 -83.835562) (xy 239.473708 -83.807944) (xy 239.485872 -83.78238)
			(xy 239.503377 -83.760131) (xy 239.514126 -83.750912) (xy 239.521492 -83.743546) (xy 239.530706 -83.732798)
			(xy 239.55297 -83.715319) (xy 239.578534 -83.703168) (xy 239.606145 -83.696939) (xy 239.620298 -83.696556)
			(xy 239.823498 -83.696556) (xy 239.837655 -83.696888) (xy 239.865274 -83.703115) (xy 239.890839 -83.715284)
			(xy 239.913087 -83.732795) (xy 239.922304 -83.743546) (xy 239.92967 -83.750912) (xy 239.940383 -83.760164)
			(xy 239.957866 -83.782415) (xy 239.970027 -83.807968) (xy 239.976269 -83.835569) (xy 239.97666 -83.849718)
			(xy 239.97666 -84.052918) (xy 239.976269 -84.067071) (xy 239.97006 -84.094688) (xy 239.957909 -84.120252)
			(xy 239.940414 -84.142504) (xy 239.92967 -84.151724) (xy 239.922304 -84.15909) (xy 239.913048 -84.1698)
			(xy 239.890797 -84.187282) (xy 239.865246 -84.199443) (xy 239.837646 -84.205688) (xy 239.823498 -84.20608)
			(xy 239.620298 -84.20608) (xy 239.613643 -84.206001) (xy 239.600407 -84.204597) (xy 239.593882 -84.203286)
			(xy 239.582619 -84.201478) (xy 239.560458 -84.206765) (xy 239.55121 -84.213446) (xy 239.518136 -84.24037)
			(xy 273.951192 -84.24037) (xy 273.951192 -83.37677) (xy 273.951682 -83.346786) (xy 273.95951 -83.28733)
			(xy 273.975031 -83.229405) (xy 273.99798 -83.174001) (xy 274.027964 -83.122067) (xy 274.06447 -83.074491)
			(xy 274.106875 -83.032086) (xy 274.154451 -82.99558) (xy 274.206385 -82.965596) (xy 274.261789 -82.942647)
			(xy 274.319714 -82.927126) (xy 274.37917 -82.919298) (xy 274.439138 -82.919298) (xy 274.498594 -82.927126)
			(xy 274.556519 -82.942647) (xy 274.611923 -82.965596) (xy 274.663857 -82.99558) (xy 274.711433 -83.032086)
			(xy 274.753838 -83.074491) (xy 274.790344 -83.122067) (xy 274.820328 -83.174001) (xy 274.843277 -83.229405)
			(xy 274.858798 -83.28733) (xy 274.866626 -83.346786) (xy 274.867116 -83.37677) (xy 274.867116 -84.144612)
			(xy 345.879928 -84.144612) (xy 345.879928 -83.281012) (xy 345.880418 -83.251028) (xy 345.888246 -83.191572)
			(xy 345.903767 -83.133647) (xy 345.926716 -83.078243) (xy 345.9567 -83.026309) (xy 345.993206 -82.978733)
			(xy 346.035611 -82.936328) (xy 346.083187 -82.899822) (xy 346.135121 -82.869838) (xy 346.190525 -82.846889)
			(xy 346.24845 -82.831368) (xy 346.307906 -82.82354) (xy 346.367874 -82.82354) (xy 346.42733 -82.831368)
			(xy 346.485255 -82.846889) (xy 346.540659 -82.869838) (xy 346.592593 -82.899822) (xy 346.640169 -82.936328)
			(xy 346.682574 -82.978733) (xy 346.71908 -83.026309) (xy 346.749064 -83.078243) (xy 346.772013 -83.133647)
			(xy 346.787534 -83.191572) (xy 346.795362 -83.251028) (xy 346.795852 -83.281012) (xy 346.795852 -84.144612)
			(xy 346.795362 -84.174596) (xy 346.787534 -84.234052) (xy 346.772013 -84.291977) (xy 346.749064 -84.347381)
			(xy 346.71908 -84.399315) (xy 346.682574 -84.446891) (xy 346.640169 -84.489296) (xy 346.592593 -84.525802)
			(xy 346.540659 -84.555786) (xy 346.485255 -84.578735) (xy 346.42733 -84.594256) (xy 346.367874 -84.602084)
			(xy 346.307906 -84.602084) (xy 346.24845 -84.594256) (xy 346.190525 -84.578735) (xy 346.135121 -84.555786)
			(xy 346.083187 -84.525802) (xy 346.035611 -84.489296) (xy 345.993206 -84.446891) (xy 345.9567 -84.399315)
			(xy 345.926716 -84.347381) (xy 345.903767 -84.291977) (xy 345.888246 -84.234052) (xy 345.880418 -84.174596)
			(xy 345.879928 -84.144612) (xy 274.867116 -84.144612) (xy 274.867116 -84.24037) (xy 274.866626 -84.270354)
			(xy 274.858798 -84.32981) (xy 274.843277 -84.387735) (xy 274.820328 -84.443139) (xy 274.790344 -84.495073)
			(xy 274.753838 -84.542649) (xy 274.711433 -84.585054) (xy 274.663857 -84.62156) (xy 274.611923 -84.651544)
			(xy 274.556519 -84.674493) (xy 274.498594 -84.690014) (xy 274.439138 -84.697842) (xy 274.37917 -84.697842)
			(xy 274.319714 -84.690014) (xy 274.261789 -84.674493) (xy 274.206385 -84.651544) (xy 274.154451 -84.62156)
			(xy 274.106875 -84.585054) (xy 274.06447 -84.542649) (xy 274.027964 -84.495073) (xy 273.99798 -84.443139)
			(xy 273.975031 -84.387735) (xy 273.95951 -84.32981) (xy 273.951682 -84.270354) (xy 273.951192 -84.24037)
			(xy 239.518136 -84.24037) (xy 239.489742 -84.263484) (xy 239.481325 -84.27109) (xy 239.471556 -84.291527)
			(xy 239.470946 -84.302854) (xy 239.470946 -84.303108) (xy 239.4712 -84.305902) (xy 239.4712 -84.421472)
			(xy 239.471738 -84.432168) (xy 239.480412 -84.451724) (xy 239.487964 -84.459318) (xy 239.54359 -84.509864)
			(xy 239.551786 -84.516586) (xy 239.571864 -84.523291) (xy 239.582452 -84.522818) (xy 239.594898 -84.522056)
			(xy 239.848898 -84.522056) (xy 239.865654 -84.522538) (xy 239.898024 -84.531212) (xy 239.927046 -84.547969)
			(xy 239.950741 -84.571667) (xy 239.967495 -84.600691) (xy 239.976165 -84.633062) (xy 239.97666 -84.649818)
			(xy 239.97666 -84.853018) (xy 239.976131 -84.869767) (xy 239.967457 -84.902123) (xy 239.950705 -84.931132)
			(xy 239.927016 -84.954818) (xy 239.898005 -84.971565) (xy 239.865647 -84.980234) (xy 239.848898 -84.98078)
			(xy 239.594898 -84.98078) (xy 239.582452 -84.980018) (xy 239.571869 -84.979594) (xy 239.551796 -84.986277)
			(xy 239.54359 -84.992972) (xy 239.487964 -85.043518) (xy 239.480298 -85.051031) (xy 239.471616 -85.070639)
			(xy 239.4712 -85.081364) (xy 239.4712 -85.169502) (xy 239.470438 -85.194902) (xy 239.469676 -85.20684)
			(xy 239.479074 -85.228684) (xy 239.558576 -85.296502) (xy 239.58169 -85.302344) (xy 239.59312 -85.299804)
			(xy 239.593374 -85.299804) (xy 239.600019 -85.298413) (xy 239.61351 -85.296883) (xy 239.620298 -85.296756)
			(xy 239.823498 -85.296756) (xy 239.837655 -85.297088) (xy 239.865274 -85.303315) (xy 239.890839 -85.315484)
			(xy 239.913087 -85.332995) (xy 239.922304 -85.343746) (xy 239.92967 -85.351112) (xy 239.940383 -85.360364)
			(xy 239.957866 -85.382615) (xy 239.970027 -85.408168) (xy 239.976269 -85.435769) (xy 239.97666 -85.449918)
			(xy 239.97666 -85.653118) (xy 239.976269 -85.667271) (xy 239.97006 -85.694888) (xy 239.957909 -85.720452)
			(xy 239.940414 -85.742704) (xy 239.92967 -85.751924) (xy 239.922304 -85.75929) (xy 239.913048 -85.77)
			(xy 239.890797 -85.787482) (xy 239.865246 -85.799643) (xy 239.837646 -85.805888) (xy 239.823498 -85.80628)
			(xy 239.620298 -85.80628) (xy 239.606142 -85.805938) (xy 239.578524 -85.799712) (xy 239.55296 -85.787546)
			(xy 239.530711 -85.770039) (xy 239.521492 -85.75929) (xy 239.514126 -85.751924) (xy 239.503381 -85.742706)
			(xy 239.485903 -85.720443) (xy 239.473751 -85.69488) (xy 239.46752 -85.66727) (xy 239.467136 -85.653118)
			(xy 239.467136 -85.603842) (xy 239.466682 -85.594302) (xy 239.459625 -85.576569) (xy 239.44661 -85.562611)
			(xy 239.43818 -85.558122) (xy 239.342168 -85.512148) (xy 239.313212 -85.515704) (xy 239.301782 -85.525102)
			(xy 239.277211 -85.544385) (xy 239.223813 -85.57679) (xy 239.166505 -85.601633) (xy 239.106351 -85.618453)
			(xy 239.044469 -85.626938) (xy 239.013238 -85.627464) (xy 238.984124 -85.626966) (xy 238.926373 -85.619515)
			(xy 238.87003 -85.604815) (xy 238.815999 -85.583103) (xy 238.765151 -85.554729) (xy 238.741458 -85.537802)
			(xy 238.729774 -85.529166) (xy 238.701326 -85.52688) (xy 238.6076 -85.574378) (xy 238.599395 -85.578913)
			(xy 238.586773 -85.592752) (xy 238.58002 -85.610224) (xy 238.57966 -85.61959) (xy 238.57966 -85.653118)
			(xy 238.579269 -85.667271) (xy 238.57306 -85.694888) (xy 238.560909 -85.720452) (xy 238.543414 -85.742704)
			(xy 238.53267 -85.751924) (xy 238.525304 -85.75929) (xy 238.516048 -85.77) (xy 238.493797 -85.787482)
			(xy 238.468246 -85.799643) (xy 238.440646 -85.805888) (xy 238.426498 -85.80628) (xy 238.223298 -85.80628)
			(xy 238.209142 -85.805938) (xy 238.181524 -85.799712) (xy 238.15596 -85.787546) (xy 238.133711 -85.770039)
			(xy 238.124492 -85.75929) (xy 238.117126 -85.751924) (xy 238.106381 -85.742706) (xy 238.088903 -85.720443)
			(xy 238.076751 -85.69488) (xy 238.07052 -85.66727) (xy 238.070136 -85.653118) (xy 233.984097 -85.653118)
			(xy 233.966678 -85.683289) (xy 233.930174 -85.730863) (xy 233.887772 -85.773266) (xy 233.840199 -85.809771)
			(xy 233.788268 -85.839755) (xy 233.732868 -85.862703) (xy 233.674947 -85.878225) (xy 233.615495 -85.886053)
			(xy 233.585512 -85.886544) (xy 232.721912 -85.886544) (xy 232.691925 -85.886112) (xy 232.632463 -85.878285)
			(xy 232.574531 -85.862763) (xy 232.519122 -85.839813) (xy 232.467181 -85.809827) (xy 232.4196 -85.773317)
			(xy 232.377191 -85.730909) (xy 232.34068 -85.683329) (xy 232.310692 -85.631389) (xy 232.28774 -85.57598)
			(xy 232.272218 -85.518049) (xy 232.264389 -85.458587) (xy 118.289959 -85.458587) (xy 118.277182 -85.506269)
			(xy 118.254246 -85.561642) (xy 118.224279 -85.613548) (xy 118.187792 -85.661098) (xy 118.145412 -85.703478)
			(xy 118.097862 -85.739965) (xy 118.045956 -85.769932) (xy 117.990583 -85.792868) (xy 117.93269 -85.808381)
			(xy 117.873268 -85.816204) (xy 117.813332 -85.816204) (xy 117.75391 -85.808381) (xy 117.696017 -85.792868)
			(xy 117.640644 -85.769932) (xy 117.588738 -85.739965) (xy 117.541188 -85.703478) (xy 117.498808 -85.661098)
			(xy 117.462321 -85.613548) (xy 117.432354 -85.561642) (xy 117.409418 -85.506269) (xy 117.393905 -85.448376)
			(xy 117.386082 -85.388954) (xy 117.385592 -85.358986) (xy 49.009819 -85.358986) (xy 49.00037 -85.409534)
			(xy 48.968871 -85.534773) (xy 48.929722 -85.657836) (xy 48.883071 -85.778255) (xy 48.829096 -85.895574)
			(xy 48.768001 -86.009348) (xy 48.700018 -86.119145) (xy 48.625404 -86.224548) (xy 48.544443 -86.325158)
			(xy 48.457443 -86.420593) (xy 48.364732 -86.510492) (xy 48.266662 -86.594513) (xy 48.163607 -86.672337)
			(xy 48.055956 -86.743669) (xy 47.944117 -86.808239) (xy 47.937853 -86.811358) (xy 99.84232 -86.811358)
			(xy 99.84232 -85.947758) (xy 99.84281 -85.917774) (xy 99.850638 -85.858318) (xy 99.866159 -85.800393)
			(xy 99.889108 -85.744989) (xy 99.919092 -85.693055) (xy 99.955598 -85.645479) (xy 99.998003 -85.603074)
			(xy 100.045579 -85.566568) (xy 100.097513 -85.536584) (xy 100.152917 -85.513635) (xy 100.210842 -85.498114)
			(xy 100.270298 -85.490286) (xy 100.330266 -85.490286) (xy 100.389722 -85.498114) (xy 100.447647 -85.513635)
			(xy 100.503051 -85.536584) (xy 100.554985 -85.566568) (xy 100.602561 -85.603074) (xy 100.644966 -85.645479)
			(xy 100.681472 -85.693055) (xy 100.711456 -85.744989) (xy 100.734405 -85.800393) (xy 100.749926 -85.858318)
			(xy 100.757754 -85.917774) (xy 100.758244 -85.947758) (xy 100.758244 -86.811358) (xy 100.757754 -86.841342)
			(xy 100.749926 -86.900798) (xy 100.734405 -86.958723) (xy 100.711456 -87.014127) (xy 100.681472 -87.066061)
			(xy 100.644966 -87.113637) (xy 100.602561 -87.156042) (xy 100.554985 -87.192548) (xy 100.503051 -87.222532)
			(xy 100.447647 -87.245481) (xy 100.389722 -87.261002) (xy 100.330266 -87.26883) (xy 100.270298 -87.26883)
			(xy 100.210842 -87.261002) (xy 100.152917 -87.245481) (xy 100.097513 -87.222532) (xy 100.045579 -87.192548)
			(xy 99.998003 -87.156042) (xy 99.955598 -87.113637) (xy 99.919092 -87.066061) (xy 99.889108 -87.014127)
			(xy 99.866159 -86.958723) (xy 99.850638 -86.900798) (xy 99.84281 -86.841342) (xy 99.84232 -86.811358)
			(xy 47.937853 -86.811358) (xy 47.828516 -86.865801) (xy 47.709591 -86.916138) (xy 47.587792 -86.959058)
			(xy 47.463582 -86.994399) (xy 47.337433 -87.022026) (xy 47.209821 -87.041835) (xy 47.081232 -87.053751)
			(xy 46.952154 -87.057728) (xy 46.823076 -87.053751) (xy 46.694487 -87.041835) (xy 46.566875 -87.022026)
			(xy 46.440726 -86.994399) (xy 46.316516 -86.959058) (xy 46.194717 -86.916138) (xy 46.075792 -86.865801)
			(xy 45.960191 -86.808239) (xy 45.848352 -86.743669) (xy 45.740701 -86.672337) (xy 45.637646 -86.594513)
			(xy 45.539576 -86.510492) (xy 45.446865 -86.420593) (xy 45.359865 -86.325158) (xy 45.278904 -86.224548)
			(xy 45.20429 -86.119145) (xy 45.136307 -86.009348) (xy 45.075212 -85.895574) (xy 45.021237 -85.778255)
			(xy 44.974586 -85.657836) (xy 44.935437 -85.534773) (xy 44.903938 -85.409534) (xy 44.880209 -85.282593)
			(xy 44.864339 -85.154433) (xy 44.856389 -85.025538) (xy 2.78524 -85.025538) (xy 3.574034 -85.814408)
			(xy 3.623456 -85.864516) (xy 3.717262 -85.969457) (xy 3.805036 -86.079494) (xy 3.886503 -86.194278)
			(xy 3.961406 -86.31345) (xy 4.029509 -86.436634) (xy 4.090598 -86.563442) (xy 4.144481 -86.693477)
			(xy 4.190988 -86.826327) (xy 4.229973 -86.961577) (xy 4.261314 -87.0988) (xy 4.284912 -87.237564)
			(xy 4.29861 -87.358982) (xy 116.623592 -87.358982) (xy 116.623592 -86.495382) (xy 116.624082 -86.465414)
			(xy 116.631905 -86.405992) (xy 116.647418 -86.348099) (xy 116.670354 -86.292726) (xy 116.700321 -86.24082)
			(xy 116.736808 -86.19327) (xy 116.779188 -86.15089) (xy 116.826738 -86.114403) (xy 116.878644 -86.084436)
			(xy 116.934017 -86.0615) (xy 116.99191 -86.045987) (xy 117.051332 -86.038164) (xy 117.111268 -86.038164)
			(xy 117.17069 -86.045987) (xy 117.228583 -86.0615) (xy 117.283956 -86.084436) (xy 117.335862 -86.114403)
			(xy 117.383412 -86.15089) (xy 117.425792 -86.19327) (xy 117.462279 -86.24082) (xy 117.492246 -86.292726)
			(xy 117.515182 -86.348099) (xy 117.530695 -86.405992) (xy 117.538518 -86.465414) (xy 117.539008 -86.495382)
			(xy 117.539008 -86.661752) (xy 229.518972 -86.661752) (xy 229.518972 -86.255098) (xy 229.519426 -86.244967)
			(xy 229.52716 -86.22624) (xy 229.541457 -86.211883) (xy 229.560151 -86.204069) (xy 229.57028 -86.203536)
			(xy 229.972616 -86.203536) (xy 229.982776 -86.203909) (xy 230.001535 -86.211717) (xy 230.01586 -86.226129)
			(xy 230.023552 -86.244936) (xy 230.023924 -86.255098) (xy 230.023924 -86.661752) (xy 230.407972 -86.661752)
			(xy 230.407972 -86.255098) (xy 230.408426 -86.244967) (xy 230.41616 -86.22624) (xy 230.430457 -86.211883)
			(xy 230.449151 -86.204069) (xy 230.45928 -86.203536) (xy 230.861616 -86.203536) (xy 230.871776 -86.203909)
			(xy 230.890535 -86.211717) (xy 230.90486 -86.226129) (xy 230.912552 -86.244936) (xy 230.912924 -86.255098)
			(xy 230.912924 -86.661752) (xy 230.912445 -86.671868) (xy 230.904717 -86.690566) (xy 230.89042 -86.704881)
			(xy 230.871732 -86.712633) (xy 230.861616 -86.71306) (xy 230.45928 -86.71306) (xy 230.449151 -86.7127)
			(xy 230.430439 -86.704937) (xy 230.416124 -86.690603) (xy 230.408387 -86.671881) (xy 230.407972 -86.661752)
			(xy 230.023924 -86.661752) (xy 230.023445 -86.671868) (xy 230.015717 -86.690566) (xy 230.00142 -86.704881)
			(xy 229.982732 -86.712633) (xy 229.972616 -86.71306) (xy 229.57028 -86.71306) (xy 229.560151 -86.7127)
			(xy 229.541439 -86.704937) (xy 229.527124 -86.690603) (xy 229.519387 -86.671881) (xy 229.518972 -86.661752)
			(xy 117.539008 -86.661752) (xy 117.539008 -87.358982) (xy 117.538518 -87.38895) (xy 117.535508 -87.411814)
			(xy 229.519988 -87.411814) (xy 229.519988 -87.00516) (xy 229.520452 -86.99505) (xy 229.528201 -86.976373)
			(xy 229.542504 -86.96208) (xy 229.561186 -86.954345) (xy 229.571296 -86.953852) (xy 229.973632 -86.953852)
			(xy 229.983737 -86.954358) (xy 230.002407 -86.962097) (xy 230.016699 -86.976387) (xy 230.024441 -86.995055)
			(xy 230.02494 -87.00516) (xy 230.02494 -87.411814) (xy 230.408988 -87.411814) (xy 230.408988 -87.00516)
			(xy 230.409452 -86.99505) (xy 230.417201 -86.976373) (xy 230.431504 -86.96208) (xy 230.450186 -86.954345)
			(xy 230.460296 -86.953852) (xy 230.862632 -86.953852) (xy 230.872737 -86.954358) (xy 230.891407 -86.962097)
			(xy 230.905699 -86.976387) (xy 230.913441 -86.995055) (xy 230.91394 -87.00516) (xy 230.91394 -87.411814)
			(xy 230.913484 -87.421944) (xy 230.905748 -87.440669) (xy 230.902365 -87.444066) (xy 232.194882 -87.444066)
			(xy 232.194882 -87.384134) (xy 232.202704 -87.324714) (xy 232.218215 -87.266824) (xy 232.241149 -87.211454)
			(xy 232.271114 -87.15955) (xy 232.307596 -87.112002) (xy 232.349973 -87.069621) (xy 232.397519 -87.033135)
			(xy 232.44942 -87.003166) (xy 232.504788 -86.980227) (xy 232.562677 -86.964712) (xy 232.622096 -86.956884)
			(xy 232.652062 -86.956392) (xy 233.515662 -86.956392) (xy 233.545633 -86.956859) (xy 233.605062 -86.964678)
			(xy 233.662961 -86.980188) (xy 233.718341 -87.003123) (xy 233.770254 -87.033091) (xy 233.81781 -87.069578)
			(xy 233.860197 -87.111961) (xy 233.896688 -87.159515) (xy 233.92666 -87.211425) (xy 233.9496 -87.266803)
			(xy 233.965115 -87.324701) (xy 233.972939 -87.384129) (xy 233.972939 -87.416385) (xy 234.381521 -87.416385)
			(xy 234.381521 -87.356415) (xy 234.389349 -87.296959) (xy 234.40487 -87.239032) (xy 234.42782 -87.183628)
			(xy 234.457804 -87.131692) (xy 234.494312 -87.084115) (xy 234.536717 -87.04171) (xy 234.584294 -87.005203)
			(xy 234.636229 -86.975219) (xy 234.691634 -86.952269) (xy 234.749561 -86.936748) (xy 234.809017 -86.928921)
			(xy 234.839002 -86.928452) (xy 235.702602 -86.928452) (xy 235.732587 -86.928914) (xy 235.792044 -86.936742)
			(xy 235.849971 -86.952264) (xy 235.905376 -86.975214) (xy 235.957312 -87.005199) (xy 236.004889 -87.041707)
			(xy 236.047295 -87.084112) (xy 236.083802 -87.13169) (xy 236.113787 -87.183626) (xy 236.136737 -87.239031)
			(xy 236.152258 -87.296958) (xy 236.155843 -87.324184) (xy 330.477876 -87.324184) (xy 330.477876 -86.460584)
			(xy 330.478366 -86.430616) (xy 330.486189 -86.371194) (xy 330.501702 -86.313301) (xy 330.524638 -86.257928)
			(xy 330.554605 -86.206022) (xy 330.591092 -86.158472) (xy 330.633472 -86.116092) (xy 330.681022 -86.079605)
			(xy 330.732928 -86.049638) (xy 330.788301 -86.026702) (xy 330.846194 -86.011189) (xy 330.905616 -86.003366)
			(xy 330.965552 -86.003366) (xy 331.024974 -86.011189) (xy 331.082867 -86.026702) (xy 331.13824 -86.049638)
			(xy 331.190146 -86.079605) (xy 331.237696 -86.116092) (xy 331.266212 -86.144608) (xy 346.641928 -86.144608)
			(xy 346.641928 -85.281008) (xy 346.642418 -85.251024) (xy 346.650246 -85.191568) (xy 346.665767 -85.133643)
			(xy 346.688716 -85.078239) (xy 346.7187 -85.026305) (xy 346.755206 -84.978729) (xy 346.797611 -84.936324)
			(xy 346.845187 -84.899818) (xy 346.897121 -84.869834) (xy 346.952525 -84.846885) (xy 347.01045 -84.831364)
			(xy 347.069906 -84.823536) (xy 347.129874 -84.823536) (xy 347.18933 -84.831364) (xy 347.247255 -84.846885)
			(xy 347.302659 -84.869834) (xy 347.354593 -84.899818) (xy 347.402169 -84.936324) (xy 347.444574 -84.978729)
			(xy 347.48108 -85.026305) (xy 347.511064 -85.078239) (xy 347.534013 -85.133643) (xy 347.549534 -85.191568)
			(xy 347.557362 -85.251024) (xy 347.557852 -85.281008) (xy 347.557852 -86.144608) (xy 347.557362 -86.174592)
			(xy 347.549534 -86.234048) (xy 347.534013 -86.291973) (xy 347.511064 -86.347377) (xy 347.48108 -86.399311)
			(xy 347.444574 -86.446887) (xy 347.402169 -86.489292) (xy 347.354593 -86.525798) (xy 347.302659 -86.555782)
			(xy 347.247255 -86.578731) (xy 347.18933 -86.594252) (xy 347.129874 -86.60208) (xy 347.069906 -86.60208)
			(xy 347.01045 -86.594252) (xy 346.952525 -86.578731) (xy 346.897121 -86.555782) (xy 346.845187 -86.525798)
			(xy 346.797611 -86.489292) (xy 346.755206 -86.446887) (xy 346.7187 -86.399311) (xy 346.688716 -86.347377)
			(xy 346.665767 -86.291973) (xy 346.650246 -86.234048) (xy 346.642418 -86.174592) (xy 346.641928 -86.144608)
			(xy 331.266212 -86.144608) (xy 331.280076 -86.158472) (xy 331.316563 -86.206022) (xy 331.34653 -86.257928)
			(xy 331.369466 -86.313301) (xy 331.384979 -86.371194) (xy 331.392802 -86.430616) (xy 331.393292 -86.460584)
			(xy 331.393292 -87.324184) (xy 331.392802 -87.354152) (xy 331.384979 -87.413574) (xy 331.369466 -87.471467)
			(xy 331.34653 -87.52684) (xy 331.316563 -87.578746) (xy 331.280076 -87.626296) (xy 331.237696 -87.668676)
			(xy 331.190146 -87.705163) (xy 331.13824 -87.73513) (xy 331.082867 -87.758066) (xy 331.024974 -87.773579)
			(xy 330.965552 -87.781402) (xy 330.905616 -87.781402) (xy 330.846194 -87.773579) (xy 330.788301 -87.758066)
			(xy 330.732928 -87.73513) (xy 330.681022 -87.705163) (xy 330.633472 -87.668676) (xy 330.591092 -87.626296)
			(xy 330.554605 -87.578746) (xy 330.524638 -87.52684) (xy 330.501702 -87.471467) (xy 330.486189 -87.413574)
			(xy 330.478366 -87.354152) (xy 330.477876 -87.324184) (xy 236.155843 -87.324184) (xy 236.160086 -87.356415)
			(xy 236.160086 -87.416385) (xy 236.152258 -87.475842) (xy 236.136737 -87.533769) (xy 236.113787 -87.589174)
			(xy 236.083802 -87.64111) (xy 236.047295 -87.688688) (xy 236.004889 -87.731093) (xy 235.957312 -87.767601)
			(xy 235.905376 -87.797586) (xy 235.849971 -87.820536) (xy 235.792044 -87.836058) (xy 235.732587 -87.843886)
			(xy 235.702602 -87.844376) (xy 234.839002 -87.844376) (xy 234.809017 -87.843879) (xy 234.749561 -87.836052)
			(xy 234.691634 -87.820531) (xy 234.636229 -87.797581) (xy 234.584294 -87.767597) (xy 234.536717 -87.73109)
			(xy 234.494312 -87.688685) (xy 234.457804 -87.641108) (xy 234.42782 -87.589172) (xy 234.40487 -87.533768)
			(xy 234.389349 -87.475841) (xy 234.381521 -87.416385) (xy 233.972939 -87.416385) (xy 233.972939 -87.444071)
			(xy 233.965115 -87.503499) (xy 233.9496 -87.561397) (xy 233.92666 -87.616775) (xy 233.896688 -87.668685)
			(xy 233.860197 -87.716239) (xy 233.81781 -87.758622) (xy 233.770254 -87.795109) (xy 233.718341 -87.825077)
			(xy 233.662961 -87.848012) (xy 233.605062 -87.863522) (xy 233.545633 -87.871341) (xy 233.515662 -87.871808)
			(xy 232.652062 -87.871808) (xy 232.622096 -87.871316) (xy 232.562677 -87.863488) (xy 232.504788 -87.847973)
			(xy 232.44942 -87.825034) (xy 232.397519 -87.795065) (xy 232.349973 -87.758579) (xy 232.307596 -87.716198)
			(xy 232.271114 -87.66865) (xy 232.241149 -87.616746) (xy 232.218215 -87.561376) (xy 232.202704 -87.503486)
			(xy 232.194882 -87.444066) (xy 230.902365 -87.444066) (xy 230.891452 -87.455026) (xy 230.87276 -87.462841)
			(xy 230.862632 -87.463376) (xy 230.460296 -87.463376) (xy 230.450139 -87.462981) (xy 230.431382 -87.45518)
			(xy 230.417058 -87.440774) (xy 230.409362 -87.421974) (xy 230.408988 -87.411814) (xy 230.02494 -87.411814)
			(xy 230.024484 -87.421944) (xy 230.016748 -87.440669) (xy 230.002452 -87.455026) (xy 229.98376 -87.462841)
			(xy 229.973632 -87.463376) (xy 229.571296 -87.463376) (xy 229.561139 -87.462981) (xy 229.542382 -87.45518)
			(xy 229.528058 -87.440774) (xy 229.520362 -87.421974) (xy 229.519988 -87.411814) (xy 117.535508 -87.411814)
			(xy 117.530695 -87.448372) (xy 117.515182 -87.506265) (xy 117.492246 -87.561638) (xy 117.462279 -87.613544)
			(xy 117.425792 -87.661094) (xy 117.383412 -87.703474) (xy 117.335862 -87.739961) (xy 117.283956 -87.769928)
			(xy 117.228583 -87.792864) (xy 117.17069 -87.808377) (xy 117.111268 -87.8162) (xy 117.051332 -87.8162)
			(xy 116.99191 -87.808377) (xy 116.934017 -87.792864) (xy 116.878644 -87.769928) (xy 116.826738 -87.739961)
			(xy 116.779188 -87.703474) (xy 116.736808 -87.661094) (xy 116.700321 -87.613544) (xy 116.670354 -87.561638)
			(xy 116.647418 -87.506265) (xy 116.631905 -87.448372) (xy 116.624082 -87.38895) (xy 116.623592 -87.358982)
			(xy 4.29861 -87.358982) (xy 4.300692 -87.377432) (xy 4.308605 -87.517966) (xy 4.30911 -87.588344)
			(xy 4.30911 -88.006187) (xy 238.124409 -88.006187) (xy 238.124409 -87.946213) (xy 238.132238 -87.886751)
			(xy 238.147762 -87.82882) (xy 238.170714 -87.773411) (xy 238.200704 -87.721472) (xy 238.237216 -87.673892)
			(xy 238.279627 -87.631486) (xy 238.32721 -87.594978) (xy 238.379152 -87.564994) (xy 238.434563 -87.542047)
			(xy 238.492496 -87.526529) (xy 238.551959 -87.518706) (xy 238.581946 -87.51824) (xy 239.445546 -87.51824)
			(xy 239.475528 -87.518729) (xy 239.53498 -87.526561) (xy 239.5929 -87.542086) (xy 239.648299 -87.565038)
			(xy 239.700228 -87.595024) (xy 239.747799 -87.631531) (xy 239.790199 -87.673935) (xy 239.826701 -87.72151)
			(xy 239.856682 -87.773442) (xy 239.879628 -87.828843) (xy 239.895148 -87.886765) (xy 239.902974 -87.946217)
			(xy 239.902974 -88.006183) (xy 239.895148 -88.065635) (xy 239.879628 -88.123557) (xy 239.870911 -88.144604)
			(xy 345.879928 -88.144604) (xy 345.879928 -87.281004) (xy 345.880418 -87.25102) (xy 345.888246 -87.191564)
			(xy 345.903767 -87.133639) (xy 345.926716 -87.078235) (xy 345.9567 -87.026301) (xy 345.993206 -86.978725)
			(xy 346.035611 -86.93632) (xy 346.083187 -86.899814) (xy 346.135121 -86.86983) (xy 346.190525 -86.846881)
			(xy 346.24845 -86.83136) (xy 346.307906 -86.823532) (xy 346.367874 -86.823532) (xy 346.42733 -86.83136)
			(xy 346.485255 -86.846881) (xy 346.540659 -86.86983) (xy 346.592593 -86.899814) (xy 346.640169 -86.93632)
			(xy 346.682574 -86.978725) (xy 346.71908 -87.026301) (xy 346.749064 -87.078235) (xy 346.772013 -87.133639)
			(xy 346.787534 -87.191564) (xy 346.795362 -87.25102) (xy 346.795852 -87.281004) (xy 346.795852 -88.144604)
			(xy 346.795362 -88.174588) (xy 346.787534 -88.234044) (xy 346.772013 -88.291969) (xy 346.749064 -88.347373)
			(xy 346.71908 -88.399307) (xy 346.682574 -88.446883) (xy 346.640169 -88.489288) (xy 346.592593 -88.525794)
			(xy 346.540659 -88.555778) (xy 346.485255 -88.578727) (xy 346.42733 -88.594248) (xy 346.367874 -88.602076)
			(xy 346.307906 -88.602076) (xy 346.24845 -88.594248) (xy 346.190525 -88.578727) (xy 346.135121 -88.555778)
			(xy 346.083187 -88.525794) (xy 346.035611 -88.489288) (xy 345.993206 -88.446883) (xy 345.9567 -88.399307)
			(xy 345.926716 -88.347373) (xy 345.903767 -88.291969) (xy 345.888246 -88.234044) (xy 345.880418 -88.174588)
			(xy 345.879928 -88.144604) (xy 239.870911 -88.144604) (xy 239.856682 -88.178958) (xy 239.826701 -88.23089)
			(xy 239.790199 -88.278465) (xy 239.747799 -88.320869) (xy 239.700228 -88.357376) (xy 239.648299 -88.387362)
			(xy 239.5929 -88.410314) (xy 239.53498 -88.425839) (xy 239.475528 -88.433671) (xy 239.445546 -88.434164)
			(xy 238.581946 -88.434164) (xy 238.551959 -88.433694) (xy 238.492496 -88.425871) (xy 238.434563 -88.410353)
			(xy 238.379152 -88.387406) (xy 238.32721 -88.357422) (xy 238.279627 -88.320914) (xy 238.237216 -88.278508)
			(xy 238.200704 -88.230928) (xy 238.170714 -88.178989) (xy 238.147762 -88.12358) (xy 238.132238 -88.065649)
			(xy 238.124409 -88.006187) (xy 4.30911 -88.006187) (xy 4.30911 -89.358978) (xy 117.385592 -89.358978)
			(xy 117.385592 -88.495378) (xy 117.386082 -88.46541) (xy 117.393905 -88.405988) (xy 117.409418 -88.348095)
			(xy 117.432354 -88.292722) (xy 117.462321 -88.240816) (xy 117.498808 -88.193266) (xy 117.541188 -88.150886)
			(xy 117.588738 -88.114399) (xy 117.640644 -88.084432) (xy 117.696017 -88.061496) (xy 117.75391 -88.045983)
			(xy 117.813332 -88.03816) (xy 117.873268 -88.03816) (xy 117.93269 -88.045983) (xy 117.990583 -88.061496)
			(xy 118.045956 -88.084432) (xy 118.097862 -88.114399) (xy 118.145412 -88.150886) (xy 118.187792 -88.193266)
			(xy 118.224279 -88.240816) (xy 118.254246 -88.292722) (xy 118.277182 -88.348095) (xy 118.292695 -88.405988)
			(xy 118.300518 -88.46541) (xy 118.301008 -88.495378) (xy 118.301008 -89.358978) (xy 118.300518 -89.388946)
			(xy 118.292695 -89.448368) (xy 118.277182 -89.506261) (xy 118.254246 -89.561634) (xy 118.224279 -89.61354)
			(xy 118.187792 -89.66109) (xy 118.145412 -89.70347) (xy 118.097862 -89.739957) (xy 118.045956 -89.769924)
			(xy 117.990583 -89.79286) (xy 117.93269 -89.808373) (xy 117.873268 -89.816196) (xy 117.813332 -89.816196)
			(xy 117.75391 -89.808373) (xy 117.696017 -89.79286) (xy 117.640644 -89.769924) (xy 117.588738 -89.739957)
			(xy 117.541188 -89.70347) (xy 117.498808 -89.66109) (xy 117.462321 -89.61354) (xy 117.432354 -89.561634)
			(xy 117.409418 -89.506261) (xy 117.393905 -89.448368) (xy 117.386082 -89.388946) (xy 117.385592 -89.358978)
			(xy 4.30911 -89.358978) (xy 4.30911 -90.174826) (xy 232.3846 -90.174826) (xy 232.3846 -89.536524)
			(xy 232.385041 -89.526371) (xy 232.392829 -89.507619) (xy 232.40722 -89.493295) (xy 232.426008 -89.485595)
			(xy 232.436162 -89.485216) (xy 233.100372 -89.485216) (xy 233.110495 -89.485639) (xy 233.129201 -89.493381)
			(xy 233.143517 -89.507696) (xy 233.15126 -89.526401) (xy 233.15168 -89.536524) (xy 233.15168 -90.174826)
			(xy 233.384852 -90.174826) (xy 233.384852 -89.536524) (xy 233.385403 -89.526423) (xy 233.393124 -89.507754)
			(xy 233.4074 -89.49346) (xy 233.426059 -89.485716) (xy 233.43616 -89.485216) (xy 234.10037 -89.485216)
			(xy 234.110492 -89.48575) (xy 234.129208 -89.493464) (xy 234.143564 -89.507735) (xy 234.151389 -89.526405)
			(xy 234.151932 -89.536524) (xy 234.151932 -90.174826) (xy 234.884976 -90.174826) (xy 234.884976 -89.536524)
			(xy 234.885435 -89.526406) (xy 234.893171 -89.507707) (xy 234.907474 -89.493393) (xy 234.926166 -89.485643)
			(xy 234.936284 -89.485216) (xy 235.600494 -89.485216) (xy 235.610617 -89.485731) (xy 235.629334 -89.493452)
			(xy 235.643689 -89.507729) (xy 235.651513 -89.526403) (xy 235.652056 -89.536524) (xy 235.652056 -90.1446)
			(xy 346.641928 -90.1446) (xy 346.641928 -89.281) (xy 346.642418 -89.251016) (xy 346.650246 -89.19156)
			(xy 346.665767 -89.133635) (xy 346.688716 -89.078231) (xy 346.7187 -89.026297) (xy 346.755206 -88.978721)
			(xy 346.797611 -88.936316) (xy 346.845187 -88.89981) (xy 346.897121 -88.869826) (xy 346.952525 -88.846877)
			(xy 347.01045 -88.831356) (xy 347.069906 -88.823528) (xy 347.129874 -88.823528) (xy 347.18933 -88.831356)
			(xy 347.247255 -88.846877) (xy 347.302659 -88.869826) (xy 347.354593 -88.89981) (xy 347.402169 -88.936316)
			(xy 347.444574 -88.978721) (xy 347.48108 -89.026297) (xy 347.511064 -89.078231) (xy 347.534013 -89.133635)
			(xy 347.549534 -89.19156) (xy 347.557362 -89.251016) (xy 347.557852 -89.281) (xy 347.557852 -90.1446)
			(xy 347.557362 -90.174584) (xy 347.549534 -90.23404) (xy 347.534013 -90.291965) (xy 347.511064 -90.347369)
			(xy 347.48108 -90.399303) (xy 347.444574 -90.446879) (xy 347.402169 -90.489284) (xy 347.354593 -90.52579)
			(xy 347.302659 -90.555774) (xy 347.247255 -90.578723) (xy 347.18933 -90.594244) (xy 347.129874 -90.602072)
			(xy 347.069906 -90.602072) (xy 347.01045 -90.594244) (xy 346.952525 -90.578723) (xy 346.897121 -90.555774)
			(xy 346.845187 -90.52579) (xy 346.797611 -90.489284) (xy 346.755206 -90.446879) (xy 346.7187 -90.399303)
			(xy 346.688716 -90.347369) (xy 346.665767 -90.291965) (xy 346.650246 -90.23404) (xy 346.642418 -90.174584)
			(xy 346.641928 -90.1446) (xy 235.652056 -90.1446) (xy 235.652056 -90.174826) (xy 235.651588 -90.184986)
			(xy 235.643804 -90.203757) (xy 235.62943 -90.218122) (xy 235.610655 -90.225894) (xy 235.600494 -90.226388)
			(xy 234.936284 -90.226388) (xy 234.926127 -90.225991) (xy 234.907372 -90.218188) (xy 234.893049 -90.203784)
			(xy 234.885352 -90.184985) (xy 234.884976 -90.174826) (xy 234.151932 -90.174826) (xy 234.151557 -90.185003)
			(xy 234.143758 -90.203804) (xy 234.129357 -90.218189) (xy 234.110548 -90.225968) (xy 234.10037 -90.226388)
			(xy 233.43616 -90.226388) (xy 233.426002 -90.226011) (xy 233.407246 -90.2182) (xy 233.392924 -90.20379)
			(xy 233.385228 -90.184987) (xy 233.384852 -90.174826) (xy 233.15168 -90.174826) (xy 233.151195 -90.184952)
			(xy 233.143463 -90.20367) (xy 233.129176 -90.218025) (xy 233.110495 -90.225846) (xy 233.100372 -90.226388)
			(xy 232.436162 -90.226388) (xy 232.426005 -90.225898) (xy 232.40724 -90.218116) (xy 232.392877 -90.20375)
			(xy 232.385099 -90.184983) (xy 232.3846 -90.174826) (xy 4.30911 -90.174826) (xy 4.30911 -94.088485)
			(xy 109.149614 -94.088485) (xy 109.149614 -94.028515) (xy 109.157442 -93.969058) (xy 109.172963 -93.911131)
			(xy 109.195912 -93.855726) (xy 109.225897 -93.80379) (xy 109.262405 -93.756213) (xy 109.30481 -93.713807)
			(xy 109.352387 -93.6773) (xy 109.404322 -93.647314) (xy 109.459727 -93.624364) (xy 109.517654 -93.608843)
			(xy 109.577111 -93.601014) (xy 109.607096 -93.600524) (xy 110.470696 -93.600524) (xy 110.500681 -93.601021)
			(xy 110.560138 -93.608848) (xy 110.618064 -93.624369) (xy 110.673469 -93.647318) (xy 110.725405 -93.677303)
			(xy 110.772982 -93.71381) (xy 110.815388 -93.756215) (xy 110.851895 -93.803792) (xy 110.88188 -93.855727)
			(xy 110.90483 -93.911132) (xy 110.920351 -93.969058) (xy 110.928179 -94.028515) (xy 110.928179 -94.088485)
			(xy 110.920351 -94.147942) (xy 110.90483 -94.205868) (xy 110.88188 -94.261273) (xy 110.851895 -94.313208)
			(xy 110.815388 -94.360785) (xy 110.772982 -94.40319) (xy 110.725405 -94.439697) (xy 110.673469 -94.469682)
			(xy 110.618064 -94.492631) (xy 110.560138 -94.508152) (xy 110.500681 -94.515979) (xy 110.470696 -94.516448)
			(xy 109.607096 -94.516448) (xy 109.577111 -94.515986) (xy 109.517654 -94.508157) (xy 109.459727 -94.492636)
			(xy 109.404322 -94.469686) (xy 109.352387 -94.4397) (xy 109.30481 -94.403193) (xy 109.262405 -94.360787)
			(xy 109.225897 -94.31321) (xy 109.195912 -94.261274) (xy 109.172963 -94.205869) (xy 109.157442 -94.147942)
			(xy 109.149614 -94.088485) (xy 4.30911 -94.088485) (xy 4.30911 -95.214948) (xy 47.274239 -95.214948)
			(xy 47.278194 -95.123111) (xy 47.290029 -95.031954) (xy 47.309656 -94.942151) (xy 47.33693 -94.854369)
			(xy 47.37165 -94.769255) (xy 47.413558 -94.687442) (xy 47.462344 -94.609534) (xy 47.517647 -94.536109)
			(xy 47.579057 -94.467709) (xy 47.646119 -94.404842) (xy 47.718338 -94.347972) (xy 47.795178 -94.297521)
			(xy 47.876071 -94.253862) (xy 47.960417 -94.217319) (xy 48.047593 -94.188162) (xy 48.136952 -94.166608)
			(xy 48.227833 -94.152814) (xy 48.319564 -94.146884) (xy 48.411465 -94.148862) (xy 48.502856 -94.158733)
			(xy 48.59306 -94.176423) (xy 48.681409 -94.201803) (xy 48.767249 -94.234683) (xy 48.849945 -94.274821)
			(xy 48.928885 -94.32192) (xy 49.003483 -94.37563) (xy 49.073189 -94.435554) (xy 49.137484 -94.501248)
			(xy 49.195895 -94.572226) (xy 49.247987 -94.647963) (xy 49.293376 -94.727898) (xy 49.331726 -94.811438)
			(xy 49.362751 -94.897966) (xy 49.386224 -94.986841) (xy 49.40197 -95.077405) (xy 49.409872 -95.168987)
			(xy 49.410366 -95.214948) (xy 71.639189 -95.214948) (xy 71.643144 -95.123111) (xy 71.654979 -95.031954)
			(xy 71.674606 -94.942151) (xy 71.70188 -94.854369) (xy 71.7366 -94.769255) (xy 71.778508 -94.687442)
			(xy 71.827294 -94.609534) (xy 71.882597 -94.536109) (xy 71.944007 -94.467709) (xy 72.011069 -94.404842)
			(xy 72.083288 -94.347972) (xy 72.160128 -94.297521) (xy 72.241021 -94.253862) (xy 72.325367 -94.217319)
			(xy 72.412543 -94.188162) (xy 72.501902 -94.166608) (xy 72.592783 -94.152814) (xy 72.684514 -94.146884)
			(xy 72.776415 -94.148862) (xy 72.867806 -94.158733) (xy 72.95801 -94.176423) (xy 73.046359 -94.201803)
			(xy 73.132199 -94.234683) (xy 73.214895 -94.274821) (xy 73.293835 -94.32192) (xy 73.368433 -94.37563)
			(xy 73.438139 -94.435554) (xy 73.502434 -94.501248) (xy 73.560845 -94.572226) (xy 73.612937 -94.647963)
			(xy 73.658326 -94.727898) (xy 73.696676 -94.811438) (xy 73.727701 -94.897966) (xy 73.751174 -94.986841)
			(xy 73.76692 -95.077405) (xy 73.774822 -95.168987) (xy 73.775316 -95.214948) (xy 73.774822 -95.260909)
			(xy 73.774772 -95.261486) (xy 163.375394 -95.261486) (xy 163.375394 -95.168314) (xy 163.383515 -95.075496)
			(xy 163.399694 -94.983738) (xy 163.423808 -94.893741) (xy 163.455675 -94.806187) (xy 163.495052 -94.721744)
			(xy 163.541638 -94.641054) (xy 163.595079 -94.564731) (xy 163.654969 -94.493357) (xy 163.720852 -94.427473)
			(xy 163.792226 -94.367583) (xy 163.868549 -94.314141) (xy 163.949238 -94.267554) (xy 164.033681 -94.228178)
			(xy 164.121235 -94.19631) (xy 164.211233 -94.172195) (xy 164.30299 -94.156015) (xy 164.395808 -94.147894)
			(xy 164.442394 -94.147386) (xy 164.442648 -94.147386) (xy 164.489237 -94.1478) (xy 164.582061 -94.155925)
			(xy 164.673824 -94.172109) (xy 164.763826 -94.196229) (xy 164.851385 -94.228101) (xy 164.935832 -94.267483)
			(xy 165.016526 -94.314074) (xy 165.092852 -94.367522) (xy 165.164229 -94.427418) (xy 165.230115 -94.493306)
			(xy 165.290008 -94.564687) (xy 165.343451 -94.641015) (xy 165.390039 -94.721711) (xy 165.429417 -94.80616)
			(xy 165.461286 -94.893719) (xy 165.485401 -94.983723) (xy 165.501581 -95.075487) (xy 165.509702 -95.168311)
			(xy 165.509702 -95.214948) (xy 187.739796 -95.214948) (xy 187.743748 -95.123155) (xy 187.755578 -95.032041)
			(xy 187.775195 -94.942281) (xy 187.802457 -94.85454) (xy 187.83716 -94.769468) (xy 187.879048 -94.687693)
			(xy 187.927811 -94.609822) (xy 187.983087 -94.536432) (xy 188.044468 -94.468065) (xy 188.111499 -94.405227)
			(xy 188.183683 -94.348385) (xy 188.260487 -94.297958) (xy 188.341341 -94.25432) (xy 188.425647 -94.217794)
			(xy 188.512781 -94.188651) (xy 188.602098 -94.167106) (xy 188.692936 -94.15332) (xy 188.784623 -94.147393)
			(xy 188.87648 -94.14937) (xy 188.967828 -94.159236) (xy 189.057988 -94.176918) (xy 189.146296 -94.202285)
			(xy 189.232095 -94.23515) (xy 189.314752 -94.275269) (xy 189.393654 -94.322345) (xy 189.468217 -94.376029)
			(xy 189.537889 -94.435925) (xy 189.602154 -94.501588) (xy 189.660537 -94.572532) (xy 189.712604 -94.648233)
			(xy 189.757972 -94.72813) (xy 189.796303 -94.81163) (xy 189.827314 -94.898117) (xy 189.850775 -94.98695)
			(xy 189.866514 -95.07747) (xy 189.874412 -95.169009) (xy 189.874906 -95.214948) (xy 279.474181 -95.214948)
			(xy 279.478136 -95.123111) (xy 279.489971 -95.031954) (xy 279.509598 -94.942151) (xy 279.536872 -94.854369)
			(xy 279.571592 -94.769255) (xy 279.6135 -94.687442) (xy 279.662286 -94.609534) (xy 279.717589 -94.536109)
			(xy 279.778999 -94.467709) (xy 279.846061 -94.404842) (xy 279.91828 -94.347972) (xy 279.99512 -94.297521)
			(xy 280.076013 -94.253862) (xy 280.160359 -94.217319) (xy 280.247535 -94.188162) (xy 280.336894 -94.166608)
			(xy 280.427775 -94.152814) (xy 280.519506 -94.146884) (xy 280.611407 -94.148862) (xy 280.702798 -94.158733)
			(xy 280.793002 -94.176423) (xy 280.881351 -94.201803) (xy 280.967191 -94.234683) (xy 281.049887 -94.274821)
			(xy 281.128827 -94.32192) (xy 281.203425 -94.37563) (xy 281.273131 -94.435554) (xy 281.337426 -94.501248)
			(xy 281.395837 -94.572226) (xy 281.447929 -94.647963) (xy 281.493318 -94.727898) (xy 281.531668 -94.811438)
			(xy 281.562693 -94.897966) (xy 281.586166 -94.986841) (xy 281.601912 -95.077405) (xy 281.609814 -95.168987)
			(xy 281.610308 -95.214948) (xy 303.839131 -95.214948) (xy 303.843086 -95.123111) (xy 303.854921 -95.031954)
			(xy 303.874548 -94.942151) (xy 303.901822 -94.854369) (xy 303.936542 -94.769255) (xy 303.97845 -94.687442)
			(xy 304.027236 -94.609534) (xy 304.082539 -94.536109) (xy 304.143949 -94.467709) (xy 304.211011 -94.404842)
			(xy 304.28323 -94.347972) (xy 304.36007 -94.297521) (xy 304.440963 -94.253862) (xy 304.525309 -94.217319)
			(xy 304.612485 -94.188162) (xy 304.701844 -94.166608) (xy 304.792725 -94.152814) (xy 304.884456 -94.146884)
			(xy 304.976357 -94.148862) (xy 305.067748 -94.158733) (xy 305.157952 -94.176423) (xy 305.246301 -94.201803)
			(xy 305.332141 -94.234683) (xy 305.414837 -94.274821) (xy 305.493777 -94.32192) (xy 305.568375 -94.37563)
			(xy 305.638081 -94.435554) (xy 305.702376 -94.501248) (xy 305.760787 -94.572226) (xy 305.812879 -94.647963)
			(xy 305.858268 -94.727898) (xy 305.896618 -94.811438) (xy 305.91901 -94.87389) (xy 338.405861 -94.87389)
			(xy 338.405861 -94.81391) (xy 338.413691 -94.754443) (xy 338.429215 -94.696507) (xy 338.45217 -94.641093)
			(xy 338.482161 -94.58915) (xy 338.518676 -94.541565) (xy 338.561089 -94.499155) (xy 338.608676 -94.462643)
			(xy 338.660622 -94.432655) (xy 338.716037 -94.409705) (xy 338.773975 -94.394184) (xy 338.833442 -94.386359)
			(xy 338.863432 -94.385892) (xy 339.727032 -94.385892) (xy 339.757012 -94.386476) (xy 339.816458 -94.394306)
			(xy 339.874374 -94.409828) (xy 339.929769 -94.432777) (xy 339.981694 -94.462759) (xy 340.029262 -94.499262)
			(xy 340.071659 -94.541662) (xy 340.108159 -94.589232) (xy 340.138137 -94.64116) (xy 340.161082 -94.696556)
			(xy 340.1766 -94.754473) (xy 340.184426 -94.81392) (xy 340.184426 -94.87388) (xy 340.1766 -94.933327)
			(xy 340.161082 -94.991244) (xy 340.138137 -95.04664) (xy 340.108159 -95.098568) (xy 340.071659 -95.146138)
			(xy 340.029262 -95.188538) (xy 339.994846 -95.214948) (xy 395.574279 -95.214948) (xy 395.578234 -95.123111)
			(xy 395.590069 -95.031954) (xy 395.609696 -94.942151) (xy 395.63697 -94.854369) (xy 395.67169 -94.769255)
			(xy 395.713598 -94.687442) (xy 395.762384 -94.609534) (xy 395.817687 -94.536109) (xy 395.879097 -94.467709)
			(xy 395.946159 -94.404842) (xy 396.018378 -94.347972) (xy 396.095218 -94.297521) (xy 396.176111 -94.253862)
			(xy 396.260457 -94.217319) (xy 396.347633 -94.188162) (xy 396.436992 -94.166608) (xy 396.527873 -94.152814)
			(xy 396.619604 -94.146884) (xy 396.711505 -94.148862) (xy 396.802896 -94.158733) (xy 396.8931 -94.176423)
			(xy 396.981449 -94.201803) (xy 397.067289 -94.234683) (xy 397.149985 -94.274821) (xy 397.228925 -94.32192)
			(xy 397.303523 -94.37563) (xy 397.373229 -94.435554) (xy 397.437524 -94.501248) (xy 397.495935 -94.572226)
			(xy 397.548027 -94.647963) (xy 397.593416 -94.727898) (xy 397.631766 -94.811438) (xy 397.662791 -94.897966)
			(xy 397.686264 -94.986841) (xy 397.70201 -95.077405) (xy 397.709912 -95.168987) (xy 397.710406 -95.214948)
			(xy 419.939229 -95.214948) (xy 419.943184 -95.123111) (xy 419.955019 -95.031954) (xy 419.974646 -94.942151)
			(xy 420.00192 -94.854369) (xy 420.03664 -94.769255) (xy 420.078548 -94.687442) (xy 420.127334 -94.609534)
			(xy 420.182637 -94.536109) (xy 420.244047 -94.467709) (xy 420.311109 -94.404842) (xy 420.383328 -94.347972)
			(xy 420.460168 -94.297521) (xy 420.541061 -94.253862) (xy 420.625407 -94.217319) (xy 420.712583 -94.188162)
			(xy 420.801942 -94.166608) (xy 420.892823 -94.152814) (xy 420.984554 -94.146884) (xy 421.076455 -94.148862)
			(xy 421.167846 -94.158733) (xy 421.25805 -94.176423) (xy 421.346399 -94.201803) (xy 421.432239 -94.234683)
			(xy 421.514935 -94.274821) (xy 421.593875 -94.32192) (xy 421.668473 -94.37563) (xy 421.738179 -94.435554)
			(xy 421.802474 -94.501248) (xy 421.860885 -94.572226) (xy 421.912977 -94.647963) (xy 421.958366 -94.727898)
			(xy 421.996716 -94.811438) (xy 422.027741 -94.897966) (xy 422.051214 -94.986841) (xy 422.06696 -95.077405)
			(xy 422.074862 -95.168987) (xy 422.075356 -95.214948) (xy 422.074862 -95.260909) (xy 422.06696 -95.352491)
			(xy 422.051214 -95.443055) (xy 422.027741 -95.53193) (xy 421.996716 -95.618458) (xy 421.958366 -95.701998)
			(xy 421.912977 -95.781933) (xy 421.860885 -95.85767) (xy 421.802474 -95.928648) (xy 421.738179 -95.994342)
			(xy 421.668473 -96.054266) (xy 421.593875 -96.107976) (xy 421.514935 -96.155075) (xy 421.432239 -96.195213)
			(xy 421.346399 -96.228093) (xy 421.25805 -96.253473) (xy 421.167846 -96.271163) (xy 421.076455 -96.281034)
			(xy 420.984554 -96.283012) (xy 420.892823 -96.277082) (xy 420.801942 -96.263288) (xy 420.712583 -96.241734)
			(xy 420.625407 -96.212577) (xy 420.541061 -96.176034) (xy 420.460168 -96.132375) (xy 420.383328 -96.081924)
			(xy 420.311109 -96.025054) (xy 420.244047 -95.962187) (xy 420.182637 -95.893787) (xy 420.127334 -95.820362)
			(xy 420.078548 -95.742454) (xy 420.03664 -95.660641) (xy 420.00192 -95.575527) (xy 419.974646 -95.487745)
			(xy 419.955019 -95.397942) (xy 419.943184 -95.306785) (xy 419.939229 -95.214948) (xy 397.710406 -95.214948)
			(xy 397.709912 -95.260909) (xy 397.70201 -95.352491) (xy 397.686264 -95.443055) (xy 397.662791 -95.53193)
			(xy 397.631766 -95.618458) (xy 397.593416 -95.701998) (xy 397.548027 -95.781933) (xy 397.495935 -95.85767)
			(xy 397.437524 -95.928648) (xy 397.373229 -95.994342) (xy 397.303523 -96.054266) (xy 397.228925 -96.107976)
			(xy 397.149985 -96.155075) (xy 397.067289 -96.195213) (xy 396.981449 -96.228093) (xy 396.8931 -96.253473)
			(xy 396.802896 -96.271163) (xy 396.711505 -96.281034) (xy 396.619604 -96.283012) (xy 396.527873 -96.277082)
			(xy 396.436992 -96.263288) (xy 396.347633 -96.241734) (xy 396.260457 -96.212577) (xy 396.176111 -96.176034)
			(xy 396.095218 -96.132375) (xy 396.018378 -96.081924) (xy 395.946159 -96.025054) (xy 395.879097 -95.962187)
			(xy 395.817687 -95.893787) (xy 395.762384 -95.820362) (xy 395.713598 -95.742454) (xy 395.67169 -95.660641)
			(xy 395.63697 -95.575527) (xy 395.609696 -95.487745) (xy 395.590069 -95.397942) (xy 395.578234 -95.306785)
			(xy 395.574279 -95.214948) (xy 339.994846 -95.214948) (xy 339.981694 -95.225041) (xy 339.929769 -95.255023)
			(xy 339.874374 -95.277972) (xy 339.816458 -95.293494) (xy 339.757012 -95.301324) (xy 339.727032 -95.301816)
			(xy 338.863432 -95.301816) (xy 338.833442 -95.301441) (xy 338.773975 -95.293616) (xy 338.716037 -95.278095)
			(xy 338.660622 -95.255145) (xy 338.608676 -95.225157) (xy 338.561089 -95.188645) (xy 338.518676 -95.146235)
			(xy 338.482161 -95.09865) (xy 338.45217 -95.046707) (xy 338.429215 -94.991293) (xy 338.413691 -94.933357)
			(xy 338.405861 -94.87389) (xy 305.91901 -94.87389) (xy 305.927643 -94.897966) (xy 305.951116 -94.986841)
			(xy 305.966862 -95.077405) (xy 305.974764 -95.168987) (xy 305.975258 -95.214948) (xy 305.974764 -95.260909)
			(xy 305.966862 -95.352491) (xy 305.951116 -95.443055) (xy 305.927643 -95.53193) (xy 305.896618 -95.618458)
			(xy 305.858268 -95.701998) (xy 305.812879 -95.781933) (xy 305.760787 -95.85767) (xy 305.702376 -95.928648)
			(xy 305.638081 -95.994342) (xy 305.568375 -96.054266) (xy 305.493777 -96.107976) (xy 305.414837 -96.155075)
			(xy 305.332141 -96.195213) (xy 305.246301 -96.228093) (xy 305.157952 -96.253473) (xy 305.067748 -96.271163)
			(xy 304.976357 -96.281034) (xy 304.884456 -96.283012) (xy 304.792725 -96.277082) (xy 304.701844 -96.263288)
			(xy 304.612485 -96.241734) (xy 304.525309 -96.212577) (xy 304.440963 -96.176034) (xy 304.36007 -96.132375)
			(xy 304.28323 -96.081924) (xy 304.211011 -96.025054) (xy 304.143949 -95.962187) (xy 304.082539 -95.893787)
			(xy 304.027236 -95.820362) (xy 303.97845 -95.742454) (xy 303.936542 -95.660641) (xy 303.901822 -95.575527)
			(xy 303.874548 -95.487745) (xy 303.854921 -95.397942) (xy 303.843086 -95.306785) (xy 303.839131 -95.214948)
			(xy 281.610308 -95.214948) (xy 281.609814 -95.260909) (xy 281.601912 -95.352491) (xy 281.586166 -95.443055)
			(xy 281.562693 -95.53193) (xy 281.531668 -95.618458) (xy 281.493318 -95.701998) (xy 281.447929 -95.781933)
			(xy 281.395837 -95.85767) (xy 281.337426 -95.928648) (xy 281.273131 -95.994342) (xy 281.203425 -96.054266)
			(xy 281.128827 -96.107976) (xy 281.049887 -96.155075) (xy 280.967191 -96.195213) (xy 280.881351 -96.228093)
			(xy 280.793002 -96.253473) (xy 280.702798 -96.271163) (xy 280.611407 -96.281034) (xy 280.519506 -96.283012)
			(xy 280.427775 -96.277082) (xy 280.336894 -96.263288) (xy 280.247535 -96.241734) (xy 280.160359 -96.212577)
			(xy 280.076013 -96.176034) (xy 279.99512 -96.132375) (xy 279.91828 -96.081924) (xy 279.846061 -96.025054)
			(xy 279.778999 -95.962187) (xy 279.717589 -95.893787) (xy 279.662286 -95.820362) (xy 279.6135 -95.742454)
			(xy 279.571592 -95.660641) (xy 279.536872 -95.575527) (xy 279.509598 -95.487745) (xy 279.489971 -95.397942)
			(xy 279.478136 -95.306785) (xy 279.474181 -95.214948) (xy 189.874906 -95.214948) (xy 189.874412 -95.260887)
			(xy 189.866514 -95.352426) (xy 189.850775 -95.442946) (xy 189.827314 -95.531779) (xy 189.796303 -95.618266)
			(xy 189.757972 -95.701766) (xy 189.712604 -95.781663) (xy 189.660537 -95.857364) (xy 189.602154 -95.928308)
			(xy 189.537889 -95.993971) (xy 189.468217 -96.053867) (xy 189.393654 -96.107551) (xy 189.314752 -96.154627)
			(xy 189.232095 -96.194746) (xy 189.146296 -96.227611) (xy 189.057988 -96.252978) (xy 188.967828 -96.27066)
			(xy 188.87648 -96.280526) (xy 188.784623 -96.282503) (xy 188.692936 -96.276576) (xy 188.602098 -96.26279)
			(xy 188.512781 -96.241245) (xy 188.425647 -96.212102) (xy 188.341341 -96.175576) (xy 188.260487 -96.131938)
			(xy 188.183683 -96.081511) (xy 188.111499 -96.024669) (xy 188.044468 -95.961831) (xy 187.983087 -95.893464)
			(xy 187.927811 -95.820074) (xy 187.879048 -95.742203) (xy 187.83716 -95.660428) (xy 187.802457 -95.575356)
			(xy 187.775195 -95.487615) (xy 187.755578 -95.397855) (xy 187.743748 -95.306741) (xy 187.739796 -95.214948)
			(xy 165.509702 -95.214948) (xy 165.509702 -95.261489) (xy 165.501581 -95.354313) (xy 165.485401 -95.446077)
			(xy 165.461286 -95.536081) (xy 165.429417 -95.62364) (xy 165.390039 -95.708089) (xy 165.343451 -95.788785)
			(xy 165.290008 -95.865113) (xy 165.230115 -95.936494) (xy 165.164229 -96.002382) (xy 165.092852 -96.062278)
			(xy 165.016526 -96.115726) (xy 164.935832 -96.162317) (xy 164.851385 -96.201699) (xy 164.763826 -96.233571)
			(xy 164.673824 -96.257691) (xy 164.582061 -96.273875) (xy 164.489237 -96.282) (xy 164.442648 -96.28251)
			(xy 164.442394 -96.28251) (xy 164.395808 -96.281906) (xy 164.30299 -96.273785) (xy 164.211233 -96.257605)
			(xy 164.121235 -96.23349) (xy 164.033681 -96.201622) (xy 163.949238 -96.162246) (xy 163.868549 -96.115659)
			(xy 163.792226 -96.062217) (xy 163.720852 -96.002327) (xy 163.654969 -95.936443) (xy 163.595079 -95.865069)
			(xy 163.541638 -95.788746) (xy 163.495052 -95.708056) (xy 163.455675 -95.623613) (xy 163.423808 -95.536059)
			(xy 163.399694 -95.446062) (xy 163.383515 -95.354304) (xy 163.375394 -95.261486) (xy 73.774772 -95.261486)
			(xy 73.76692 -95.352491) (xy 73.751174 -95.443055) (xy 73.727701 -95.53193) (xy 73.696676 -95.618458)
			(xy 73.658326 -95.701998) (xy 73.612937 -95.781933) (xy 73.560845 -95.85767) (xy 73.502434 -95.928648)
			(xy 73.438139 -95.994342) (xy 73.368433 -96.054266) (xy 73.293835 -96.107976) (xy 73.214895 -96.155075)
			(xy 73.132199 -96.195213) (xy 73.046359 -96.228093) (xy 72.95801 -96.253473) (xy 72.867806 -96.271163)
			(xy 72.776415 -96.281034) (xy 72.684514 -96.283012) (xy 72.592783 -96.277082) (xy 72.501902 -96.263288)
			(xy 72.412543 -96.241734) (xy 72.325367 -96.212577) (xy 72.241021 -96.176034) (xy 72.160128 -96.132375)
			(xy 72.083288 -96.081924) (xy 72.011069 -96.025054) (xy 71.944007 -95.962187) (xy 71.882597 -95.893787)
			(xy 71.827294 -95.820362) (xy 71.778508 -95.742454) (xy 71.7366 -95.660641) (xy 71.70188 -95.575527)
			(xy 71.674606 -95.487745) (xy 71.654979 -95.397942) (xy 71.643144 -95.306785) (xy 71.639189 -95.214948)
			(xy 49.410366 -95.214948) (xy 49.409872 -95.260909) (xy 49.40197 -95.352491) (xy 49.386224 -95.443055)
			(xy 49.362751 -95.53193) (xy 49.331726 -95.618458) (xy 49.293376 -95.701998) (xy 49.247987 -95.781933)
			(xy 49.195895 -95.85767) (xy 49.137484 -95.928648) (xy 49.073189 -95.994342) (xy 49.003483 -96.054266)
			(xy 48.928885 -96.107976) (xy 48.849945 -96.155075) (xy 48.767249 -96.195213) (xy 48.681409 -96.228093)
			(xy 48.59306 -96.253473) (xy 48.502856 -96.271163) (xy 48.411465 -96.281034) (xy 48.319564 -96.283012)
			(xy 48.227833 -96.277082) (xy 48.136952 -96.263288) (xy 48.047593 -96.241734) (xy 47.960417 -96.212577)
			(xy 47.876071 -96.176034) (xy 47.795178 -96.132375) (xy 47.718338 -96.081924) (xy 47.646119 -96.025054)
			(xy 47.579057 -95.962187) (xy 47.517647 -95.893787) (xy 47.462344 -95.820362) (xy 47.413558 -95.742454)
			(xy 47.37165 -95.660641) (xy 47.33693 -95.575527) (xy 47.309656 -95.487745) (xy 47.290029 -95.397942)
			(xy 47.278194 -95.306785) (xy 47.274239 -95.214948) (xy 4.30911 -95.214948) (xy 4.30911 -98.766863)
			(xy 206.090008 -98.766863) (xy 206.090008 -98.633301) (xy 206.098072 -98.499983) (xy 206.114172 -98.367395)
			(xy 206.138247 -98.236021) (xy 206.17021 -98.10634) (xy 206.209945 -97.978826) (xy 206.257307 -97.853943)
			(xy 206.312122 -97.732148) (xy 206.374192 -97.613885) (xy 206.443288 -97.499586) (xy 206.51916 -97.389666)
			(xy 206.60153 -97.284529) (xy 206.690098 -97.184556) (xy 206.78454 -97.090114) (xy 206.884513 -97.001546)
			(xy 206.98965 -96.919176) (xy 207.09957 -96.843304) (xy 207.213869 -96.774208) (xy 207.332132 -96.712138)
			(xy 207.453927 -96.657323) (xy 207.57881 -96.609961) (xy 207.706324 -96.570226) (xy 207.836005 -96.538263)
			(xy 207.967379 -96.514188) (xy 208.099967 -96.498088) (xy 208.233285 -96.490024) (xy 208.366847 -96.490024)
			(xy 208.500165 -96.498088) (xy 208.632753 -96.514188) (xy 208.764127 -96.538263) (xy 208.893808 -96.570226)
			(xy 209.021322 -96.609961) (xy 209.146205 -96.657323) (xy 209.268 -96.712138) (xy 209.386263 -96.774208)
			(xy 209.500562 -96.843304) (xy 209.610482 -96.919176) (xy 209.715619 -97.001546) (xy 209.815592 -97.090114)
			(xy 209.910034 -97.184556) (xy 209.998602 -97.284529) (xy 210.080972 -97.389666) (xy 210.156844 -97.499586)
			(xy 210.22594 -97.613885) (xy 210.28801 -97.732148) (xy 210.342825 -97.853943) (xy 210.390187 -97.978826)
			(xy 210.429922 -98.10634) (xy 210.461885 -98.236021) (xy 210.48596 -98.367395) (xy 210.50206 -98.499983)
			(xy 210.510124 -98.633301) (xy 210.510628 -98.700082) (xy 210.510124 -98.766863) (xy 257.089906 -98.766863)
			(xy 257.089906 -98.633301) (xy 257.09797 -98.499983) (xy 257.11407 -98.367395) (xy 257.138145 -98.236021)
			(xy 257.170108 -98.10634) (xy 257.209843 -97.978826) (xy 257.257205 -97.853943) (xy 257.31202 -97.732148)
			(xy 257.37409 -97.613885) (xy 257.443186 -97.499586) (xy 257.519058 -97.389666) (xy 257.601428 -97.284529)
			(xy 257.689996 -97.184556) (xy 257.784438 -97.090114) (xy 257.884411 -97.001546) (xy 257.989548 -96.919176)
			(xy 258.099468 -96.843304) (xy 258.213767 -96.774208) (xy 258.33203 -96.712138) (xy 258.453825 -96.657323)
			(xy 258.578708 -96.609961) (xy 258.706222 -96.570226) (xy 258.835903 -96.538263) (xy 258.967277 -96.514188)
			(xy 259.099865 -96.498088) (xy 259.233183 -96.490024) (xy 259.366745 -96.490024) (xy 259.500063 -96.498088)
			(xy 259.632651 -96.514188) (xy 259.764025 -96.538263) (xy 259.893706 -96.570226) (xy 260.02122 -96.609961)
			(xy 260.146103 -96.657323) (xy 260.267898 -96.712138) (xy 260.386161 -96.774208) (xy 260.50046 -96.843304)
			(xy 260.61038 -96.919176) (xy 260.715517 -97.001546) (xy 260.81549 -97.090114) (xy 260.909932 -97.184556)
			(xy 260.9985 -97.284529) (xy 261.08087 -97.389666) (xy 261.156742 -97.499586) (xy 261.225838 -97.613885)
			(xy 261.287908 -97.732148) (xy 261.342723 -97.853943) (xy 261.390085 -97.978826) (xy 261.42982 -98.10634)
			(xy 261.461783 -98.236021) (xy 261.485858 -98.367395) (xy 261.501958 -98.499983) (xy 261.510022 -98.633301)
			(xy 261.510526 -98.700082) (xy 261.510022 -98.766863) (xy 261.501958 -98.900181) (xy 261.485858 -99.032769)
			(xy 261.461783 -99.164143) (xy 261.42982 -99.293824) (xy 261.390085 -99.421338) (xy 261.342723 -99.546221)
			(xy 261.287908 -99.668016) (xy 261.225838 -99.786279) (xy 261.156742 -99.900578) (xy 261.08087 -100.010498)
			(xy 260.9985 -100.115635) (xy 260.943379 -100.177854) (xy 269.509748 -100.177854) (xy 269.509748 -99.314254)
			(xy 269.510238 -99.28427) (xy 269.518066 -99.224814) (xy 269.533587 -99.166889) (xy 269.556536 -99.111485)
			(xy 269.58652 -99.059551) (xy 269.623026 -99.011975) (xy 269.665431 -98.96957) (xy 269.713007 -98.933064)
			(xy 269.764941 -98.90308) (xy 269.820345 -98.880131) (xy 269.87827 -98.86461) (xy 269.937726 -98.856782)
			(xy 269.997694 -98.856782) (xy 270.05715 -98.86461) (xy 270.115075 -98.880131) (xy 270.170479 -98.90308)
			(xy 270.222413 -98.933064) (xy 270.269989 -98.96957) (xy 270.312394 -99.011975) (xy 270.3489 -99.059551)
			(xy 270.378884 -99.111485) (xy 270.401833 -99.166889) (xy 270.417354 -99.224814) (xy 270.425182 -99.28427)
			(xy 270.425672 -99.314254) (xy 270.425672 -100.177854) (xy 270.425182 -100.207838) (xy 270.417354 -100.267294)
			(xy 270.401833 -100.325219) (xy 270.394382 -100.343208) (xy 271.060672 -100.343208) (xy 271.060672 -100.100384)
			(xy 271.179544 -99.919028) (xy 271.242028 -99.823524) (xy 271.266158 -99.786694) (xy 271.270041 -99.780374)
			(xy 271.274292 -99.766168) (xy 271.27454 -99.758754) (xy 271.27454 -99.732846) (xy 271.274334 -99.726697)
			(xy 271.271389 -99.714756) (xy 271.268698 -99.709224) (xy 271.15516 -99.535234) (xy 271.135094 -99.504246)
			(xy 271.129506 -99.49561) (xy 271.069054 -99.4029) (xy 271.068546 -99.402138) (xy 271.068038 -99.401376)
			(xy 271.067784 -99.400868) (xy 271.067276 -99.400106) (xy 271.060672 -99.389692) (xy 271.060672 -99.146868)
			(xy 271.061343 -99.135321) (xy 271.071296 -99.114478) (xy 271.089223 -99.099913) (xy 271.100296 -99.096576)
			(xy 271.112234 -99.095052) (xy 271.848834 -99.095052) (xy 271.85959 -99.095586) (xy 271.87928 -99.104241)
			(xy 271.886934 -99.111816) (xy 271.89311 -99.119231) (xy 271.900039 -99.137226) (xy 271.900396 -99.146868)
			(xy 271.900396 -99.389692) (xy 271.684496 -99.720146) (xy 271.680497 -99.728376) (xy 271.677945 -99.74648)
			(xy 271.681881 -99.764335) (xy 271.686528 -99.772216) (xy 271.718786 -99.822) (xy 271.900396 -100.099114)
			(xy 271.900396 -100.248212) (xy 277.63216 -100.248212) (xy 277.63216 -99.241864) (xy 277.632655 -99.231758)
			(xy 277.640397 -99.213087) (xy 277.65469 -99.198794) (xy 277.673362 -99.191054) (xy 277.683468 -99.190556)
			(xy 278.864568 -99.190556) (xy 278.874669 -99.19111) (xy 278.893338 -99.198829) (xy 278.907633 -99.213104)
			(xy 278.915377 -99.231763) (xy 278.915876 -99.241864) (xy 278.915876 -100.248212) (xy 282.1686 -100.248212)
			(xy 282.1686 -99.241864) (xy 282.169056 -99.231753) (xy 282.176805 -99.213074) (xy 282.191111 -99.19878)
			(xy 282.209797 -99.191047) (xy 282.219908 -99.190556) (xy 283.401262 -99.190556) (xy 283.411388 -99.191058)
			(xy 283.430111 -99.198777) (xy 283.44447 -99.213059) (xy 283.452287 -99.231741) (xy 283.452824 -99.241864)
			(xy 283.452824 -100.17633) (xy 285.8389 -100.17633) (xy 285.8389 -99.31273) (xy 285.83939 -99.282746)
			(xy 285.847218 -99.22329) (xy 285.862739 -99.165365) (xy 285.885688 -99.109961) (xy 285.915672 -99.058027)
			(xy 285.952178 -99.010451) (xy 285.994583 -98.968046) (xy 286.042159 -98.93154) (xy 286.094093 -98.901556)
			(xy 286.149497 -98.878607) (xy 286.207422 -98.863086) (xy 286.266878 -98.855258) (xy 286.326846 -98.855258)
			(xy 286.386302 -98.863086) (xy 286.444227 -98.878607) (xy 286.499631 -98.901556) (xy 286.551565 -98.93154)
			(xy 286.599141 -98.968046) (xy 286.641546 -99.010451) (xy 286.678052 -99.058027) (xy 286.708036 -99.109961)
			(xy 286.730985 -99.165365) (xy 286.746506 -99.22329) (xy 286.754334 -99.282746) (xy 286.754824 -99.31273)
			(xy 286.754824 -100.17633) (xy 286.754799 -100.177854) (xy 385.6101 -100.177854) (xy 385.6101 -99.314254)
			(xy 385.61059 -99.284286) (xy 385.618413 -99.224864) (xy 385.633926 -99.166971) (xy 385.656862 -99.111598)
			(xy 385.686829 -99.059692) (xy 385.723316 -99.012142) (xy 385.765696 -98.969762) (xy 385.813246 -98.933275)
			(xy 385.865152 -98.903308) (xy 385.920525 -98.880372) (xy 385.978418 -98.864859) (xy 386.03784 -98.857036)
			(xy 386.097776 -98.857036) (xy 386.157198 -98.864859) (xy 386.215091 -98.880372) (xy 386.270464 -98.903308)
			(xy 386.32237 -98.933275) (xy 386.36992 -98.969762) (xy 386.4123 -99.012142) (xy 386.448787 -99.059692)
			(xy 386.478754 -99.111598) (xy 386.50169 -99.166971) (xy 386.517203 -99.224864) (xy 386.525026 -99.284286)
			(xy 386.525516 -99.314254) (xy 386.525516 -100.177854) (xy 386.525026 -100.207822) (xy 386.517203 -100.267244)
			(xy 386.50169 -100.325137) (xy 386.494205 -100.343208) (xy 387.160516 -100.343208) (xy 387.160516 -100.115624)
			(xy 387.16077 -100.11156) (xy 387.161024 -100.10902) (xy 387.161024 -100.100384) (xy 387.166612 -100.091748)
			(xy 387.167882 -100.089716) (xy 387.168898 -100.087684) (xy 387.366256 -99.786694) (xy 387.370139 -99.780374)
			(xy 387.37439 -99.766168) (xy 387.374638 -99.758754) (xy 387.374638 -99.7331) (xy 387.374453 -99.725764)
			(xy 387.370309 -99.711693) (xy 387.36651 -99.705414) (xy 387.168644 -99.402392) (xy 387.166358 -99.398582)
			(xy 387.166104 -99.398074) (xy 387.165088 -99.396296) (xy 387.161024 -99.389692) (xy 387.161024 -99.381564)
			(xy 387.16077 -99.379024) (xy 387.160516 -99.37496) (xy 387.160516 -99.146868) (xy 387.160956 -99.136654)
			(xy 387.168786 -99.117786) (xy 387.183239 -99.10335) (xy 387.202118 -99.095544) (xy 387.212332 -99.095052)
			(xy 387.948932 -99.095052) (xy 387.959138 -99.095555) (xy 387.977994 -99.103372) (xy 387.992428 -99.117806)
			(xy 388.000245 -99.136662) (xy 388.000748 -99.146868) (xy 388.000748 -99.374452) (xy 388.000494 -99.378516)
			(xy 388.00024 -99.381056) (xy 388.00024 -99.389692) (xy 387.994398 -99.39909) (xy 387.993636 -99.40036)
			(xy 387.992366 -99.402392) (xy 387.786626 -99.717098) (xy 387.781537 -99.725601) (xy 387.777725 -99.745032)
			(xy 387.781561 -99.764458) (xy 387.786626 -99.772978) (xy 387.992366 -100.086414) (xy 387.993382 -100.088446)
			(xy 387.994652 -100.090478) (xy 388.00024 -100.099114) (xy 388.00024 -100.10775) (xy 388.000494 -100.11029)
			(xy 388.000748 -100.114354) (xy 388.000748 -100.248212) (xy 393.732004 -100.248212) (xy 393.732004 -99.241864)
			(xy 393.732392 -99.231707) (xy 393.7402 -99.212953) (xy 393.754607 -99.198631) (xy 393.773407 -99.190933)
			(xy 393.783566 -99.190556) (xy 394.964666 -99.190556) (xy 394.974792 -99.191055) (xy 394.993516 -99.198775)
			(xy 395.007874 -99.213058) (xy 395.015691 -99.23174) (xy 395.016228 -99.241864) (xy 395.016228 -100.248212)
			(xy 398.268952 -100.248212) (xy 398.268952 -99.241864) (xy 398.269454 -99.231759) (xy 398.277195 -99.213089)
			(xy 398.291486 -99.198797) (xy 398.310155 -99.191055) (xy 398.32026 -99.190556) (xy 399.50136 -99.190556)
			(xy 399.511474 -99.191048) (xy 399.530169 -99.198775) (xy 399.544483 -99.213067) (xy 399.552237 -99.23175)
			(xy 399.552668 -99.241864) (xy 399.552668 -100.17633) (xy 401.939252 -100.17633) (xy 401.939252 -99.31273)
			(xy 401.939742 -99.282762) (xy 401.947565 -99.22334) (xy 401.963078 -99.165447) (xy 401.986014 -99.110074)
			(xy 402.015981 -99.058168) (xy 402.052468 -99.010618) (xy 402.094848 -98.968238) (xy 402.142398 -98.931751)
			(xy 402.194304 -98.901784) (xy 402.249677 -98.878848) (xy 402.30757 -98.863335) (xy 402.366992 -98.855512)
			(xy 402.426928 -98.855512) (xy 402.48635 -98.863335) (xy 402.544243 -98.878848) (xy 402.599616 -98.901784)
			(xy 402.651522 -98.931751) (xy 402.699072 -98.968238) (xy 402.741452 -99.010618) (xy 402.777939 -99.058168)
			(xy 402.807906 -99.110074) (xy 402.830842 -99.165447) (xy 402.846355 -99.22334) (xy 402.854178 -99.282762)
			(xy 402.854668 -99.31273) (xy 402.854668 -100.17633) (xy 402.854178 -100.206298) (xy 402.846355 -100.26572)
			(xy 402.830842 -100.323613) (xy 402.807906 -100.378986) (xy 402.777939 -100.430892) (xy 402.741452 -100.478442)
			(xy 402.699072 -100.520822) (xy 402.651522 -100.557309) (xy 402.599616 -100.587276) (xy 402.544243 -100.610212)
			(xy 402.48635 -100.625725) (xy 402.426928 -100.633548) (xy 402.366992 -100.633548) (xy 402.30757 -100.625725)
			(xy 402.249677 -100.610212) (xy 402.194304 -100.587276) (xy 402.142398 -100.557309) (xy 402.094848 -100.520822)
			(xy 402.052468 -100.478442) (xy 402.015981 -100.430892) (xy 401.986014 -100.378986) (xy 401.963078 -100.323613)
			(xy 401.947565 -100.26572) (xy 401.939742 -100.206298) (xy 401.939252 -100.17633) (xy 399.552668 -100.17633)
			(xy 399.552668 -100.248212) (xy 399.552293 -100.258339) (xy 399.544535 -100.277049) (xy 399.530206 -100.291364)
			(xy 399.511488 -100.299104) (xy 399.50136 -100.29952) (xy 398.32026 -100.29952) (xy 398.310151 -100.299048)
			(xy 398.291476 -100.291301) (xy 398.277183 -100.277001) (xy 398.269446 -100.258321) (xy 398.268952 -100.248212)
			(xy 395.016228 -100.248212) (xy 395.015789 -100.258363) (xy 395.007995 -100.277111) (xy 394.993604 -100.291433)
			(xy 394.974819 -100.299137) (xy 394.964666 -100.29952) (xy 393.783566 -100.29952) (xy 393.773432 -100.2991)
			(xy 393.754703 -100.291354) (xy 393.740346 -100.277047) (xy 393.732535 -100.258344) (xy 393.732004 -100.248212)
			(xy 388.000748 -100.248212) (xy 388.000748 -100.343208) (xy 388.000225 -100.353412) (xy 387.992416 -100.372268)
			(xy 387.977988 -100.386703) (xy 387.959136 -100.394521) (xy 387.948932 -100.395024) (xy 387.212332 -100.395024)
			(xy 387.202113 -100.394562) (xy 387.183228 -100.386751) (xy 387.168772 -100.372305) (xy 387.160946 -100.353426)
			(xy 387.160516 -100.343208) (xy 386.494205 -100.343208) (xy 386.478754 -100.38051) (xy 386.448787 -100.432416)
			(xy 386.4123 -100.479966) (xy 386.36992 -100.522346) (xy 386.32237 -100.558833) (xy 386.270464 -100.5888)
			(xy 386.215091 -100.611736) (xy 386.157198 -100.627249) (xy 386.097776 -100.635072) (xy 386.03784 -100.635072)
			(xy 385.978418 -100.627249) (xy 385.920525 -100.611736) (xy 385.865152 -100.5888) (xy 385.813246 -100.558833)
			(xy 385.765696 -100.522346) (xy 385.723316 -100.479966) (xy 385.686829 -100.432416) (xy 385.656862 -100.38051)
			(xy 385.633926 -100.325137) (xy 385.618413 -100.267244) (xy 385.61059 -100.207822) (xy 385.6101 -100.177854)
			(xy 286.754799 -100.177854) (xy 286.754334 -100.206314) (xy 286.746506 -100.26577) (xy 286.730985 -100.323695)
			(xy 286.708036 -100.379099) (xy 286.678052 -100.431033) (xy 286.641546 -100.478609) (xy 286.599141 -100.521014)
			(xy 286.551565 -100.55752) (xy 286.499631 -100.587504) (xy 286.444227 -100.610453) (xy 286.386302 -100.625974)
			(xy 286.326846 -100.633802) (xy 286.266878 -100.633802) (xy 286.207422 -100.625974) (xy 286.149497 -100.610453)
			(xy 286.094093 -100.587504) (xy 286.042159 -100.55752) (xy 285.994583 -100.521014) (xy 285.952178 -100.478609)
			(xy 285.915672 -100.431033) (xy 285.885688 -100.379099) (xy 285.862739 -100.323695) (xy 285.847218 -100.26577)
			(xy 285.83939 -100.206314) (xy 285.8389 -100.17633) (xy 283.452824 -100.17633) (xy 283.452824 -100.248212)
			(xy 283.452325 -100.258318) (xy 283.444588 -100.276992) (xy 283.430296 -100.291286) (xy 283.411622 -100.299024)
			(xy 283.401516 -100.29952) (xy 282.220162 -100.29952) (xy 282.210028 -100.299103) (xy 282.191298 -100.291356)
			(xy 282.176942 -100.277048) (xy 282.169131 -100.258344) (xy 282.1686 -100.248212) (xy 278.915876 -100.248212)
			(xy 278.915494 -100.258338) (xy 278.907737 -100.277047) (xy 278.89341 -100.291362) (xy 278.874695 -100.299102)
			(xy 278.864568 -100.29952) (xy 277.683468 -100.29952) (xy 277.67336 -100.299042) (xy 277.654685 -100.291297)
			(xy 277.640392 -100.276999) (xy 277.632654 -100.258321) (xy 277.63216 -100.248212) (xy 271.900396 -100.248212)
			(xy 271.900396 -100.343208) (xy 271.89973 -100.354757) (xy 271.889779 -100.375603) (xy 271.871848 -100.390167)
			(xy 271.860772 -100.3935) (xy 271.848834 -100.395024) (xy 271.112234 -100.395024) (xy 271.101479 -100.394485)
			(xy 271.081791 -100.385831) (xy 271.074134 -100.37826) (xy 271.067944 -100.370855) (xy 271.061025 -100.352853)
			(xy 271.060672 -100.343208) (xy 270.394382 -100.343208) (xy 270.378884 -100.380623) (xy 270.3489 -100.432557)
			(xy 270.312394 -100.480133) (xy 270.269989 -100.522538) (xy 270.222413 -100.559044) (xy 270.170479 -100.589028)
			(xy 270.115075 -100.611977) (xy 270.05715 -100.627498) (xy 269.997694 -100.635326) (xy 269.937726 -100.635326)
			(xy 269.87827 -100.627498) (xy 269.820345 -100.611977) (xy 269.764941 -100.589028) (xy 269.713007 -100.559044)
			(xy 269.665431 -100.522538) (xy 269.623026 -100.480133) (xy 269.58652 -100.432557) (xy 269.556536 -100.380623)
			(xy 269.533587 -100.325219) (xy 269.518066 -100.267294) (xy 269.510238 -100.207838) (xy 269.509748 -100.177854)
			(xy 260.943379 -100.177854) (xy 260.909932 -100.215608) (xy 260.81549 -100.31005) (xy 260.715517 -100.398618)
			(xy 260.61038 -100.480988) (xy 260.50046 -100.55686) (xy 260.386161 -100.625956) (xy 260.267898 -100.688026)
			(xy 260.146103 -100.742841) (xy 260.02122 -100.790203) (xy 259.893706 -100.829938) (xy 259.764025 -100.861901)
			(xy 259.632651 -100.885976) (xy 259.500063 -100.902076) (xy 259.366745 -100.91014) (xy 259.233183 -100.91014)
			(xy 259.099865 -100.902076) (xy 258.967277 -100.885976) (xy 258.835903 -100.861901) (xy 258.706222 -100.829938)
			(xy 258.578708 -100.790203) (xy 258.453825 -100.742841) (xy 258.33203 -100.688026) (xy 258.213767 -100.625956)
			(xy 258.099468 -100.55686) (xy 257.989548 -100.480988) (xy 257.884411 -100.398618) (xy 257.784438 -100.31005)
			(xy 257.689996 -100.215608) (xy 257.601428 -100.115635) (xy 257.519058 -100.010498) (xy 257.443186 -99.900578)
			(xy 257.37409 -99.786279) (xy 257.31202 -99.668016) (xy 257.257205 -99.546221) (xy 257.209843 -99.421338)
			(xy 257.170108 -99.293824) (xy 257.138145 -99.164143) (xy 257.11407 -99.032769) (xy 257.09797 -98.900181)
			(xy 257.089906 -98.766863) (xy 210.510124 -98.766863) (xy 210.50206 -98.900181) (xy 210.48596 -99.032769)
			(xy 210.461885 -99.164143) (xy 210.429922 -99.293824) (xy 210.390187 -99.421338) (xy 210.342825 -99.546221)
			(xy 210.28801 -99.668016) (xy 210.22594 -99.786279) (xy 210.156844 -99.900578) (xy 210.080972 -100.010498)
			(xy 209.998602 -100.115635) (xy 209.910034 -100.215608) (xy 209.815592 -100.31005) (xy 209.715619 -100.398618)
			(xy 209.610482 -100.480988) (xy 209.500562 -100.55686) (xy 209.386263 -100.625956) (xy 209.268 -100.688026)
			(xy 209.146205 -100.742841) (xy 209.021322 -100.790203) (xy 208.893808 -100.829938) (xy 208.764127 -100.861901)
			(xy 208.632753 -100.885976) (xy 208.500165 -100.902076) (xy 208.366847 -100.91014) (xy 208.233285 -100.91014)
			(xy 208.099967 -100.902076) (xy 207.967379 -100.885976) (xy 207.836005 -100.861901) (xy 207.706324 -100.829938)
			(xy 207.57881 -100.790203) (xy 207.453927 -100.742841) (xy 207.332132 -100.688026) (xy 207.213869 -100.625956)
			(xy 207.09957 -100.55686) (xy 206.98965 -100.480988) (xy 206.884513 -100.398618) (xy 206.78454 -100.31005)
			(xy 206.690098 -100.215608) (xy 206.60153 -100.115635) (xy 206.51916 -100.010498) (xy 206.443288 -99.900578)
			(xy 206.374192 -99.786279) (xy 206.312122 -99.668016) (xy 206.257307 -99.546221) (xy 206.209945 -99.421338)
			(xy 206.17021 -99.293824) (xy 206.138247 -99.164143) (xy 206.114172 -99.032769) (xy 206.098072 -98.900181)
			(xy 206.090008 -98.766863) (xy 4.30911 -98.766863) (xy 4.30911 -100.177854) (xy 37.31006 -100.177854)
			(xy 37.31006 -99.314254) (xy 37.31055 -99.284286) (xy 37.318373 -99.224864) (xy 37.333886 -99.166971)
			(xy 37.356822 -99.111598) (xy 37.386789 -99.059692) (xy 37.423276 -99.012142) (xy 37.465656 -98.969762)
			(xy 37.513206 -98.933275) (xy 37.565112 -98.903308) (xy 37.620485 -98.880372) (xy 37.678378 -98.864859)
			(xy 37.7378 -98.857036) (xy 37.797736 -98.857036) (xy 37.857158 -98.864859) (xy 37.915051 -98.880372)
			(xy 37.970424 -98.903308) (xy 38.02233 -98.933275) (xy 38.06988 -98.969762) (xy 38.11226 -99.012142)
			(xy 38.148747 -99.059692) (xy 38.178714 -99.111598) (xy 38.20165 -99.166971) (xy 38.217163 -99.224864)
			(xy 38.224986 -99.284286) (xy 38.225476 -99.314254) (xy 38.225476 -100.177854) (xy 38.224986 -100.207822)
			(xy 38.217163 -100.267244) (xy 38.20165 -100.325137) (xy 38.194165 -100.343208) (xy 38.860476 -100.343208)
			(xy 38.860476 -100.115624) (xy 38.86073 -100.11156) (xy 38.860984 -100.10902) (xy 38.860984 -100.100384)
			(xy 38.866572 -100.091748) (xy 38.867842 -100.089716) (xy 38.868858 -100.087684) (xy 39.074598 -99.773994)
			(xy 39.078662 -99.767644) (xy 39.080694 -99.760786) (xy 39.08425 -99.750118) (xy 39.081202 -99.727258)
			(xy 38.868604 -99.402392) (xy 38.866318 -99.398582) (xy 38.866064 -99.398074) (xy 38.865048 -99.396296)
			(xy 38.860984 -99.389692) (xy 38.860984 -99.381564) (xy 38.86073 -99.379024) (xy 38.860476 -99.37496)
			(xy 38.860476 -99.146868) (xy 38.860955 -99.136659) (xy 38.868777 -99.117798) (xy 38.883218 -99.103364)
			(xy 38.902083 -99.095551) (xy 38.912292 -99.095052) (xy 39.648892 -99.095052) (xy 39.659095 -99.095588)
			(xy 39.677951 -99.103392) (xy 39.692386 -99.117816) (xy 39.700205 -99.136665) (xy 39.700708 -99.146868)
			(xy 39.700708 -99.374452) (xy 39.700454 -99.378516) (xy 39.7002 -99.381056) (xy 39.7002 -99.389692)
			(xy 39.694358 -99.39909) (xy 39.693596 -99.40036) (xy 39.692326 -99.402392) (xy 39.481506 -99.724718)
			(xy 39.479474 -99.734116) (xy 39.477775 -99.744101) (xy 39.481433 -99.764005) (xy 39.486586 -99.772724)
			(xy 39.692326 -100.086414) (xy 39.693342 -100.088446) (xy 39.694612 -100.090478) (xy 39.7002 -100.099114)
			(xy 39.7002 -100.10775) (xy 39.700454 -100.11029) (xy 39.700708 -100.114354) (xy 39.700708 -100.248212)
			(xy 45.431964 -100.248212) (xy 45.431964 -99.241864) (xy 45.432391 -99.231712) (xy 45.440192 -99.212966)
			(xy 45.454586 -99.198645) (xy 45.473372 -99.19094) (xy 45.483526 -99.190556) (xy 46.664626 -99.190556)
			(xy 46.674756 -99.191006) (xy 46.693481 -99.198745) (xy 46.707837 -99.213043) (xy 46.715653 -99.231736)
			(xy 46.716188 -99.241864) (xy 46.716188 -100.248212) (xy 49.968912 -100.248212) (xy 49.968912 -99.241864)
			(xy 49.969356 -99.231751) (xy 49.977108 -99.21307) (xy 49.991417 -99.198776) (xy 50.010107 -99.191045)
			(xy 50.02022 -99.190556) (xy 51.20132 -99.190556) (xy 51.211425 -99.191067) (xy 51.230095 -99.198804)
			(xy 51.244387 -99.213092) (xy 51.252129 -99.23176) (xy 51.252628 -99.241864) (xy 51.252628 -100.17633)
			(xy 53.639212 -100.17633) (xy 53.639212 -99.31273) (xy 53.639702 -99.282762) (xy 53.647525 -99.22334)
			(xy 53.663038 -99.165447) (xy 53.685974 -99.110074) (xy 53.715941 -99.058168) (xy 53.752428 -99.010618)
			(xy 53.794808 -98.968238) (xy 53.842358 -98.931751) (xy 53.894264 -98.901784) (xy 53.949637 -98.878848)
			(xy 54.00753 -98.863335) (xy 54.066952 -98.855512) (xy 54.126888 -98.855512) (xy 54.18631 -98.863335)
			(xy 54.244203 -98.878848) (xy 54.299576 -98.901784) (xy 54.351482 -98.931751) (xy 54.399032 -98.968238)
			(xy 54.441412 -99.010618) (xy 54.477899 -99.058168) (xy 54.507866 -99.110074) (xy 54.530802 -99.165447)
			(xy 54.546315 -99.22334) (xy 54.554138 -99.282762) (xy 54.554628 -99.31273) (xy 54.554628 -100.17633)
			(xy 54.554603 -100.177854) (xy 153.409904 -100.177854) (xy 153.409904 -99.314254) (xy 153.410394 -99.28427)
			(xy 153.418222 -99.224814) (xy 153.433743 -99.166889) (xy 153.456692 -99.111485) (xy 153.486676 -99.059551)
			(xy 153.523182 -99.011975) (xy 153.565587 -98.96957) (xy 153.613163 -98.933064) (xy 153.665097 -98.90308)
			(xy 153.720501 -98.880131) (xy 153.778426 -98.86461) (xy 153.837882 -98.856782) (xy 153.89785 -98.856782)
			(xy 153.957306 -98.86461) (xy 154.015231 -98.880131) (xy 154.070635 -98.90308) (xy 154.122569 -98.933064)
			(xy 154.170145 -98.96957) (xy 154.21255 -99.011975) (xy 154.249056 -99.059551) (xy 154.27904 -99.111485)
			(xy 154.301989 -99.166889) (xy 154.31751 -99.224814) (xy 154.325338 -99.28427) (xy 154.325828 -99.314254)
			(xy 154.325828 -100.177854) (xy 154.325338 -100.207838) (xy 154.31751 -100.267294) (xy 154.301989 -100.325219)
			(xy 154.294538 -100.343208) (xy 154.96032 -100.343208) (xy 154.96032 -100.115624) (xy 154.960574 -100.11156)
			(xy 154.960828 -100.10902) (xy 154.960828 -100.100384) (xy 154.966416 -100.091748) (xy 154.967686 -100.089716)
			(xy 154.968702 -100.087684) (xy 155.16606 -99.786694) (xy 155.169944 -99.780374) (xy 155.174194 -99.766168)
			(xy 155.174442 -99.758754) (xy 155.174442 -99.7331) (xy 155.174257 -99.725764) (xy 155.170113 -99.711693)
			(xy 155.166314 -99.705414) (xy 154.968448 -99.402392) (xy 154.966162 -99.398582) (xy 154.965908 -99.398074)
			(xy 154.964892 -99.396296) (xy 154.960828 -99.389692) (xy 154.960828 -99.381564) (xy 154.960574 -99.379024)
			(xy 154.96032 -99.37496) (xy 154.96032 -99.146868) (xy 154.960687 -99.13664) (xy 154.968527 -99.117745)
			(xy 154.983002 -99.103289) (xy 155.001907 -99.095473) (xy 155.012136 -99.095052) (xy 155.748736 -99.095052)
			(xy 155.758942 -99.095551) (xy 155.777798 -99.10337) (xy 155.792232 -99.117805) (xy 155.800049 -99.136662)
			(xy 155.800552 -99.146868) (xy 155.800552 -99.374452) (xy 155.800298 -99.378516) (xy 155.800044 -99.381056)
			(xy 155.800044 -99.389692) (xy 155.794202 -99.39909) (xy 155.79344 -99.40036) (xy 155.79217 -99.402392)
			(xy 155.58643 -99.717098) (xy 155.58134 -99.725601) (xy 155.577529 -99.745032) (xy 155.581365 -99.764458)
			(xy 155.58643 -99.772978) (xy 155.79217 -100.086414) (xy 155.793186 -100.088446) (xy 155.794456 -100.090478)
			(xy 155.800044 -100.099114) (xy 155.800044 -100.10775) (xy 155.800298 -100.11029) (xy 155.800552 -100.114354)
			(xy 155.800552 -100.248212) (xy 161.531808 -100.248212) (xy 161.531808 -99.241864) (xy 161.532192 -99.231707)
			(xy 161.540001 -99.212952) (xy 161.554409 -99.198629) (xy 161.57321 -99.190932) (xy 161.58337 -99.190556)
			(xy 162.76447 -99.190556) (xy 162.774597 -99.191051) (xy 162.79332 -99.198772) (xy 162.807678 -99.213056)
			(xy 162.815496 -99.23174) (xy 162.816032 -99.241864) (xy 162.816032 -100.248212) (xy 166.068756 -100.248212)
			(xy 166.068756 -99.241864) (xy 166.069255 -99.231758) (xy 166.076996 -99.213088) (xy 166.091288 -99.198796)
			(xy 166.109958 -99.191055) (xy 166.120064 -99.190556) (xy 167.301164 -99.190556) (xy 167.311265 -99.191114)
			(xy 167.329934 -99.198831) (xy 167.344228 -99.213106) (xy 167.351972 -99.231764) (xy 167.352472 -99.241864)
			(xy 167.352472 -100.17633) (xy 169.739056 -100.17633) (xy 169.739056 -99.31273) (xy 169.739546 -99.282746)
			(xy 169.747374 -99.22329) (xy 169.762895 -99.165365) (xy 169.785844 -99.109961) (xy 169.815828 -99.058027)
			(xy 169.852334 -99.010451) (xy 169.894739 -98.968046) (xy 169.942315 -98.93154) (xy 169.994249 -98.901556)
			(xy 170.049653 -98.878607) (xy 170.107578 -98.863086) (xy 170.167034 -98.855258) (xy 170.227002 -98.855258)
			(xy 170.286458 -98.863086) (xy 170.344383 -98.878607) (xy 170.399787 -98.901556) (xy 170.451721 -98.93154)
			(xy 170.499297 -98.968046) (xy 170.541702 -99.010451) (xy 170.578208 -99.058027) (xy 170.608192 -99.109961)
			(xy 170.631141 -99.165365) (xy 170.646662 -99.22329) (xy 170.65449 -99.282746) (xy 170.65498 -99.31273)
			(xy 170.65498 -100.17633) (xy 170.65449 -100.206314) (xy 170.646662 -100.26577) (xy 170.631141 -100.323695)
			(xy 170.608192 -100.379099) (xy 170.578208 -100.431033) (xy 170.541702 -100.478609) (xy 170.499297 -100.521014)
			(xy 170.451721 -100.55752) (xy 170.399787 -100.587504) (xy 170.344383 -100.610453) (xy 170.286458 -100.625974)
			(xy 170.227002 -100.633802) (xy 170.167034 -100.633802) (xy 170.107578 -100.625974) (xy 170.049653 -100.610453)
			(xy 169.994249 -100.587504) (xy 169.942315 -100.55752) (xy 169.894739 -100.521014) (xy 169.852334 -100.478609)
			(xy 169.815828 -100.431033) (xy 169.785844 -100.379099) (xy 169.762895 -100.323695) (xy 169.747374 -100.26577)
			(xy 169.739546 -100.206314) (xy 169.739056 -100.17633) (xy 167.352472 -100.17633) (xy 167.352472 -100.248212)
			(xy 167.352093 -100.258339) (xy 167.344336 -100.277048) (xy 167.330008 -100.291363) (xy 167.311291 -100.299103)
			(xy 167.301164 -100.29952) (xy 166.120064 -100.29952) (xy 166.109955 -100.299045) (xy 166.09128 -100.291299)
			(xy 166.076987 -100.277) (xy 166.06925 -100.258321) (xy 166.068756 -100.248212) (xy 162.816032 -100.248212)
			(xy 162.815589 -100.258363) (xy 162.807796 -100.27711) (xy 162.793406 -100.291431) (xy 162.774623 -100.299136)
			(xy 162.76447 -100.29952) (xy 161.58337 -100.29952) (xy 161.573236 -100.299097) (xy 161.554507 -100.291352)
			(xy 161.54015 -100.277046) (xy 161.532339 -100.258344) (xy 161.531808 -100.248212) (xy 155.800552 -100.248212)
			(xy 155.800552 -100.343208) (xy 155.800025 -100.353412) (xy 155.792217 -100.372267) (xy 155.77779 -100.386701)
			(xy 155.75894 -100.39452) (xy 155.748736 -100.395024) (xy 155.012136 -100.395024) (xy 155.001918 -100.394559)
			(xy 154.983033 -100.386749) (xy 154.968576 -100.372304) (xy 154.96075 -100.353426) (xy 154.96032 -100.343208)
			(xy 154.294538 -100.343208) (xy 154.27904 -100.380623) (xy 154.249056 -100.432557) (xy 154.21255 -100.480133)
			(xy 154.170145 -100.522538) (xy 154.122569 -100.559044) (xy 154.070635 -100.589028) (xy 154.015231 -100.611977)
			(xy 153.957306 -100.627498) (xy 153.89785 -100.635326) (xy 153.837882 -100.635326) (xy 153.778426 -100.627498)
			(xy 153.720501 -100.611977) (xy 153.665097 -100.589028) (xy 153.613163 -100.559044) (xy 153.565587 -100.522538)
			(xy 153.523182 -100.480133) (xy 153.486676 -100.432557) (xy 153.456692 -100.380623) (xy 153.433743 -100.325219)
			(xy 153.418222 -100.267294) (xy 153.410394 -100.207838) (xy 153.409904 -100.177854) (xy 54.554603 -100.177854)
			(xy 54.554138 -100.206298) (xy 54.546315 -100.26572) (xy 54.530802 -100.323613) (xy 54.507866 -100.378986)
			(xy 54.477899 -100.430892) (xy 54.441412 -100.478442) (xy 54.399032 -100.520822) (xy 54.351482 -100.557309)
			(xy 54.299576 -100.587276) (xy 54.244203 -100.610212) (xy 54.18631 -100.625725) (xy 54.126888 -100.633548)
			(xy 54.066952 -100.633548) (xy 54.00753 -100.625725) (xy 53.949637 -100.610212) (xy 53.894264 -100.587276)
			(xy 53.842358 -100.557309) (xy 53.794808 -100.520822) (xy 53.752428 -100.478442) (xy 53.715941 -100.430892)
			(xy 53.685974 -100.378986) (xy 53.663038 -100.323613) (xy 53.647525 -100.26572) (xy 53.639702 -100.206298)
			(xy 53.639212 -100.17633) (xy 51.252628 -100.17633) (xy 51.252628 -100.248212) (xy 51.252125 -100.258318)
			(xy 51.244389 -100.276991) (xy 51.230098 -100.291284) (xy 51.211426 -100.299024) (xy 51.20132 -100.29952)
			(xy 50.02022 -100.29952) (xy 50.010101 -100.299068) (xy 49.991402 -100.29133) (xy 49.977088 -100.277025)
			(xy 49.969338 -100.25833) (xy 49.968912 -100.248212) (xy 46.716188 -100.248212) (xy 46.715788 -100.258368)
			(xy 46.707986 -100.277124) (xy 46.693583 -100.291447) (xy 46.674785 -100.299144) (xy 46.664626 -100.29952)
			(xy 45.483526 -100.29952) (xy 45.473396 -100.299051) (xy 45.454668 -100.291325) (xy 45.440309 -100.277032)
			(xy 45.432496 -100.25834) (xy 45.431964 -100.248212) (xy 39.700708 -100.248212) (xy 39.700708 -100.343208)
			(xy 39.700224 -100.353417) (xy 39.692408 -100.372281) (xy 39.677967 -100.386717) (xy 39.659101 -100.394528)
			(xy 39.648892 -100.395024) (xy 38.912292 -100.395024) (xy 38.902085 -100.394525) (xy 38.883224 -100.386711)
			(xy 38.868789 -100.372276) (xy 38.860975 -100.353415) (xy 38.860476 -100.343208) (xy 38.194165 -100.343208)
			(xy 38.178714 -100.38051) (xy 38.148747 -100.432416) (xy 38.11226 -100.479966) (xy 38.06988 -100.522346)
			(xy 38.02233 -100.558833) (xy 37.970424 -100.5888) (xy 37.915051 -100.611736) (xy 37.857158 -100.627249)
			(xy 37.797736 -100.635072) (xy 37.7378 -100.635072) (xy 37.678378 -100.627249) (xy 37.620485 -100.611736)
			(xy 37.565112 -100.5888) (xy 37.513206 -100.558833) (xy 37.465656 -100.522346) (xy 37.423276 -100.479966)
			(xy 37.386789 -100.432416) (xy 37.356822 -100.38051) (xy 37.333886 -100.325137) (xy 37.318373 -100.267244)
			(xy 37.31055 -100.207822) (xy 37.31006 -100.177854) (xy 4.30911 -100.177854) (xy 4.30911 -101.984302)
			(xy 35.277552 -101.984302) (xy 35.277552 -101.120702) (xy 35.278042 -101.090734) (xy 35.285865 -101.031312)
			(xy 35.301378 -100.973419) (xy 35.324314 -100.918046) (xy 35.354281 -100.86614) (xy 35.390768 -100.81859)
			(xy 35.433148 -100.77621) (xy 35.480698 -100.739723) (xy 35.532604 -100.709756) (xy 35.587977 -100.68682)
			(xy 35.64587 -100.671307) (xy 35.705292 -100.663484) (xy 35.765228 -100.663484) (xy 35.82465 -100.671307)
			(xy 35.882543 -100.68682) (xy 35.937916 -100.709756) (xy 35.989822 -100.739723) (xy 36.037372 -100.77621)
			(xy 36.079752 -100.81859) (xy 36.116239 -100.86614) (xy 36.146206 -100.918046) (xy 36.169142 -100.973419)
			(xy 36.184655 -101.031312) (xy 36.192478 -101.090734) (xy 36.192968 -101.120702) (xy 36.192968 -101.984302)
			(xy 36.192478 -102.01427) (xy 36.184655 -102.073692) (xy 36.169142 -102.131585) (xy 36.161657 -102.149656)
			(xy 36.827968 -102.149656) (xy 36.827968 -101.922072) (xy 36.828222 -101.918008) (xy 36.828476 -101.915468)
			(xy 36.828476 -101.906832) (xy 36.834064 -101.898196) (xy 36.835334 -101.896164) (xy 36.83635 -101.894132)
			(xy 37.04209 -101.580442) (xy 37.046154 -101.574092) (xy 37.048186 -101.567234) (xy 37.051742 -101.556566)
			(xy 37.048694 -101.533706) (xy 36.836096 -101.20884) (xy 36.83381 -101.20503) (xy 36.833556 -101.204522)
			(xy 36.83254 -101.202744) (xy 36.828476 -101.19614) (xy 36.828476 -101.188012) (xy 36.828222 -101.185472)
			(xy 36.827968 -101.181408) (xy 36.827968 -100.953316) (xy 36.828494 -100.943111) (xy 36.836299 -100.924253)
			(xy 36.850726 -100.909817) (xy 36.869579 -100.902001) (xy 36.879784 -100.9015) (xy 37.616384 -100.9015)
			(xy 37.626607 -100.901926) (xy 37.645497 -100.909747) (xy 37.659953 -100.924203) (xy 37.667774 -100.943093)
			(xy 37.6682 -100.953316) (xy 37.6682 -101.1809) (xy 37.667946 -101.184964) (xy 37.667692 -101.187504)
			(xy 37.667692 -101.19614) (xy 37.66185 -101.205538) (xy 37.661088 -101.206808) (xy 37.659818 -101.20884)
			(xy 37.448998 -101.531166) (xy 37.446966 -101.540564) (xy 37.445241 -101.550546) (xy 37.448917 -101.570454)
			(xy 37.454078 -101.579172) (xy 37.659818 -101.892862) (xy 37.660834 -101.894894) (xy 37.662104 -101.896926)
			(xy 37.667692 -101.905562) (xy 37.667692 -101.914198) (xy 37.667946 -101.916738) (xy 37.6682 -101.920802)
			(xy 37.6682 -102.04831) (xy 45.431964 -102.04831) (xy 45.431964 -101.041962) (xy 45.432403 -101.031799)
			(xy 45.440195 -101.013024) (xy 45.454577 -100.998659) (xy 45.473362 -100.99089) (xy 45.483526 -100.9904)
			(xy 46.664626 -100.9904) (xy 46.674781 -100.990911) (xy 46.693543 -100.998687) (xy 46.707906 -101.013047)
			(xy 46.715687 -101.031807) (xy 46.716188 -101.041962) (xy 46.716188 -102.04831) (xy 46.716175 -102.048564)
			(xy 49.968912 -102.048564) (xy 49.968912 -101.041962) (xy 49.969395 -101.031836) (xy 49.97713 -101.01312)
			(xy 49.991416 -100.998766) (xy 50.010097 -100.990943) (xy 50.02022 -100.9904) (xy 51.20132 -100.9904)
			(xy 51.21143 -100.990869) (xy 51.230109 -100.998613) (xy 51.244403 -101.012915) (xy 51.252137 -101.031598)
			(xy 51.252628 -101.041708) (xy 51.252628 -101.976428) (xy 51.785012 -101.976428) (xy 51.785012 -101.112828)
			(xy 51.785502 -101.08286) (xy 51.793325 -101.023438) (xy 51.808838 -100.965545) (xy 51.831774 -100.910172)
			(xy 51.861741 -100.858266) (xy 51.898228 -100.810716) (xy 51.940608 -100.768336) (xy 51.988158 -100.731849)
			(xy 52.040064 -100.701882) (xy 52.095437 -100.678946) (xy 52.15333 -100.663433) (xy 52.212752 -100.65561)
			(xy 52.272688 -100.65561) (xy 52.33211 -100.663433) (xy 52.390003 -100.678946) (xy 52.445376 -100.701882)
			(xy 52.497282 -100.731849) (xy 52.544832 -100.768336) (xy 52.587212 -100.810716) (xy 52.623699 -100.858266)
			(xy 52.653666 -100.910172) (xy 52.676602 -100.965545) (xy 52.692115 -101.023438) (xy 52.699938 -101.08286)
			(xy 52.700428 -101.112828) (xy 52.700428 -101.976428) (xy 52.700299 -101.984302) (xy 151.377396 -101.984302)
			(xy 151.377396 -101.120702) (xy 151.377886 -101.090718) (xy 151.385714 -101.031262) (xy 151.401235 -100.973337)
			(xy 151.424184 -100.917933) (xy 151.454168 -100.865999) (xy 151.490674 -100.818423) (xy 151.533079 -100.776018)
			(xy 151.580655 -100.739512) (xy 151.632589 -100.709528) (xy 151.687993 -100.686579) (xy 151.745918 -100.671058)
			(xy 151.805374 -100.66323) (xy 151.865342 -100.66323) (xy 151.924798 -100.671058) (xy 151.982723 -100.686579)
			(xy 152.038127 -100.709528) (xy 152.090061 -100.739512) (xy 152.137637 -100.776018) (xy 152.180042 -100.818423)
			(xy 152.216548 -100.865999) (xy 152.246532 -100.917933) (xy 152.269481 -100.973337) (xy 152.285002 -101.031262)
			(xy 152.29283 -101.090718) (xy 152.29332 -101.120702) (xy 152.29332 -101.984302) (xy 152.29283 -102.014286)
			(xy 152.285002 -102.073742) (xy 152.269481 -102.131667) (xy 152.26203 -102.149656) (xy 152.927812 -102.149656)
			(xy 152.927812 -101.922072) (xy 152.928066 -101.918008) (xy 152.92832 -101.915468) (xy 152.92832 -101.906832)
			(xy 152.933908 -101.898196) (xy 152.935178 -101.896164) (xy 152.936194 -101.894132) (xy 153.133552 -101.593142)
			(xy 153.137417 -101.586812) (xy 153.141679 -101.572614) (xy 153.141934 -101.565202) (xy 153.141934 -101.539548)
			(xy 153.14173 -101.532214) (xy 153.137599 -101.518142) (xy 153.133806 -101.511862) (xy 152.93594 -101.20884)
			(xy 152.933654 -101.20503) (xy 152.9334 -101.204522) (xy 152.932384 -101.202744) (xy 152.92832 -101.19614)
			(xy 152.92832 -101.188012) (xy 152.928066 -101.185472) (xy 152.927812 -101.181408) (xy 152.927812 -100.953316)
			(xy 152.928226 -100.943092) (xy 152.936049 -100.9242) (xy 152.95051 -100.909742) (xy 152.969404 -100.901923)
			(xy 152.979628 -100.9015) (xy 153.716228 -100.9015) (xy 153.72644 -100.901959) (xy 153.745305 -100.909784)
			(xy 153.759741 -100.924232) (xy 153.76755 -100.943104) (xy 153.768044 -100.953316) (xy 153.768044 -101.1809)
			(xy 153.76779 -101.184964) (xy 153.767536 -101.187504) (xy 153.767536 -101.19614) (xy 153.761694 -101.205538)
			(xy 153.760932 -101.206808) (xy 153.759662 -101.20884) (xy 153.553922 -101.523546) (xy 153.548877 -101.532072)
			(xy 153.545051 -101.551488) (xy 153.548868 -101.570907) (xy 153.553922 -101.579426) (xy 153.759662 -101.892862)
			(xy 153.760678 -101.894894) (xy 153.761948 -101.896926) (xy 153.767536 -101.905562) (xy 153.767536 -101.914198)
			(xy 153.76779 -101.916738) (xy 153.768044 -101.920802) (xy 153.768044 -102.04831) (xy 161.531808 -102.04831)
			(xy 161.531808 -101.041962) (xy 161.532302 -101.031805) (xy 161.540083 -101.013041) (xy 161.554448 -100.998678)
			(xy 161.573213 -100.9909) (xy 161.58337 -100.9904) (xy 162.76447 -100.9904) (xy 162.774621 -100.990957)
			(xy 162.793383 -100.998714) (xy 162.807748 -101.01306) (xy 162.81553 -101.031811) (xy 162.816032 -101.041962)
			(xy 162.816032 -102.04831) (xy 162.816022 -102.048564) (xy 166.068756 -102.048564) (xy 166.068756 -101.041962)
			(xy 166.069196 -101.031831) (xy 166.076939 -101.013106) (xy 166.09124 -100.99875) (xy 166.109935 -100.990935)
			(xy 166.120064 -100.9904) (xy 167.301164 -100.9904) (xy 167.311284 -100.990846) (xy 167.329987 -100.998582)
			(xy 167.344302 -101.01289) (xy 167.352049 -101.031588) (xy 167.352472 -101.041708) (xy 167.352472 -101.976428)
			(xy 167.884856 -101.976428) (xy 167.884856 -101.112828) (xy 167.885346 -101.082844) (xy 167.893174 -101.023388)
			(xy 167.908695 -100.965463) (xy 167.931644 -100.910059) (xy 167.961628 -100.858125) (xy 167.998134 -100.810549)
			(xy 168.040539 -100.768144) (xy 168.088115 -100.731638) (xy 168.140049 -100.701654) (xy 168.195453 -100.678705)
			(xy 168.253378 -100.663184) (xy 168.312834 -100.655356) (xy 168.372802 -100.655356) (xy 168.432258 -100.663184)
			(xy 168.490183 -100.678705) (xy 168.545587 -100.701654) (xy 168.597521 -100.731638) (xy 168.645097 -100.768144)
			(xy 168.687502 -100.810549) (xy 168.724008 -100.858125) (xy 168.753992 -100.910059) (xy 168.776941 -100.965463)
			(xy 168.792462 -101.023388) (xy 168.80029 -101.082844) (xy 168.80078 -101.112828) (xy 168.80078 -101.976428)
			(xy 168.800651 -101.984302) (xy 267.47724 -101.984302) (xy 267.47724 -101.120702) (xy 267.47773 -101.090718)
			(xy 267.485558 -101.031262) (xy 267.501079 -100.973337) (xy 267.524028 -100.917933) (xy 267.554012 -100.865999)
			(xy 267.590518 -100.818423) (xy 267.632923 -100.776018) (xy 267.680499 -100.739512) (xy 267.732433 -100.709528)
			(xy 267.787837 -100.686579) (xy 267.845762 -100.671058) (xy 267.905218 -100.66323) (xy 267.965186 -100.66323)
			(xy 268.024642 -100.671058) (xy 268.082567 -100.686579) (xy 268.137971 -100.709528) (xy 268.189905 -100.739512)
			(xy 268.237481 -100.776018) (xy 268.279886 -100.818423) (xy 268.316392 -100.865999) (xy 268.346376 -100.917933)
			(xy 268.369325 -100.973337) (xy 268.384846 -101.031262) (xy 268.392674 -101.090718) (xy 268.393164 -101.120702)
			(xy 268.393164 -101.984302) (xy 268.392674 -102.014286) (xy 268.384846 -102.073742) (xy 268.369325 -102.131667)
			(xy 268.361874 -102.149656) (xy 269.028164 -102.149656) (xy 269.028164 -101.906832) (xy 269.147036 -101.725476)
			(xy 269.20952 -101.629972) (xy 269.23365 -101.593142) (xy 269.237515 -101.586812) (xy 269.241777 -101.572614)
			(xy 269.242032 -101.565202) (xy 269.242032 -101.539294) (xy 269.241845 -101.533144) (xy 269.238887 -101.521203)
			(xy 269.23619 -101.515672) (xy 269.122652 -101.341682) (xy 269.102586 -101.310694) (xy 269.096998 -101.302058)
			(xy 269.036546 -101.209348) (xy 269.036038 -101.208586) (xy 269.03553 -101.207824) (xy 269.035276 -101.207316)
			(xy 269.034768 -101.206554) (xy 269.028164 -101.19614) (xy 269.028164 -100.953316) (xy 269.028801 -100.941766)
			(xy 269.038772 -100.920923) (xy 269.05671 -100.90636) (xy 269.067788 -100.903024) (xy 269.079726 -100.9015)
			(xy 269.816326 -100.9015) (xy 269.827079 -100.902054) (xy 269.846768 -100.910697) (xy 269.854426 -100.918264)
			(xy 269.860622 -100.925665) (xy 269.867539 -100.94367) (xy 269.867888 -100.953316) (xy 269.867888 -101.19614)
			(xy 269.651988 -101.526594) (xy 269.647951 -101.534808) (xy 269.645414 -101.552923) (xy 269.649365 -101.570783)
			(xy 269.65402 -101.578664) (xy 269.686278 -101.628448) (xy 269.867888 -101.905562) (xy 269.867888 -102.04831)
			(xy 277.63216 -102.04831) (xy 277.63216 -101.041962) (xy 277.632596 -101.03183) (xy 277.64034 -101.013105)
			(xy 277.654642 -100.998749) (xy 277.673338 -100.990935) (xy 277.683468 -100.9904) (xy 278.864568 -100.9904)
			(xy 278.87472 -100.990848) (xy 278.893472 -100.998633) (xy 278.907796 -101.013022) (xy 278.915497 -101.031808)
			(xy 278.915876 -101.041962) (xy 278.915876 -102.04831) (xy 282.1686 -102.04831) (xy 282.1686 -101.041962)
			(xy 282.169101 -101.031806) (xy 282.176881 -101.013044) (xy 282.191244 -100.998681) (xy 282.210006 -100.990901)
			(xy 282.220162 -100.9904) (xy 283.401262 -100.9904) (xy 283.411413 -100.990964) (xy 283.430174 -100.998719)
			(xy 283.444539 -101.013063) (xy 283.452321 -101.031812) (xy 283.452824 -101.041962) (xy 283.452824 -101.976428)
			(xy 283.9847 -101.976428) (xy 283.9847 -101.112828) (xy 283.98519 -101.082844) (xy 283.993018 -101.023388)
			(xy 284.008539 -100.965463) (xy 284.031488 -100.910059) (xy 284.061472 -100.858125) (xy 284.097978 -100.810549)
			(xy 284.140383 -100.768144) (xy 284.187959 -100.731638) (xy 284.239893 -100.701654) (xy 284.295297 -100.678705)
			(xy 284.353222 -100.663184) (xy 284.412678 -100.655356) (xy 284.472646 -100.655356) (xy 284.532102 -100.663184)
			(xy 284.590027 -100.678705) (xy 284.645431 -100.701654) (xy 284.697365 -100.731638) (xy 284.744941 -100.768144)
			(xy 284.787346 -100.810549) (xy 284.823852 -100.858125) (xy 284.853836 -100.910059) (xy 284.876785 -100.965463)
			(xy 284.892306 -101.023388) (xy 284.900134 -101.082844) (xy 284.900624 -101.112828) (xy 284.900624 -101.976428)
			(xy 284.900495 -101.984302) (xy 383.577592 -101.984302) (xy 383.577592 -101.120702) (xy 383.578082 -101.090734)
			(xy 383.585905 -101.031312) (xy 383.601418 -100.973419) (xy 383.624354 -100.918046) (xy 383.654321 -100.86614)
			(xy 383.690808 -100.81859) (xy 383.733188 -100.77621) (xy 383.780738 -100.739723) (xy 383.832644 -100.709756)
			(xy 383.888017 -100.68682) (xy 383.94591 -100.671307) (xy 384.005332 -100.663484) (xy 384.065268 -100.663484)
			(xy 384.12469 -100.671307) (xy 384.182583 -100.68682) (xy 384.237956 -100.709756) (xy 384.289862 -100.739723)
			(xy 384.337412 -100.77621) (xy 384.379792 -100.81859) (xy 384.416279 -100.86614) (xy 384.446246 -100.918046)
			(xy 384.469182 -100.973419) (xy 384.484695 -101.031312) (xy 384.492518 -101.090734) (xy 384.493008 -101.120702)
			(xy 384.493008 -101.984302) (xy 384.492518 -102.01427) (xy 384.484695 -102.073692) (xy 384.469182 -102.131585)
			(xy 384.461697 -102.149656) (xy 385.128008 -102.149656) (xy 385.128008 -101.922072) (xy 385.128262 -101.918008)
			(xy 385.128516 -101.915468) (xy 385.128516 -101.906832) (xy 385.134104 -101.898196) (xy 385.135374 -101.896164)
			(xy 385.13639 -101.894132) (xy 385.333748 -101.593142) (xy 385.337613 -101.586812) (xy 385.341875 -101.572614)
			(xy 385.34213 -101.565202) (xy 385.34213 -101.539548) (xy 385.341927 -101.532214) (xy 385.337795 -101.518142)
			(xy 385.334002 -101.511862) (xy 385.136136 -101.20884) (xy 385.13385 -101.20503) (xy 385.133596 -101.204522)
			(xy 385.13258 -101.202744) (xy 385.128516 -101.19614) (xy 385.128516 -101.188012) (xy 385.128262 -101.185472)
			(xy 385.128008 -101.181408) (xy 385.128008 -100.953316) (xy 385.128426 -100.943092) (xy 385.136248 -100.924201)
			(xy 385.150708 -100.909744) (xy 385.1696 -100.901924) (xy 385.179824 -100.9015) (xy 385.916424 -100.9015)
			(xy 385.926635 -100.901962) (xy 385.945501 -100.909786) (xy 385.959936 -100.924233) (xy 385.967745 -100.943104)
			(xy 385.96824 -100.953316) (xy 385.96824 -101.1809) (xy 385.967986 -101.184964) (xy 385.967732 -101.187504)
			(xy 385.967732 -101.19614) (xy 385.96189 -101.205538) (xy 385.961128 -101.206808) (xy 385.959858 -101.20884)
			(xy 385.754118 -101.523546) (xy 385.749073 -101.532072) (xy 385.745248 -101.551488) (xy 385.749064 -101.570906)
			(xy 385.754118 -101.579426) (xy 385.959858 -101.892862) (xy 385.960874 -101.894894) (xy 385.962144 -101.896926)
			(xy 385.967732 -101.905562) (xy 385.967732 -101.914198) (xy 385.967986 -101.916738) (xy 385.96824 -101.920802)
			(xy 385.96824 -102.04831) (xy 393.732004 -102.04831) (xy 393.732004 -101.041962) (xy 393.732501 -101.031806)
			(xy 393.740282 -101.013042) (xy 393.754646 -100.99868) (xy 393.77341 -100.990901) (xy 393.783566 -100.9904)
			(xy 394.964666 -100.9904) (xy 394.974817 -100.99096) (xy 394.993578 -100.998717) (xy 395.007943 -101.013062)
			(xy 395.015725 -101.031812) (xy 395.016228 -101.041962) (xy 395.016228 -102.04831) (xy 395.016218 -102.048564)
			(xy 398.268952 -102.048564) (xy 398.268952 -101.041962) (xy 398.269396 -101.031831) (xy 398.277138 -101.013107)
			(xy 398.291438 -100.998752) (xy 398.310131 -100.990936) (xy 398.32026 -100.9904) (xy 399.50136 -100.9904)
			(xy 399.51148 -100.990849) (xy 399.530183 -100.998584) (xy 399.544498 -101.012891) (xy 399.552245 -101.031588)
			(xy 399.552668 -101.041708) (xy 399.552668 -101.976428) (xy 400.085052 -101.976428) (xy 400.085052 -101.112828)
			(xy 400.085542 -101.08286) (xy 400.093365 -101.023438) (xy 400.108878 -100.965545) (xy 400.131814 -100.910172)
			(xy 400.161781 -100.858266) (xy 400.198268 -100.810716) (xy 400.240648 -100.768336) (xy 400.288198 -100.731849)
			(xy 400.340104 -100.701882) (xy 400.395477 -100.678946) (xy 400.45337 -100.663433) (xy 400.512792 -100.65561)
			(xy 400.572728 -100.65561) (xy 400.63215 -100.663433) (xy 400.690043 -100.678946) (xy 400.745416 -100.701882)
			(xy 400.797322 -100.731849) (xy 400.844872 -100.768336) (xy 400.887252 -100.810716) (xy 400.923739 -100.858266)
			(xy 400.953706 -100.910172) (xy 400.976642 -100.965545) (xy 400.992155 -101.023438) (xy 400.999978 -101.08286)
			(xy 401.000468 -101.112828) (xy 401.000468 -101.976428) (xy 400.999978 -102.006396) (xy 400.992155 -102.065818)
			(xy 400.976642 -102.123711) (xy 400.953706 -102.179084) (xy 400.923739 -102.23099) (xy 400.887252 -102.27854)
			(xy 400.844872 -102.32092) (xy 400.797322 -102.357407) (xy 400.745416 -102.387374) (xy 400.690043 -102.41031)
			(xy 400.63215 -102.425823) (xy 400.572728 -102.433646) (xy 400.512792 -102.433646) (xy 400.45337 -102.425823)
			(xy 400.395477 -102.41031) (xy 400.340104 -102.387374) (xy 400.288198 -102.357407) (xy 400.240648 -102.32092)
			(xy 400.198268 -102.27854) (xy 400.161781 -102.23099) (xy 400.131814 -102.179084) (xy 400.108878 -102.123711)
			(xy 400.093365 -102.065818) (xy 400.085542 -102.006396) (xy 400.085052 -101.976428) (xy 399.552668 -101.976428)
			(xy 399.552668 -102.04831) (xy 399.552182 -102.058436) (xy 399.544452 -102.077156) (xy 399.530166 -102.091512)
			(xy 399.511484 -102.099332) (xy 399.50136 -102.099872) (xy 398.32026 -102.099872) (xy 398.310145 -102.099447)
			(xy 398.291461 -102.091691) (xy 398.277166 -102.077375) (xy 398.269438 -102.058679) (xy 398.268952 -102.048564)
			(xy 395.016218 -102.048564) (xy 395.015843 -102.058486) (xy 395.008049 -102.077288) (xy 394.993651 -102.091674)
			(xy 394.974843 -102.099452) (xy 394.964666 -102.099872) (xy 393.783566 -102.099872) (xy 393.773407 -102.099395)
			(xy 393.754639 -102.091611) (xy 393.740276 -102.077241) (xy 393.732501 -102.058469) (xy 393.732004 -102.04831)
			(xy 385.96824 -102.04831) (xy 385.96824 -102.149656) (xy 385.967753 -102.159872) (xy 385.959948 -102.178754)
			(xy 385.945511 -102.19321) (xy 385.926639 -102.201039) (xy 385.916424 -102.201472) (xy 385.179824 -102.201472)
			(xy 385.169598 -102.201067) (xy 385.150703 -102.193244) (xy 385.136245 -102.17878) (xy 385.128429 -102.159882)
			(xy 385.128008 -102.149656) (xy 384.461697 -102.149656) (xy 384.446246 -102.186958) (xy 384.416279 -102.238864)
			(xy 384.379792 -102.286414) (xy 384.337412 -102.328794) (xy 384.289862 -102.365281) (xy 384.237956 -102.395248)
			(xy 384.182583 -102.418184) (xy 384.12469 -102.433697) (xy 384.065268 -102.44152) (xy 384.005332 -102.44152)
			(xy 383.94591 -102.433697) (xy 383.888017 -102.418184) (xy 383.832644 -102.395248) (xy 383.780738 -102.365281)
			(xy 383.733188 -102.328794) (xy 383.690808 -102.286414) (xy 383.654321 -102.238864) (xy 383.624354 -102.186958)
			(xy 383.601418 -102.131585) (xy 383.585905 -102.073692) (xy 383.578082 -102.01427) (xy 383.577592 -101.984302)
			(xy 284.900495 -101.984302) (xy 284.900134 -102.006412) (xy 284.892306 -102.065868) (xy 284.876785 -102.123793)
			(xy 284.853836 -102.179197) (xy 284.823852 -102.231131) (xy 284.787346 -102.278707) (xy 284.744941 -102.321112)
			(xy 284.697365 -102.357618) (xy 284.645431 -102.387602) (xy 284.590027 -102.410551) (xy 284.532102 -102.426072)
			(xy 284.472646 -102.4339) (xy 284.412678 -102.4339) (xy 284.353222 -102.426072) (xy 284.295297 -102.410551)
			(xy 284.239893 -102.387602) (xy 284.187959 -102.357618) (xy 284.140383 -102.321112) (xy 284.097978 -102.278707)
			(xy 284.061472 -102.231131) (xy 284.031488 -102.179197) (xy 284.008539 -102.123793) (xy 283.993018 -102.065868)
			(xy 283.98519 -102.006412) (xy 283.9847 -101.976428) (xy 283.452824 -101.976428) (xy 283.452824 -102.04831)
			(xy 283.452443 -102.058487) (xy 283.444648 -102.077289) (xy 283.430249 -102.091675) (xy 283.411439 -102.099453)
			(xy 283.401262 -102.099872) (xy 282.220162 -102.099872) (xy 282.210003 -102.099398) (xy 282.191235 -102.091613)
			(xy 282.176871 -102.077242) (xy 282.169096 -102.058469) (xy 282.1686 -102.04831) (xy 278.915876 -102.04831)
			(xy 278.915382 -102.058435) (xy 278.907654 -102.077154) (xy 278.89337 -102.091509) (xy 278.874691 -102.099331)
			(xy 278.864568 -102.099872) (xy 277.683468 -102.099872) (xy 277.673308 -102.099504) (xy 277.65455 -102.091693)
			(xy 277.640227 -102.077279) (xy 277.632533 -102.058472) (xy 277.63216 -102.04831) (xy 269.867888 -102.04831)
			(xy 269.867888 -102.149656) (xy 269.867265 -102.161209) (xy 269.857293 -102.182058) (xy 269.839346 -102.196618)
			(xy 269.828264 -102.199948) (xy 269.816326 -102.201472) (xy 269.079726 -102.201472) (xy 269.068968 -102.200953)
			(xy 269.049279 -102.192286) (xy 269.041626 -102.184708) (xy 269.035412 -102.17732) (xy 269.028507 -102.159305)
			(xy 269.028164 -102.149656) (xy 268.361874 -102.149656) (xy 268.346376 -102.187071) (xy 268.316392 -102.239005)
			(xy 268.279886 -102.286581) (xy 268.237481 -102.328986) (xy 268.189905 -102.365492) (xy 268.137971 -102.395476)
			(xy 268.082567 -102.418425) (xy 268.024642 -102.433946) (xy 267.965186 -102.441774) (xy 267.905218 -102.441774)
			(xy 267.845762 -102.433946) (xy 267.787837 -102.418425) (xy 267.732433 -102.395476) (xy 267.680499 -102.365492)
			(xy 267.632923 -102.328986) (xy 267.590518 -102.286581) (xy 267.554012 -102.239005) (xy 267.524028 -102.187071)
			(xy 267.501079 -102.131667) (xy 267.485558 -102.073742) (xy 267.47773 -102.014286) (xy 267.47724 -101.984302)
			(xy 168.800651 -101.984302) (xy 168.80029 -102.006412) (xy 168.792462 -102.065868) (xy 168.776941 -102.123793)
			(xy 168.753992 -102.179197) (xy 168.724008 -102.231131) (xy 168.687502 -102.278707) (xy 168.645097 -102.321112)
			(xy 168.597521 -102.357618) (xy 168.545587 -102.387602) (xy 168.490183 -102.410551) (xy 168.432258 -102.426072)
			(xy 168.372802 -102.4339) (xy 168.312834 -102.4339) (xy 168.253378 -102.426072) (xy 168.195453 -102.410551)
			(xy 168.140049 -102.387602) (xy 168.088115 -102.357618) (xy 168.040539 -102.321112) (xy 167.998134 -102.278707)
			(xy 167.961628 -102.231131) (xy 167.931644 -102.179197) (xy 167.908695 -102.123793) (xy 167.893174 -102.065868)
			(xy 167.885346 -102.006412) (xy 167.884856 -101.976428) (xy 167.352472 -101.976428) (xy 167.352472 -102.04831)
			(xy 167.351982 -102.058436) (xy 167.344253 -102.077155) (xy 167.329968 -102.09151) (xy 167.311287 -102.099331)
			(xy 167.301164 -102.099872) (xy 166.120064 -102.099872) (xy 166.109949 -102.099444) (xy 166.091265 -102.091689)
			(xy 166.076971 -102.077374) (xy 166.069242 -102.058679) (xy 166.068756 -102.048564) (xy 162.816022 -102.048564)
			(xy 162.815644 -102.058486) (xy 162.80785 -102.077287) (xy 162.793453 -102.091672) (xy 162.774646 -102.099451)
			(xy 162.76447 -102.099872) (xy 161.58337 -102.099872) (xy 161.573212 -102.099392) (xy 161.554444 -102.091609)
			(xy 161.54008 -102.07724) (xy 161.532305 -102.058469) (xy 161.531808 -102.04831) (xy 153.768044 -102.04831)
			(xy 153.768044 -102.149656) (xy 153.767553 -102.159871) (xy 153.759749 -102.178752) (xy 153.745313 -102.193209)
			(xy 153.726443 -102.201039) (xy 153.716228 -102.201472) (xy 152.979628 -102.201472) (xy 152.969403 -102.201064)
			(xy 152.950508 -102.193242) (xy 152.936049 -102.178779) (xy 152.928233 -102.159881) (xy 152.927812 -102.149656)
			(xy 152.26203 -102.149656) (xy 152.246532 -102.187071) (xy 152.216548 -102.239005) (xy 152.180042 -102.286581)
			(xy 152.137637 -102.328986) (xy 152.090061 -102.365492) (xy 152.038127 -102.395476) (xy 151.982723 -102.418425)
			(xy 151.924798 -102.433946) (xy 151.865342 -102.441774) (xy 151.805374 -102.441774) (xy 151.745918 -102.433946)
			(xy 151.687993 -102.418425) (xy 151.632589 -102.395476) (xy 151.580655 -102.365492) (xy 151.533079 -102.328986)
			(xy 151.490674 -102.286581) (xy 151.454168 -102.239005) (xy 151.424184 -102.187071) (xy 151.401235 -102.131667)
			(xy 151.385714 -102.073742) (xy 151.377886 -102.014286) (xy 151.377396 -101.984302) (xy 52.700299 -101.984302)
			(xy 52.699938 -102.006396) (xy 52.692115 -102.065818) (xy 52.676602 -102.123711) (xy 52.653666 -102.179084)
			(xy 52.623699 -102.23099) (xy 52.587212 -102.27854) (xy 52.544832 -102.32092) (xy 52.497282 -102.357407)
			(xy 52.445376 -102.387374) (xy 52.390003 -102.41031) (xy 52.33211 -102.425823) (xy 52.272688 -102.433646)
			(xy 52.212752 -102.433646) (xy 52.15333 -102.425823) (xy 52.095437 -102.41031) (xy 52.040064 -102.387374)
			(xy 51.988158 -102.357407) (xy 51.940608 -102.32092) (xy 51.898228 -102.27854) (xy 51.861741 -102.23099)
			(xy 51.831774 -102.179084) (xy 51.808838 -102.123711) (xy 51.793325 -102.065818) (xy 51.785502 -102.006396)
			(xy 51.785012 -101.976428) (xy 51.252628 -101.976428) (xy 51.252628 -102.04831) (xy 51.252181 -102.058441)
			(xy 51.244444 -102.077169) (xy 51.230145 -102.091526) (xy 51.211449 -102.099339) (xy 51.20132 -102.099872)
			(xy 50.02022 -102.099872) (xy 50.010095 -102.099467) (xy 49.991387 -102.09172) (xy 49.977071 -102.0774)
			(xy 49.96933 -102.058689) (xy 49.968912 -102.048564) (xy 46.716175 -102.048564) (xy 46.715675 -102.058465)
			(xy 46.707902 -102.077229) (xy 46.693543 -102.091593) (xy 46.674781 -102.099372) (xy 46.664626 -102.099872)
			(xy 45.483526 -102.099872) (xy 45.473357 -102.099415) (xy 45.454565 -102.09164) (xy 45.44018 -102.077265)
			(xy 45.432392 -102.058478) (xy 45.431964 -102.04831) (xy 37.6682 -102.04831) (xy 37.6682 -102.149656)
			(xy 37.667752 -102.159877) (xy 37.65994 -102.178766) (xy 37.64549 -102.193224) (xy 37.626605 -102.201046)
			(xy 37.616384 -102.201472) (xy 36.879784 -102.201472) (xy 36.869556 -102.2011) (xy 36.85066 -102.193263)
			(xy 36.836203 -102.17879) (xy 36.828388 -102.159885) (xy 36.827968 -102.149656) (xy 36.161657 -102.149656)
			(xy 36.146206 -102.186958) (xy 36.116239 -102.238864) (xy 36.079752 -102.286414) (xy 36.037372 -102.328794)
			(xy 35.989822 -102.365281) (xy 35.937916 -102.395248) (xy 35.882543 -102.418184) (xy 35.82465 -102.433697)
			(xy 35.765228 -102.44152) (xy 35.705292 -102.44152) (xy 35.64587 -102.433697) (xy 35.587977 -102.418184)
			(xy 35.532604 -102.395248) (xy 35.480698 -102.365281) (xy 35.433148 -102.328794) (xy 35.390768 -102.286414)
			(xy 35.354281 -102.238864) (xy 35.324314 -102.186958) (xy 35.301378 -102.131585) (xy 35.285865 -102.073692)
			(xy 35.278042 -102.01427) (xy 35.277552 -101.984302) (xy 4.30911 -101.984302) (xy 4.30911 -103.777796)
			(xy 37.31006 -103.777796) (xy 37.31006 -102.914196) (xy 37.31055 -102.884228) (xy 37.318373 -102.824806)
			(xy 37.333886 -102.766913) (xy 37.356822 -102.71154) (xy 37.386789 -102.659634) (xy 37.423276 -102.612084)
			(xy 37.465656 -102.569704) (xy 37.513206 -102.533217) (xy 37.565112 -102.50325) (xy 37.620485 -102.480314)
			(xy 37.678378 -102.464801) (xy 37.7378 -102.456978) (xy 37.797736 -102.456978) (xy 37.857158 -102.464801)
			(xy 37.915051 -102.480314) (xy 37.970424 -102.50325) (xy 38.02233 -102.533217) (xy 38.06988 -102.569704)
			(xy 38.11226 -102.612084) (xy 38.148747 -102.659634) (xy 38.178714 -102.71154) (xy 38.20165 -102.766913)
			(xy 38.217163 -102.824806) (xy 38.224986 -102.884228) (xy 38.225476 -102.914196) (xy 38.225476 -103.777796)
			(xy 38.224986 -103.807764) (xy 38.217163 -103.867186) (xy 38.20165 -103.925079) (xy 38.194165 -103.94315)
			(xy 38.860476 -103.94315) (xy 38.860476 -103.715566) (xy 38.86073 -103.711502) (xy 38.860984 -103.708962)
			(xy 38.860984 -103.700326) (xy 38.866572 -103.69169) (xy 38.867842 -103.689658) (xy 38.868858 -103.687626)
			(xy 39.074598 -103.373936) (xy 39.078662 -103.367586) (xy 39.080694 -103.360728) (xy 39.08425 -103.35006)
			(xy 39.081202 -103.3272) (xy 38.868604 -103.002334) (xy 38.866318 -102.998524) (xy 38.866064 -102.998016)
			(xy 38.865048 -102.996238) (xy 38.860984 -102.989634) (xy 38.860984 -102.981506) (xy 38.86073 -102.978966)
			(xy 38.860476 -102.974902) (xy 38.860476 -102.74681) (xy 38.860873 -102.736634) (xy 38.868662 -102.717833)
			(xy 38.883056 -102.703446) (xy 38.901862 -102.695667) (xy 38.912038 -102.695248) (xy 39.648892 -102.695248)
			(xy 39.659064 -102.69578) (xy 39.67787 -102.703537) (xy 39.692296 -102.71788) (xy 39.70016 -102.736641)
			(xy 39.700708 -102.74681) (xy 39.700708 -102.974394) (xy 39.700454 -102.978458) (xy 39.7002 -102.980998)
			(xy 39.7002 -102.989634) (xy 39.694358 -102.999032) (xy 39.693596 -103.000302) (xy 39.692326 -103.002334)
			(xy 39.481506 -103.32466) (xy 39.479474 -103.334058) (xy 39.477751 -103.344041) (xy 39.481426 -103.363948)
			(xy 39.486586 -103.372666) (xy 39.692326 -103.686356) (xy 39.693342 -103.688388) (xy 39.694612 -103.69042)
			(xy 39.7002 -103.699056) (xy 39.7002 -103.707692) (xy 39.700454 -103.710232) (xy 39.700708 -103.714296)
			(xy 39.700708 -103.848408) (xy 45.431964 -103.848408) (xy 45.431964 -102.84206) (xy 45.432388 -102.831908)
			(xy 45.44019 -102.813161) (xy 45.454585 -102.798841) (xy 45.473372 -102.791136) (xy 45.483526 -102.790752)
			(xy 46.664626 -102.790752) (xy 46.674756 -102.791205) (xy 46.69348 -102.798944) (xy 46.707836 -102.81324)
			(xy 46.715652 -102.831932) (xy 46.716188 -102.84206) (xy 46.716188 -103.848408) (xy 49.968912 -103.848408)
			(xy 49.968912 -102.84206) (xy 49.969353 -102.831947) (xy 49.977106 -102.813266) (xy 49.991416 -102.798972)
			(xy 50.010107 -102.791241) (xy 50.02022 -102.790752) (xy 51.20132 -102.790752) (xy 51.211424 -102.791267)
			(xy 51.230094 -102.799003) (xy 51.244386 -102.81329) (xy 51.252129 -102.831956) (xy 51.252628 -102.84206)
			(xy 51.252628 -103.776272) (xy 53.639212 -103.776272) (xy 53.639212 -102.912672) (xy 53.639702 -102.882704)
			(xy 53.647525 -102.823282) (xy 53.663038 -102.765389) (xy 53.685974 -102.710016) (xy 53.715941 -102.65811)
			(xy 53.752428 -102.61056) (xy 53.794808 -102.56818) (xy 53.842358 -102.531693) (xy 53.894264 -102.501726)
			(xy 53.949637 -102.47879) (xy 54.00753 -102.463277) (xy 54.066952 -102.455454) (xy 54.126888 -102.455454)
			(xy 54.18631 -102.463277) (xy 54.244203 -102.47879) (xy 54.299576 -102.501726) (xy 54.351482 -102.531693)
			(xy 54.399032 -102.56818) (xy 54.441412 -102.61056) (xy 54.477899 -102.65811) (xy 54.507866 -102.710016)
			(xy 54.530802 -102.765389) (xy 54.546315 -102.823282) (xy 54.554138 -102.882704) (xy 54.554628 -102.912672)
			(xy 54.554628 -103.776272) (xy 54.554603 -103.777796) (xy 153.409904 -103.777796) (xy 153.409904 -102.914196)
			(xy 153.410394 -102.884212) (xy 153.418222 -102.824756) (xy 153.433743 -102.766831) (xy 153.456692 -102.711427)
			(xy 153.486676 -102.659493) (xy 153.523182 -102.611917) (xy 153.565587 -102.569512) (xy 153.613163 -102.533006)
			(xy 153.665097 -102.503022) (xy 153.720501 -102.480073) (xy 153.778426 -102.464552) (xy 153.837882 -102.456724)
			(xy 153.89785 -102.456724) (xy 153.957306 -102.464552) (xy 154.015231 -102.480073) (xy 154.070635 -102.503022)
			(xy 154.122569 -102.533006) (xy 154.170145 -102.569512) (xy 154.21255 -102.611917) (xy 154.249056 -102.659493)
			(xy 154.27904 -102.711427) (xy 154.301989 -102.766831) (xy 154.31751 -102.824756) (xy 154.325338 -102.884212)
			(xy 154.325828 -102.914196) (xy 154.325828 -103.777796) (xy 154.325338 -103.80778) (xy 154.31751 -103.867236)
			(xy 154.301989 -103.925161) (xy 154.294538 -103.94315) (xy 154.96032 -103.94315) (xy 154.96032 -103.715566)
			(xy 154.960574 -103.711502) (xy 154.960828 -103.708962) (xy 154.960828 -103.700326) (xy 154.966416 -103.69169)
			(xy 154.967686 -103.689658) (xy 154.968702 -103.687626) (xy 155.16606 -103.386636) (xy 155.169928 -103.380308)
			(xy 155.174188 -103.366108) (xy 155.174442 -103.358696) (xy 155.174442 -103.333042) (xy 155.174239 -103.325708)
			(xy 155.170107 -103.311636) (xy 155.166314 -103.305356) (xy 154.968448 -103.002334) (xy 154.966162 -102.998524)
			(xy 154.965908 -102.998016) (xy 154.964892 -102.996238) (xy 154.960828 -102.989634) (xy 154.960828 -102.981506)
			(xy 154.960574 -102.978966) (xy 154.96032 -102.974902) (xy 154.96032 -102.74681) (xy 154.960841 -102.736655)
			(xy 154.968609 -102.71789) (xy 154.982966 -102.703525) (xy 155.001727 -102.695747) (xy 155.011882 -102.695248)
			(xy 155.748736 -102.695248) (xy 155.75891 -102.695744) (xy 155.777718 -102.703515) (xy 155.792142 -102.717869)
			(xy 155.800005 -102.736638) (xy 155.800552 -102.74681) (xy 155.800552 -102.974394) (xy 155.800298 -102.978458)
			(xy 155.800044 -102.980998) (xy 155.800044 -102.989634) (xy 155.794202 -102.999032) (xy 155.79344 -103.000302)
			(xy 155.79217 -103.002334) (xy 155.58643 -103.31704) (xy 155.581389 -103.325568) (xy 155.577561 -103.344983)
			(xy 155.581376 -103.364401) (xy 155.58643 -103.37292) (xy 155.79217 -103.686356) (xy 155.793186 -103.688388)
			(xy 155.794456 -103.69042) (xy 155.800044 -103.699056) (xy 155.800044 -103.707692) (xy 155.800298 -103.710232)
			(xy 155.800552 -103.714296) (xy 155.800552 -103.848408) (xy 161.531808 -103.848408) (xy 161.531808 -102.84206)
			(xy 161.532189 -102.831902) (xy 161.539999 -102.813147) (xy 161.554408 -102.798825) (xy 161.57321 -102.791128)
			(xy 161.58337 -102.790752) (xy 162.76447 -102.790752) (xy 162.774596 -102.791251) (xy 162.793319 -102.798971)
			(xy 162.807677 -102.813254) (xy 162.815495 -102.831936) (xy 162.816032 -102.84206) (xy 162.816032 -103.848408)
			(xy 166.068756 -103.848408) (xy 166.068756 -102.84206) (xy 166.069251 -102.831954) (xy 166.076994 -102.813283)
			(xy 166.091287 -102.798992) (xy 166.109958 -102.791251) (xy 166.120064 -102.790752) (xy 167.301164 -102.790752)
			(xy 167.311265 -102.791314) (xy 167.329933 -102.79903) (xy 167.344227 -102.813304) (xy 167.351971 -102.83196)
			(xy 167.352472 -102.84206) (xy 167.352472 -103.776272) (xy 169.739056 -103.776272) (xy 169.739056 -102.912672)
			(xy 169.739546 -102.882688) (xy 169.747374 -102.823232) (xy 169.762895 -102.765307) (xy 169.785844 -102.709903)
			(xy 169.815828 -102.657969) (xy 169.852334 -102.610393) (xy 169.894739 -102.567988) (xy 169.942315 -102.531482)
			(xy 169.994249 -102.501498) (xy 170.049653 -102.478549) (xy 170.107578 -102.463028) (xy 170.167034 -102.4552)
			(xy 170.227002 -102.4552) (xy 170.286458 -102.463028) (xy 170.344383 -102.478549) (xy 170.399787 -102.501498)
			(xy 170.451721 -102.531482) (xy 170.499297 -102.567988) (xy 170.541702 -102.610393) (xy 170.578208 -102.657969)
			(xy 170.608192 -102.709903) (xy 170.631141 -102.765307) (xy 170.646662 -102.823232) (xy 170.65449 -102.882688)
			(xy 170.65498 -102.912672) (xy 170.65498 -103.776272) (xy 170.654955 -103.777796) (xy 269.509748 -103.777796)
			(xy 269.509748 -102.914196) (xy 269.510238 -102.884212) (xy 269.518066 -102.824756) (xy 269.533587 -102.766831)
			(xy 269.556536 -102.711427) (xy 269.58652 -102.659493) (xy 269.623026 -102.611917) (xy 269.665431 -102.569512)
			(xy 269.713007 -102.533006) (xy 269.764941 -102.503022) (xy 269.820345 -102.480073) (xy 269.87827 -102.464552)
			(xy 269.937726 -102.456724) (xy 269.997694 -102.456724) (xy 270.05715 -102.464552) (xy 270.115075 -102.480073)
			(xy 270.170479 -102.503022) (xy 270.222413 -102.533006) (xy 270.269989 -102.569512) (xy 270.312394 -102.611917)
			(xy 270.3489 -102.659493) (xy 270.378884 -102.711427) (xy 270.401833 -102.766831) (xy 270.417354 -102.824756)
			(xy 270.425182 -102.884212) (xy 270.425672 -102.914196) (xy 270.425672 -103.777796) (xy 270.425182 -103.80778)
			(xy 270.417354 -103.867236) (xy 270.401833 -103.925161) (xy 270.394382 -103.94315) (xy 271.060672 -103.94315)
			(xy 271.060672 -103.700326) (xy 271.205452 -103.4796) (xy 271.254728 -103.404162) (xy 271.27454 -103.373936)
			(xy 271.279459 -103.365458) (xy 271.28321 -103.346242) (xy 271.279491 -103.327021) (xy 271.27454 -103.318564)
			(xy 271.129506 -103.095552) (xy 271.07388 -103.010208) (xy 271.069562 -103.004112) (xy 271.06626 -102.998524)
			(xy 271.065752 -102.997508) (xy 271.060672 -102.989634) (xy 271.060672 -102.74681) (xy 271.061073 -102.736635)
			(xy 271.068861 -102.717834) (xy 271.083254 -102.703447) (xy 271.102059 -102.695668) (xy 271.112234 -102.695248)
			(xy 271.848834 -102.695248) (xy 271.858995 -102.695706) (xy 271.877767 -102.703493) (xy 271.892131 -102.71787)
			(xy 271.899903 -102.736648) (xy 271.900396 -102.74681) (xy 271.900396 -102.989634) (xy 271.684496 -103.320088)
			(xy 271.680463 -103.328304) (xy 271.677923 -103.346418) (xy 271.681873 -103.364277) (xy 271.686528 -103.372158)
			(xy 271.718786 -103.421942) (xy 271.73428 -103.445564) (xy 271.900396 -103.699056) (xy 271.900396 -103.848408)
			(xy 277.63216 -103.848408) (xy 277.63216 -102.84206) (xy 277.632651 -102.831954) (xy 277.640395 -102.813282)
			(xy 277.654689 -102.79899) (xy 277.673362 -102.79125) (xy 277.683468 -102.790752) (xy 278.864568 -102.790752)
			(xy 278.874669 -102.79131) (xy 278.893337 -102.799028) (xy 278.907632 -102.813302) (xy 278.915376 -102.83196)
			(xy 278.915876 -102.84206) (xy 278.915876 -103.848408) (xy 282.1686 -103.848408) (xy 282.1686 -102.84206)
			(xy 282.169052 -102.831949) (xy 282.176803 -102.81327) (xy 282.19111 -102.798976) (xy 282.209796 -102.791243)
			(xy 282.219908 -102.790752) (xy 283.401262 -102.790752) (xy 283.411388 -102.791258) (xy 283.43011 -102.798976)
			(xy 283.444468 -102.813256) (xy 283.452287 -102.831937) (xy 283.452824 -102.84206) (xy 283.452824 -103.776272)
			(xy 285.8389 -103.776272) (xy 285.8389 -102.912672) (xy 285.83939 -102.882688) (xy 285.847218 -102.823232)
			(xy 285.862739 -102.765307) (xy 285.885688 -102.709903) (xy 285.915672 -102.657969) (xy 285.952178 -102.610393)
			(xy 285.994583 -102.567988) (xy 286.042159 -102.531482) (xy 286.094093 -102.501498) (xy 286.149497 -102.478549)
			(xy 286.207422 -102.463028) (xy 286.266878 -102.4552) (xy 286.326846 -102.4552) (xy 286.386302 -102.463028)
			(xy 286.444227 -102.478549) (xy 286.499631 -102.501498) (xy 286.551565 -102.531482) (xy 286.599141 -102.567988)
			(xy 286.641546 -102.610393) (xy 286.678052 -102.657969) (xy 286.708036 -102.709903) (xy 286.730985 -102.765307)
			(xy 286.746506 -102.823232) (xy 286.754334 -102.882688) (xy 286.754824 -102.912672) (xy 286.754824 -103.776272)
			(xy 286.754799 -103.777796) (xy 385.6101 -103.777796) (xy 385.6101 -102.914196) (xy 385.61059 -102.884228)
			(xy 385.618413 -102.824806) (xy 385.633926 -102.766913) (xy 385.656862 -102.71154) (xy 385.686829 -102.659634)
			(xy 385.723316 -102.612084) (xy 385.765696 -102.569704) (xy 385.813246 -102.533217) (xy 385.865152 -102.50325)
			(xy 385.920525 -102.480314) (xy 385.978418 -102.464801) (xy 386.03784 -102.456978) (xy 386.097776 -102.456978)
			(xy 386.157198 -102.464801) (xy 386.215091 -102.480314) (xy 386.270464 -102.50325) (xy 386.32237 -102.533217)
			(xy 386.36992 -102.569704) (xy 386.4123 -102.612084) (xy 386.448787 -102.659634) (xy 386.478754 -102.71154)
			(xy 386.50169 -102.766913) (xy 386.517203 -102.824806) (xy 386.525026 -102.884228) (xy 386.525516 -102.914196)
			(xy 386.525516 -103.777796) (xy 386.525026 -103.807764) (xy 386.517203 -103.867186) (xy 386.50169 -103.925079)
			(xy 386.494205 -103.94315) (xy 387.160516 -103.94315) (xy 387.160516 -103.715566) (xy 387.16077 -103.711502)
			(xy 387.161024 -103.708962) (xy 387.161024 -103.700326) (xy 387.166612 -103.69169) (xy 387.167882 -103.689658)
			(xy 387.168898 -103.687626) (xy 387.366256 -103.386636) (xy 387.370124 -103.380308) (xy 387.374384 -103.366108)
			(xy 387.374638 -103.358696) (xy 387.374638 -103.333042) (xy 387.374436 -103.325708) (xy 387.370304 -103.311636)
			(xy 387.36651 -103.305356) (xy 387.168644 -103.002334) (xy 387.166358 -102.998524) (xy 387.166104 -102.998016)
			(xy 387.165088 -102.996238) (xy 387.161024 -102.989634) (xy 387.161024 -102.981506) (xy 387.16077 -102.978966)
			(xy 387.160516 -102.974902) (xy 387.160516 -102.74681) (xy 387.161041 -102.736656) (xy 387.168808 -102.717891)
			(xy 387.183164 -102.703526) (xy 387.201924 -102.695747) (xy 387.212078 -102.695248) (xy 387.948932 -102.695248)
			(xy 387.959106 -102.695748) (xy 387.977913 -102.703517) (xy 387.992338 -102.71787) (xy 388.000201 -102.736638)
			(xy 388.000748 -102.74681) (xy 388.000748 -102.974394) (xy 388.000494 -102.978458) (xy 388.00024 -102.980998)
			(xy 388.00024 -102.989634) (xy 387.994398 -102.999032) (xy 387.993636 -103.000302) (xy 387.992366 -103.002334)
			(xy 387.786626 -103.31704) (xy 387.781585 -103.325568) (xy 387.777758 -103.344983) (xy 387.781572 -103.364401)
			(xy 387.786626 -103.37292) (xy 387.992366 -103.686356) (xy 387.993382 -103.688388) (xy 387.994652 -103.69042)
			(xy 388.00024 -103.699056) (xy 388.00024 -103.707692) (xy 388.000494 -103.710232) (xy 388.000748 -103.714296)
			(xy 388.000748 -103.848408) (xy 393.732004 -103.848408) (xy 393.732004 -102.84206) (xy 393.732389 -102.831903)
			(xy 393.740199 -102.813149) (xy 393.754606 -102.798827) (xy 393.773406 -102.791129) (xy 393.783566 -102.790752)
			(xy 394.964666 -102.790752) (xy 394.974792 -102.791255) (xy 394.993515 -102.798974) (xy 395.007872 -102.813255)
			(xy 395.015691 -102.831937) (xy 395.016228 -102.84206) (xy 395.016228 -103.848408) (xy 398.268952 -103.848408)
			(xy 398.268952 -102.84206) (xy 398.269451 -102.831955) (xy 398.277193 -102.813285) (xy 398.291485 -102.798993)
			(xy 398.310155 -102.791251) (xy 398.32026 -102.790752) (xy 399.50136 -102.790752) (xy 399.51146 -102.791317)
			(xy 399.530128 -102.799032) (xy 399.544423 -102.813305) (xy 399.552167 -102.831961) (xy 399.552668 -102.84206)
			(xy 399.552668 -103.776272) (xy 401.939252 -103.776272) (xy 401.939252 -102.912672) (xy 401.939742 -102.882704)
			(xy 401.947565 -102.823282) (xy 401.963078 -102.765389) (xy 401.986014 -102.710016) (xy 402.015981 -102.65811)
			(xy 402.052468 -102.61056) (xy 402.094848 -102.56818) (xy 402.142398 -102.531693) (xy 402.194304 -102.501726)
			(xy 402.249677 -102.47879) (xy 402.30757 -102.463277) (xy 402.366992 -102.455454) (xy 402.426928 -102.455454)
			(xy 402.48635 -102.463277) (xy 402.544243 -102.47879) (xy 402.599616 -102.501726) (xy 402.651522 -102.531693)
			(xy 402.699072 -102.56818) (xy 402.741452 -102.61056) (xy 402.777939 -102.65811) (xy 402.807906 -102.710016)
			(xy 402.830842 -102.765389) (xy 402.846355 -102.823282) (xy 402.854178 -102.882704) (xy 402.854668 -102.912672)
			(xy 402.854668 -103.776272) (xy 402.854178 -103.80624) (xy 402.846355 -103.865662) (xy 402.830842 -103.923555)
			(xy 402.807906 -103.978928) (xy 402.777939 -104.030834) (xy 402.741452 -104.078384) (xy 402.699072 -104.120764)
			(xy 402.651522 -104.157251) (xy 402.599616 -104.187218) (xy 402.544243 -104.210154) (xy 402.48635 -104.225667)
			(xy 402.426928 -104.23349) (xy 402.366992 -104.23349) (xy 402.30757 -104.225667) (xy 402.249677 -104.210154)
			(xy 402.194304 -104.187218) (xy 402.142398 -104.157251) (xy 402.094848 -104.120764) (xy 402.052468 -104.078384)
			(xy 402.015981 -104.030834) (xy 401.986014 -103.978928) (xy 401.963078 -103.923555) (xy 401.947565 -103.865662)
			(xy 401.939742 -103.80624) (xy 401.939252 -103.776272) (xy 399.552668 -103.776272) (xy 399.552668 -103.848408)
			(xy 399.55229 -103.858535) (xy 399.544533 -103.877245) (xy 399.530204 -103.89156) (xy 399.511487 -103.899299)
			(xy 399.50136 -103.899716) (xy 398.32026 -103.899716) (xy 398.310151 -103.899248) (xy 398.291475 -103.8915)
			(xy 398.277182 -103.877198) (xy 398.269446 -103.858518) (xy 398.268952 -103.848408) (xy 395.016228 -103.848408)
			(xy 395.015785 -103.858559) (xy 395.007992 -103.877306) (xy 394.993603 -103.891628) (xy 394.974819 -103.899333)
			(xy 394.964666 -103.899716) (xy 393.783566 -103.899716) (xy 393.773432 -103.8993) (xy 393.754701 -103.891553)
			(xy 393.740345 -103.877245) (xy 393.732535 -103.858541) (xy 393.732004 -103.848408) (xy 388.000748 -103.848408)
			(xy 388.000748 -103.94315) (xy 388.000295 -103.95332) (xy 387.992524 -103.972116) (xy 387.978147 -103.986504)
			(xy 387.959356 -103.994288) (xy 387.949186 -103.994712) (xy 387.212332 -103.994712) (xy 387.202157 -103.994199)
			(xy 387.183344 -103.986443) (xy 387.168915 -103.972093) (xy 387.161057 -103.953322) (xy 387.160516 -103.94315)
			(xy 386.494205 -103.94315) (xy 386.478754 -103.980452) (xy 386.448787 -104.032358) (xy 386.4123 -104.079908)
			(xy 386.36992 -104.122288) (xy 386.32237 -104.158775) (xy 386.270464 -104.188742) (xy 386.215091 -104.211678)
			(xy 386.157198 -104.227191) (xy 386.097776 -104.235014) (xy 386.03784 -104.235014) (xy 385.978418 -104.227191)
			(xy 385.920525 -104.211678) (xy 385.865152 -104.188742) (xy 385.813246 -104.158775) (xy 385.765696 -104.122288)
			(xy 385.723316 -104.079908) (xy 385.686829 -104.032358) (xy 385.656862 -103.980452) (xy 385.633926 -103.925079)
			(xy 385.618413 -103.867186) (xy 385.61059 -103.807764) (xy 385.6101 -103.777796) (xy 286.754799 -103.777796)
			(xy 286.754334 -103.806256) (xy 286.746506 -103.865712) (xy 286.730985 -103.923637) (xy 286.708036 -103.979041)
			(xy 286.678052 -104.030975) (xy 286.641546 -104.078551) (xy 286.599141 -104.120956) (xy 286.551565 -104.157462)
			(xy 286.499631 -104.187446) (xy 286.444227 -104.210395) (xy 286.386302 -104.225916) (xy 286.326846 -104.233744)
			(xy 286.266878 -104.233744) (xy 286.207422 -104.225916) (xy 286.149497 -104.210395) (xy 286.094093 -104.187446)
			(xy 286.042159 -104.157462) (xy 285.994583 -104.120956) (xy 285.952178 -104.078551) (xy 285.915672 -104.030975)
			(xy 285.885688 -103.979041) (xy 285.862739 -103.923637) (xy 285.847218 -103.865712) (xy 285.83939 -103.806256)
			(xy 285.8389 -103.776272) (xy 283.452824 -103.776272) (xy 283.452824 -103.848408) (xy 283.452322 -103.858514)
			(xy 283.444586 -103.877188) (xy 283.430295 -103.891482) (xy 283.411622 -103.89922) (xy 283.401516 -103.899716)
			(xy 282.220162 -103.899716) (xy 282.210027 -103.899303) (xy 282.191297 -103.891555) (xy 282.176941 -103.877246)
			(xy 282.16913 -103.858541) (xy 282.1686 -103.848408) (xy 278.915876 -103.848408) (xy 278.91549 -103.858534)
			(xy 278.907735 -103.877242) (xy 278.893409 -103.891557) (xy 278.874694 -103.899298) (xy 278.864568 -103.899716)
			(xy 277.683468 -103.899716) (xy 277.673359 -103.899242) (xy 277.654683 -103.891496) (xy 277.64039 -103.877197)
			(xy 277.632654 -103.858517) (xy 277.63216 -103.848408) (xy 271.900396 -103.848408) (xy 271.900396 -103.94315)
			(xy 271.899896 -103.953314) (xy 271.892134 -103.972101) (xy 271.877772 -103.986487) (xy 271.858997 -103.99428)
			(xy 271.848834 -103.994712) (xy 271.112234 -103.994712) (xy 271.102058 -103.994307) (xy 271.083255 -103.986524)
			(xy 271.068867 -103.972132) (xy 271.06109 -103.953326) (xy 271.060672 -103.94315) (xy 270.394382 -103.94315)
			(xy 270.378884 -103.980565) (xy 270.3489 -104.032499) (xy 270.312394 -104.080075) (xy 270.269989 -104.12248)
			(xy 270.222413 -104.158986) (xy 270.170479 -104.18897) (xy 270.115075 -104.211919) (xy 270.05715 -104.22744)
			(xy 269.997694 -104.235268) (xy 269.937726 -104.235268) (xy 269.87827 -104.22744) (xy 269.820345 -104.211919)
			(xy 269.764941 -104.18897) (xy 269.713007 -104.158986) (xy 269.665431 -104.12248) (xy 269.623026 -104.080075)
			(xy 269.58652 -104.032499) (xy 269.556536 -103.980565) (xy 269.533587 -103.925161) (xy 269.518066 -103.867236)
			(xy 269.510238 -103.80778) (xy 269.509748 -103.777796) (xy 170.654955 -103.777796) (xy 170.65449 -103.806256)
			(xy 170.646662 -103.865712) (xy 170.631141 -103.923637) (xy 170.608192 -103.979041) (xy 170.578208 -104.030975)
			(xy 170.541702 -104.078551) (xy 170.499297 -104.120956) (xy 170.451721 -104.157462) (xy 170.399787 -104.187446)
			(xy 170.344383 -104.210395) (xy 170.286458 -104.225916) (xy 170.227002 -104.233744) (xy 170.167034 -104.233744)
			(xy 170.107578 -104.225916) (xy 170.049653 -104.210395) (xy 169.994249 -104.187446) (xy 169.942315 -104.157462)
			(xy 169.894739 -104.120956) (xy 169.852334 -104.078551) (xy 169.815828 -104.030975) (xy 169.785844 -103.979041)
			(xy 169.762895 -103.923637) (xy 169.747374 -103.865712) (xy 169.739546 -103.806256) (xy 169.739056 -103.776272)
			(xy 167.352472 -103.776272) (xy 167.352472 -103.848408) (xy 167.35209 -103.858534) (xy 167.344334 -103.877244)
			(xy 167.330007 -103.891558) (xy 167.311291 -103.899298) (xy 167.301164 -103.899716) (xy 166.120064 -103.899716)
			(xy 166.109955 -103.899245) (xy 166.091279 -103.891498) (xy 166.076986 -103.877198) (xy 166.06925 -103.858517)
			(xy 166.068756 -103.848408) (xy 162.816032 -103.848408) (xy 162.815585 -103.858559) (xy 162.807793 -103.877305)
			(xy 162.793405 -103.891627) (xy 162.774622 -103.899332) (xy 162.76447 -103.899716) (xy 161.58337 -103.899716)
			(xy 161.573236 -103.899297) (xy 161.554506 -103.891551) (xy 161.540149 -103.877244) (xy 161.532339 -103.85854)
			(xy 161.531808 -103.848408) (xy 155.800552 -103.848408) (xy 155.800552 -103.94315) (xy 155.800095 -103.95332)
			(xy 155.792325 -103.972115) (xy 155.777949 -103.986502) (xy 155.759159 -103.994287) (xy 155.74899 -103.994712)
			(xy 155.012136 -103.994712) (xy 155.001961 -103.994195) (xy 154.983148 -103.986441) (xy 154.96872 -103.972092)
			(xy 154.960862 -103.953322) (xy 154.96032 -103.94315) (xy 154.294538 -103.94315) (xy 154.27904 -103.980565)
			(xy 154.249056 -104.032499) (xy 154.21255 -104.080075) (xy 154.170145 -104.12248) (xy 154.122569 -104.158986)
			(xy 154.070635 -104.18897) (xy 154.015231 -104.211919) (xy 153.957306 -104.22744) (xy 153.89785 -104.235268)
			(xy 153.837882 -104.235268) (xy 153.778426 -104.22744) (xy 153.720501 -104.211919) (xy 153.665097 -104.18897)
			(xy 153.613163 -104.158986) (xy 153.565587 -104.12248) (xy 153.523182 -104.080075) (xy 153.486676 -104.032499)
			(xy 153.456692 -103.980565) (xy 153.433743 -103.925161) (xy 153.418222 -103.867236) (xy 153.410394 -103.80778)
			(xy 153.409904 -103.777796) (xy 54.554603 -103.777796) (xy 54.554138 -103.80624) (xy 54.546315 -103.865662)
			(xy 54.530802 -103.923555) (xy 54.507866 -103.978928) (xy 54.477899 -104.030834) (xy 54.441412 -104.078384)
			(xy 54.399032 -104.120764) (xy 54.351482 -104.157251) (xy 54.299576 -104.187218) (xy 54.244203 -104.210154)
			(xy 54.18631 -104.225667) (xy 54.126888 -104.23349) (xy 54.066952 -104.23349) (xy 54.00753 -104.225667)
			(xy 53.949637 -104.210154) (xy 53.894264 -104.187218) (xy 53.842358 -104.157251) (xy 53.794808 -104.120764)
			(xy 53.752428 -104.078384) (xy 53.715941 -104.030834) (xy 53.685974 -103.978928) (xy 53.663038 -103.923555)
			(xy 53.647525 -103.865662) (xy 53.639702 -103.80624) (xy 53.639212 -103.776272) (xy 51.252628 -103.776272)
			(xy 51.252628 -103.848408) (xy 51.252122 -103.858514) (xy 51.244387 -103.877187) (xy 51.230097 -103.89148)
			(xy 51.211426 -103.89922) (xy 51.20132 -103.899716) (xy 50.02022 -103.899716) (xy 50.010101 -103.899268)
			(xy 49.991401 -103.89153) (xy 49.977086 -103.877223) (xy 49.969337 -103.858527) (xy 49.968912 -103.848408)
			(xy 46.716188 -103.848408) (xy 46.715785 -103.858564) (xy 46.707984 -103.877319) (xy 46.693582 -103.891642)
			(xy 46.674784 -103.89934) (xy 46.664626 -103.899716) (xy 45.483526 -103.899716) (xy 45.473396 -103.899251)
			(xy 45.454667 -103.891524) (xy 45.440308 -103.87723) (xy 45.432495 -103.858536) (xy 45.431964 -103.848408)
			(xy 39.700708 -103.848408) (xy 39.700708 -103.94315) (xy 39.700196 -103.953313) (xy 39.692436 -103.972098)
			(xy 39.678078 -103.986483) (xy 39.659308 -103.994277) (xy 39.649146 -103.994712) (xy 38.912292 -103.994712)
			(xy 38.902115 -103.994231) (xy 38.8833 -103.986462) (xy 38.868874 -103.972103) (xy 38.861017 -103.953325)
			(xy 38.860476 -103.94315) (xy 38.194165 -103.94315) (xy 38.178714 -103.980452) (xy 38.148747 -104.032358)
			(xy 38.11226 -104.079908) (xy 38.06988 -104.122288) (xy 38.02233 -104.158775) (xy 37.970424 -104.188742)
			(xy 37.915051 -104.211678) (xy 37.857158 -104.227191) (xy 37.797736 -104.235014) (xy 37.7378 -104.235014)
			(xy 37.678378 -104.227191) (xy 37.620485 -104.211678) (xy 37.565112 -104.188742) (xy 37.513206 -104.158775)
			(xy 37.465656 -104.122288) (xy 37.423276 -104.079908) (xy 37.386789 -104.032358) (xy 37.356822 -103.980452)
			(xy 37.333886 -103.925079) (xy 37.318373 -103.867186) (xy 37.31055 -103.807764) (xy 37.31006 -103.777796)
			(xy 4.30911 -103.777796) (xy 4.30911 -105.584498) (xy 34.667952 -105.584498) (xy 34.667952 -104.720898)
			(xy 34.668442 -104.69093) (xy 34.676265 -104.631508) (xy 34.691778 -104.573615) (xy 34.714714 -104.518242)
			(xy 34.744681 -104.466336) (xy 34.781168 -104.418786) (xy 34.823548 -104.376406) (xy 34.871098 -104.339919)
			(xy 34.923004 -104.309952) (xy 34.978377 -104.287016) (xy 35.03627 -104.271503) (xy 35.095692 -104.26368)
			(xy 35.155628 -104.26368) (xy 35.21505 -104.271503) (xy 35.272943 -104.287016) (xy 35.328316 -104.309952)
			(xy 35.380222 -104.339919) (xy 35.427772 -104.376406) (xy 35.470152 -104.418786) (xy 35.506639 -104.466336)
			(xy 35.536606 -104.518242) (xy 35.559542 -104.573615) (xy 35.575055 -104.631508) (xy 35.582878 -104.69093)
			(xy 35.583368 -104.720898) (xy 35.583368 -105.584498) (xy 35.582878 -105.614466) (xy 35.575055 -105.673888)
			(xy 35.559542 -105.731781) (xy 35.552057 -105.749852) (xy 36.218368 -105.749852) (xy 36.218368 -105.522268)
			(xy 36.218622 -105.518204) (xy 36.218876 -105.515664) (xy 36.218876 -105.507028) (xy 36.224464 -105.498392)
			(xy 36.225734 -105.49636) (xy 36.22675 -105.494328) (xy 36.43249 -105.180638) (xy 36.436554 -105.174288)
			(xy 36.438586 -105.16743) (xy 36.442142 -105.156762) (xy 36.439094 -105.133902) (xy 36.226496 -104.809036)
			(xy 36.22421 -104.805226) (xy 36.223956 -104.804718) (xy 36.22294 -104.80294) (xy 36.218876 -104.796336)
			(xy 36.218876 -104.788208) (xy 36.218622 -104.785668) (xy 36.218368 -104.781604) (xy 36.218368 -104.553512)
			(xy 36.218891 -104.543307) (xy 36.226697 -104.524449) (xy 36.241125 -104.510013) (xy 36.259979 -104.502197)
			(xy 36.270184 -104.501696) (xy 37.006784 -104.501696) (xy 37.017006 -104.502125) (xy 37.035895 -104.509946)
			(xy 37.050352 -104.524401) (xy 37.058174 -104.54329) (xy 37.0586 -104.553512) (xy 37.0586 -104.781096)
			(xy 37.058346 -104.78516) (xy 37.058092 -104.7877) (xy 37.058092 -104.796336) (xy 37.05225 -104.805734)
			(xy 37.051488 -104.807004) (xy 37.050218 -104.809036) (xy 36.839398 -105.131362) (xy 36.837366 -105.14076)
			(xy 36.835643 -105.150743) (xy 36.839318 -105.17065) (xy 36.844478 -105.179368) (xy 37.050218 -105.493058)
			(xy 37.051234 -105.49509) (xy 37.052504 -105.497122) (xy 37.058092 -105.505758) (xy 37.058092 -105.514394)
			(xy 37.058346 -105.516934) (xy 37.0586 -105.520998) (xy 37.0586 -105.648252) (xy 45.431964 -105.648252)
			(xy 45.431964 -104.641904) (xy 45.432424 -104.631755) (xy 45.440212 -104.613009) (xy 45.454596 -104.598687)
			(xy 45.473375 -104.590981) (xy 45.483526 -104.590596) (xy 46.664626 -104.590596) (xy 46.674749 -104.591104)
			(xy 46.693462 -104.598832) (xy 46.707816 -104.613111) (xy 46.715642 -104.631784) (xy 46.716188 -104.641904)
			(xy 46.716188 -105.648252) (xy 49.968912 -105.648252) (xy 49.968912 -104.641904) (xy 49.96932 -104.63178)
			(xy 49.977069 -104.613074) (xy 49.991388 -104.59876) (xy 50.010096 -104.591016) (xy 50.02022 -104.590596)
			(xy 51.20132 -104.590596) (xy 51.21143 -104.591068) (xy 51.230108 -104.598812) (xy 51.244402 -104.613113)
			(xy 51.252136 -104.631794) (xy 51.252628 -104.641904) (xy 51.252628 -105.57637) (xy 51.785012 -105.57637)
			(xy 51.785012 -104.71277) (xy 51.785502 -104.682802) (xy 51.793325 -104.62338) (xy 51.808838 -104.565487)
			(xy 51.831774 -104.510114) (xy 51.861741 -104.458208) (xy 51.898228 -104.410658) (xy 51.940608 -104.368278)
			(xy 51.988158 -104.331791) (xy 52.040064 -104.301824) (xy 52.095437 -104.278888) (xy 52.15333 -104.263375)
			(xy 52.212752 -104.255552) (xy 52.272688 -104.255552) (xy 52.33211 -104.263375) (xy 52.390003 -104.278888)
			(xy 52.445376 -104.301824) (xy 52.497282 -104.331791) (xy 52.544832 -104.368278) (xy 52.587212 -104.410658)
			(xy 52.623699 -104.458208) (xy 52.653666 -104.510114) (xy 52.676602 -104.565487) (xy 52.692115 -104.62338)
			(xy 52.699938 -104.682802) (xy 52.700428 -104.71277) (xy 52.700428 -105.57637) (xy 52.700295 -105.584498)
			(xy 150.767796 -105.584498) (xy 150.767796 -104.720898) (xy 150.768286 -104.690914) (xy 150.776114 -104.631458)
			(xy 150.791635 -104.573533) (xy 150.814584 -104.518129) (xy 150.844568 -104.466195) (xy 150.881074 -104.418619)
			(xy 150.923479 -104.376214) (xy 150.971055 -104.339708) (xy 151.022989 -104.309724) (xy 151.078393 -104.286775)
			(xy 151.136318 -104.271254) (xy 151.195774 -104.263426) (xy 151.255742 -104.263426) (xy 151.315198 -104.271254)
			(xy 151.373123 -104.286775) (xy 151.428527 -104.309724) (xy 151.480461 -104.339708) (xy 151.528037 -104.376214)
			(xy 151.570442 -104.418619) (xy 151.606948 -104.466195) (xy 151.636932 -104.518129) (xy 151.659881 -104.573533)
			(xy 151.675402 -104.631458) (xy 151.68323 -104.690914) (xy 151.68372 -104.720898) (xy 151.68372 -105.584498)
			(xy 151.68323 -105.614482) (xy 151.675402 -105.673938) (xy 151.659881 -105.731863) (xy 151.65243 -105.749852)
			(xy 152.318212 -105.749852) (xy 152.318212 -105.522268) (xy 152.318466 -105.518204) (xy 152.31872 -105.515664)
			(xy 152.31872 -105.507028) (xy 152.324308 -105.498392) (xy 152.325578 -105.49636) (xy 152.326594 -105.494328)
			(xy 152.523952 -105.193338) (xy 152.527818 -105.187009) (xy 152.53208 -105.17281) (xy 152.532334 -105.165398)
			(xy 152.532334 -105.139744) (xy 152.532132 -105.13241) (xy 152.528 -105.118338) (xy 152.524206 -105.112058)
			(xy 152.32634 -104.809036) (xy 152.324054 -104.805226) (xy 152.3238 -104.804718) (xy 152.322784 -104.80294)
			(xy 152.31872 -104.796336) (xy 152.31872 -104.788208) (xy 152.318466 -104.785668) (xy 152.318212 -104.781604)
			(xy 152.318212 -104.553512) (xy 152.318623 -104.543288) (xy 152.326447 -104.524395) (xy 152.340909 -104.509938)
			(xy 152.359803 -104.502119) (xy 152.370028 -104.501696) (xy 153.106628 -104.501696) (xy 153.116839 -104.502159)
			(xy 153.135704 -104.509983) (xy 153.150139 -104.52443) (xy 153.157949 -104.5433) (xy 153.158444 -104.553512)
			(xy 153.158444 -104.781096) (xy 153.15819 -104.78516) (xy 153.157936 -104.7877) (xy 153.157936 -104.796336)
			(xy 153.152094 -104.805734) (xy 153.151332 -104.807004) (xy 153.150062 -104.809036) (xy 152.944322 -105.123742)
			(xy 152.93928 -105.132269) (xy 152.935453 -105.151685) (xy 152.939268 -105.171103) (xy 152.944322 -105.179622)
			(xy 153.150062 -105.493058) (xy 153.151078 -105.49509) (xy 153.152348 -105.497122) (xy 153.157936 -105.505758)
			(xy 153.157936 -105.514394) (xy 153.15819 -105.516934) (xy 153.158444 -105.520998) (xy 153.158444 -105.648252)
			(xy 161.531808 -105.648252) (xy 161.531808 -104.641904) (xy 161.532225 -104.631749) (xy 161.540021 -104.612995)
			(xy 161.554419 -104.598672) (xy 161.573213 -104.590973) (xy 161.58337 -104.590596) (xy 162.76447 -104.590596)
			(xy 162.774589 -104.59115) (xy 162.793302 -104.598859) (xy 162.807657 -104.613125) (xy 162.815486 -104.631788)
			(xy 162.816032 -104.641904) (xy 162.816032 -105.648252) (xy 166.068756 -105.648252) (xy 166.068756 -104.641904)
			(xy 166.069287 -104.631801) (xy 166.077015 -104.613131) (xy 166.091298 -104.598838) (xy 166.109961 -104.591095)
			(xy 166.120064 -104.590596) (xy 167.301164 -104.590596) (xy 167.311284 -104.591046) (xy 167.329986 -104.598781)
			(xy 167.344301 -104.613087) (xy 167.352048 -104.631785) (xy 167.352472 -104.641904) (xy 167.352472 -105.57637)
			(xy 167.884856 -105.57637) (xy 167.884856 -104.71277) (xy 167.885346 -104.682786) (xy 167.893174 -104.62333)
			(xy 167.908695 -104.565405) (xy 167.931644 -104.510001) (xy 167.961628 -104.458067) (xy 167.998134 -104.410491)
			(xy 168.040539 -104.368086) (xy 168.088115 -104.33158) (xy 168.140049 -104.301596) (xy 168.195453 -104.278647)
			(xy 168.253378 -104.263126) (xy 168.312834 -104.255298) (xy 168.372802 -104.255298) (xy 168.432258 -104.263126)
			(xy 168.490183 -104.278647) (xy 168.545587 -104.301596) (xy 168.597521 -104.33158) (xy 168.645097 -104.368086)
			(xy 168.687502 -104.410491) (xy 168.724008 -104.458067) (xy 168.753992 -104.510001) (xy 168.776941 -104.565405)
			(xy 168.792462 -104.62333) (xy 168.80029 -104.682786) (xy 168.80078 -104.71277) (xy 168.80078 -105.57637)
			(xy 168.800647 -105.584498) (xy 266.86764 -105.584498) (xy 266.86764 -104.720898) (xy 266.86813 -104.690914)
			(xy 266.875958 -104.631458) (xy 266.891479 -104.573533) (xy 266.914428 -104.518129) (xy 266.944412 -104.466195)
			(xy 266.980918 -104.418619) (xy 267.023323 -104.376214) (xy 267.070899 -104.339708) (xy 267.122833 -104.309724)
			(xy 267.178237 -104.286775) (xy 267.236162 -104.271254) (xy 267.295618 -104.263426) (xy 267.355586 -104.263426)
			(xy 267.415042 -104.271254) (xy 267.472967 -104.286775) (xy 267.528371 -104.309724) (xy 267.580305 -104.339708)
			(xy 267.627881 -104.376214) (xy 267.670286 -104.418619) (xy 267.706792 -104.466195) (xy 267.736776 -104.518129)
			(xy 267.759725 -104.573533) (xy 267.775246 -104.631458) (xy 267.783074 -104.690914) (xy 267.783564 -104.720898)
			(xy 267.783564 -105.584498) (xy 267.783074 -105.614482) (xy 267.775246 -105.673938) (xy 267.759725 -105.731863)
			(xy 267.752274 -105.749852) (xy 268.418564 -105.749852) (xy 268.418564 -105.507028) (xy 268.537436 -105.325672)
			(xy 268.59992 -105.230168) (xy 268.62405 -105.193338) (xy 268.627916 -105.187009) (xy 268.632177 -105.17281)
			(xy 268.632432 -105.165398) (xy 268.632432 -105.13949) (xy 268.632246 -105.13334) (xy 268.629288 -105.121399)
			(xy 268.62659 -105.115868) (xy 268.513052 -104.941878) (xy 268.492986 -104.91089) (xy 268.487398 -104.902254)
			(xy 268.426946 -104.809544) (xy 268.426438 -104.808782) (xy 268.42593 -104.80802) (xy 268.425676 -104.807512)
			(xy 268.425168 -104.80675) (xy 268.418564 -104.796336) (xy 268.418564 -104.553512) (xy 268.419198 -104.541961)
			(xy 268.429171 -104.521118) (xy 268.44711 -104.506556) (xy 268.458188 -104.50322) (xy 268.470126 -104.501696)
			(xy 269.206726 -104.501696) (xy 269.217479 -104.50225) (xy 269.237169 -104.510893) (xy 269.244826 -104.51846)
			(xy 269.25102 -104.525862) (xy 269.257938 -104.543867) (xy 269.258288 -104.553512) (xy 269.258288 -104.796336)
			(xy 269.042388 -105.12679) (xy 269.038354 -105.135006) (xy 269.035816 -105.15312) (xy 269.039765 -105.170979)
			(xy 269.04442 -105.17886) (xy 269.076678 -105.228644) (xy 269.258288 -105.505758) (xy 269.258288 -105.648252)
			(xy 277.63216 -105.648252) (xy 277.63216 -104.641904) (xy 277.632687 -104.6318) (xy 277.640416 -104.61313)
			(xy 277.6547 -104.598837) (xy 277.673365 -104.591095) (xy 277.683468 -104.590596) (xy 278.864568 -104.590596)
			(xy 278.874688 -104.591042) (xy 278.89339 -104.598779) (xy 278.907706 -104.613086) (xy 278.915453 -104.631784)
			(xy 278.915876 -104.641904) (xy 278.915876 -105.648252) (xy 282.1686 -105.648252) (xy 282.1686 -104.641904)
			(xy 282.169019 -104.631782) (xy 282.176766 -104.613078) (xy 282.191082 -104.598764) (xy 282.209786 -104.591019)
			(xy 282.219908 -104.590596) (xy 283.401262 -104.590596) (xy 283.411381 -104.591157) (xy 283.430093 -104.598864)
			(xy 283.444449 -104.613127) (xy 283.452277 -104.631789) (xy 283.452824 -104.641904) (xy 283.452824 -105.57637)
			(xy 283.9847 -105.57637) (xy 283.9847 -104.71277) (xy 283.98519 -104.682786) (xy 283.993018 -104.62333)
			(xy 284.008539 -104.565405) (xy 284.031488 -104.510001) (xy 284.061472 -104.458067) (xy 284.097978 -104.410491)
			(xy 284.140383 -104.368086) (xy 284.187959 -104.33158) (xy 284.239893 -104.301596) (xy 284.295297 -104.278647)
			(xy 284.353222 -104.263126) (xy 284.412678 -104.255298) (xy 284.472646 -104.255298) (xy 284.532102 -104.263126)
			(xy 284.590027 -104.278647) (xy 284.645431 -104.301596) (xy 284.697365 -104.33158) (xy 284.744941 -104.368086)
			(xy 284.787346 -104.410491) (xy 284.823852 -104.458067) (xy 284.853836 -104.510001) (xy 284.876785 -104.565405)
			(xy 284.892306 -104.62333) (xy 284.900134 -104.682786) (xy 284.900624 -104.71277) (xy 284.900624 -105.57637)
			(xy 284.900491 -105.584498) (xy 382.967992 -105.584498) (xy 382.967992 -104.720898) (xy 382.968482 -104.69093)
			(xy 382.976305 -104.631508) (xy 382.991818 -104.573615) (xy 383.014754 -104.518242) (xy 383.044721 -104.466336)
			(xy 383.081208 -104.418786) (xy 383.123588 -104.376406) (xy 383.171138 -104.339919) (xy 383.223044 -104.309952)
			(xy 383.278417 -104.287016) (xy 383.33631 -104.271503) (xy 383.395732 -104.26368) (xy 383.455668 -104.26368)
			(xy 383.51509 -104.271503) (xy 383.572983 -104.287016) (xy 383.628356 -104.309952) (xy 383.680262 -104.339919)
			(xy 383.727812 -104.376406) (xy 383.770192 -104.418786) (xy 383.806679 -104.466336) (xy 383.836646 -104.518242)
			(xy 383.859582 -104.573615) (xy 383.875095 -104.631508) (xy 383.882918 -104.69093) (xy 383.883408 -104.720898)
			(xy 383.883408 -105.584498) (xy 383.882918 -105.614466) (xy 383.875095 -105.673888) (xy 383.859582 -105.731781)
			(xy 383.852097 -105.749852) (xy 384.518408 -105.749852) (xy 384.518408 -105.522268) (xy 384.518662 -105.518204)
			(xy 384.518916 -105.515664) (xy 384.518916 -105.507028) (xy 384.524504 -105.498392) (xy 384.525774 -105.49636)
			(xy 384.52679 -105.494328) (xy 384.724148 -105.193338) (xy 384.728014 -105.187009) (xy 384.732275 -105.17281)
			(xy 384.73253 -105.165398) (xy 384.73253 -105.139744) (xy 384.732328 -105.13241) (xy 384.728196 -105.118338)
			(xy 384.724402 -105.112058) (xy 384.526536 -104.809036) (xy 384.52425 -104.805226) (xy 384.523996 -104.804718)
			(xy 384.52298 -104.80294) (xy 384.518916 -104.796336) (xy 384.518916 -104.788208) (xy 384.518662 -104.785668)
			(xy 384.518408 -104.781604) (xy 384.518408 -104.553512) (xy 384.518823 -104.543288) (xy 384.526646 -104.524397)
			(xy 384.541107 -104.50994) (xy 384.56 -104.50212) (xy 384.570224 -104.501696) (xy 385.306824 -104.501696)
			(xy 385.317035 -104.502162) (xy 385.335899 -104.509985) (xy 385.350335 -104.524431) (xy 385.358145 -104.543301)
			(xy 385.35864 -104.553512) (xy 385.35864 -104.781096) (xy 385.358386 -104.78516) (xy 385.358132 -104.7877)
			(xy 385.358132 -104.796336) (xy 385.35229 -104.805734) (xy 385.351528 -104.807004) (xy 385.350258 -104.809036)
			(xy 385.144518 -105.123742) (xy 385.139476 -105.132269) (xy 385.13565 -105.151685) (xy 385.139465 -105.171103)
			(xy 385.144518 -105.179622) (xy 385.350258 -105.493058) (xy 385.351274 -105.49509) (xy 385.352544 -105.497122)
			(xy 385.358132 -105.505758) (xy 385.358132 -105.514394) (xy 385.358386 -105.516934) (xy 385.35864 -105.520998)
			(xy 385.35864 -105.648252) (xy 393.732004 -105.648252) (xy 393.732004 -104.641904) (xy 393.732425 -104.63175)
			(xy 393.74022 -104.612997) (xy 393.754617 -104.598673) (xy 393.77341 -104.590974) (xy 393.783566 -104.590596)
			(xy 394.964666 -104.590596) (xy 394.974785 -104.591153) (xy 394.993497 -104.598862) (xy 395.007853 -104.613126)
			(xy 395.015681 -104.631788) (xy 395.016228 -104.641904) (xy 395.016228 -105.648252) (xy 398.268952 -105.648252)
			(xy 398.268952 -104.641904) (xy 398.269487 -104.631801) (xy 398.277215 -104.613133) (xy 398.291496 -104.598839)
			(xy 398.310158 -104.591096) (xy 398.32026 -104.590596) (xy 399.50136 -104.590596) (xy 399.511479 -104.591049)
			(xy 399.530181 -104.598783) (xy 399.544497 -104.613088) (xy 399.552244 -104.631785) (xy 399.552668 -104.641904)
			(xy 399.552668 -105.57637) (xy 400.085052 -105.57637) (xy 400.085052 -104.71277) (xy 400.085542 -104.682802)
			(xy 400.093365 -104.62338) (xy 400.108878 -104.565487) (xy 400.131814 -104.510114) (xy 400.161781 -104.458208)
			(xy 400.198268 -104.410658) (xy 400.240648 -104.368278) (xy 400.288198 -104.331791) (xy 400.340104 -104.301824)
			(xy 400.395477 -104.278888) (xy 400.45337 -104.263375) (xy 400.512792 -104.255552) (xy 400.572728 -104.255552)
			(xy 400.63215 -104.263375) (xy 400.690043 -104.278888) (xy 400.745416 -104.301824) (xy 400.797322 -104.331791)
			(xy 400.844872 -104.368278) (xy 400.887252 -104.410658) (xy 400.923739 -104.458208) (xy 400.953706 -104.510114)
			(xy 400.976642 -104.565487) (xy 400.992155 -104.62338) (xy 400.999978 -104.682802) (xy 401.000468 -104.71277)
			(xy 401.000468 -105.57637) (xy 400.999978 -105.606338) (xy 400.992155 -105.66576) (xy 400.976642 -105.723653)
			(xy 400.953706 -105.779026) (xy 400.923739 -105.830932) (xy 400.887252 -105.878482) (xy 400.844872 -105.920862)
			(xy 400.797322 -105.957349) (xy 400.745416 -105.987316) (xy 400.690043 -106.010252) (xy 400.63215 -106.025765)
			(xy 400.572728 -106.033588) (xy 400.512792 -106.033588) (xy 400.45337 -106.025765) (xy 400.395477 -106.010252)
			(xy 400.340104 -105.987316) (xy 400.288198 -105.957349) (xy 400.240648 -105.920862) (xy 400.198268 -105.878482)
			(xy 400.161781 -105.830932) (xy 400.131814 -105.779026) (xy 400.108878 -105.723653) (xy 400.093365 -105.66576)
			(xy 400.085542 -105.606338) (xy 400.085052 -105.57637) (xy 399.552668 -105.57637) (xy 399.552668 -105.648252)
			(xy 399.552244 -105.658375) (xy 399.544506 -105.677084) (xy 399.530191 -105.691401) (xy 399.511483 -105.699142)
			(xy 399.50136 -105.69956) (xy 398.32026 -105.69956) (xy 398.31013 -105.699216) (xy 398.291418 -105.691447)
			(xy 398.277104 -105.677108) (xy 398.269367 -105.658383) (xy 398.268952 -105.648252) (xy 395.016228 -105.648252)
			(xy 395.01574 -105.6584) (xy 395.007965 -105.677145) (xy 394.993589 -105.69147) (xy 394.974815 -105.699176)
			(xy 394.964666 -105.69956) (xy 393.783566 -105.69956) (xy 393.773437 -105.699101) (xy 393.754715 -105.691362)
			(xy 393.74036 -105.677068) (xy 393.732542 -105.658379) (xy 393.732004 -105.648252) (xy 385.35864 -105.648252)
			(xy 385.35864 -105.749852) (xy 385.35815 -105.760068) (xy 385.350346 -105.778949) (xy 385.33591 -105.793406)
			(xy 385.317039 -105.801235) (xy 385.306824 -105.801668) (xy 384.570224 -105.801668) (xy 384.559998 -105.801267)
			(xy 384.541102 -105.793443) (xy 384.526644 -105.778978) (xy 384.518828 -105.760078) (xy 384.518408 -105.749852)
			(xy 383.852097 -105.749852) (xy 383.836646 -105.787154) (xy 383.806679 -105.83906) (xy 383.770192 -105.88661)
			(xy 383.727812 -105.92899) (xy 383.680262 -105.965477) (xy 383.628356 -105.995444) (xy 383.572983 -106.01838)
			(xy 383.51509 -106.033893) (xy 383.455668 -106.041716) (xy 383.395732 -106.041716) (xy 383.33631 -106.033893)
			(xy 383.278417 -106.01838) (xy 383.223044 -105.995444) (xy 383.171138 -105.965477) (xy 383.123588 -105.92899)
			(xy 383.081208 -105.88661) (xy 383.044721 -105.83906) (xy 383.014754 -105.787154) (xy 382.991818 -105.731781)
			(xy 382.976305 -105.673888) (xy 382.968482 -105.614466) (xy 382.967992 -105.584498) (xy 284.900491 -105.584498)
			(xy 284.900134 -105.606354) (xy 284.892306 -105.66581) (xy 284.876785 -105.723735) (xy 284.853836 -105.779139)
			(xy 284.823852 -105.831073) (xy 284.787346 -105.878649) (xy 284.744941 -105.921054) (xy 284.697365 -105.95756)
			(xy 284.645431 -105.987544) (xy 284.590027 -106.010493) (xy 284.532102 -106.026014) (xy 284.472646 -106.033842)
			(xy 284.412678 -106.033842) (xy 284.353222 -106.026014) (xy 284.295297 -106.010493) (xy 284.239893 -105.987544)
			(xy 284.187959 -105.95756) (xy 284.140383 -105.921054) (xy 284.097978 -105.878649) (xy 284.061472 -105.831073)
			(xy 284.031488 -105.779139) (xy 284.008539 -105.723735) (xy 283.993018 -105.66581) (xy 283.98519 -105.606354)
			(xy 283.9847 -105.57637) (xy 283.452824 -105.57637) (xy 283.452824 -105.648252) (xy 283.452345 -105.658368)
			(xy 283.444617 -105.677066) (xy 283.43032 -105.691381) (xy 283.411632 -105.699133) (xy 283.401516 -105.69956)
			(xy 282.220162 -105.69956) (xy 282.210033 -105.699105) (xy 282.191311 -105.691364) (xy 282.176956 -105.677069)
			(xy 282.169138 -105.658379) (xy 282.1686 -105.648252) (xy 278.915876 -105.648252) (xy 278.915444 -105.658374)
			(xy 278.907707 -105.677081) (xy 278.893395 -105.691398) (xy 278.87469 -105.699141) (xy 278.864568 -105.69956)
			(xy 277.683468 -105.69956) (xy 277.673338 -105.699209) (xy 277.654626 -105.691443) (xy 277.640312 -105.677106)
			(xy 277.632575 -105.658382) (xy 277.63216 -105.648252) (xy 269.258288 -105.648252) (xy 269.258288 -105.749852)
			(xy 269.257662 -105.761405) (xy 269.247692 -105.782254) (xy 269.229746 -105.796814) (xy 269.218664 -105.800144)
			(xy 269.206726 -105.801668) (xy 268.470126 -105.801668) (xy 268.459368 -105.80115) (xy 268.439679 -105.792483)
			(xy 268.432026 -105.784904) (xy 268.42581 -105.777518) (xy 268.418906 -105.759501) (xy 268.418564 -105.749852)
			(xy 267.752274 -105.749852) (xy 267.736776 -105.787267) (xy 267.706792 -105.839201) (xy 267.670286 -105.886777)
			(xy 267.627881 -105.929182) (xy 267.580305 -105.965688) (xy 267.528371 -105.995672) (xy 267.472967 -106.018621)
			(xy 267.415042 -106.034142) (xy 267.355586 -106.04197) (xy 267.295618 -106.04197) (xy 267.236162 -106.034142)
			(xy 267.178237 -106.018621) (xy 267.122833 -105.995672) (xy 267.070899 -105.965688) (xy 267.023323 -105.929182)
			(xy 266.980918 -105.886777) (xy 266.944412 -105.839201) (xy 266.914428 -105.787267) (xy 266.891479 -105.731863)
			(xy 266.875958 -105.673938) (xy 266.86813 -105.614482) (xy 266.86764 -105.584498) (xy 168.800647 -105.584498)
			(xy 168.80029 -105.606354) (xy 168.792462 -105.66581) (xy 168.776941 -105.723735) (xy 168.753992 -105.779139)
			(xy 168.724008 -105.831073) (xy 168.687502 -105.878649) (xy 168.645097 -105.921054) (xy 168.597521 -105.95756)
			(xy 168.545587 -105.987544) (xy 168.490183 -106.010493) (xy 168.432258 -106.026014) (xy 168.372802 -106.033842)
			(xy 168.312834 -106.033842) (xy 168.253378 -106.026014) (xy 168.195453 -106.010493) (xy 168.140049 -105.987544)
			(xy 168.088115 -105.95756) (xy 168.040539 -105.921054) (xy 167.998134 -105.878649) (xy 167.961628 -105.831073)
			(xy 167.931644 -105.779139) (xy 167.908695 -105.723735) (xy 167.893174 -105.66581) (xy 167.885346 -105.606354)
			(xy 167.884856 -105.57637) (xy 167.352472 -105.57637) (xy 167.352472 -105.648252) (xy 167.352044 -105.658375)
			(xy 167.344306 -105.677083) (xy 167.329993 -105.6914) (xy 167.311287 -105.699142) (xy 167.301164 -105.69956)
			(xy 166.120064 -105.69956) (xy 166.109934 -105.699213) (xy 166.091222 -105.691445) (xy 166.076908 -105.677107)
			(xy 166.069171 -105.658382) (xy 166.068756 -105.648252) (xy 162.816032 -105.648252) (xy 162.81554 -105.658399)
			(xy 162.807766 -105.677144) (xy 162.793391 -105.691468) (xy 162.774618 -105.699175) (xy 162.76447 -105.69956)
			(xy 161.58337 -105.69956) (xy 161.573241 -105.699098) (xy 161.554519 -105.69136) (xy 161.540164 -105.677067)
			(xy 161.532346 -105.658378) (xy 161.531808 -105.648252) (xy 153.158444 -105.648252) (xy 153.158444 -105.749852)
			(xy 153.15795 -105.760067) (xy 153.150147 -105.778948) (xy 153.135712 -105.793405) (xy 153.116843 -105.801235)
			(xy 153.106628 -105.801668) (xy 152.370028 -105.801668) (xy 152.359802 -105.801264) (xy 152.340906 -105.793441)
			(xy 152.326448 -105.778977) (xy 152.318632 -105.760078) (xy 152.318212 -105.749852) (xy 151.65243 -105.749852)
			(xy 151.636932 -105.787267) (xy 151.606948 -105.839201) (xy 151.570442 -105.886777) (xy 151.528037 -105.929182)
			(xy 151.480461 -105.965688) (xy 151.428527 -105.995672) (xy 151.373123 -106.018621) (xy 151.315198 -106.034142)
			(xy 151.255742 -106.04197) (xy 151.195774 -106.04197) (xy 151.136318 -106.034142) (xy 151.078393 -106.018621)
			(xy 151.022989 -105.995672) (xy 150.971055 -105.965688) (xy 150.923479 -105.929182) (xy 150.881074 -105.886777)
			(xy 150.844568 -105.839201) (xy 150.814584 -105.787267) (xy 150.791635 -105.731863) (xy 150.776114 -105.673938)
			(xy 150.768286 -105.614482) (xy 150.767796 -105.584498) (xy 52.700295 -105.584498) (xy 52.699938 -105.606338)
			(xy 52.692115 -105.66576) (xy 52.676602 -105.723653) (xy 52.653666 -105.779026) (xy 52.623699 -105.830932)
			(xy 52.587212 -105.878482) (xy 52.544832 -105.920862) (xy 52.497282 -105.957349) (xy 52.445376 -105.987316)
			(xy 52.390003 -106.010252) (xy 52.33211 -106.025765) (xy 52.272688 -106.033588) (xy 52.212752 -106.033588)
			(xy 52.15333 -106.025765) (xy 52.095437 -106.010252) (xy 52.040064 -105.987316) (xy 51.988158 -105.957349)
			(xy 51.940608 -105.920862) (xy 51.898228 -105.878482) (xy 51.861741 -105.830932) (xy 51.831774 -105.779026)
			(xy 51.808838 -105.723653) (xy 51.793325 -105.66576) (xy 51.785502 -105.606338) (xy 51.785012 -105.57637)
			(xy 51.252628 -105.57637) (xy 51.252628 -105.648252) (xy 51.252145 -105.658368) (xy 51.244418 -105.677065)
			(xy 51.230122 -105.69138) (xy 51.211435 -105.699132) (xy 51.20132 -105.69956) (xy 50.02022 -105.69956)
			(xy 50.010094 -105.699167) (xy 49.991383 -105.691418) (xy 49.977067 -105.677094) (xy 49.969328 -105.658378)
			(xy 49.968912 -105.648252) (xy 46.716188 -105.648252) (xy 46.715739 -105.658404) (xy 46.707957 -105.677158)
			(xy 46.693568 -105.691484) (xy 46.67478 -105.699183) (xy 46.664626 -105.69956) (xy 45.483526 -105.69956)
			(xy 45.473401 -105.699052) (xy 45.45468 -105.691333) (xy 45.440323 -105.677053) (xy 45.432503 -105.658374)
			(xy 45.431964 -105.648252) (xy 37.0586 -105.648252) (xy 37.0586 -105.749852) (xy 37.058149 -105.760073)
			(xy 37.050338 -105.778962) (xy 37.035889 -105.79342) (xy 37.017004 -105.801242) (xy 37.006784 -105.801668)
			(xy 36.270184 -105.801668) (xy 36.259955 -105.8013) (xy 36.241058 -105.793462) (xy 36.226602 -105.778988)
			(xy 36.218787 -105.760081) (xy 36.218368 -105.749852) (xy 35.552057 -105.749852) (xy 35.536606 -105.787154)
			(xy 35.506639 -105.83906) (xy 35.470152 -105.88661) (xy 35.427772 -105.92899) (xy 35.380222 -105.965477)
			(xy 35.328316 -105.995444) (xy 35.272943 -106.01838) (xy 35.21505 -106.033893) (xy 35.155628 -106.041716)
			(xy 35.095692 -106.041716) (xy 35.03627 -106.033893) (xy 34.978377 -106.01838) (xy 34.923004 -105.995444)
			(xy 34.871098 -105.965477) (xy 34.823548 -105.92899) (xy 34.781168 -105.88661) (xy 34.744681 -105.83906)
			(xy 34.714714 -105.787154) (xy 34.691778 -105.731781) (xy 34.676265 -105.673888) (xy 34.668442 -105.614466)
			(xy 34.667952 -105.584498) (xy 4.30911 -105.584498) (xy 4.30911 -107.377738) (xy 37.31006 -107.377738)
			(xy 37.31006 -106.514138) (xy 37.31055 -106.48417) (xy 37.318373 -106.424748) (xy 37.333886 -106.366855)
			(xy 37.356822 -106.311482) (xy 37.386789 -106.259576) (xy 37.423276 -106.212026) (xy 37.465656 -106.169646)
			(xy 37.513206 -106.133159) (xy 37.565112 -106.103192) (xy 37.620485 -106.080256) (xy 37.678378 -106.064743)
			(xy 37.7378 -106.05692) (xy 37.797736 -106.05692) (xy 37.857158 -106.064743) (xy 37.915051 -106.080256)
			(xy 37.970424 -106.103192) (xy 38.02233 -106.133159) (xy 38.06988 -106.169646) (xy 38.11226 -106.212026)
			(xy 38.148747 -106.259576) (xy 38.178714 -106.311482) (xy 38.20165 -106.366855) (xy 38.217163 -106.424748)
			(xy 38.224986 -106.48417) (xy 38.225476 -106.514138) (xy 38.225476 -107.377738) (xy 38.224986 -107.407706)
			(xy 38.217163 -107.467128) (xy 38.20165 -107.525021) (xy 38.194165 -107.543092) (xy 38.860476 -107.543092)
			(xy 38.860476 -107.315508) (xy 38.86073 -107.311444) (xy 38.860984 -107.308904) (xy 38.860984 -107.300268)
			(xy 38.866572 -107.291632) (xy 38.867842 -107.2896) (xy 38.868858 -107.287568) (xy 39.074598 -106.973878)
			(xy 39.078662 -106.967528) (xy 39.080694 -106.96067) (xy 39.08425 -106.950002) (xy 39.081202 -106.927142)
			(xy 38.868604 -106.602276) (xy 38.866318 -106.598466) (xy 38.866064 -106.597958) (xy 38.865048 -106.59618)
			(xy 38.860984 -106.589576) (xy 38.860984 -106.581448) (xy 38.86073 -106.578908) (xy 38.860476 -106.574844)
			(xy 38.860476 -106.346752) (xy 38.860942 -106.336542) (xy 38.868769 -106.317681) (xy 38.883215 -106.303247)
			(xy 38.902082 -106.295435) (xy 38.912292 -106.294936) (xy 39.648892 -106.294936) (xy 39.659093 -106.295487)
			(xy 39.677946 -106.303288) (xy 39.69238 -106.317707) (xy 39.700202 -106.336551) (xy 39.700708 -106.346752)
			(xy 39.700708 -106.574336) (xy 39.700454 -106.5784) (xy 39.7002 -106.58094) (xy 39.7002 -106.589576)
			(xy 39.694358 -106.598974) (xy 39.693596 -106.600244) (xy 39.692326 -106.602276) (xy 39.481506 -106.924602)
			(xy 39.479474 -106.934) (xy 39.477784 -106.943986) (xy 39.481436 -106.963889) (xy 39.486586 -106.972608)
			(xy 39.692326 -107.286298) (xy 39.693342 -107.28833) (xy 39.694612 -107.290362) (xy 39.7002 -107.298998)
			(xy 39.7002 -107.307634) (xy 39.700454 -107.310174) (xy 39.700708 -107.314238) (xy 39.700708 -107.448096)
			(xy 45.431964 -107.448096) (xy 45.431964 -106.441748) (xy 45.43246 -106.431601) (xy 45.440233 -106.412857)
			(xy 45.454607 -106.398533) (xy 45.473378 -106.390825) (xy 45.483526 -106.39044) (xy 46.664626 -106.39044)
			(xy 46.674754 -106.390905) (xy 46.693476 -106.398641) (xy 46.707832 -106.412934) (xy 46.71565 -106.431622)
			(xy 46.716188 -106.441748) (xy 46.716188 -107.448096) (xy 49.968912 -107.448096) (xy 49.968912 -106.441748)
			(xy 49.969356 -106.431627) (xy 49.97709 -106.412922) (xy 49.991399 -106.398606) (xy 50.010099 -106.390861)
			(xy 50.02022 -106.39044) (xy 51.20132 -106.39044) (xy 51.211449 -106.3908) (xy 51.230161 -106.398563)
			(xy 51.244476 -106.412897) (xy 51.252213 -106.431619) (xy 51.252628 -106.441748) (xy 51.252628 -107.376214)
			(xy 53.639212 -107.376214) (xy 53.639212 -106.512614) (xy 53.639702 -106.482646) (xy 53.647525 -106.423224)
			(xy 53.663038 -106.365331) (xy 53.685974 -106.309958) (xy 53.715941 -106.258052) (xy 53.752428 -106.210502)
			(xy 53.794808 -106.168122) (xy 53.842358 -106.131635) (xy 53.894264 -106.101668) (xy 53.949637 -106.078732)
			(xy 54.00753 -106.063219) (xy 54.066952 -106.055396) (xy 54.126888 -106.055396) (xy 54.18631 -106.063219)
			(xy 54.244203 -106.078732) (xy 54.299576 -106.101668) (xy 54.351482 -106.131635) (xy 54.399032 -106.168122)
			(xy 54.441412 -106.210502) (xy 54.477899 -106.258052) (xy 54.507866 -106.309958) (xy 54.530802 -106.365331)
			(xy 54.546315 -106.423224) (xy 54.554138 -106.482646) (xy 54.554628 -106.512614) (xy 54.554628 -107.376214)
			(xy 54.554603 -107.377738) (xy 153.409904 -107.377738) (xy 153.409904 -106.514138) (xy 153.410394 -106.484154)
			(xy 153.418222 -106.424698) (xy 153.433743 -106.366773) (xy 153.456692 -106.311369) (xy 153.486676 -106.259435)
			(xy 153.523182 -106.211859) (xy 153.565587 -106.169454) (xy 153.613163 -106.132948) (xy 153.665097 -106.102964)
			(xy 153.720501 -106.080015) (xy 153.778426 -106.064494) (xy 153.837882 -106.056666) (xy 153.89785 -106.056666)
			(xy 153.957306 -106.064494) (xy 154.015231 -106.080015) (xy 154.070635 -106.102964) (xy 154.122569 -106.132948)
			(xy 154.170145 -106.169454) (xy 154.21255 -106.211859) (xy 154.249056 -106.259435) (xy 154.27904 -106.311369)
			(xy 154.301989 -106.366773) (xy 154.31751 -106.424698) (xy 154.325338 -106.484154) (xy 154.325828 -106.514138)
			(xy 154.325828 -107.377738) (xy 154.325338 -107.407722) (xy 154.31751 -107.467178) (xy 154.301989 -107.525103)
			(xy 154.294538 -107.543092) (xy 154.96032 -107.543092) (xy 154.96032 -107.315508) (xy 154.960574 -107.311444)
			(xy 154.960828 -107.308904) (xy 154.960828 -107.300268) (xy 154.966416 -107.291632) (xy 154.967686 -107.2896)
			(xy 154.968702 -107.287568) (xy 155.16606 -106.986578) (xy 155.16995 -106.980261) (xy 155.174196 -106.966053)
			(xy 155.174442 -106.958638) (xy 155.174442 -106.932984) (xy 155.174222 -106.925651) (xy 155.170102 -106.91158)
			(xy 155.166314 -106.905298) (xy 154.968448 -106.602276) (xy 154.966162 -106.598466) (xy 154.965908 -106.597958)
			(xy 154.964892 -106.59618) (xy 154.960828 -106.589576) (xy 154.960828 -106.581448) (xy 154.960574 -106.578908)
			(xy 154.96032 -106.574844) (xy 154.96032 -106.346752) (xy 154.960743 -106.336537) (xy 154.968579 -106.317667)
			(xy 154.983038 -106.303232) (xy 155.00192 -106.295427) (xy 155.012136 -106.294936) (xy 155.748736 -106.294936)
			(xy 155.75894 -106.295451) (xy 155.777793 -106.303267) (xy 155.792227 -106.317696) (xy 155.800047 -106.336548)
			(xy 155.800552 -106.346752) (xy 155.800552 -106.574336) (xy 155.800298 -106.5784) (xy 155.800044 -106.58094)
			(xy 155.800044 -106.589576) (xy 155.794202 -106.598974) (xy 155.79344 -106.600244) (xy 155.79217 -106.602276)
			(xy 155.58643 -106.916982) (xy 155.581354 -106.925492) (xy 155.577537 -106.944919) (xy 155.581368 -106.964343)
			(xy 155.58643 -106.972862) (xy 155.79217 -107.286298) (xy 155.793186 -107.28833) (xy 155.794456 -107.290362)
			(xy 155.800044 -107.298998) (xy 155.800044 -107.307634) (xy 155.800298 -107.310174) (xy 155.800552 -107.314238)
			(xy 155.800552 -107.448096) (xy 161.531808 -107.448096) (xy 161.531808 -106.441748) (xy 161.532261 -106.431596)
			(xy 161.540042 -106.412843) (xy 161.55443 -106.398518) (xy 161.573216 -106.390818) (xy 161.58337 -106.39044)
			(xy 162.76447 -106.39044) (xy 162.774595 -106.390951) (xy 162.793315 -106.398669) (xy 162.807673 -106.412948)
			(xy 162.815493 -106.431626) (xy 162.816032 -106.441748) (xy 162.816032 -107.448096) (xy 166.068756 -107.448096)
			(xy 166.068756 -106.441748) (xy 166.069254 -106.431634) (xy 166.076978 -106.41294) (xy 166.091269 -106.398626)
			(xy 166.109951 -106.390871) (xy 166.120064 -106.39044) (xy 167.301164 -106.39044) (xy 167.311289 -106.390847)
			(xy 167.329999 -106.39859) (xy 167.344316 -106.412911) (xy 167.352056 -106.431623) (xy 167.352472 -106.441748)
			(xy 167.352472 -107.376214) (xy 169.739056 -107.376214) (xy 169.739056 -106.512614) (xy 169.739546 -106.48263)
			(xy 169.747374 -106.423174) (xy 169.762895 -106.365249) (xy 169.785844 -106.309845) (xy 169.815828 -106.257911)
			(xy 169.852334 -106.210335) (xy 169.894739 -106.16793) (xy 169.942315 -106.131424) (xy 169.994249 -106.10144)
			(xy 170.049653 -106.078491) (xy 170.107578 -106.06297) (xy 170.167034 -106.055142) (xy 170.227002 -106.055142)
			(xy 170.286458 -106.06297) (xy 170.344383 -106.078491) (xy 170.399787 -106.10144) (xy 170.451721 -106.131424)
			(xy 170.499297 -106.16793) (xy 170.541702 -106.210335) (xy 170.578208 -106.257911) (xy 170.608192 -106.309845)
			(xy 170.631141 -106.365249) (xy 170.646662 -106.423174) (xy 170.65449 -106.48263) (xy 170.65498 -106.512614)
			(xy 170.65498 -107.376214) (xy 170.654955 -107.377738) (xy 269.509748 -107.377738) (xy 269.509748 -106.514138)
			(xy 269.510238 -106.484154) (xy 269.518066 -106.424698) (xy 269.533587 -106.366773) (xy 269.556536 -106.311369)
			(xy 269.58652 -106.259435) (xy 269.623026 -106.211859) (xy 269.665431 -106.169454) (xy 269.713007 -106.132948)
			(xy 269.764941 -106.102964) (xy 269.820345 -106.080015) (xy 269.87827 -106.064494) (xy 269.937726 -106.056666)
			(xy 269.997694 -106.056666) (xy 270.05715 -106.064494) (xy 270.115075 -106.080015) (xy 270.170479 -106.102964)
			(xy 270.222413 -106.132948) (xy 270.269989 -106.169454) (xy 270.312394 -106.211859) (xy 270.3489 -106.259435)
			(xy 270.378884 -106.311369) (xy 270.401833 -106.366773) (xy 270.417354 -106.424698) (xy 270.425182 -106.484154)
			(xy 270.425672 -106.514138) (xy 270.425672 -107.377738) (xy 270.425182 -107.407722) (xy 270.417354 -107.467178)
			(xy 270.401833 -107.525103) (xy 270.394382 -107.543092) (xy 271.060672 -107.543092) (xy 271.060672 -107.300268)
			(xy 271.179544 -107.118912) (xy 271.242028 -107.023408) (xy 271.266158 -106.986578) (xy 271.270047 -106.980261)
			(xy 271.274294 -106.966053) (xy 271.27454 -106.958638) (xy 271.27454 -106.93273) (xy 271.27434 -106.926581)
			(xy 271.271391 -106.91464) (xy 271.268698 -106.909108) (xy 271.15516 -106.735118) (xy 271.135094 -106.70413)
			(xy 271.129506 -106.695494) (xy 271.069054 -106.602784) (xy 271.068546 -106.602022) (xy 271.068038 -106.60126)
			(xy 271.067784 -106.600752) (xy 271.067276 -106.59999) (xy 271.060672 -106.589576) (xy 271.060672 -106.346752)
			(xy 271.061331 -106.335204) (xy 271.07129 -106.31436) (xy 271.089221 -106.299796) (xy 271.100296 -106.29646)
			(xy 271.112234 -106.294936) (xy 271.848834 -106.294936) (xy 271.859589 -106.295474) (xy 271.879279 -106.304127)
			(xy 271.886934 -106.3117) (xy 271.893146 -106.319089) (xy 271.900053 -106.337104) (xy 271.900396 -106.346752)
			(xy 271.900396 -106.589576) (xy 271.684496 -106.92003) (xy 271.680509 -106.928266) (xy 271.677953 -106.946366)
			(xy 271.681883 -106.964219) (xy 271.686528 -106.9721) (xy 271.718786 -107.021884) (xy 271.900396 -107.298998)
			(xy 271.900396 -107.448096) (xy 277.63216 -107.448096) (xy 277.63216 -106.441748) (xy 277.632654 -106.431634)
			(xy 277.640379 -106.412939) (xy 277.654671 -106.398624) (xy 277.673354 -106.39087) (xy 277.683468 -106.39044)
			(xy 278.864568 -106.39044) (xy 278.874693 -106.390843) (xy 278.893404 -106.398588) (xy 278.907721 -106.412909)
			(xy 278.91546 -106.431622) (xy 278.915876 -106.441748) (xy 278.915876 -107.448096) (xy 282.1686 -107.448096)
			(xy 282.1686 -106.441748) (xy 282.169055 -106.431629) (xy 282.176788 -106.412926) (xy 282.191092 -106.39861)
			(xy 282.209789 -106.390863) (xy 282.219908 -106.39044) (xy 283.401262 -106.39044) (xy 283.411386 -106.390958)
			(xy 283.430106 -106.398673) (xy 283.444464 -106.41295) (xy 283.452285 -106.431627) (xy 283.452824 -106.441748)
			(xy 283.452824 -107.376214) (xy 285.8389 -107.376214) (xy 285.8389 -106.512614) (xy 285.83939 -106.48263)
			(xy 285.847218 -106.423174) (xy 285.862739 -106.365249) (xy 285.885688 -106.309845) (xy 285.915672 -106.257911)
			(xy 285.952178 -106.210335) (xy 285.994583 -106.16793) (xy 286.042159 -106.131424) (xy 286.094093 -106.10144)
			(xy 286.149497 -106.078491) (xy 286.207422 -106.06297) (xy 286.266878 -106.055142) (xy 286.326846 -106.055142)
			(xy 286.386302 -106.06297) (xy 286.444227 -106.078491) (xy 286.499631 -106.10144) (xy 286.551565 -106.131424)
			(xy 286.599141 -106.16793) (xy 286.641546 -106.210335) (xy 286.678052 -106.257911) (xy 286.708036 -106.309845)
			(xy 286.730985 -106.365249) (xy 286.746506 -106.423174) (xy 286.754334 -106.48263) (xy 286.754824 -106.512614)
			(xy 286.754824 -107.376214) (xy 286.754799 -107.377738) (xy 385.6101 -107.377738) (xy 385.6101 -106.514138)
			(xy 385.61059 -106.48417) (xy 385.618413 -106.424748) (xy 385.633926 -106.366855) (xy 385.656862 -106.311482)
			(xy 385.686829 -106.259576) (xy 385.723316 -106.212026) (xy 385.765696 -106.169646) (xy 385.813246 -106.133159)
			(xy 385.865152 -106.103192) (xy 385.920525 -106.080256) (xy 385.978418 -106.064743) (xy 386.03784 -106.05692)
			(xy 386.097776 -106.05692) (xy 386.157198 -106.064743) (xy 386.215091 -106.080256) (xy 386.270464 -106.103192)
			(xy 386.32237 -106.133159) (xy 386.36992 -106.169646) (xy 386.4123 -106.212026) (xy 386.448787 -106.259576)
			(xy 386.478754 -106.311482) (xy 386.50169 -106.366855) (xy 386.517203 -106.424748) (xy 386.525026 -106.48417)
			(xy 386.525516 -106.514138) (xy 386.525516 -107.377738) (xy 386.525026 -107.407706) (xy 386.517203 -107.467128)
			(xy 386.50169 -107.525021) (xy 386.494205 -107.543092) (xy 387.160516 -107.543092) (xy 387.160516 -107.315508)
			(xy 387.16077 -107.311444) (xy 387.161024 -107.308904) (xy 387.161024 -107.300268) (xy 387.166612 -107.291632)
			(xy 387.167882 -107.2896) (xy 387.168898 -107.287568) (xy 387.366256 -106.986578) (xy 387.370145 -106.980261)
			(xy 387.374392 -106.966053) (xy 387.374638 -106.958638) (xy 387.374638 -106.932984) (xy 387.374419 -106.925651)
			(xy 387.370298 -106.91158) (xy 387.36651 -106.905298) (xy 387.168644 -106.602276) (xy 387.166358 -106.598466)
			(xy 387.166104 -106.597958) (xy 387.165088 -106.59618) (xy 387.161024 -106.589576) (xy 387.161024 -106.581448)
			(xy 387.16077 -106.578908) (xy 387.160516 -106.574844) (xy 387.160516 -106.346752) (xy 387.160943 -106.336537)
			(xy 387.168778 -106.317668) (xy 387.183236 -106.303233) (xy 387.202116 -106.295428) (xy 387.212332 -106.294936)
			(xy 387.948932 -106.294936) (xy 387.959136 -106.295454) (xy 387.977989 -106.303269) (xy 387.992422 -106.317697)
			(xy 388.000243 -106.336548) (xy 388.000748 -106.346752) (xy 388.000748 -106.574336) (xy 388.000494 -106.5784)
			(xy 388.00024 -106.58094) (xy 388.00024 -106.589576) (xy 387.994398 -106.598974) (xy 387.993636 -106.600244)
			(xy 387.992366 -106.602276) (xy 387.786626 -106.916982) (xy 387.78155 -106.925492) (xy 387.777734 -106.944919)
			(xy 387.781564 -106.964342) (xy 387.786626 -106.972862) (xy 387.992366 -107.286298) (xy 387.993382 -107.28833)
			(xy 387.994652 -107.290362) (xy 388.00024 -107.298998) (xy 388.00024 -107.307634) (xy 388.000494 -107.310174)
			(xy 388.000748 -107.314238) (xy 388.000748 -107.448096) (xy 393.732004 -107.448096) (xy 393.732004 -106.441748)
			(xy 393.732461 -106.431596) (xy 393.740242 -106.412844) (xy 393.754628 -106.398519) (xy 393.773413 -106.390819)
			(xy 393.783566 -106.39044) (xy 394.964666 -106.39044) (xy 394.974791 -106.390955) (xy 394.993511 -106.398671)
			(xy 395.007868 -106.412949) (xy 395.015689 -106.431626) (xy 395.016228 -106.441748) (xy 395.016228 -107.448096)
			(xy 398.268952 -107.448096) (xy 398.268952 -106.441748) (xy 398.269454 -106.431635) (xy 398.277178 -106.412941)
			(xy 398.291467 -106.398627) (xy 398.310147 -106.390872) (xy 398.32026 -106.39044) (xy 399.50136 -106.39044)
			(xy 399.511485 -106.39085) (xy 399.530195 -106.398592) (xy 399.544512 -106.412912) (xy 399.552252 -106.431623)
			(xy 399.552668 -106.441748) (xy 399.552668 -107.376214) (xy 401.939252 -107.376214) (xy 401.939252 -106.512614)
			(xy 401.939742 -106.482646) (xy 401.947565 -106.423224) (xy 401.963078 -106.365331) (xy 401.986014 -106.309958)
			(xy 402.015981 -106.258052) (xy 402.052468 -106.210502) (xy 402.094848 -106.168122) (xy 402.142398 -106.131635)
			(xy 402.194304 -106.101668) (xy 402.249677 -106.078732) (xy 402.30757 -106.063219) (xy 402.366992 -106.055396)
			(xy 402.426928 -106.055396) (xy 402.48635 -106.063219) (xy 402.544243 -106.078732) (xy 402.599616 -106.101668)
			(xy 402.651522 -106.131635) (xy 402.699072 -106.168122) (xy 402.741452 -106.210502) (xy 402.777939 -106.258052)
			(xy 402.807906 -106.309958) (xy 402.830842 -106.365331) (xy 402.846355 -106.423224) (xy 402.854178 -106.482646)
			(xy 402.854668 -106.512614) (xy 402.854668 -107.376214) (xy 402.854178 -107.406182) (xy 402.846355 -107.465604)
			(xy 402.830842 -107.523497) (xy 402.807906 -107.57887) (xy 402.777939 -107.630776) (xy 402.741452 -107.678326)
			(xy 402.699072 -107.720706) (xy 402.651522 -107.757193) (xy 402.599616 -107.78716) (xy 402.544243 -107.810096)
			(xy 402.48635 -107.825609) (xy 402.426928 -107.833432) (xy 402.366992 -107.833432) (xy 402.30757 -107.825609)
			(xy 402.249677 -107.810096) (xy 402.194304 -107.78716) (xy 402.142398 -107.757193) (xy 402.094848 -107.720706)
			(xy 402.052468 -107.678326) (xy 402.015981 -107.630776) (xy 401.986014 -107.57887) (xy 401.963078 -107.523497)
			(xy 401.947565 -107.465604) (xy 401.939742 -107.406182) (xy 401.939252 -107.376214) (xy 399.552668 -107.376214)
			(xy 399.552668 -107.448096) (xy 399.55228 -107.458222) (xy 399.544527 -107.476932) (xy 399.530202 -107.491247)
			(xy 399.511486 -107.498987) (xy 399.50136 -107.499404) (xy 398.32026 -107.499404) (xy 398.310149 -107.498948)
			(xy 398.291471 -107.491198) (xy 398.277178 -107.476892) (xy 398.269444 -107.458207) (xy 398.268952 -107.448096)
			(xy 395.016228 -107.448096) (xy 395.015776 -107.458246) (xy 395.007987 -107.476993) (xy 394.9936 -107.491316)
			(xy 394.974818 -107.499021) (xy 394.964666 -107.499404) (xy 393.783566 -107.499404) (xy 393.773443 -107.498903)
			(xy 393.754729 -107.491172) (xy 393.740375 -107.476891) (xy 393.73255 -107.458217) (xy 393.732004 -107.448096)
			(xy 388.000748 -107.448096) (xy 388.000748 -107.543092) (xy 388.000212 -107.553295) (xy 387.992408 -107.572151)
			(xy 387.977984 -107.586586) (xy 387.959135 -107.594405) (xy 387.948932 -107.594908) (xy 387.212332 -107.594908)
			(xy 387.202111 -107.594462) (xy 387.183223 -107.586647) (xy 387.168766 -107.572197) (xy 387.160943 -107.553312)
			(xy 387.160516 -107.543092) (xy 386.494205 -107.543092) (xy 386.478754 -107.580394) (xy 386.448787 -107.6323)
			(xy 386.4123 -107.67985) (xy 386.36992 -107.72223) (xy 386.32237 -107.758717) (xy 386.270464 -107.788684)
			(xy 386.215091 -107.81162) (xy 386.157198 -107.827133) (xy 386.097776 -107.834956) (xy 386.03784 -107.834956)
			(xy 385.978418 -107.827133) (xy 385.920525 -107.81162) (xy 385.865152 -107.788684) (xy 385.813246 -107.758717)
			(xy 385.765696 -107.72223) (xy 385.723316 -107.67985) (xy 385.686829 -107.6323) (xy 385.656862 -107.580394)
			(xy 385.633926 -107.525021) (xy 385.618413 -107.467128) (xy 385.61059 -107.407706) (xy 385.6101 -107.377738)
			(xy 286.754799 -107.377738) (xy 286.754334 -107.406198) (xy 286.746506 -107.465654) (xy 286.730985 -107.523579)
			(xy 286.708036 -107.578983) (xy 286.678052 -107.630917) (xy 286.641546 -107.678493) (xy 286.599141 -107.720898)
			(xy 286.551565 -107.757404) (xy 286.499631 -107.787388) (xy 286.444227 -107.810337) (xy 286.386302 -107.825858)
			(xy 286.326846 -107.833686) (xy 286.266878 -107.833686) (xy 286.207422 -107.825858) (xy 286.149497 -107.810337)
			(xy 286.094093 -107.787388) (xy 286.042159 -107.757404) (xy 285.994583 -107.720898) (xy 285.952178 -107.678493)
			(xy 285.915672 -107.630917) (xy 285.885688 -107.578983) (xy 285.862739 -107.523579) (xy 285.847218 -107.465654)
			(xy 285.83939 -107.406198) (xy 285.8389 -107.376214) (xy 283.452824 -107.376214) (xy 283.452824 -107.448096)
			(xy 283.452312 -107.458202) (xy 283.44458 -107.476875) (xy 283.430292 -107.491169) (xy 283.411621 -107.498908)
			(xy 283.401516 -107.499404) (xy 282.220162 -107.499404) (xy 282.210038 -107.498906) (xy 282.191325 -107.491174)
			(xy 282.176971 -107.476892) (xy 282.169146 -107.458217) (xy 282.1686 -107.448096) (xy 278.915876 -107.448096)
			(xy 278.91548 -107.458221) (xy 278.907729 -107.476929) (xy 278.893406 -107.491245) (xy 278.874693 -107.498986)
			(xy 278.864568 -107.499404) (xy 277.683468 -107.499404) (xy 277.673358 -107.498941) (xy 277.65468 -107.491194)
			(xy 277.640386 -107.47689) (xy 277.632652 -107.458207) (xy 277.63216 -107.448096) (xy 271.900396 -107.448096)
			(xy 271.900396 -107.543092) (xy 271.899718 -107.554639) (xy 271.889773 -107.575486) (xy 271.871846 -107.59005)
			(xy 271.860772 -107.593384) (xy 271.848834 -107.594908) (xy 271.112234 -107.594908) (xy 271.101479 -107.594374)
			(xy 271.08179 -107.585717) (xy 271.074134 -107.578144) (xy 271.067937 -107.570744) (xy 271.061022 -107.552738)
			(xy 271.060672 -107.543092) (xy 270.394382 -107.543092) (xy 270.378884 -107.580507) (xy 270.3489 -107.632441)
			(xy 270.312394 -107.680017) (xy 270.269989 -107.722422) (xy 270.222413 -107.758928) (xy 270.170479 -107.788912)
			(xy 270.115075 -107.811861) (xy 270.05715 -107.827382) (xy 269.997694 -107.83521) (xy 269.937726 -107.83521)
			(xy 269.87827 -107.827382) (xy 269.820345 -107.811861) (xy 269.764941 -107.788912) (xy 269.713007 -107.758928)
			(xy 269.665431 -107.722422) (xy 269.623026 -107.680017) (xy 269.58652 -107.632441) (xy 269.556536 -107.580507)
			(xy 269.533587 -107.525103) (xy 269.518066 -107.467178) (xy 269.510238 -107.407722) (xy 269.509748 -107.377738)
			(xy 170.654955 -107.377738) (xy 170.65449 -107.406198) (xy 170.646662 -107.465654) (xy 170.631141 -107.523579)
			(xy 170.608192 -107.578983) (xy 170.578208 -107.630917) (xy 170.541702 -107.678493) (xy 170.499297 -107.720898)
			(xy 170.451721 -107.757404) (xy 170.399787 -107.787388) (xy 170.344383 -107.810337) (xy 170.286458 -107.825858)
			(xy 170.227002 -107.833686) (xy 170.167034 -107.833686) (xy 170.107578 -107.825858) (xy 170.049653 -107.810337)
			(xy 169.994249 -107.787388) (xy 169.942315 -107.757404) (xy 169.894739 -107.720898) (xy 169.852334 -107.678493)
			(xy 169.815828 -107.630917) (xy 169.785844 -107.578983) (xy 169.762895 -107.523579) (xy 169.747374 -107.465654)
			(xy 169.739546 -107.406198) (xy 169.739056 -107.376214) (xy 167.352472 -107.376214) (xy 167.352472 -107.448096)
			(xy 167.35208 -107.458222) (xy 167.344328 -107.476931) (xy 167.330004 -107.491246) (xy 167.31129 -107.498986)
			(xy 167.301164 -107.499404) (xy 166.120064 -107.499404) (xy 166.109953 -107.498944) (xy 166.091275 -107.491196)
			(xy 166.076982 -107.476891) (xy 166.069248 -107.458207) (xy 166.068756 -107.448096) (xy 162.816032 -107.448096)
			(xy 162.815576 -107.458246) (xy 162.807787 -107.476992) (xy 162.793402 -107.491314) (xy 162.774622 -107.49902)
			(xy 162.76447 -107.499404) (xy 161.58337 -107.499404) (xy 161.573247 -107.498899) (xy 161.554533 -107.49117)
			(xy 161.54018 -107.47689) (xy 161.532354 -107.458217) (xy 161.531808 -107.448096) (xy 155.800552 -107.448096)
			(xy 155.800552 -107.543092) (xy 155.800013 -107.553295) (xy 155.792209 -107.572149) (xy 155.777786 -107.586584)
			(xy 155.758938 -107.594404) (xy 155.748736 -107.594908) (xy 155.012136 -107.594908) (xy 155.001916 -107.594458)
			(xy 154.983028 -107.586645) (xy 154.96857 -107.572196) (xy 154.960747 -107.553312) (xy 154.96032 -107.543092)
			(xy 154.294538 -107.543092) (xy 154.27904 -107.580507) (xy 154.249056 -107.632441) (xy 154.21255 -107.680017)
			(xy 154.170145 -107.722422) (xy 154.122569 -107.758928) (xy 154.070635 -107.788912) (xy 154.015231 -107.811861)
			(xy 153.957306 -107.827382) (xy 153.89785 -107.83521) (xy 153.837882 -107.83521) (xy 153.778426 -107.827382)
			(xy 153.720501 -107.811861) (xy 153.665097 -107.788912) (xy 153.613163 -107.758928) (xy 153.565587 -107.722422)
			(xy 153.523182 -107.680017) (xy 153.486676 -107.632441) (xy 153.456692 -107.580507) (xy 153.433743 -107.525103)
			(xy 153.418222 -107.467178) (xy 153.410394 -107.407722) (xy 153.409904 -107.377738) (xy 54.554603 -107.377738)
			(xy 54.554138 -107.406182) (xy 54.546315 -107.465604) (xy 54.530802 -107.523497) (xy 54.507866 -107.57887)
			(xy 54.477899 -107.630776) (xy 54.441412 -107.678326) (xy 54.399032 -107.720706) (xy 54.351482 -107.757193)
			(xy 54.299576 -107.78716) (xy 54.244203 -107.810096) (xy 54.18631 -107.825609) (xy 54.126888 -107.833432)
			(xy 54.066952 -107.833432) (xy 54.00753 -107.825609) (xy 53.949637 -107.810096) (xy 53.894264 -107.78716)
			(xy 53.842358 -107.757193) (xy 53.794808 -107.720706) (xy 53.752428 -107.678326) (xy 53.715941 -107.630776)
			(xy 53.685974 -107.57887) (xy 53.663038 -107.523497) (xy 53.647525 -107.465604) (xy 53.639702 -107.406182)
			(xy 53.639212 -107.376214) (xy 51.252628 -107.376214) (xy 51.252628 -107.448096) (xy 51.252112 -107.458201)
			(xy 51.244381 -107.476874) (xy 51.230094 -107.491168) (xy 51.211425 -107.498908) (xy 51.20132 -107.499404)
			(xy 50.02022 -107.499404) (xy 50.010099 -107.498968) (xy 49.991397 -107.491227) (xy 49.977082 -107.476917)
			(xy 49.969335 -107.458217) (xy 49.968912 -107.448096) (xy 46.716188 -107.448096) (xy 46.715775 -107.458251)
			(xy 46.707978 -107.477006) (xy 46.693579 -107.49133) (xy 46.674783 -107.499028) (xy 46.664626 -107.499404)
			(xy 45.483526 -107.499404) (xy 45.473406 -107.498854) (xy 45.454694 -107.491142) (xy 45.440338 -107.476876)
			(xy 45.43251 -107.458212) (xy 45.431964 -107.448096) (xy 39.700708 -107.448096) (xy 39.700708 -107.543092)
			(xy 39.700281 -107.553314) (xy 39.692459 -107.572203) (xy 39.678003 -107.586659) (xy 39.659114 -107.594481)
			(xy 39.648892 -107.594908) (xy 38.912292 -107.594908) (xy 38.902083 -107.594424) (xy 38.883219 -107.586608)
			(xy 38.868783 -107.572167) (xy 38.860972 -107.553301) (xy 38.860476 -107.543092) (xy 38.194165 -107.543092)
			(xy 38.178714 -107.580394) (xy 38.148747 -107.6323) (xy 38.11226 -107.67985) (xy 38.06988 -107.72223)
			(xy 38.02233 -107.758717) (xy 37.970424 -107.788684) (xy 37.915051 -107.81162) (xy 37.857158 -107.827133)
			(xy 37.797736 -107.834956) (xy 37.7378 -107.834956) (xy 37.678378 -107.827133) (xy 37.620485 -107.81162)
			(xy 37.565112 -107.788684) (xy 37.513206 -107.758717) (xy 37.465656 -107.72223) (xy 37.423276 -107.67985)
			(xy 37.386789 -107.6323) (xy 37.356822 -107.580394) (xy 37.333886 -107.525021) (xy 37.318373 -107.467128)
			(xy 37.31055 -107.407706) (xy 37.31006 -107.377738) (xy 4.30911 -107.377738) (xy 4.30911 -109.18444)
			(xy 34.667952 -109.18444) (xy 34.667952 -108.32084) (xy 34.668442 -108.290872) (xy 34.676265 -108.23145)
			(xy 34.691778 -108.173557) (xy 34.714714 -108.118184) (xy 34.744681 -108.066278) (xy 34.781168 -108.018728)
			(xy 34.823548 -107.976348) (xy 34.871098 -107.939861) (xy 34.923004 -107.909894) (xy 34.978377 -107.886958)
			(xy 35.03627 -107.871445) (xy 35.095692 -107.863622) (xy 35.155628 -107.863622) (xy 35.21505 -107.871445)
			(xy 35.272943 -107.886958) (xy 35.328316 -107.909894) (xy 35.380222 -107.939861) (xy 35.427772 -107.976348)
			(xy 35.470152 -108.018728) (xy 35.506639 -108.066278) (xy 35.536606 -108.118184) (xy 35.559542 -108.173557)
			(xy 35.575055 -108.23145) (xy 35.582878 -108.290872) (xy 35.583368 -108.32084) (xy 35.583368 -109.18444)
			(xy 35.582878 -109.214408) (xy 35.575055 -109.27383) (xy 35.559542 -109.331723) (xy 35.552057 -109.349794)
			(xy 36.218368 -109.349794) (xy 36.218368 -109.12221) (xy 36.218622 -109.118146) (xy 36.218876 -109.115606)
			(xy 36.218876 -109.10697) (xy 36.224464 -109.098334) (xy 36.225734 -109.096302) (xy 36.22675 -109.09427)
			(xy 36.43249 -108.78058) (xy 36.436554 -108.77423) (xy 36.438586 -108.767372) (xy 36.442142 -108.756704)
			(xy 36.439094 -108.733844) (xy 36.226496 -108.408978) (xy 36.22421 -108.405168) (xy 36.223956 -108.40466)
			(xy 36.22294 -108.402882) (xy 36.218876 -108.396278) (xy 36.218876 -108.38815) (xy 36.218622 -108.38561)
			(xy 36.218368 -108.381546) (xy 36.218368 -108.153454) (xy 36.218797 -108.14329) (xy 36.226592 -108.124514)
			(xy 36.240978 -108.110149) (xy 36.259765 -108.102382) (xy 36.26993 -108.101892) (xy 37.006784 -108.101892)
			(xy 37.01696 -108.102388) (xy 37.035775 -108.11015) (xy 37.050203 -108.124505) (xy 37.05806 -108.14328)
			(xy 37.0586 -108.153454) (xy 37.0586 -108.381038) (xy 37.058346 -108.385102) (xy 37.058092 -108.387642)
			(xy 37.058092 -108.396278) (xy 37.05225 -108.405676) (xy 37.051488 -108.406946) (xy 37.050218 -108.408978)
			(xy 36.839398 -108.731304) (xy 36.837366 -108.740702) (xy 36.835676 -108.750688) (xy 36.839329 -108.77059)
			(xy 36.844478 -108.77931) (xy 37.050218 -109.093) (xy 37.051234 -109.095032) (xy 37.052504 -109.097064)
			(xy 37.058092 -109.1057) (xy 37.058092 -109.114336) (xy 37.058346 -109.116876) (xy 37.0586 -109.12094)
			(xy 37.0586 -109.248194) (xy 45.431964 -109.248194) (xy 45.431964 -108.241846) (xy 45.432402 -108.231674)
			(xy 45.440177 -108.212875) (xy 45.454559 -108.198488) (xy 45.473354 -108.190706) (xy 45.483526 -108.190284)
			(xy 46.664626 -108.190284) (xy 46.674805 -108.190643) (xy 46.693609 -108.198446) (xy 46.707995 -108.212851)
			(xy 46.715771 -108.231666) (xy 46.716188 -108.241846) (xy 46.716188 -109.248194) (xy 46.716175 -109.248448)
			(xy 49.968912 -109.248448) (xy 49.968912 -108.241846) (xy 49.969464 -108.231726) (xy 49.977171 -108.213011)
			(xy 49.991437 -108.198654) (xy 50.010103 -108.190828) (xy 50.02022 -108.190284) (xy 51.20132 -108.190284)
			(xy 51.211428 -108.190768) (xy 51.230104 -108.198509) (xy 51.244397 -108.212806) (xy 51.252134 -108.231484)
			(xy 51.252628 -108.241592) (xy 51.252628 -109.176312) (xy 51.785012 -109.176312) (xy 51.785012 -108.312712)
			(xy 51.785502 -108.282744) (xy 51.793325 -108.223322) (xy 51.808838 -108.165429) (xy 51.831774 -108.110056)
			(xy 51.861741 -108.05815) (xy 51.898228 -108.0106) (xy 51.940608 -107.96822) (xy 51.988158 -107.931733)
			(xy 52.040064 -107.901766) (xy 52.095437 -107.87883) (xy 52.15333 -107.863317) (xy 52.212752 -107.855494)
			(xy 52.272688 -107.855494) (xy 52.33211 -107.863317) (xy 52.390003 -107.87883) (xy 52.445376 -107.901766)
			(xy 52.497282 -107.931733) (xy 52.544832 -107.96822) (xy 52.587212 -108.0106) (xy 52.623699 -108.05815)
			(xy 52.653666 -108.110056) (xy 52.676602 -108.165429) (xy 52.692115 -108.223322) (xy 52.699938 -108.282744)
			(xy 52.700428 -108.312712) (xy 52.700428 -109.176312) (xy 52.700295 -109.18444) (xy 150.767796 -109.18444)
			(xy 150.767796 -108.32084) (xy 150.768286 -108.290856) (xy 150.776114 -108.2314) (xy 150.791635 -108.173475)
			(xy 150.814584 -108.118071) (xy 150.844568 -108.066137) (xy 150.881074 -108.018561) (xy 150.923479 -107.976156)
			(xy 150.971055 -107.93965) (xy 151.022989 -107.909666) (xy 151.078393 -107.886717) (xy 151.136318 -107.871196)
			(xy 151.195774 -107.863368) (xy 151.255742 -107.863368) (xy 151.315198 -107.871196) (xy 151.373123 -107.886717)
			(xy 151.428527 -107.909666) (xy 151.480461 -107.93965) (xy 151.528037 -107.976156) (xy 151.570442 -108.018561)
			(xy 151.606948 -108.066137) (xy 151.636932 -108.118071) (xy 151.659881 -108.173475) (xy 151.675402 -108.2314)
			(xy 151.68323 -108.290856) (xy 151.68372 -108.32084) (xy 151.68372 -109.18444) (xy 151.68323 -109.214424)
			(xy 151.675402 -109.27388) (xy 151.659881 -109.331805) (xy 151.65243 -109.349794) (xy 152.318212 -109.349794)
			(xy 152.318212 -109.10697) (xy 152.3238 -109.098588) (xy 152.324054 -109.09808) (xy 152.326086 -109.095032)
			(xy 152.32634 -109.094524) (xy 152.53208 -108.78058) (xy 152.537076 -108.772145) (xy 152.540896 -108.752934)
			(xy 152.537251 -108.733689) (xy 152.532334 -108.725208) (xy 152.446482 -108.593128) (xy 152.437084 -108.57865)
			(xy 152.324816 -108.406692) (xy 152.324308 -108.405676) (xy 152.322276 -108.402628) (xy 152.322022 -108.40212)
			(xy 152.318212 -108.396278) (xy 152.318212 -108.153454) (xy 152.318433 -108.14708) (xy 152.321649 -108.134744)
			(xy 152.324562 -108.12907) (xy 152.329327 -108.121076) (xy 152.343328 -108.10884) (xy 152.360731 -108.102292)
			(xy 152.370028 -108.101892) (xy 153.106628 -108.101892) (xy 153.118153 -108.102486) (xy 153.138976 -108.11237)
			(xy 153.153558 -108.130221) (xy 153.15692 -108.141262) (xy 153.15692 -108.141516) (xy 153.158444 -108.153454)
			(xy 153.158444 -108.396278) (xy 153.154634 -108.40212) (xy 153.15438 -108.402628) (xy 153.150316 -108.408724)
			(xy 153.150062 -108.408978) (xy 153.01214 -108.620052) (xy 152.959054 -108.701332) (xy 152.946608 -108.720382)
			(xy 152.944576 -108.723176) (xy 152.943306 -108.725208) (xy 152.939094 -108.732619) (xy 152.935385 -108.749245)
			(xy 152.937348 -108.766167) (xy 152.940766 -108.773976) (xy 153.127964 -109.059472) (xy 153.130504 -109.063282)
			(xy 153.150316 -109.093254) (xy 153.15057 -109.093762) (xy 153.15184 -109.095794) (xy 153.153618 -109.098334)
			(xy 153.158444 -109.1057) (xy 153.158444 -109.248194) (xy 161.531808 -109.248194) (xy 161.531808 -108.241846)
			(xy 161.532301 -108.231681) (xy 161.540065 -108.212893) (xy 161.554429 -108.198508) (xy 161.573206 -108.190716)
			(xy 161.58337 -108.190284) (xy 162.76447 -108.190284) (xy 162.774645 -108.19069) (xy 162.793448 -108.198473)
			(xy 162.807836 -108.212865) (xy 162.815613 -108.231671) (xy 162.816032 -108.241846) (xy 162.816032 -109.248194)
			(xy 162.816022 -109.248448) (xy 166.068756 -109.248448) (xy 166.068756 -108.241846) (xy 166.069265 -108.23172)
			(xy 166.07698 -108.212997) (xy 166.09126 -108.198639) (xy 166.109941 -108.190821) (xy 166.120064 -108.190284)
			(xy 167.301164 -108.190284) (xy 167.311282 -108.190745) (xy 167.329982 -108.198479) (xy 167.344297 -108.212781)
			(xy 167.352046 -108.231474) (xy 167.352472 -108.241592) (xy 167.352472 -109.176312) (xy 167.884856 -109.176312)
			(xy 167.884856 -108.312712) (xy 167.885346 -108.282728) (xy 167.893174 -108.223272) (xy 167.908695 -108.165347)
			(xy 167.931644 -108.109943) (xy 167.961628 -108.058009) (xy 167.998134 -108.010433) (xy 168.040539 -107.968028)
			(xy 168.088115 -107.931522) (xy 168.140049 -107.901538) (xy 168.195453 -107.878589) (xy 168.253378 -107.863068)
			(xy 168.312834 -107.85524) (xy 168.372802 -107.85524) (xy 168.432258 -107.863068) (xy 168.490183 -107.878589)
			(xy 168.545587 -107.901538) (xy 168.597521 -107.931522) (xy 168.645097 -107.968028) (xy 168.687502 -108.010433)
			(xy 168.724008 -108.058009) (xy 168.753992 -108.109943) (xy 168.776941 -108.165347) (xy 168.792462 -108.223272)
			(xy 168.80029 -108.282728) (xy 168.80078 -108.312712) (xy 168.80078 -109.176312) (xy 168.800647 -109.18444)
			(xy 266.86764 -109.18444) (xy 266.86764 -108.32084) (xy 266.86813 -108.290856) (xy 266.875958 -108.2314)
			(xy 266.891479 -108.173475) (xy 266.914428 -108.118071) (xy 266.944412 -108.066137) (xy 266.980918 -108.018561)
			(xy 267.023323 -107.976156) (xy 267.070899 -107.93965) (xy 267.122833 -107.909666) (xy 267.178237 -107.886717)
			(xy 267.236162 -107.871196) (xy 267.295618 -107.863368) (xy 267.355586 -107.863368) (xy 267.415042 -107.871196)
			(xy 267.472967 -107.886717) (xy 267.528371 -107.909666) (xy 267.580305 -107.93965) (xy 267.627881 -107.976156)
			(xy 267.670286 -108.018561) (xy 267.706792 -108.066137) (xy 267.736776 -108.118071) (xy 267.759725 -108.173475)
			(xy 267.775246 -108.2314) (xy 267.783074 -108.290856) (xy 267.783564 -108.32084) (xy 267.783564 -109.18444)
			(xy 267.783074 -109.214424) (xy 267.775246 -109.27388) (xy 267.759725 -109.331805) (xy 267.752274 -109.349794)
			(xy 268.418564 -109.349794) (xy 268.418564 -109.10697) (xy 268.537436 -108.925614) (xy 268.59992 -108.83011)
			(xy 268.62405 -108.79328) (xy 268.627938 -108.786963) (xy 268.632186 -108.772755) (xy 268.632432 -108.76534)
			(xy 268.632432 -108.739432) (xy 268.632232 -108.733283) (xy 268.629283 -108.721342) (xy 268.62659 -108.71581)
			(xy 268.513052 -108.54182) (xy 268.492986 -108.510832) (xy 268.487398 -108.502196) (xy 268.426946 -108.409486)
			(xy 268.426438 -108.408724) (xy 268.42593 -108.407962) (xy 268.425676 -108.407454) (xy 268.425168 -108.406692)
			(xy 268.418564 -108.396278) (xy 268.418564 -108.153454) (xy 268.418996 -108.14329) (xy 268.426791 -108.124515)
			(xy 268.441175 -108.11015) (xy 268.459961 -108.102382) (xy 268.470126 -108.101892) (xy 269.206726 -108.101892)
			(xy 269.21688 -108.102411) (xy 269.235641 -108.110185) (xy 269.250004 -108.124542) (xy 269.257785 -108.1433)
			(xy 269.258288 -108.153454) (xy 269.258288 -108.396278) (xy 269.042388 -108.726732) (xy 269.038401 -108.734967)
			(xy 269.035846 -108.753068) (xy 269.039776 -108.770921) (xy 269.04442 -108.778802) (xy 269.076678 -108.828586)
			(xy 269.258288 -109.1057) (xy 269.258288 -109.248194) (xy 277.63216 -109.248194) (xy 277.63216 -108.241846)
			(xy 277.632665 -108.23172) (xy 277.640381 -108.212996) (xy 277.654663 -108.198637) (xy 277.673345 -108.19082)
			(xy 277.683468 -108.190284) (xy 278.864568 -108.190284) (xy 278.874718 -108.190747) (xy 278.893467 -108.198529)
			(xy 278.907791 -108.212913) (xy 278.915495 -108.231694) (xy 278.915876 -108.241846) (xy 278.915876 -109.248194)
			(xy 282.1686 -109.248194) (xy 282.1686 -108.241846) (xy 282.169101 -108.231682) (xy 282.176863 -108.212896)
			(xy 282.191225 -108.198511) (xy 282.209999 -108.190717) (xy 282.220162 -108.190284) (xy 283.401262 -108.190284)
			(xy 283.411437 -108.190696) (xy 283.430239 -108.198477) (xy 283.444627 -108.212867) (xy 283.452405 -108.231671)
			(xy 283.452824 -108.241846) (xy 283.452824 -109.176312) (xy 283.9847 -109.176312) (xy 283.9847 -108.312712)
			(xy 283.98519 -108.282728) (xy 283.993018 -108.223272) (xy 284.008539 -108.165347) (xy 284.031488 -108.109943)
			(xy 284.061472 -108.058009) (xy 284.097978 -108.010433) (xy 284.140383 -107.968028) (xy 284.187959 -107.931522)
			(xy 284.239893 -107.901538) (xy 284.295297 -107.878589) (xy 284.353222 -107.863068) (xy 284.412678 -107.85524)
			(xy 284.472646 -107.85524) (xy 284.532102 -107.863068) (xy 284.590027 -107.878589) (xy 284.645431 -107.901538)
			(xy 284.697365 -107.931522) (xy 284.744941 -107.968028) (xy 284.787346 -108.010433) (xy 284.823852 -108.058009)
			(xy 284.853836 -108.109943) (xy 284.876785 -108.165347) (xy 284.892306 -108.223272) (xy 284.900134 -108.282728)
			(xy 284.900624 -108.312712) (xy 284.900624 -109.176312) (xy 284.900491 -109.18444) (xy 382.967992 -109.18444)
			(xy 382.967992 -108.32084) (xy 382.968482 -108.290872) (xy 382.976305 -108.23145) (xy 382.991818 -108.173557)
			(xy 383.014754 -108.118184) (xy 383.044721 -108.066278) (xy 383.081208 -108.018728) (xy 383.123588 -107.976348)
			(xy 383.171138 -107.939861) (xy 383.223044 -107.909894) (xy 383.278417 -107.886958) (xy 383.33631 -107.871445)
			(xy 383.395732 -107.863622) (xy 383.455668 -107.863622) (xy 383.51509 -107.871445) (xy 383.572983 -107.886958)
			(xy 383.628356 -107.909894) (xy 383.680262 -107.939861) (xy 383.727812 -107.976348) (xy 383.770192 -108.018728)
			(xy 383.806679 -108.066278) (xy 383.836646 -108.118184) (xy 383.859582 -108.173557) (xy 383.875095 -108.23145)
			(xy 383.882918 -108.290872) (xy 383.883408 -108.32084) (xy 383.883408 -109.18444) (xy 383.882918 -109.214408)
			(xy 383.875095 -109.27383) (xy 383.859582 -109.331723) (xy 383.852097 -109.349794) (xy 384.518408 -109.349794)
			(xy 384.518408 -109.10697) (xy 384.523996 -109.098588) (xy 384.52425 -109.09808) (xy 384.526282 -109.095032)
			(xy 384.526536 -109.094524) (xy 384.732276 -108.78058) (xy 384.737272 -108.772145) (xy 384.741092 -108.752934)
			(xy 384.737447 -108.733689) (xy 384.73253 -108.725208) (xy 384.646678 -108.593128) (xy 384.63728 -108.57865)
			(xy 384.525012 -108.406692) (xy 384.524504 -108.405676) (xy 384.522472 -108.402628) (xy 384.522218 -108.40212)
			(xy 384.518408 -108.396278) (xy 384.518408 -108.153454) (xy 384.51863 -108.14708) (xy 384.521845 -108.134744)
			(xy 384.524758 -108.12907) (xy 384.529525 -108.121078) (xy 384.543525 -108.108841) (xy 384.560928 -108.102293)
			(xy 384.570224 -108.101892) (xy 385.306824 -108.101892) (xy 385.318348 -108.102489) (xy 385.339171 -108.112372)
			(xy 385.353754 -108.130221) (xy 385.357116 -108.141262) (xy 385.357116 -108.141516) (xy 385.35864 -108.153454)
			(xy 385.35864 -108.396278) (xy 385.35483 -108.40212) (xy 385.354576 -108.402628) (xy 385.350512 -108.408724)
			(xy 385.350258 -108.408978) (xy 385.212336 -108.620052) (xy 385.15925 -108.701332) (xy 385.146804 -108.720382)
			(xy 385.144772 -108.723176) (xy 385.143502 -108.725208) (xy 385.13929 -108.732619) (xy 385.135581 -108.749245)
			(xy 385.137545 -108.766167) (xy 385.140962 -108.773976) (xy 385.32816 -109.059472) (xy 385.3307 -109.063282)
			(xy 385.350512 -109.093254) (xy 385.350766 -109.093762) (xy 385.352036 -109.095794) (xy 385.353814 -109.098334)
			(xy 385.35864 -109.1057) (xy 385.35864 -109.248194) (xy 393.732004 -109.248194) (xy 393.732004 -108.241846)
			(xy 393.732501 -108.231682) (xy 393.740264 -108.212894) (xy 393.754627 -108.198509) (xy 393.773402 -108.190716)
			(xy 393.783566 -108.190284) (xy 394.964666 -108.190284) (xy 394.974841 -108.190693) (xy 394.993644 -108.198475)
			(xy 395.008031 -108.212866) (xy 395.015809 -108.231671) (xy 395.016228 -108.241846) (xy 395.016228 -109.248194)
			(xy 395.016218 -109.248448) (xy 398.268952 -109.248448) (xy 398.268952 -108.241846) (xy 398.269465 -108.231721)
			(xy 398.27718 -108.212998) (xy 398.291458 -108.19864) (xy 398.310138 -108.190821) (xy 398.32026 -108.190284)
			(xy 399.50136 -108.190284) (xy 399.511478 -108.190749) (xy 399.530178 -108.19848) (xy 399.544493 -108.212782)
			(xy 399.552242 -108.231475) (xy 399.552668 -108.241592) (xy 399.552668 -109.176312) (xy 400.085052 -109.176312)
			(xy 400.085052 -108.312712) (xy 400.085542 -108.282744) (xy 400.093365 -108.223322) (xy 400.108878 -108.165429)
			(xy 400.131814 -108.110056) (xy 400.161781 -108.05815) (xy 400.198268 -108.0106) (xy 400.240648 -107.96822)
			(xy 400.288198 -107.931733) (xy 400.340104 -107.901766) (xy 400.395477 -107.87883) (xy 400.45337 -107.863317)
			(xy 400.512792 -107.855494) (xy 400.572728 -107.855494) (xy 400.63215 -107.863317) (xy 400.690043 -107.87883)
			(xy 400.745416 -107.901766) (xy 400.797322 -107.931733) (xy 400.844872 -107.96822) (xy 400.887252 -108.0106)
			(xy 400.923739 -108.05815) (xy 400.953706 -108.110056) (xy 400.976642 -108.165429) (xy 400.992155 -108.223322)
			(xy 400.999978 -108.282744) (xy 401.000468 -108.312712) (xy 401.000468 -109.176312) (xy 400.999978 -109.20628)
			(xy 400.992155 -109.265702) (xy 400.976642 -109.323595) (xy 400.953706 -109.378968) (xy 400.923739 -109.430874)
			(xy 400.887252 -109.478424) (xy 400.844872 -109.520804) (xy 400.797322 -109.557291) (xy 400.745416 -109.587258)
			(xy 400.690043 -109.610194) (xy 400.63215 -109.625707) (xy 400.572728 -109.63353) (xy 400.512792 -109.63353)
			(xy 400.45337 -109.625707) (xy 400.395477 -109.610194) (xy 400.340104 -109.587258) (xy 400.288198 -109.557291)
			(xy 400.240648 -109.520804) (xy 400.198268 -109.478424) (xy 400.161781 -109.430874) (xy 400.131814 -109.378968)
			(xy 400.108878 -109.323595) (xy 400.093365 -109.265702) (xy 400.085542 -109.20628) (xy 400.085052 -109.176312)
			(xy 399.552668 -109.176312) (xy 399.552668 -109.248194) (xy 399.552169 -109.258319) (xy 399.544444 -109.277039)
			(xy 399.530162 -109.291395) (xy 399.511483 -109.299216) (xy 399.50136 -109.299756) (xy 398.32026 -109.299756)
			(xy 398.310156 -109.299249) (xy 398.291487 -109.291509) (xy 398.277196 -109.277219) (xy 398.269453 -109.258552)
			(xy 398.268952 -109.248448) (xy 395.016218 -109.248448) (xy 395.015831 -109.258369) (xy 395.008041 -109.277171)
			(xy 394.993647 -109.291557) (xy 394.974842 -109.299336) (xy 394.964666 -109.299756) (xy 393.783566 -109.299756)
			(xy 393.773405 -109.299294) (xy 393.754634 -109.291508) (xy 393.74027 -109.277132) (xy 393.732498 -109.258355)
			(xy 393.732004 -109.248194) (xy 385.35864 -109.248194) (xy 385.35864 -109.349794) (xy 385.358405 -109.356167)
			(xy 385.355199 -109.368504) (xy 385.35229 -109.374178) (xy 385.347539 -109.382182) (xy 385.333535 -109.394422)
			(xy 385.316123 -109.400963) (xy 385.306824 -109.401356) (xy 384.570224 -109.401356) (xy 384.558709 -109.400687)
			(xy 384.537893 -109.390833) (xy 384.523303 -109.373014) (xy 384.519932 -109.361986) (xy 384.519932 -109.361732)
			(xy 384.518408 -109.349794) (xy 383.852097 -109.349794) (xy 383.836646 -109.387096) (xy 383.806679 -109.439002)
			(xy 383.770192 -109.486552) (xy 383.727812 -109.528932) (xy 383.680262 -109.565419) (xy 383.628356 -109.595386)
			(xy 383.572983 -109.618322) (xy 383.51509 -109.633835) (xy 383.455668 -109.641658) (xy 383.395732 -109.641658)
			(xy 383.33631 -109.633835) (xy 383.278417 -109.618322) (xy 383.223044 -109.595386) (xy 383.171138 -109.565419)
			(xy 383.123588 -109.528932) (xy 383.081208 -109.486552) (xy 383.044721 -109.439002) (xy 383.014754 -109.387096)
			(xy 382.991818 -109.331723) (xy 382.976305 -109.27383) (xy 382.968482 -109.214408) (xy 382.967992 -109.18444)
			(xy 284.900491 -109.18444) (xy 284.900134 -109.206296) (xy 284.892306 -109.265752) (xy 284.876785 -109.323677)
			(xy 284.853836 -109.379081) (xy 284.823852 -109.431015) (xy 284.787346 -109.478591) (xy 284.744941 -109.520996)
			(xy 284.697365 -109.557502) (xy 284.645431 -109.587486) (xy 284.590027 -109.610435) (xy 284.532102 -109.625956)
			(xy 284.472646 -109.633784) (xy 284.412678 -109.633784) (xy 284.353222 -109.625956) (xy 284.295297 -109.610435)
			(xy 284.239893 -109.587486) (xy 284.187959 -109.557502) (xy 284.140383 -109.520996) (xy 284.097978 -109.478591)
			(xy 284.061472 -109.431015) (xy 284.031488 -109.379081) (xy 284.008539 -109.323677) (xy 283.993018 -109.265752)
			(xy 283.98519 -109.206296) (xy 283.9847 -109.176312) (xy 283.452824 -109.176312) (xy 283.452824 -109.248194)
			(xy 283.45243 -109.25837) (xy 283.44464 -109.277172) (xy 283.430245 -109.291558) (xy 283.411438 -109.299337)
			(xy 283.401262 -109.299756) (xy 282.220162 -109.299756) (xy 282.210001 -109.299298) (xy 282.19123 -109.29151)
			(xy 282.176866 -109.277133) (xy 282.169094 -109.258355) (xy 282.1686 -109.248194) (xy 278.915876 -109.248194)
			(xy 278.915369 -109.258318) (xy 278.907646 -109.277036) (xy 278.893366 -109.291392) (xy 278.87469 -109.299214)
			(xy 278.864568 -109.299756) (xy 277.683468 -109.299756) (xy 277.673319 -109.299306) (xy 277.654576 -109.29151)
			(xy 277.640256 -109.277123) (xy 277.632548 -109.258345) (xy 277.63216 -109.248194) (xy 269.258288 -109.248194)
			(xy 269.258288 -109.349794) (xy 269.257762 -109.359948) (xy 269.249995 -109.378712) (xy 269.235639 -109.393077)
			(xy 269.21688 -109.400856) (xy 269.206726 -109.401356) (xy 268.470126 -109.401356) (xy 268.459955 -109.400915)
			(xy 268.44116 -109.393137) (xy 268.426774 -109.378757) (xy 268.418989 -109.359964) (xy 268.418564 -109.349794)
			(xy 267.752274 -109.349794) (xy 267.736776 -109.387209) (xy 267.706792 -109.439143) (xy 267.670286 -109.486719)
			(xy 267.627881 -109.529124) (xy 267.580305 -109.56563) (xy 267.528371 -109.595614) (xy 267.472967 -109.618563)
			(xy 267.415042 -109.634084) (xy 267.355586 -109.641912) (xy 267.295618 -109.641912) (xy 267.236162 -109.634084)
			(xy 267.178237 -109.618563) (xy 267.122833 -109.595614) (xy 267.070899 -109.56563) (xy 267.023323 -109.529124)
			(xy 266.980918 -109.486719) (xy 266.944412 -109.439143) (xy 266.914428 -109.387209) (xy 266.891479 -109.331805)
			(xy 266.875958 -109.27388) (xy 266.86813 -109.214424) (xy 266.86764 -109.18444) (xy 168.800647 -109.18444)
			(xy 168.80029 -109.206296) (xy 168.792462 -109.265752) (xy 168.776941 -109.323677) (xy 168.753992 -109.379081)
			(xy 168.724008 -109.431015) (xy 168.687502 -109.478591) (xy 168.645097 -109.520996) (xy 168.597521 -109.557502)
			(xy 168.545587 -109.587486) (xy 168.490183 -109.610435) (xy 168.432258 -109.625956) (xy 168.372802 -109.633784)
			(xy 168.312834 -109.633784) (xy 168.253378 -109.625956) (xy 168.195453 -109.610435) (xy 168.140049 -109.587486)
			(xy 168.088115 -109.557502) (xy 168.040539 -109.520996) (xy 167.998134 -109.478591) (xy 167.961628 -109.431015)
			(xy 167.931644 -109.379081) (xy 167.908695 -109.323677) (xy 167.893174 -109.265752) (xy 167.885346 -109.206296)
			(xy 167.884856 -109.176312) (xy 167.352472 -109.176312) (xy 167.352472 -109.248194) (xy 167.351969 -109.258319)
			(xy 167.344245 -109.277038) (xy 167.329964 -109.291394) (xy 167.311286 -109.299215) (xy 167.301164 -109.299756)
			(xy 166.120064 -109.299756) (xy 166.10996 -109.299246) (xy 166.091292 -109.291507) (xy 166.077 -109.277219)
			(xy 166.069257 -109.258552) (xy 166.068756 -109.248448) (xy 162.816022 -109.248448) (xy 162.815631 -109.258369)
			(xy 162.807842 -109.277169) (xy 162.793449 -109.291555) (xy 162.774645 -109.299335) (xy 162.76447 -109.299756)
			(xy 161.58337 -109.299756) (xy 161.57321 -109.299291) (xy 161.554439 -109.291506) (xy 161.540074 -109.277131)
			(xy 161.532302 -109.258355) (xy 161.531808 -109.248194) (xy 153.158444 -109.248194) (xy 153.158444 -109.349794)
			(xy 153.158209 -109.356167) (xy 153.155003 -109.368504) (xy 153.152094 -109.374178) (xy 153.147341 -109.38218)
			(xy 153.133337 -109.39442) (xy 153.115927 -109.400962) (xy 153.106628 -109.401356) (xy 152.370028 -109.401356)
			(xy 152.358513 -109.400684) (xy 152.337697 -109.390832) (xy 152.323107 -109.373013) (xy 152.319736 -109.361986)
			(xy 152.319736 -109.361732) (xy 152.318212 -109.349794) (xy 151.65243 -109.349794) (xy 151.636932 -109.387209)
			(xy 151.606948 -109.439143) (xy 151.570442 -109.486719) (xy 151.528037 -109.529124) (xy 151.480461 -109.56563)
			(xy 151.428527 -109.595614) (xy 151.373123 -109.618563) (xy 151.315198 -109.634084) (xy 151.255742 -109.641912)
			(xy 151.195774 -109.641912) (xy 151.136318 -109.634084) (xy 151.078393 -109.618563) (xy 151.022989 -109.595614)
			(xy 150.971055 -109.56563) (xy 150.923479 -109.529124) (xy 150.881074 -109.486719) (xy 150.844568 -109.439143)
			(xy 150.814584 -109.387209) (xy 150.791635 -109.331805) (xy 150.776114 -109.27388) (xy 150.768286 -109.214424)
			(xy 150.767796 -109.18444) (xy 52.700295 -109.18444) (xy 52.699938 -109.20628) (xy 52.692115 -109.265702)
			(xy 52.676602 -109.323595) (xy 52.653666 -109.378968) (xy 52.623699 -109.430874) (xy 52.587212 -109.478424)
			(xy 52.544832 -109.520804) (xy 52.497282 -109.557291) (xy 52.445376 -109.587258) (xy 52.390003 -109.610194)
			(xy 52.33211 -109.625707) (xy 52.272688 -109.63353) (xy 52.212752 -109.63353) (xy 52.15333 -109.625707)
			(xy 52.095437 -109.610194) (xy 52.040064 -109.587258) (xy 51.988158 -109.557291) (xy 51.940608 -109.520804)
			(xy 51.898228 -109.478424) (xy 51.861741 -109.430874) (xy 51.831774 -109.378968) (xy 51.808838 -109.323595)
			(xy 51.793325 -109.265702) (xy 51.785502 -109.20628) (xy 51.785012 -109.176312) (xy 51.252628 -109.176312)
			(xy 51.252628 -109.248194) (xy 51.252168 -109.258324) (xy 51.244436 -109.277051) (xy 51.230141 -109.291409)
			(xy 51.211448 -109.299223) (xy 51.20132 -109.299756) (xy 50.02022 -109.299756) (xy 50.010119 -109.2992)
			(xy 49.991452 -109.291479) (xy 49.977159 -109.277205) (xy 49.969413 -109.258548) (xy 49.968912 -109.248448)
			(xy 46.716175 -109.248448) (xy 46.715662 -109.258348) (xy 46.707895 -109.277112) (xy 46.693539 -109.291477)
			(xy 46.67478 -109.299256) (xy 46.664626 -109.299756) (xy 45.483526 -109.299756) (xy 45.473355 -109.299315)
			(xy 45.45456 -109.291537) (xy 45.440174 -109.277157) (xy 45.432389 -109.258364) (xy 45.431964 -109.248194)
			(xy 37.0586 -109.248194) (xy 37.0586 -109.349794) (xy 37.058063 -109.359947) (xy 37.050297 -109.378708)
			(xy 37.035945 -109.393073) (xy 37.01719 -109.400854) (xy 37.007038 -109.401356) (xy 36.270184 -109.401356)
			(xy 36.260011 -109.400839) (xy 36.241205 -109.393076) (xy 36.226781 -109.378728) (xy 36.218916 -109.359964)
			(xy 36.218368 -109.349794) (xy 35.552057 -109.349794) (xy 35.536606 -109.387096) (xy 35.506639 -109.439002)
			(xy 35.470152 -109.486552) (xy 35.427772 -109.528932) (xy 35.380222 -109.565419) (xy 35.328316 -109.595386)
			(xy 35.272943 -109.618322) (xy 35.21505 -109.633835) (xy 35.155628 -109.641658) (xy 35.095692 -109.641658)
			(xy 35.03627 -109.633835) (xy 34.978377 -109.618322) (xy 34.923004 -109.595386) (xy 34.871098 -109.565419)
			(xy 34.823548 -109.528932) (xy 34.781168 -109.486552) (xy 34.744681 -109.439002) (xy 34.714714 -109.387096)
			(xy 34.691778 -109.331723) (xy 34.676265 -109.27383) (xy 34.668442 -109.214408) (xy 34.667952 -109.18444)
			(xy 4.30911 -109.18444) (xy 4.30911 -110.977934) (xy 37.31006 -110.977934) (xy 37.31006 -110.114334)
			(xy 37.31055 -110.084366) (xy 37.318373 -110.024944) (xy 37.333886 -109.967051) (xy 37.356822 -109.911678)
			(xy 37.386789 -109.859772) (xy 37.423276 -109.812222) (xy 37.465656 -109.769842) (xy 37.513206 -109.733355)
			(xy 37.565112 -109.703388) (xy 37.620485 -109.680452) (xy 37.678378 -109.664939) (xy 37.7378 -109.657116)
			(xy 37.797736 -109.657116) (xy 37.857158 -109.664939) (xy 37.915051 -109.680452) (xy 37.970424 -109.703388)
			(xy 38.02233 -109.733355) (xy 38.06988 -109.769842) (xy 38.11226 -109.812222) (xy 38.148747 -109.859772)
			(xy 38.178714 -109.911678) (xy 38.20165 -109.967051) (xy 38.217163 -110.024944) (xy 38.224986 -110.084366)
			(xy 38.225476 -110.114334) (xy 38.225476 -110.977934) (xy 38.224986 -111.007902) (xy 38.217163 -111.067324)
			(xy 38.20165 -111.125217) (xy 38.194165 -111.143288) (xy 38.860476 -111.143288) (xy 38.860476 -110.915704)
			(xy 38.86073 -110.91164) (xy 38.860984 -110.9091) (xy 38.860984 -110.900464) (xy 38.866572 -110.891828)
			(xy 38.867842 -110.889796) (xy 38.868858 -110.887764) (xy 39.078662 -110.567978) (xy 39.080948 -110.55985)
			(xy 39.083395 -110.549201) (xy 39.080117 -110.527622) (xy 39.074598 -110.518194) (xy 38.868604 -110.202472)
			(xy 38.866318 -110.198662) (xy 38.866064 -110.198154) (xy 38.865048 -110.196376) (xy 38.860984 -110.189772)
			(xy 38.860984 -110.181644) (xy 38.86073 -110.179104) (xy 38.860476 -110.17504) (xy 38.860476 -109.946948)
			(xy 38.860951 -109.93673) (xy 38.868757 -109.917846) (xy 38.883199 -109.903388) (xy 38.902075 -109.895562)
			(xy 38.912292 -109.895132) (xy 39.648892 -109.895132) (xy 39.659119 -109.89552) (xy 39.678015 -109.90335)
			(xy 39.692473 -109.917818) (xy 39.700288 -109.936721) (xy 39.700708 -109.946948) (xy 39.700708 -110.174532)
			(xy 39.700454 -110.178596) (xy 39.7002 -110.181136) (xy 39.7002 -110.189772) (xy 39.694358 -110.19917)
			(xy 39.693596 -110.20044) (xy 39.692326 -110.202472) (xy 39.486586 -110.517178) (xy 39.481517 -110.525691)
			(xy 39.477703 -110.545115) (xy 39.481528 -110.564537) (xy 39.486586 -110.573058) (xy 39.692326 -110.886494)
			(xy 39.693342 -110.888526) (xy 39.694612 -110.890558) (xy 39.7002 -110.899194) (xy 39.7002 -110.90783)
			(xy 39.700454 -110.91037) (xy 39.700708 -110.914434) (xy 39.700708 -111.048292) (xy 45.431964 -111.048292)
			(xy 45.431964 -110.041944) (xy 45.432457 -110.031797) (xy 45.440231 -110.013053) (xy 45.454606 -109.998729)
			(xy 45.473378 -109.991021) (xy 45.483526 -109.990636) (xy 46.664626 -109.990636) (xy 46.674754 -109.991105)
			(xy 46.693475 -109.998841) (xy 46.70783 -110.013132) (xy 46.715649 -110.031818) (xy 46.716188 -110.041944)
			(xy 46.716188 -111.048292) (xy 49.968912 -111.048292) (xy 49.968912 -110.041944) (xy 49.969352 -110.031823)
			(xy 49.977088 -110.013118) (xy 49.991398 -109.998802) (xy 50.010099 -109.991057) (xy 50.02022 -109.990636)
			(xy 51.20132 -109.990636) (xy 51.211448 -109.991) (xy 51.230159 -109.998762) (xy 51.244474 -110.013095)
			(xy 51.252212 -110.031815) (xy 51.252628 -110.041944) (xy 51.252628 -110.97641) (xy 53.639212 -110.97641)
			(xy 53.639212 -110.11281) (xy 53.639702 -110.082842) (xy 53.647525 -110.02342) (xy 53.663038 -109.965527)
			(xy 53.685974 -109.910154) (xy 53.715941 -109.858248) (xy 53.752428 -109.810698) (xy 53.794808 -109.768318)
			(xy 53.842358 -109.731831) (xy 53.894264 -109.701864) (xy 53.949637 -109.678928) (xy 54.00753 -109.663415)
			(xy 54.066952 -109.655592) (xy 54.126888 -109.655592) (xy 54.18631 -109.663415) (xy 54.244203 -109.678928)
			(xy 54.299576 -109.701864) (xy 54.351482 -109.731831) (xy 54.399032 -109.768318) (xy 54.441412 -109.810698)
			(xy 54.477899 -109.858248) (xy 54.507866 -109.910154) (xy 54.530802 -109.965527) (xy 54.546315 -110.02342)
			(xy 54.554138 -110.082842) (xy 54.554628 -110.11281) (xy 54.554628 -110.97641) (xy 54.554603 -110.977934)
			(xy 153.409904 -110.977934) (xy 153.409904 -110.114334) (xy 153.410394 -110.08435) (xy 153.418222 -110.024894)
			(xy 153.433743 -109.966969) (xy 153.456692 -109.911565) (xy 153.486676 -109.859631) (xy 153.523182 -109.812055)
			(xy 153.565587 -109.76965) (xy 153.613163 -109.733144) (xy 153.665097 -109.70316) (xy 153.720501 -109.680211)
			(xy 153.778426 -109.66469) (xy 153.837882 -109.656862) (xy 153.89785 -109.656862) (xy 153.957306 -109.66469)
			(xy 154.015231 -109.680211) (xy 154.070635 -109.70316) (xy 154.122569 -109.733144) (xy 154.170145 -109.76965)
			(xy 154.21255 -109.812055) (xy 154.249056 -109.859631) (xy 154.27904 -109.911565) (xy 154.301989 -109.966969)
			(xy 154.31751 -110.024894) (xy 154.325338 -110.08435) (xy 154.325828 -110.114334) (xy 154.325828 -110.977934)
			(xy 154.325338 -111.007918) (xy 154.31751 -111.067374) (xy 154.301989 -111.125299) (xy 154.294538 -111.143288)
			(xy 154.96032 -111.143288) (xy 154.96032 -110.915704) (xy 154.960574 -110.91164) (xy 154.960828 -110.9091)
			(xy 154.960828 -110.900464) (xy 154.966416 -110.891828) (xy 154.967686 -110.889796) (xy 154.968702 -110.887764)
			(xy 155.16606 -110.586774) (xy 155.169914 -110.580438) (xy 155.174183 -110.566245) (xy 155.174442 -110.558834)
			(xy 155.174442 -110.53318) (xy 155.174224 -110.525847) (xy 155.170103 -110.511776) (xy 155.166314 -110.505494)
			(xy 154.968448 -110.202472) (xy 154.966162 -110.198662) (xy 154.965908 -110.198154) (xy 154.964892 -110.196376)
			(xy 154.960828 -110.189772) (xy 154.960828 -110.181644) (xy 154.960574 -110.179104) (xy 154.96032 -110.17504)
			(xy 154.96032 -109.946948) (xy 154.960752 -109.936725) (xy 154.968566 -109.917832) (xy 154.983022 -109.903373)
			(xy 155.001913 -109.895554) (xy 155.012136 -109.895132) (xy 155.748736 -109.895132) (xy 155.758966 -109.895484)
			(xy 155.777863 -109.903328) (xy 155.792319 -109.917807) (xy 155.800133 -109.936717) (xy 155.800552 -109.946948)
			(xy 155.800552 -110.174532) (xy 155.800298 -110.178596) (xy 155.800044 -110.181136) (xy 155.800044 -110.189772)
			(xy 155.794202 -110.19917) (xy 155.79344 -110.20044) (xy 155.79217 -110.202472) (xy 155.58643 -110.517178)
			(xy 155.581357 -110.52569) (xy 155.57754 -110.545115) (xy 155.581369 -110.564538) (xy 155.58643 -110.573058)
			(xy 155.79217 -110.886494) (xy 155.793186 -110.888526) (xy 155.794456 -110.890558) (xy 155.800044 -110.899194)
			(xy 155.800044 -110.90783) (xy 155.800298 -110.91037) (xy 155.800552 -110.914434) (xy 155.800552 -111.048292)
			(xy 161.531808 -111.048292) (xy 161.531808 -110.041944) (xy 161.532258 -110.031792) (xy 161.54004 -110.013039)
			(xy 161.554429 -109.998714) (xy 161.573216 -109.991014) (xy 161.58337 -109.990636) (xy 162.76447 -109.990636)
			(xy 162.774594 -109.991151) (xy 162.793314 -109.998868) (xy 162.807671 -110.013146) (xy 162.815492 -110.031822)
			(xy 162.816032 -110.041944) (xy 162.816032 -111.048292) (xy 166.068756 -111.048292) (xy 166.068756 -110.041944)
			(xy 166.069251 -110.03183) (xy 166.076977 -110.013136) (xy 166.091268 -109.998821) (xy 166.109951 -109.991067)
			(xy 166.120064 -109.990636) (xy 167.301164 -109.990636) (xy 167.311289 -109.991047) (xy 167.329998 -109.998789)
			(xy 167.344315 -110.013108) (xy 167.352055 -110.031819) (xy 167.352472 -110.041944) (xy 167.352472 -110.97641)
			(xy 169.739056 -110.97641) (xy 169.739056 -110.11281) (xy 169.739546 -110.082826) (xy 169.747374 -110.02337)
			(xy 169.762895 -109.965445) (xy 169.785844 -109.910041) (xy 169.815828 -109.858107) (xy 169.852334 -109.810531)
			(xy 169.894739 -109.768126) (xy 169.942315 -109.73162) (xy 169.994249 -109.701636) (xy 170.049653 -109.678687)
			(xy 170.107578 -109.663166) (xy 170.167034 -109.655338) (xy 170.227002 -109.655338) (xy 170.286458 -109.663166)
			(xy 170.344383 -109.678687) (xy 170.399787 -109.701636) (xy 170.451721 -109.73162) (xy 170.499297 -109.768126)
			(xy 170.541702 -109.810531) (xy 170.578208 -109.858107) (xy 170.608192 -109.910041) (xy 170.631141 -109.965445)
			(xy 170.646662 -110.02337) (xy 170.65449 -110.082826) (xy 170.65498 -110.11281) (xy 170.65498 -110.97641)
			(xy 170.654955 -110.977934) (xy 269.509748 -110.977934) (xy 269.509748 -110.114334) (xy 269.510238 -110.08435)
			(xy 269.518066 -110.024894) (xy 269.533587 -109.966969) (xy 269.556536 -109.911565) (xy 269.58652 -109.859631)
			(xy 269.623026 -109.812055) (xy 269.665431 -109.76965) (xy 269.713007 -109.733144) (xy 269.764941 -109.70316)
			(xy 269.820345 -109.680211) (xy 269.87827 -109.66469) (xy 269.937726 -109.656862) (xy 269.997694 -109.656862)
			(xy 270.05715 -109.66469) (xy 270.115075 -109.680211) (xy 270.170479 -109.70316) (xy 270.222413 -109.733144)
			(xy 270.269989 -109.76965) (xy 270.312394 -109.812055) (xy 270.3489 -109.859631) (xy 270.378884 -109.911565)
			(xy 270.401833 -109.966969) (xy 270.417354 -110.024894) (xy 270.425182 -110.08435) (xy 270.425672 -110.114334)
			(xy 270.425672 -110.977934) (xy 270.425182 -111.007918) (xy 270.417354 -111.067374) (xy 270.401833 -111.125299)
			(xy 270.394382 -111.143288) (xy 271.060672 -111.143288) (xy 271.060672 -110.900464) (xy 271.179544 -110.719108)
			(xy 271.242028 -110.623604) (xy 271.266158 -110.586774) (xy 271.270012 -110.580438) (xy 271.274281 -110.566245)
			(xy 271.27454 -110.558834) (xy 271.27454 -110.532926) (xy 271.274341 -110.526776) (xy 271.271391 -110.514836)
			(xy 271.268698 -110.509304) (xy 271.15516 -110.335314) (xy 271.135094 -110.304326) (xy 271.129506 -110.29569)
			(xy 271.069054 -110.20298) (xy 271.068546 -110.202218) (xy 271.068038 -110.201456) (xy 271.067784 -110.200948)
			(xy 271.067276 -110.200186) (xy 271.060672 -110.189772) (xy 271.060672 -109.946948) (xy 271.061328 -109.935399)
			(xy 271.071289 -109.914556) (xy 271.089221 -109.899992) (xy 271.100296 -109.896656) (xy 271.112234 -109.895132)
			(xy 271.848834 -109.895132) (xy 271.859589 -109.895672) (xy 271.879279 -109.904324) (xy 271.886934 -109.911896)
			(xy 271.893145 -109.919286) (xy 271.900052 -109.9373) (xy 271.900396 -109.946948) (xy 271.900396 -110.189772)
			(xy 271.684496 -110.520226) (xy 271.680433 -110.52843) (xy 271.677904 -110.546552) (xy 271.681866 -110.564415)
			(xy 271.686528 -110.572296) (xy 271.718786 -110.62208) (xy 271.900396 -110.899194) (xy 271.900396 -111.048292)
			(xy 277.63216 -111.048292) (xy 277.63216 -110.041944) (xy 277.632651 -110.031829) (xy 277.640377 -110.013134)
			(xy 277.654671 -109.99882) (xy 277.673354 -109.991066) (xy 277.683468 -109.990636) (xy 278.864568 -109.990636)
			(xy 278.874693 -109.991043) (xy 278.893403 -109.998787) (xy 278.90772 -110.013107) (xy 278.91546 -110.031819)
			(xy 278.915876 -110.041944) (xy 278.915876 -111.048292) (xy 282.1686 -111.048292) (xy 282.1686 -110.041944)
			(xy 282.169052 -110.031824) (xy 282.176786 -110.013122) (xy 282.191092 -109.998806) (xy 282.209789 -109.991059)
			(xy 282.219908 -109.990636) (xy 283.401262 -109.990636) (xy 283.411386 -109.991158) (xy 283.430105 -109.998872)
			(xy 283.444463 -110.013148) (xy 283.452284 -110.031823) (xy 283.452824 -110.041944) (xy 283.452824 -110.97641)
			(xy 285.8389 -110.97641) (xy 285.8389 -110.11281) (xy 285.83939 -110.082826) (xy 285.847218 -110.02337)
			(xy 285.862739 -109.965445) (xy 285.885688 -109.910041) (xy 285.915672 -109.858107) (xy 285.952178 -109.810531)
			(xy 285.994583 -109.768126) (xy 286.042159 -109.73162) (xy 286.094093 -109.701636) (xy 286.149497 -109.678687)
			(xy 286.207422 -109.663166) (xy 286.266878 -109.655338) (xy 286.326846 -109.655338) (xy 286.386302 -109.663166)
			(xy 286.444227 -109.678687) (xy 286.499631 -109.701636) (xy 286.551565 -109.73162) (xy 286.599141 -109.768126)
			(xy 286.641546 -109.810531) (xy 286.678052 -109.858107) (xy 286.708036 -109.910041) (xy 286.730985 -109.965445)
			(xy 286.746506 -110.02337) (xy 286.754334 -110.082826) (xy 286.754824 -110.11281) (xy 286.754824 -110.97641)
			(xy 286.754799 -110.977934) (xy 385.6101 -110.977934) (xy 385.6101 -110.114334) (xy 385.61059 -110.084366)
			(xy 385.618413 -110.024944) (xy 385.633926 -109.967051) (xy 385.656862 -109.911678) (xy 385.686829 -109.859772)
			(xy 385.723316 -109.812222) (xy 385.765696 -109.769842) (xy 385.813246 -109.733355) (xy 385.865152 -109.703388)
			(xy 385.920525 -109.680452) (xy 385.978418 -109.664939) (xy 386.03784 -109.657116) (xy 386.097776 -109.657116)
			(xy 386.157198 -109.664939) (xy 386.215091 -109.680452) (xy 386.270464 -109.703388) (xy 386.32237 -109.733355)
			(xy 386.36992 -109.769842) (xy 386.4123 -109.812222) (xy 386.448787 -109.859772) (xy 386.478754 -109.911678)
			(xy 386.50169 -109.967051) (xy 386.517203 -110.024944) (xy 386.525026 -110.084366) (xy 386.525516 -110.114334)
			(xy 386.525516 -110.977934) (xy 386.525026 -111.007902) (xy 386.517203 -111.067324) (xy 386.50169 -111.125217)
			(xy 386.494205 -111.143288) (xy 387.160516 -111.143288) (xy 387.160516 -110.915704) (xy 387.16077 -110.91164)
			(xy 387.161024 -110.9091) (xy 387.161024 -110.900464) (xy 387.166612 -110.891828) (xy 387.167882 -110.889796)
			(xy 387.168898 -110.887764) (xy 387.366256 -110.586774) (xy 387.370109 -110.580438) (xy 387.374379 -110.566245)
			(xy 387.374638 -110.558834) (xy 387.374638 -110.53318) (xy 387.37442 -110.525847) (xy 387.370299 -110.511776)
			(xy 387.36651 -110.505494) (xy 387.168644 -110.202472) (xy 387.166358 -110.198662) (xy 387.166104 -110.198154)
			(xy 387.165088 -110.196376) (xy 387.161024 -110.189772) (xy 387.161024 -110.181644) (xy 387.16077 -110.179104)
			(xy 387.160516 -110.17504) (xy 387.160516 -109.946948) (xy 387.160952 -109.936725) (xy 387.168765 -109.917833)
			(xy 387.18322 -109.903374) (xy 387.20211 -109.895555) (xy 387.212332 -109.895132) (xy 387.948932 -109.895132)
			(xy 387.959162 -109.895487) (xy 387.978059 -109.90333) (xy 387.992515 -109.917808) (xy 388.000329 -109.936718)
			(xy 388.000748 -109.946948) (xy 388.000748 -110.174532) (xy 388.000494 -110.178596) (xy 388.00024 -110.181136)
			(xy 388.00024 -110.189772) (xy 387.994398 -110.19917) (xy 387.993636 -110.20044) (xy 387.992366 -110.202472)
			(xy 387.786626 -110.517178) (xy 387.781553 -110.52569) (xy 387.777736 -110.545115) (xy 387.781565 -110.564539)
			(xy 387.786626 -110.573058) (xy 387.992366 -110.886494) (xy 387.993382 -110.888526) (xy 387.994652 -110.890558)
			(xy 388.00024 -110.899194) (xy 388.00024 -110.90783) (xy 388.000494 -110.91037) (xy 388.000748 -110.914434)
			(xy 388.000748 -111.048292) (xy 393.732004 -111.048292) (xy 393.732004 -110.041944) (xy 393.732458 -110.031792)
			(xy 393.74024 -110.01304) (xy 393.754627 -109.998715) (xy 393.773413 -109.991015) (xy 393.783566 -109.990636)
			(xy 394.964666 -109.990636) (xy 394.97479 -109.991155) (xy 394.99351 -109.99887) (xy 395.007867 -110.013147)
			(xy 395.015688 -110.031823) (xy 395.016228 -110.041944) (xy 395.016228 -111.048292) (xy 398.268952 -111.048292)
			(xy 398.268952 -110.041944) (xy 398.269451 -110.03183) (xy 398.277176 -110.013137) (xy 398.291466 -109.998823)
			(xy 398.310147 -109.991068) (xy 398.32026 -109.990636) (xy 399.50136 -109.990636) (xy 399.511484 -109.99105)
			(xy 399.530194 -109.998791) (xy 399.544511 -110.013109) (xy 399.552251 -110.03182) (xy 399.552668 -110.041944)
			(xy 399.552668 -110.97641) (xy 401.939252 -110.97641) (xy 401.939252 -110.11281) (xy 401.939742 -110.082842)
			(xy 401.947565 -110.02342) (xy 401.963078 -109.965527) (xy 401.986014 -109.910154) (xy 402.015981 -109.858248)
			(xy 402.052468 -109.810698) (xy 402.094848 -109.768318) (xy 402.142398 -109.731831) (xy 402.194304 -109.701864)
			(xy 402.249677 -109.678928) (xy 402.30757 -109.663415) (xy 402.366992 -109.655592) (xy 402.426928 -109.655592)
			(xy 402.48635 -109.663415) (xy 402.544243 -109.678928) (xy 402.599616 -109.701864) (xy 402.651522 -109.731831)
			(xy 402.699072 -109.768318) (xy 402.741452 -109.810698) (xy 402.777939 -109.858248) (xy 402.807906 -109.910154)
			(xy 402.830842 -109.965527) (xy 402.846355 -110.02342) (xy 402.854178 -110.082842) (xy 402.854668 -110.11281)
			(xy 402.854668 -110.97641) (xy 402.854178 -111.006378) (xy 402.846355 -111.0658) (xy 402.830842 -111.123693)
			(xy 402.807906 -111.179066) (xy 402.777939 -111.230972) (xy 402.741452 -111.278522) (xy 402.699072 -111.320902)
			(xy 402.651522 -111.357389) (xy 402.599616 -111.387356) (xy 402.544243 -111.410292) (xy 402.48635 -111.425805)
			(xy 402.426928 -111.433628) (xy 402.366992 -111.433628) (xy 402.30757 -111.425805) (xy 402.249677 -111.410292)
			(xy 402.194304 -111.387356) (xy 402.142398 -111.357389) (xy 402.094848 -111.320902) (xy 402.052468 -111.278522)
			(xy 402.015981 -111.230972) (xy 401.986014 -111.179066) (xy 401.963078 -111.123693) (xy 401.947565 -111.0658)
			(xy 401.939742 -111.006378) (xy 401.939252 -110.97641) (xy 399.552668 -110.97641) (xy 399.552668 -111.048292)
			(xy 399.552277 -111.058418) (xy 399.544525 -111.077128) (xy 399.530201 -111.091443) (xy 399.511486 -111.099183)
			(xy 399.50136 -111.0996) (xy 398.32026 -111.0996) (xy 398.310149 -111.099148) (xy 398.29147 -111.091397)
			(xy 398.277176 -111.07709) (xy 398.269443 -111.058404) (xy 398.268952 -111.048292) (xy 395.016228 -111.048292)
			(xy 395.015772 -111.058442) (xy 395.007985 -111.077189) (xy 394.993599 -111.091512) (xy 394.974818 -111.099217)
			(xy 394.964666 -111.0996) (xy 393.783566 -111.0996) (xy 393.773442 -111.099103) (xy 393.754728 -111.091371)
			(xy 393.740374 -111.077089) (xy 393.732549 -111.058413) (xy 393.732004 -111.048292) (xy 388.000748 -111.048292)
			(xy 388.000748 -111.143288) (xy 388.000209 -111.153491) (xy 387.992406 -111.172346) (xy 387.977983 -111.186782)
			(xy 387.959135 -111.194601) (xy 387.948932 -111.195104) (xy 387.212332 -111.195104) (xy 387.202111 -111.194662)
			(xy 387.183222 -111.186847) (xy 387.168765 -111.172395) (xy 387.160942 -111.153509) (xy 387.160516 -111.143288)
			(xy 386.494205 -111.143288) (xy 386.478754 -111.18059) (xy 386.448787 -111.232496) (xy 386.4123 -111.280046)
			(xy 386.36992 -111.322426) (xy 386.32237 -111.358913) (xy 386.270464 -111.38888) (xy 386.215091 -111.411816)
			(xy 386.157198 -111.427329) (xy 386.097776 -111.435152) (xy 386.03784 -111.435152) (xy 385.978418 -111.427329)
			(xy 385.920525 -111.411816) (xy 385.865152 -111.38888) (xy 385.813246 -111.358913) (xy 385.765696 -111.322426)
			(xy 385.723316 -111.280046) (xy 385.686829 -111.232496) (xy 385.656862 -111.18059) (xy 385.633926 -111.125217)
			(xy 385.618413 -111.067324) (xy 385.61059 -111.007902) (xy 385.6101 -110.977934) (xy 286.754799 -110.977934)
			(xy 286.754334 -111.006394) (xy 286.746506 -111.06585) (xy 286.730985 -111.123775) (xy 286.708036 -111.179179)
			(xy 286.678052 -111.231113) (xy 286.641546 -111.278689) (xy 286.599141 -111.321094) (xy 286.551565 -111.3576)
			(xy 286.499631 -111.387584) (xy 286.444227 -111.410533) (xy 286.386302 -111.426054) (xy 286.326846 -111.433882)
			(xy 286.266878 -111.433882) (xy 286.207422 -111.426054) (xy 286.149497 -111.410533) (xy 286.094093 -111.387584)
			(xy 286.042159 -111.3576) (xy 285.994583 -111.321094) (xy 285.952178 -111.278689) (xy 285.915672 -111.231113)
			(xy 285.885688 -111.179179) (xy 285.862739 -111.123775) (xy 285.847218 -111.06585) (xy 285.83939 -111.006394)
			(xy 285.8389 -110.97641) (xy 283.452824 -110.97641) (xy 283.452824 -111.048292) (xy 283.452309 -111.058397)
			(xy 283.444578 -111.077071) (xy 283.430291 -111.091365) (xy 283.411621 -111.099104) (xy 283.401516 -111.0996)
			(xy 282.220162 -111.0996) (xy 282.210038 -111.099106) (xy 282.191323 -111.091373) (xy 282.17697 -111.07709)
			(xy 282.169145 -111.058414) (xy 282.1686 -111.048292) (xy 278.915876 -111.048292) (xy 278.915477 -111.058417)
			(xy 278.907727 -111.077125) (xy 278.893405 -111.09144) (xy 278.874693 -111.099182) (xy 278.864568 -111.0996)
			(xy 277.683468 -111.0996) (xy 277.673357 -111.099141) (xy 277.654678 -111.091393) (xy 277.640385 -111.077088)
			(xy 277.632651 -111.058403) (xy 277.63216 -111.048292) (xy 271.900396 -111.048292) (xy 271.900396 -111.143288)
			(xy 271.899791 -111.154843) (xy 271.88981 -111.175691) (xy 271.871856 -111.19025) (xy 271.860772 -111.19358)
			(xy 271.848834 -111.195104) (xy 271.112234 -111.195104) (xy 271.101478 -111.194571) (xy 271.081789 -111.185913)
			(xy 271.074134 -111.17834) (xy 271.067935 -111.170941) (xy 271.061021 -111.152934) (xy 271.060672 -111.143288)
			(xy 270.394382 -111.143288) (xy 270.378884 -111.180703) (xy 270.3489 -111.232637) (xy 270.312394 -111.280213)
			(xy 270.269989 -111.322618) (xy 270.222413 -111.359124) (xy 270.170479 -111.389108) (xy 270.115075 -111.412057)
			(xy 270.05715 -111.427578) (xy 269.997694 -111.435406) (xy 269.937726 -111.435406) (xy 269.87827 -111.427578)
			(xy 269.820345 -111.412057) (xy 269.764941 -111.389108) (xy 269.713007 -111.359124) (xy 269.665431 -111.322618)
			(xy 269.623026 -111.280213) (xy 269.58652 -111.232637) (xy 269.556536 -111.180703) (xy 269.533587 -111.125299)
			(xy 269.518066 -111.067374) (xy 269.510238 -111.007918) (xy 269.509748 -110.977934) (xy 170.654955 -110.977934)
			(xy 170.65449 -111.006394) (xy 170.646662 -111.06585) (xy 170.631141 -111.123775) (xy 170.608192 -111.179179)
			(xy 170.578208 -111.231113) (xy 170.541702 -111.278689) (xy 170.499297 -111.321094) (xy 170.451721 -111.3576)
			(xy 170.399787 -111.387584) (xy 170.344383 -111.410533) (xy 170.286458 -111.426054) (xy 170.227002 -111.433882)
			(xy 170.167034 -111.433882) (xy 170.107578 -111.426054) (xy 170.049653 -111.410533) (xy 169.994249 -111.387584)
			(xy 169.942315 -111.3576) (xy 169.894739 -111.321094) (xy 169.852334 -111.278689) (xy 169.815828 -111.231113)
			(xy 169.785844 -111.179179) (xy 169.762895 -111.123775) (xy 169.747374 -111.06585) (xy 169.739546 -111.006394)
			(xy 169.739056 -110.97641) (xy 167.352472 -110.97641) (xy 167.352472 -111.048292) (xy 167.352077 -111.058417)
			(xy 167.344326 -111.077126) (xy 167.330003 -111.091442) (xy 167.31129 -111.099182) (xy 167.301164 -111.0996)
			(xy 166.120064 -111.0996) (xy 166.109953 -111.099144) (xy 166.091274 -111.091395) (xy 166.07698 -111.077089)
			(xy 166.069247 -111.058403) (xy 166.068756 -111.048292) (xy 162.816032 -111.048292) (xy 162.815572 -111.058442)
			(xy 162.807786 -111.077188) (xy 162.793401 -111.09151) (xy 162.774621 -111.099216) (xy 162.76447 -111.0996)
			(xy 161.58337 -111.0996) (xy 161.573246 -111.099099) (xy 161.554532 -111.091369) (xy 161.540178 -111.077088)
			(xy 161.532353 -111.058413) (xy 161.531808 -111.048292) (xy 155.800552 -111.048292) (xy 155.800552 -111.143288)
			(xy 155.800009 -111.153491) (xy 155.792207 -111.172345) (xy 155.777785 -111.18678) (xy 155.758938 -111.1946)
			(xy 155.748736 -111.195104) (xy 155.012136 -111.195104) (xy 155.001915 -111.194658) (xy 154.983026 -111.186845)
			(xy 154.968569 -111.172394) (xy 154.960746 -111.153509) (xy 154.96032 -111.143288) (xy 154.294538 -111.143288)
			(xy 154.27904 -111.180703) (xy 154.249056 -111.232637) (xy 154.21255 -111.280213) (xy 154.170145 -111.322618)
			(xy 154.122569 -111.359124) (xy 154.070635 -111.389108) (xy 154.015231 -111.412057) (xy 153.957306 -111.427578)
			(xy 153.89785 -111.435406) (xy 153.837882 -111.435406) (xy 153.778426 -111.427578) (xy 153.720501 -111.412057)
			(xy 153.665097 -111.389108) (xy 153.613163 -111.359124) (xy 153.565587 -111.322618) (xy 153.523182 -111.280213)
			(xy 153.486676 -111.232637) (xy 153.456692 -111.180703) (xy 153.433743 -111.125299) (xy 153.418222 -111.067374)
			(xy 153.410394 -111.007918) (xy 153.409904 -110.977934) (xy 54.554603 -110.977934) (xy 54.554138 -111.006378)
			(xy 54.546315 -111.0658) (xy 54.530802 -111.123693) (xy 54.507866 -111.179066) (xy 54.477899 -111.230972)
			(xy 54.441412 -111.278522) (xy 54.399032 -111.320902) (xy 54.351482 -111.357389) (xy 54.299576 -111.387356)
			(xy 54.244203 -111.410292) (xy 54.18631 -111.425805) (xy 54.126888 -111.433628) (xy 54.066952 -111.433628)
			(xy 54.00753 -111.425805) (xy 53.949637 -111.410292) (xy 53.894264 -111.387356) (xy 53.842358 -111.357389)
			(xy 53.794808 -111.320902) (xy 53.752428 -111.278522) (xy 53.715941 -111.230972) (xy 53.685974 -111.179066)
			(xy 53.663038 -111.123693) (xy 53.647525 -111.0658) (xy 53.639702 -111.006378) (xy 53.639212 -110.97641)
			(xy 51.252628 -110.97641) (xy 51.252628 -111.048292) (xy 51.252109 -111.058397) (xy 51.244379 -111.077069)
			(xy 51.230093 -111.091364) (xy 51.211424 -111.099103) (xy 51.20132 -111.0996) (xy 50.02022 -111.0996)
			(xy 50.010099 -111.099168) (xy 49.991396 -111.091426) (xy 49.977081 -111.077115) (xy 49.969335 -111.058413)
			(xy 49.968912 -111.048292) (xy 46.716188 -111.048292) (xy 46.715772 -111.058447) (xy 46.707976 -111.077202)
			(xy 46.693578 -111.091526) (xy 46.674783 -111.099224) (xy 46.664626 -111.0996) (xy 45.483526 -111.0996)
			(xy 45.473406 -111.099053) (xy 45.454693 -111.091342) (xy 45.440337 -111.077074) (xy 45.43251 -111.058409)
			(xy 45.431964 -111.048292) (xy 39.700708 -111.048292) (xy 39.700708 -111.143288) (xy 39.700278 -111.15351)
			(xy 39.692457 -111.172398) (xy 39.678002 -111.186855) (xy 39.659114 -111.194677) (xy 39.648892 -111.195104)
			(xy 38.912292 -111.195104) (xy 38.902068 -111.194694) (xy 38.883178 -111.186866) (xy 38.868723 -111.172405)
			(xy 38.860902 -111.153512) (xy 38.860476 -111.143288) (xy 38.194165 -111.143288) (xy 38.178714 -111.18059)
			(xy 38.148747 -111.232496) (xy 38.11226 -111.280046) (xy 38.06988 -111.322426) (xy 38.02233 -111.358913)
			(xy 37.970424 -111.38888) (xy 37.915051 -111.411816) (xy 37.857158 -111.427329) (xy 37.797736 -111.435152)
			(xy 37.7378 -111.435152) (xy 37.678378 -111.427329) (xy 37.620485 -111.411816) (xy 37.565112 -111.38888)
			(xy 37.513206 -111.358913) (xy 37.465656 -111.322426) (xy 37.423276 -111.280046) (xy 37.386789 -111.232496)
			(xy 37.356822 -111.18059) (xy 37.333886 -111.125217) (xy 37.318373 -111.067324) (xy 37.31055 -111.007902)
			(xy 37.31006 -110.977934) (xy 4.30911 -110.977934) (xy 4.30911 -112.784382) (xy 34.667952 -112.784382)
			(xy 34.667952 -111.920782) (xy 34.668442 -111.890814) (xy 34.676265 -111.831392) (xy 34.691778 -111.773499)
			(xy 34.714714 -111.718126) (xy 34.744681 -111.66622) (xy 34.781168 -111.61867) (xy 34.823548 -111.57629)
			(xy 34.871098 -111.539803) (xy 34.923004 -111.509836) (xy 34.978377 -111.4869) (xy 35.03627 -111.471387)
			(xy 35.095692 -111.463564) (xy 35.155628 -111.463564) (xy 35.21505 -111.471387) (xy 35.272943 -111.4869)
			(xy 35.328316 -111.509836) (xy 35.380222 -111.539803) (xy 35.427772 -111.57629) (xy 35.470152 -111.61867)
			(xy 35.506639 -111.66622) (xy 35.536606 -111.718126) (xy 35.559542 -111.773499) (xy 35.575055 -111.831392)
			(xy 35.582878 -111.890814) (xy 35.583368 -111.920782) (xy 35.583368 -112.784382) (xy 35.582878 -112.81435)
			(xy 35.575055 -112.873772) (xy 35.559542 -112.931665) (xy 35.552057 -112.949736) (xy 36.218368 -112.949736)
			(xy 36.218368 -112.722152) (xy 36.218622 -112.718088) (xy 36.218876 -112.715548) (xy 36.218876 -112.706912)
			(xy 36.224464 -112.698276) (xy 36.225734 -112.696244) (xy 36.22675 -112.694212) (xy 36.436554 -112.374426)
			(xy 36.43884 -112.366298) (xy 36.44132 -112.355654) (xy 36.43802 -112.334069) (xy 36.43249 -112.324642)
			(xy 36.226496 -112.00892) (xy 36.22421 -112.00511) (xy 36.223956 -112.004602) (xy 36.22294 -112.002824)
			(xy 36.218876 -111.99622) (xy 36.218876 -111.988092) (xy 36.218622 -111.985552) (xy 36.218368 -111.981488)
			(xy 36.218368 -111.753396) (xy 36.218878 -111.74319) (xy 36.226689 -111.724331) (xy 36.241121 -111.709896)
			(xy 36.259978 -111.702081) (xy 36.270184 -111.70158) (xy 37.006784 -111.70158) (xy 37.017004 -111.702025)
			(xy 37.03589 -111.709842) (xy 37.050346 -111.724293) (xy 37.058171 -111.743176) (xy 37.0586 -111.753396)
			(xy 37.0586 -111.98098) (xy 37.058346 -111.985044) (xy 37.058092 -111.987584) (xy 37.058092 -111.99622)
			(xy 37.05225 -112.005618) (xy 37.051488 -112.006888) (xy 37.050218 -112.00892) (xy 36.844478 -112.323626)
			(xy 36.839452 -112.332161) (xy 36.835625 -112.351571) (xy 36.839431 -112.370986) (xy 36.844478 -112.379506)
			(xy 37.050218 -112.692942) (xy 37.051234 -112.694974) (xy 37.052504 -112.697006) (xy 37.058092 -112.705642)
			(xy 37.058092 -112.714278) (xy 37.058346 -112.716818) (xy 37.0586 -112.720882) (xy 37.0586 -112.848136)
			(xy 45.431964 -112.848136) (xy 45.431964 -111.841788) (xy 45.432411 -111.831638) (xy 45.440204 -111.812892)
			(xy 45.454592 -111.79857) (xy 45.473374 -111.790864) (xy 45.483526 -111.79048) (xy 46.664626 -111.79048)
			(xy 46.674759 -111.790906) (xy 46.693489 -111.79865) (xy 46.707846 -111.812955) (xy 46.715657 -111.831657)
			(xy 46.716188 -111.841788) (xy 46.716188 -112.848136) (xy 49.968912 -112.848136) (xy 49.968912 -111.841788)
			(xy 49.969306 -111.831663) (xy 49.977061 -111.812957) (xy 49.991384 -111.798643) (xy 50.010095 -111.7909)
			(xy 50.02022 -111.79048) (xy 51.20132 -111.79048) (xy 51.211428 -111.790968) (xy 51.230102 -111.798709)
			(xy 51.244396 -111.813004) (xy 51.252134 -111.83168) (xy 51.252628 -111.841788) (xy 51.252628 -112.776508)
			(xy 51.785012 -112.776508) (xy 51.785012 -111.912908) (xy 51.785502 -111.88294) (xy 51.793325 -111.823518)
			(xy 51.808838 -111.765625) (xy 51.831774 -111.710252) (xy 51.861741 -111.658346) (xy 51.898228 -111.610796)
			(xy 51.940608 -111.568416) (xy 51.988158 -111.531929) (xy 52.040064 -111.501962) (xy 52.095437 -111.479026)
			(xy 52.15333 -111.463513) (xy 52.212752 -111.45569) (xy 52.272688 -111.45569) (xy 52.33211 -111.463513)
			(xy 52.390003 -111.479026) (xy 52.445376 -111.501962) (xy 52.497282 -111.531929) (xy 52.544832 -111.568416)
			(xy 52.587212 -111.610796) (xy 52.623699 -111.658346) (xy 52.653666 -111.710252) (xy 52.676602 -111.765625)
			(xy 52.692115 -111.823518) (xy 52.699938 -111.88294) (xy 52.700428 -111.912908) (xy 52.700428 -112.776508)
			(xy 52.700299 -112.784382) (xy 150.767796 -112.784382) (xy 150.767796 -111.920782) (xy 150.768286 -111.890798)
			(xy 150.776114 -111.831342) (xy 150.791635 -111.773417) (xy 150.814584 -111.718013) (xy 150.844568 -111.666079)
			(xy 150.881074 -111.618503) (xy 150.923479 -111.576098) (xy 150.971055 -111.539592) (xy 151.022989 -111.509608)
			(xy 151.078393 -111.486659) (xy 151.136318 -111.471138) (xy 151.195774 -111.46331) (xy 151.255742 -111.46331)
			(xy 151.315198 -111.471138) (xy 151.373123 -111.486659) (xy 151.428527 -111.509608) (xy 151.480461 -111.539592)
			(xy 151.528037 -111.576098) (xy 151.570442 -111.618503) (xy 151.606948 -111.666079) (xy 151.636932 -111.718013)
			(xy 151.659881 -111.773417) (xy 151.675402 -111.831342) (xy 151.68323 -111.890798) (xy 151.68372 -111.920782)
			(xy 151.68372 -112.784382) (xy 151.68323 -112.814366) (xy 151.675402 -112.873822) (xy 151.659881 -112.931747)
			(xy 151.65243 -112.949736) (xy 152.318212 -112.949736) (xy 152.318212 -112.706912) (xy 152.3238 -112.69853)
			(xy 152.324054 -112.698022) (xy 152.326086 -112.694974) (xy 152.32634 -112.694466) (xy 152.53208 -112.380522)
			(xy 152.537041 -112.372069) (xy 152.540873 -112.35287) (xy 152.537243 -112.333631) (xy 152.532334 -112.32515)
			(xy 152.446482 -112.19307) (xy 152.437084 -112.178592) (xy 152.324816 -112.006634) (xy 152.324308 -112.005618)
			(xy 152.322276 -112.00257) (xy 152.322022 -112.002062) (xy 152.318212 -111.99622) (xy 152.318212 -111.753396)
			(xy 152.318609 -111.743171) (xy 152.326439 -111.724278) (xy 152.340905 -111.709821) (xy 152.359802 -111.702003)
			(xy 152.370028 -111.70158) (xy 153.106628 -111.70158) (xy 153.116837 -111.702059) (xy 153.135699 -111.70988)
			(xy 153.150134 -111.724322) (xy 153.157946 -111.743187) (xy 153.158444 -111.753396) (xy 153.158444 -111.99622)
			(xy 153.154634 -112.002062) (xy 153.15438 -112.00257) (xy 153.150316 -112.008666) (xy 153.150062 -112.00892)
			(xy 153.01214 -112.219994) (xy 152.959054 -112.301274) (xy 152.946608 -112.320324) (xy 152.944576 -112.323118)
			(xy 152.943306 -112.32515) (xy 152.939064 -112.332545) (xy 152.935365 -112.349181) (xy 152.937341 -112.366109)
			(xy 152.940766 -112.373918) (xy 153.127964 -112.659414) (xy 153.130504 -112.663224) (xy 153.150316 -112.693196)
			(xy 153.15057 -112.693704) (xy 153.15184 -112.695736) (xy 153.153618 -112.698276) (xy 153.158444 -112.705642)
			(xy 153.158444 -112.848136) (xy 161.531808 -112.848136) (xy 161.531808 -111.841788) (xy 161.532212 -111.831632)
			(xy 161.540013 -111.812878) (xy 161.554415 -111.798554) (xy 161.573212 -111.790857) (xy 161.58337 -111.79048)
			(xy 162.76447 -111.79048) (xy 162.7746 -111.790952) (xy 162.793328 -111.798677) (xy 162.807687 -111.812969)
			(xy 162.8155 -111.831661) (xy 162.816032 -111.841788) (xy 162.816032 -112.848136) (xy 166.068756 -112.848136)
			(xy 166.068756 -111.841788) (xy 166.069274 -111.831684) (xy 166.077008 -111.813014) (xy 166.091294 -111.798721)
			(xy 166.10996 -111.790979) (xy 166.120064 -111.79048) (xy 167.301164 -111.79048) (xy 167.311282 -111.790945)
			(xy 167.329981 -111.798678) (xy 167.344295 -111.812979) (xy 167.352045 -111.831671) (xy 167.352472 -111.841788)
			(xy 167.352472 -112.776508) (xy 167.884856 -112.776508) (xy 167.884856 -111.912908) (xy 167.885346 -111.882924)
			(xy 167.893174 -111.823468) (xy 167.908695 -111.765543) (xy 167.931644 -111.710139) (xy 167.961628 -111.658205)
			(xy 167.998134 -111.610629) (xy 168.040539 -111.568224) (xy 168.088115 -111.531718) (xy 168.140049 -111.501734)
			(xy 168.195453 -111.478785) (xy 168.253378 -111.463264) (xy 168.312834 -111.455436) (xy 168.372802 -111.455436)
			(xy 168.432258 -111.463264) (xy 168.490183 -111.478785) (xy 168.545587 -111.501734) (xy 168.597521 -111.531718)
			(xy 168.645097 -111.568224) (xy 168.687502 -111.610629) (xy 168.724008 -111.658205) (xy 168.753992 -111.710139)
			(xy 168.776941 -111.765543) (xy 168.792462 -111.823468) (xy 168.80029 -111.882924) (xy 168.80078 -111.912908)
			(xy 168.80078 -112.776508) (xy 168.800651 -112.784382) (xy 266.86764 -112.784382) (xy 266.86764 -111.920782)
			(xy 266.86813 -111.890798) (xy 266.875958 -111.831342) (xy 266.891479 -111.773417) (xy 266.914428 -111.718013)
			(xy 266.944412 -111.666079) (xy 266.980918 -111.618503) (xy 267.023323 -111.576098) (xy 267.070899 -111.539592)
			(xy 267.122833 -111.509608) (xy 267.178237 -111.486659) (xy 267.236162 -111.471138) (xy 267.295618 -111.46331)
			(xy 267.355586 -111.46331) (xy 267.415042 -111.471138) (xy 267.472967 -111.486659) (xy 267.528371 -111.509608)
			(xy 267.580305 -111.539592) (xy 267.627881 -111.576098) (xy 267.670286 -111.618503) (xy 267.706792 -111.666079)
			(xy 267.736776 -111.718013) (xy 267.759725 -111.773417) (xy 267.775246 -111.831342) (xy 267.783074 -111.890798)
			(xy 267.783564 -111.920782) (xy 267.783564 -112.784382) (xy 267.783074 -112.814366) (xy 267.775246 -112.873822)
			(xy 267.759725 -112.931747) (xy 267.752274 -112.949736) (xy 268.418564 -112.949736) (xy 268.418564 -112.706912)
			(xy 268.537436 -112.525556) (xy 268.59992 -112.430052) (xy 268.62405 -112.393222) (xy 268.627922 -112.386896)
			(xy 268.63218 -112.372695) (xy 268.632432 -112.365282) (xy 268.632432 -112.339374) (xy 268.632252 -112.333223)
			(xy 268.629289 -112.321282) (xy 268.62659 -112.315752) (xy 268.513052 -112.141762) (xy 268.492986 -112.110774)
			(xy 268.487398 -112.102138) (xy 268.426946 -112.009428) (xy 268.426438 -112.008666) (xy 268.42593 -112.007904)
			(xy 268.425676 -112.007396) (xy 268.425168 -112.006634) (xy 268.418564 -111.99622) (xy 268.418564 -111.753396)
			(xy 268.419262 -111.741852) (xy 268.429203 -111.721011) (xy 268.447119 -111.706443) (xy 268.458188 -111.703104)
			(xy 268.470126 -111.70158) (xy 269.206726 -111.70158) (xy 269.217479 -111.702139) (xy 269.237168 -111.710779)
			(xy 269.244826 -111.718344) (xy 269.251013 -111.725751) (xy 269.257935 -111.743752) (xy 269.258288 -111.753396)
			(xy 269.258288 -111.99622) (xy 269.042388 -112.326674) (xy 269.038367 -112.334895) (xy 269.035824 -112.353005)
			(xy 269.039768 -112.370863) (xy 269.04442 -112.378744) (xy 269.076678 -112.428528) (xy 269.258288 -112.705642)
			(xy 269.258288 -112.848136) (xy 277.63216 -112.848136) (xy 277.63216 -111.841788) (xy 277.632675 -111.831683)
			(xy 277.640409 -111.813013) (xy 277.654696 -111.79872) (xy 277.673364 -111.790978) (xy 277.683468 -111.79048)
			(xy 278.864568 -111.79048) (xy 278.874686 -111.790941) (xy 278.893385 -111.798675) (xy 278.9077 -111.812978)
			(xy 278.91545 -111.83167) (xy 278.915876 -111.841788) (xy 278.915876 -112.848136) (xy 282.1686 -112.848136)
			(xy 282.1686 -111.841788) (xy 282.169076 -111.831679) (xy 282.176817 -111.813) (xy 282.191117 -111.798706)
			(xy 282.209798 -111.790972) (xy 282.219908 -111.79048) (xy 283.401262 -111.79048) (xy 283.411391 -111.790959)
			(xy 283.430119 -111.798682) (xy 283.444478 -111.812971) (xy 283.452291 -111.831661) (xy 283.452824 -111.841788)
			(xy 283.452824 -112.776508) (xy 283.9847 -112.776508) (xy 283.9847 -111.912908) (xy 283.98519 -111.882924)
			(xy 283.993018 -111.823468) (xy 284.008539 -111.765543) (xy 284.031488 -111.710139) (xy 284.061472 -111.658205)
			(xy 284.097978 -111.610629) (xy 284.140383 -111.568224) (xy 284.187959 -111.531718) (xy 284.239893 -111.501734)
			(xy 284.295297 -111.478785) (xy 284.353222 -111.463264) (xy 284.412678 -111.455436) (xy 284.472646 -111.455436)
			(xy 284.532102 -111.463264) (xy 284.590027 -111.478785) (xy 284.645431 -111.501734) (xy 284.697365 -111.531718)
			(xy 284.744941 -111.568224) (xy 284.787346 -111.610629) (xy 284.823852 -111.658205) (xy 284.853836 -111.710139)
			(xy 284.876785 -111.765543) (xy 284.892306 -111.823468) (xy 284.900134 -111.882924) (xy 284.900624 -111.912908)
			(xy 284.900624 -112.776508) (xy 284.900495 -112.784382) (xy 382.967992 -112.784382) (xy 382.967992 -111.920782)
			(xy 382.968482 -111.890814) (xy 382.976305 -111.831392) (xy 382.991818 -111.773499) (xy 383.014754 -111.718126)
			(xy 383.044721 -111.66622) (xy 383.081208 -111.61867) (xy 383.123588 -111.57629) (xy 383.171138 -111.539803)
			(xy 383.223044 -111.509836) (xy 383.278417 -111.4869) (xy 383.33631 -111.471387) (xy 383.395732 -111.463564)
			(xy 383.455668 -111.463564) (xy 383.51509 -111.471387) (xy 383.572983 -111.4869) (xy 383.628356 -111.509836)
			(xy 383.680262 -111.539803) (xy 383.727812 -111.57629) (xy 383.770192 -111.61867) (xy 383.806679 -111.66622)
			(xy 383.836646 -111.718126) (xy 383.859582 -111.773499) (xy 383.875095 -111.831392) (xy 383.882918 -111.890814)
			(xy 383.883408 -111.920782) (xy 383.883408 -112.784382) (xy 383.882918 -112.81435) (xy 383.875095 -112.873772)
			(xy 383.859582 -112.931665) (xy 383.852097 -112.949736) (xy 384.518408 -112.949736) (xy 384.518408 -112.722152)
			(xy 384.518662 -112.718088) (xy 384.518916 -112.715548) (xy 384.518916 -112.706912) (xy 384.524504 -112.698276)
			(xy 384.525774 -112.696244) (xy 384.52679 -112.694212) (xy 384.724148 -112.393222) (xy 384.72802 -112.386896)
			(xy 384.732278 -112.372695) (xy 384.73253 -112.365282) (xy 384.73253 -112.339628) (xy 384.732335 -112.332293)
			(xy 384.728198 -112.318222) (xy 384.724402 -112.311942) (xy 384.526536 -112.00892) (xy 384.52425 -112.00511)
			(xy 384.523996 -112.004602) (xy 384.52298 -112.002824) (xy 384.518916 -111.99622) (xy 384.518916 -111.988092)
			(xy 384.518662 -111.985552) (xy 384.518408 -111.981488) (xy 384.518408 -111.753396) (xy 384.518809 -111.743171)
			(xy 384.526638 -111.724279) (xy 384.541103 -111.709823) (xy 384.559999 -111.702004) (xy 384.570224 -111.70158)
			(xy 385.306824 -111.70158) (xy 385.317033 -111.702062) (xy 385.335894 -111.709882) (xy 385.350329 -111.724322)
			(xy 385.358142 -111.743187) (xy 385.35864 -111.753396) (xy 385.35864 -111.98098) (xy 385.358386 -111.985044)
			(xy 385.358132 -111.987584) (xy 385.358132 -111.99622) (xy 385.35229 -112.005618) (xy 385.351528 -112.006888)
			(xy 385.350258 -112.00892) (xy 385.144518 -112.323626) (xy 385.139489 -112.33216) (xy 385.135659 -112.351571)
			(xy 385.139468 -112.370987) (xy 385.144518 -112.379506) (xy 385.350258 -112.692942) (xy 385.351274 -112.694974)
			(xy 385.352544 -112.697006) (xy 385.358132 -112.705642) (xy 385.358132 -112.714278) (xy 385.358386 -112.716818)
			(xy 385.35864 -112.720882) (xy 385.35864 -112.848136) (xy 393.732004 -112.848136) (xy 393.732004 -111.841788)
			(xy 393.732412 -111.831633) (xy 393.740212 -111.812879) (xy 393.754613 -111.798556) (xy 393.773408 -111.790857)
			(xy 393.783566 -111.79048) (xy 394.964666 -111.79048) (xy 394.974795 -111.790956) (xy 394.993523 -111.79868)
			(xy 395.007882 -111.81297) (xy 395.015695 -111.831661) (xy 395.016228 -111.841788) (xy 395.016228 -112.848136)
			(xy 398.268952 -112.848136) (xy 398.268952 -111.841788) (xy 398.269474 -111.831684) (xy 398.277207 -111.813015)
			(xy 398.291492 -111.798723) (xy 398.310157 -111.79098) (xy 398.32026 -111.79048) (xy 399.50136 -111.79048)
			(xy 399.511477 -111.790948) (xy 399.530176 -111.79868) (xy 399.544491 -111.81298) (xy 399.552241 -111.831671)
			(xy 399.552668 -111.841788) (xy 399.552668 -112.776508) (xy 400.085052 -112.776508) (xy 400.085052 -111.912908)
			(xy 400.085542 -111.88294) (xy 400.093365 -111.823518) (xy 400.108878 -111.765625) (xy 400.131814 -111.710252)
			(xy 400.161781 -111.658346) (xy 400.198268 -111.610796) (xy 400.240648 -111.568416) (xy 400.288198 -111.531929)
			(xy 400.340104 -111.501962) (xy 400.395477 -111.479026) (xy 400.45337 -111.463513) (xy 400.512792 -111.45569)
			(xy 400.572728 -111.45569) (xy 400.63215 -111.463513) (xy 400.690043 -111.479026) (xy 400.745416 -111.501962)
			(xy 400.797322 -111.531929) (xy 400.844872 -111.568416) (xy 400.887252 -111.610796) (xy 400.923739 -111.658346)
			(xy 400.953706 -111.710252) (xy 400.976642 -111.765625) (xy 400.992155 -111.823518) (xy 400.999978 -111.88294)
			(xy 401.000468 -111.912908) (xy 401.000468 -112.776508) (xy 400.999978 -112.806476) (xy 400.992155 -112.865898)
			(xy 400.976642 -112.923791) (xy 400.953706 -112.979164) (xy 400.923739 -113.03107) (xy 400.887252 -113.07862)
			(xy 400.844872 -113.121) (xy 400.797322 -113.157487) (xy 400.745416 -113.187454) (xy 400.690043 -113.21039)
			(xy 400.63215 -113.225903) (xy 400.572728 -113.233726) (xy 400.512792 -113.233726) (xy 400.45337 -113.225903)
			(xy 400.395477 -113.21039) (xy 400.340104 -113.187454) (xy 400.288198 -113.157487) (xy 400.240648 -113.121)
			(xy 400.198268 -113.07862) (xy 400.161781 -113.03107) (xy 400.131814 -112.979164) (xy 400.108878 -112.923791)
			(xy 400.093365 -112.865898) (xy 400.085542 -112.806476) (xy 400.085052 -112.776508) (xy 399.552668 -112.776508)
			(xy 399.552668 -112.848136) (xy 399.552313 -112.858265) (xy 399.544547 -112.876975) (xy 399.530211 -112.891289)
			(xy 399.511489 -112.899028) (xy 399.50136 -112.899444) (xy 398.32026 -112.899444) (xy 398.310154 -112.898949)
			(xy 398.291483 -112.891206) (xy 398.277192 -112.876913) (xy 398.269451 -112.858242) (xy 398.268952 -112.848136)
			(xy 395.016228 -112.848136) (xy 395.015808 -112.858289) (xy 395.008006 -112.877037) (xy 394.99361 -112.891358)
			(xy 394.974821 -112.899061) (xy 394.964666 -112.899444) (xy 393.783566 -112.899444) (xy 393.773435 -112.899001)
			(xy 393.75471 -112.891259) (xy 393.740354 -112.876959) (xy 393.732539 -112.858265) (xy 393.732004 -112.848136)
			(xy 385.35864 -112.848136) (xy 385.35864 -112.949736) (xy 385.358148 -112.959943) (xy 385.350328 -112.978801)
			(xy 385.335891 -112.993235) (xy 385.317031 -113.001051) (xy 385.306824 -113.001552) (xy 384.570224 -113.001552)
			(xy 384.560022 -113.001) (xy 384.541168 -112.993201) (xy 384.526732 -112.978782) (xy 384.518912 -112.959937)
			(xy 384.518408 -112.949736) (xy 383.852097 -112.949736) (xy 383.836646 -112.987038) (xy 383.806679 -113.038944)
			(xy 383.770192 -113.086494) (xy 383.727812 -113.128874) (xy 383.680262 -113.165361) (xy 383.628356 -113.195328)
			(xy 383.572983 -113.218264) (xy 383.51509 -113.233777) (xy 383.455668 -113.2416) (xy 383.395732 -113.2416)
			(xy 383.33631 -113.233777) (xy 383.278417 -113.218264) (xy 383.223044 -113.195328) (xy 383.171138 -113.165361)
			(xy 383.123588 -113.128874) (xy 383.081208 -113.086494) (xy 383.044721 -113.038944) (xy 383.014754 -112.987038)
			(xy 382.991818 -112.931665) (xy 382.976305 -112.873772) (xy 382.968482 -112.81435) (xy 382.967992 -112.784382)
			(xy 284.900495 -112.784382) (xy 284.900134 -112.806492) (xy 284.892306 -112.865948) (xy 284.876785 -112.923873)
			(xy 284.853836 -112.979277) (xy 284.823852 -113.031211) (xy 284.787346 -113.078787) (xy 284.744941 -113.121192)
			(xy 284.697365 -113.157698) (xy 284.645431 -113.187682) (xy 284.590027 -113.210631) (xy 284.532102 -113.226152)
			(xy 284.472646 -113.23398) (xy 284.412678 -113.23398) (xy 284.353222 -113.226152) (xy 284.295297 -113.210631)
			(xy 284.239893 -113.187682) (xy 284.187959 -113.157698) (xy 284.140383 -113.121192) (xy 284.097978 -113.078787)
			(xy 284.061472 -113.031211) (xy 284.031488 -112.979277) (xy 284.008539 -112.923873) (xy 283.993018 -112.865948)
			(xy 283.98519 -112.806492) (xy 283.9847 -112.776508) (xy 283.452824 -112.776508) (xy 283.452824 -112.848136)
			(xy 283.452345 -112.858244) (xy 283.4446 -112.876919) (xy 283.430302 -112.891211) (xy 283.411624 -112.898949)
			(xy 283.401516 -112.899444) (xy 282.220162 -112.899444) (xy 282.210031 -112.899004) (xy 282.191306 -112.891261)
			(xy 282.17695 -112.87696) (xy 282.169135 -112.858265) (xy 282.1686 -112.848136) (xy 278.915876 -112.848136)
			(xy 278.915444 -112.85825) (xy 278.90769 -112.876934) (xy 278.893377 -112.891228) (xy 278.874683 -112.898957)
			(xy 278.864568 -112.899444) (xy 277.683468 -112.899444) (xy 277.673363 -112.898942) (xy 277.654692 -112.891202)
			(xy 277.6404 -112.876911) (xy 277.632659 -112.858241) (xy 277.63216 -112.848136) (xy 269.258288 -112.848136)
			(xy 269.258288 -112.949736) (xy 269.25765 -112.961288) (xy 269.247686 -112.982136) (xy 269.229744 -112.996697)
			(xy 269.218664 -113.000028) (xy 269.206726 -113.001552) (xy 268.470126 -113.001552) (xy 268.459368 -113.001039)
			(xy 268.439678 -112.992369) (xy 268.432026 -112.984788) (xy 268.425846 -112.977375) (xy 268.418921 -112.959379)
			(xy 268.418564 -112.949736) (xy 267.752274 -112.949736) (xy 267.736776 -112.987151) (xy 267.706792 -113.039085)
			(xy 267.670286 -113.086661) (xy 267.627881 -113.129066) (xy 267.580305 -113.165572) (xy 267.528371 -113.195556)
			(xy 267.472967 -113.218505) (xy 267.415042 -113.234026) (xy 267.355586 -113.241854) (xy 267.295618 -113.241854)
			(xy 267.236162 -113.234026) (xy 267.178237 -113.218505) (xy 267.122833 -113.195556) (xy 267.070899 -113.165572)
			(xy 267.023323 -113.129066) (xy 266.980918 -113.086661) (xy 266.944412 -113.039085) (xy 266.914428 -112.987151)
			(xy 266.891479 -112.931747) (xy 266.875958 -112.873822) (xy 266.86813 -112.814366) (xy 266.86764 -112.784382)
			(xy 168.800651 -112.784382) (xy 168.80029 -112.806492) (xy 168.792462 -112.865948) (xy 168.776941 -112.923873)
			(xy 168.753992 -112.979277) (xy 168.724008 -113.031211) (xy 168.687502 -113.078787) (xy 168.645097 -113.121192)
			(xy 168.597521 -113.157698) (xy 168.545587 -113.187682) (xy 168.490183 -113.210631) (xy 168.432258 -113.226152)
			(xy 168.372802 -113.23398) (xy 168.312834 -113.23398) (xy 168.253378 -113.226152) (xy 168.195453 -113.210631)
			(xy 168.140049 -113.187682) (xy 168.088115 -113.157698) (xy 168.040539 -113.121192) (xy 167.998134 -113.078787)
			(xy 167.961628 -113.031211) (xy 167.931644 -112.979277) (xy 167.908695 -112.923873) (xy 167.893174 -112.865948)
			(xy 167.885346 -112.806492) (xy 167.884856 -112.776508) (xy 167.352472 -112.776508) (xy 167.352472 -112.848136)
			(xy 167.352044 -112.858251) (xy 167.344289 -112.876935) (xy 167.329974 -112.891229) (xy 167.311279 -112.898958)
			(xy 167.301164 -112.899444) (xy 166.120064 -112.899444) (xy 166.109958 -112.898945) (xy 166.091288 -112.891204)
			(xy 166.076996 -112.876912) (xy 166.069255 -112.858242) (xy 166.068756 -112.848136) (xy 162.816032 -112.848136)
			(xy 162.815609 -112.858288) (xy 162.807807 -112.877035) (xy 162.793412 -112.891356) (xy 162.774625 -112.899061)
			(xy 162.76447 -112.899444) (xy 161.58337 -112.899444) (xy 161.573239 -112.898998) (xy 161.554514 -112.891257)
			(xy 161.540159 -112.876958) (xy 161.532343 -112.858265) (xy 161.531808 -112.848136) (xy 153.158444 -112.848136)
			(xy 153.158444 -112.949736) (xy 153.157948 -112.959943) (xy 153.150129 -112.9788) (xy 153.135693 -112.993234)
			(xy 153.116835 -113.00105) (xy 153.106628 -113.001552) (xy 152.370028 -113.001552) (xy 152.359826 -113.000996)
			(xy 152.340972 -112.9932) (xy 152.326536 -112.978782) (xy 152.318716 -112.959937) (xy 152.318212 -112.949736)
			(xy 151.65243 -112.949736) (xy 151.636932 -112.987151) (xy 151.606948 -113.039085) (xy 151.570442 -113.086661)
			(xy 151.528037 -113.129066) (xy 151.480461 -113.165572) (xy 151.428527 -113.195556) (xy 151.373123 -113.218505)
			(xy 151.315198 -113.234026) (xy 151.255742 -113.241854) (xy 151.195774 -113.241854) (xy 151.136318 -113.234026)
			(xy 151.078393 -113.218505) (xy 151.022989 -113.195556) (xy 150.971055 -113.165572) (xy 150.923479 -113.129066)
			(xy 150.881074 -113.086661) (xy 150.844568 -113.039085) (xy 150.814584 -112.987151) (xy 150.791635 -112.931747)
			(xy 150.776114 -112.873822) (xy 150.768286 -112.814366) (xy 150.767796 -112.784382) (xy 52.700299 -112.784382)
			(xy 52.699938 -112.806476) (xy 52.692115 -112.865898) (xy 52.676602 -112.923791) (xy 52.653666 -112.979164)
			(xy 52.623699 -113.03107) (xy 52.587212 -113.07862) (xy 52.544832 -113.121) (xy 52.497282 -113.157487)
			(xy 52.445376 -113.187454) (xy 52.390003 -113.21039) (xy 52.33211 -113.225903) (xy 52.272688 -113.233726)
			(xy 52.212752 -113.233726) (xy 52.15333 -113.225903) (xy 52.095437 -113.21039) (xy 52.040064 -113.187454)
			(xy 51.988158 -113.157487) (xy 51.940608 -113.121) (xy 51.898228 -113.07862) (xy 51.861741 -113.03107)
			(xy 51.831774 -112.979164) (xy 51.808838 -112.923791) (xy 51.793325 -112.865898) (xy 51.785502 -112.806476)
			(xy 51.785012 -112.776508) (xy 51.252628 -112.776508) (xy 51.252628 -112.848136) (xy 51.252145 -112.858244)
			(xy 51.244401 -112.876917) (xy 51.230104 -112.89121) (xy 51.211428 -112.898948) (xy 51.20132 -112.899444)
			(xy 50.02022 -112.899444) (xy 50.010118 -112.8989) (xy 49.991449 -112.891177) (xy 49.977155 -112.876898)
			(xy 49.969411 -112.858237) (xy 49.968912 -112.848136) (xy 46.716188 -112.848136) (xy 46.715808 -112.858294)
			(xy 46.707998 -112.877049) (xy 46.693589 -112.891372) (xy 46.674786 -112.899068) (xy 46.664626 -112.899444)
			(xy 45.483526 -112.899444) (xy 45.473399 -112.898952) (xy 45.454675 -112.89123) (xy 45.440317 -112.876945)
			(xy 45.4325 -112.85826) (xy 45.431964 -112.848136) (xy 37.0586 -112.848136) (xy 37.0586 -112.949736)
			(xy 37.058147 -112.959948) (xy 37.05032 -112.978814) (xy 37.03587 -112.993249) (xy 37.016997 -113.001058)
			(xy 37.006784 -113.001552) (xy 36.270184 -113.001552) (xy 36.25998 -113.001032) (xy 36.241125 -112.993221)
			(xy 36.226691 -112.978792) (xy 36.218872 -112.95994) (xy 36.218368 -112.949736) (xy 35.552057 -112.949736)
			(xy 35.536606 -112.987038) (xy 35.506639 -113.038944) (xy 35.470152 -113.086494) (xy 35.427772 -113.128874)
			(xy 35.380222 -113.165361) (xy 35.328316 -113.195328) (xy 35.272943 -113.218264) (xy 35.21505 -113.233777)
			(xy 35.155628 -113.2416) (xy 35.095692 -113.2416) (xy 35.03627 -113.233777) (xy 34.978377 -113.218264)
			(xy 34.923004 -113.195328) (xy 34.871098 -113.165361) (xy 34.823548 -113.128874) (xy 34.781168 -113.086494)
			(xy 34.744681 -113.038944) (xy 34.714714 -112.987038) (xy 34.691778 -112.931665) (xy 34.676265 -112.873772)
			(xy 34.668442 -112.81435) (xy 34.667952 -112.784382) (xy 4.30911 -112.784382) (xy 4.30911 -117.838474)
			(xy 72.584056 -117.838474) (xy 72.584056 -116.832126) (xy 72.584548 -116.821999) (xy 72.59227 -116.803275)
			(xy 72.606555 -116.788917) (xy 72.62524 -116.7811) (xy 72.635364 -116.780564) (xy 73.816464 -116.780564)
			(xy 73.826611 -116.781051) (xy 73.845356 -116.788827) (xy 73.859679 -116.803204) (xy 73.867387 -116.821977)
			(xy 73.867772 -116.832126) (xy 73.867772 -117.758718) (xy 74.474832 -117.758718) (xy 74.474832 -116.895118)
			(xy 74.475322 -116.865134) (xy 74.48315 -116.805678) (xy 74.498671 -116.747753) (xy 74.52162 -116.692349)
			(xy 74.551604 -116.640415) (xy 74.58811 -116.592839) (xy 74.630515 -116.550434) (xy 74.678091 -116.513928)
			(xy 74.730025 -116.483944) (xy 74.785429 -116.460995) (xy 74.843354 -116.445474) (xy 74.90281 -116.437646)
			(xy 74.962778 -116.437646) (xy 75.022234 -116.445474) (xy 75.080159 -116.460995) (xy 75.135563 -116.483944)
			(xy 75.187497 -116.513928) (xy 75.235073 -116.550434) (xy 75.277478 -116.592839) (xy 75.313984 -116.640415)
			(xy 75.343968 -116.692349) (xy 75.366917 -116.747753) (xy 75.382438 -116.805678) (xy 75.390266 -116.865134)
			(xy 75.390756 -116.895118) (xy 75.390756 -117.758718) (xy 75.390266 -117.788702) (xy 75.383713 -117.838474)
			(xy 188.6839 -117.838474) (xy 188.6839 -116.832126) (xy 188.684447 -116.822006) (xy 188.692158 -116.803293)
			(xy 188.706426 -116.788937) (xy 188.725091 -116.78111) (xy 188.735208 -116.780564) (xy 189.916308 -116.780564)
			(xy 189.926458 -116.781015) (xy 189.945204 -116.788806) (xy 189.959525 -116.803193) (xy 189.967231 -116.821974)
			(xy 189.967616 -116.832126) (xy 189.967616 -117.758718) (xy 190.574676 -117.758718) (xy 190.574676 -116.895118)
			(xy 190.575166 -116.865134) (xy 190.582994 -116.805678) (xy 190.598515 -116.747753) (xy 190.621464 -116.692349)
			(xy 190.651448 -116.640415) (xy 190.687954 -116.592839) (xy 190.730359 -116.550434) (xy 190.777935 -116.513928)
			(xy 190.829869 -116.483944) (xy 190.885273 -116.460995) (xy 190.943198 -116.445474) (xy 191.002654 -116.437646)
			(xy 191.062622 -116.437646) (xy 191.122078 -116.445474) (xy 191.180003 -116.460995) (xy 191.235407 -116.483944)
			(xy 191.287341 -116.513928) (xy 191.334917 -116.550434) (xy 191.377322 -116.592839) (xy 191.413828 -116.640415)
			(xy 191.443812 -116.692349) (xy 191.466761 -116.747753) (xy 191.482282 -116.805678) (xy 191.49011 -116.865134)
			(xy 191.4906 -116.895118) (xy 191.4906 -117.758718) (xy 191.49011 -117.788702) (xy 191.483557 -117.838474)
			(xy 304.783744 -117.838474) (xy 304.783744 -116.832126) (xy 304.784185 -116.821955) (xy 304.791963 -116.80316)
			(xy 304.806343 -116.788774) (xy 304.825136 -116.780989) (xy 304.835306 -116.780564) (xy 306.016406 -116.780564)
			(xy 306.026581 -116.78096) (xy 306.045381 -116.788751) (xy 306.059767 -116.803146) (xy 306.067547 -116.821951)
			(xy 306.067968 -116.832126) (xy 306.067968 -117.758718) (xy 306.675028 -117.758718) (xy 306.675028 -116.895118)
			(xy 306.675518 -116.86515) (xy 306.683341 -116.805728) (xy 306.698854 -116.747835) (xy 306.72179 -116.692462)
			(xy 306.751757 -116.640556) (xy 306.788244 -116.593006) (xy 306.830624 -116.550626) (xy 306.878174 -116.514139)
			(xy 306.93008 -116.484172) (xy 306.985453 -116.461236) (xy 307.043346 -116.445723) (xy 307.102768 -116.4379)
			(xy 307.162704 -116.4379) (xy 307.222126 -116.445723) (xy 307.280019 -116.461236) (xy 307.335392 -116.484172)
			(xy 307.387298 -116.514139) (xy 307.434848 -116.550626) (xy 307.477228 -116.593006) (xy 307.513715 -116.640556)
			(xy 307.543682 -116.692462) (xy 307.566618 -116.747835) (xy 307.582131 -116.805728) (xy 307.589954 -116.86515)
			(xy 307.590444 -116.895118) (xy 307.590444 -117.758718) (xy 307.589954 -117.788686) (xy 307.583399 -117.838474)
			(xy 420.884096 -117.838474) (xy 420.884096 -116.832126) (xy 420.884646 -116.822006) (xy 420.892358 -116.803294)
			(xy 420.906624 -116.788938) (xy 420.925288 -116.78111) (xy 420.935404 -116.780564) (xy 422.116504 -116.780564)
			(xy 422.126654 -116.781018) (xy 422.145399 -116.788808) (xy 422.159721 -116.803194) (xy 422.167427 -116.821974)
			(xy 422.167812 -116.832126) (xy 422.167812 -117.759226) (xy 422.774872 -117.759226) (xy 422.774872 -116.895626)
			(xy 422.775362 -116.865642) (xy 422.78319 -116.806186) (xy 422.798711 -116.748261) (xy 422.82166 -116.692857)
			(xy 422.851644 -116.640923) (xy 422.88815 -116.593347) (xy 422.930555 -116.550942) (xy 422.978131 -116.514436)
			(xy 423.030065 -116.484452) (xy 423.085469 -116.461503) (xy 423.143394 -116.445982) (xy 423.20285 -116.438154)
			(xy 423.262818 -116.438154) (xy 423.322274 -116.445982) (xy 423.380199 -116.461503) (xy 423.435603 -116.484452)
			(xy 423.487537 -116.514436) (xy 423.535113 -116.550942) (xy 423.577518 -116.593347) (xy 423.614024 -116.640923)
			(xy 423.644008 -116.692857) (xy 423.666957 -116.748261) (xy 423.682478 -116.806186) (xy 423.690306 -116.865642)
			(xy 423.690796 -116.895626) (xy 423.690796 -117.759226) (xy 423.690306 -117.78921) (xy 423.682478 -117.848666)
			(xy 423.666957 -117.906591) (xy 423.644008 -117.961995) (xy 423.614024 -118.013929) (xy 423.577518 -118.061505)
			(xy 423.535113 -118.10391) (xy 423.487537 -118.140416) (xy 423.435603 -118.1704) (xy 423.380199 -118.193349)
			(xy 423.322274 -118.20887) (xy 423.262818 -118.216698) (xy 423.20285 -118.216698) (xy 423.143394 -118.20887)
			(xy 423.085469 -118.193349) (xy 423.030065 -118.1704) (xy 422.978131 -118.140416) (xy 422.930555 -118.10391)
			(xy 422.88815 -118.061505) (xy 422.851644 -118.013929) (xy 422.82166 -117.961995) (xy 422.798711 -117.906591)
			(xy 422.78319 -117.848666) (xy 422.775362 -117.78921) (xy 422.774872 -117.759226) (xy 422.167812 -117.759226)
			(xy 422.167812 -117.838474) (xy 422.167254 -117.848593) (xy 422.159544 -117.867303) (xy 422.14528 -117.881659)
			(xy 422.126619 -117.889488) (xy 422.116504 -117.890036) (xy 420.935404 -117.890036) (xy 420.925255 -117.889576)
			(xy 420.906509 -117.881788) (xy 420.892187 -117.867404) (xy 420.884481 -117.848625) (xy 420.884096 -117.838474)
			(xy 307.583399 -117.838474) (xy 307.582131 -117.848108) (xy 307.566618 -117.906001) (xy 307.543682 -117.961374)
			(xy 307.513715 -118.01328) (xy 307.477228 -118.06083) (xy 307.434848 -118.10321) (xy 307.387298 -118.139697)
			(xy 307.335392 -118.169664) (xy 307.280019 -118.1926) (xy 307.222126 -118.208113) (xy 307.162704 -118.215936)
			(xy 307.102768 -118.215936) (xy 307.043346 -118.208113) (xy 306.985453 -118.1926) (xy 306.93008 -118.169664)
			(xy 306.878174 -118.139697) (xy 306.830624 -118.10321) (xy 306.788244 -118.06083) (xy 306.751757 -118.01328)
			(xy 306.72179 -117.961374) (xy 306.698854 -117.906001) (xy 306.683341 -117.848108) (xy 306.675518 -117.788686)
			(xy 306.675028 -117.758718) (xy 306.067968 -117.758718) (xy 306.067968 -117.838474) (xy 306.067515 -117.848643)
			(xy 306.05974 -117.867436) (xy 306.045363 -117.881822) (xy 306.026575 -117.889609) (xy 306.016406 -117.890036)
			(xy 304.835306 -117.890036) (xy 304.825132 -117.889631) (xy 304.806332 -117.881843) (xy 304.791946 -117.867451)
			(xy 304.784165 -117.848649) (xy 304.783744 -117.838474) (xy 191.483557 -117.838474) (xy 191.482282 -117.848158)
			(xy 191.466761 -117.906083) (xy 191.443812 -117.961487) (xy 191.413828 -118.013421) (xy 191.377322 -118.060997)
			(xy 191.334917 -118.103402) (xy 191.287341 -118.139908) (xy 191.235407 -118.169892) (xy 191.180003 -118.192841)
			(xy 191.122078 -118.208362) (xy 191.062622 -118.21619) (xy 191.002654 -118.21619) (xy 190.943198 -118.208362)
			(xy 190.885273 -118.192841) (xy 190.829869 -118.169892) (xy 190.777935 -118.139908) (xy 190.730359 -118.103402)
			(xy 190.687954 -118.060997) (xy 190.651448 -118.013421) (xy 190.621464 -117.961487) (xy 190.598515 -117.906083)
			(xy 190.582994 -117.848158) (xy 190.575166 -117.788702) (xy 190.574676 -117.758718) (xy 189.967616 -117.758718)
			(xy 189.967616 -117.838474) (xy 189.967151 -117.848604) (xy 189.959424 -117.867333) (xy 189.94513 -117.881692)
			(xy 189.926436 -117.889505) (xy 189.916308 -117.890036) (xy 188.735208 -117.890036) (xy 188.725059 -117.889573)
			(xy 188.706314 -117.881786) (xy 188.691991 -117.867403) (xy 188.684285 -117.848625) (xy 188.6839 -117.838474)
			(xy 75.383713 -117.838474) (xy 75.382438 -117.848158) (xy 75.366917 -117.906083) (xy 75.343968 -117.961487)
			(xy 75.313984 -118.013421) (xy 75.277478 -118.060997) (xy 75.235073 -118.103402) (xy 75.187497 -118.139908)
			(xy 75.135563 -118.169892) (xy 75.080159 -118.192841) (xy 75.022234 -118.208362) (xy 74.962778 -118.21619)
			(xy 74.90281 -118.21619) (xy 74.843354 -118.208362) (xy 74.785429 -118.192841) (xy 74.730025 -118.169892)
			(xy 74.678091 -118.139908) (xy 74.630515 -118.103402) (xy 74.58811 -118.060997) (xy 74.551604 -118.013421)
			(xy 74.52162 -117.961487) (xy 74.498671 -117.906083) (xy 74.48315 -117.848158) (xy 74.475322 -117.788702)
			(xy 74.474832 -117.758718) (xy 73.867772 -117.758718) (xy 73.867772 -117.838474) (xy 73.867253 -117.848598)
			(xy 73.859536 -117.867316) (xy 73.845259 -117.881673) (xy 73.826585 -117.889495) (xy 73.816464 -117.890036)
			(xy 72.635364 -117.890036) (xy 72.625212 -117.889609) (xy 72.606466 -117.881808) (xy 72.592145 -117.867414)
			(xy 72.58444 -117.848628) (xy 72.584056 -117.838474) (xy 4.30911 -117.838474) (xy 4.30911 -120.087898)
			(xy 34.667952 -120.087898) (xy 34.667952 -119.224298) (xy 34.668442 -119.19433) (xy 34.676265 -119.134908)
			(xy 34.691778 -119.077015) (xy 34.714714 -119.021642) (xy 34.744681 -118.969736) (xy 34.781168 -118.922186)
			(xy 34.823548 -118.879806) (xy 34.871098 -118.843319) (xy 34.923004 -118.813352) (xy 34.978377 -118.790416)
			(xy 35.03627 -118.774903) (xy 35.095692 -118.76708) (xy 35.155628 -118.76708) (xy 35.21505 -118.774903)
			(xy 35.272943 -118.790416) (xy 35.328316 -118.813352) (xy 35.380222 -118.843319) (xy 35.427772 -118.879806)
			(xy 35.470152 -118.922186) (xy 35.506639 -118.969736) (xy 35.536606 -119.021642) (xy 35.559542 -119.077015)
			(xy 35.575055 -119.134908) (xy 35.582878 -119.19433) (xy 35.583368 -119.224298) (xy 35.583368 -120.087898)
			(xy 35.582878 -120.117866) (xy 35.575055 -120.177288) (xy 35.559542 -120.235181) (xy 35.552057 -120.253252)
			(xy 36.218368 -120.253252) (xy 36.218368 -120.010428) (xy 36.223956 -120.002046) (xy 36.22421 -120.001538)
			(xy 36.226242 -119.99849) (xy 36.226496 -119.997982) (xy 36.432236 -119.684038) (xy 36.437263 -119.67562)
			(xy 36.441066 -119.656399) (xy 36.437411 -119.637149) (xy 36.43249 -119.628666) (xy 36.346638 -119.496586)
			(xy 36.33724 -119.482108) (xy 36.224972 -119.31015) (xy 36.224464 -119.309134) (xy 36.222432 -119.306086)
			(xy 36.222178 -119.305578) (xy 36.218368 -119.299736) (xy 36.218368 -119.056912) (xy 36.218891 -119.046707)
			(xy 36.226697 -119.027849) (xy 36.241125 -119.013413) (xy 36.259979 -119.005597) (xy 36.270184 -119.005096)
			(xy 37.006784 -119.005096) (xy 37.017006 -119.005525) (xy 37.035895 -119.013346) (xy 37.050352 -119.027801)
			(xy 37.058174 -119.04669) (xy 37.0586 -119.056912) (xy 37.0586 -119.299736) (xy 37.05479 -119.305578)
			(xy 37.054536 -119.306086) (xy 37.050472 -119.312182) (xy 37.050218 -119.312436) (xy 36.912296 -119.52351)
			(xy 36.85921 -119.60479) (xy 36.846764 -119.62384) (xy 36.844732 -119.626634) (xy 36.843462 -119.628666)
			(xy 36.83928 -119.636092) (xy 36.835556 -119.652709) (xy 36.837509 -119.669627) (xy 36.840922 -119.677434)
			(xy 37.02812 -119.96293) (xy 37.03066 -119.96674) (xy 37.050472 -119.996712) (xy 37.050726 -119.99722)
			(xy 37.051996 -119.999252) (xy 37.053774 -120.001792) (xy 37.0586 -120.009158) (xy 37.0586 -120.158256)
			(xy 45.431964 -120.158256) (xy 45.431964 -119.151908) (xy 45.432427 -119.141759) (xy 45.440214 -119.123014)
			(xy 45.454597 -119.108691) (xy 45.473375 -119.100985) (xy 45.483526 -119.1006) (xy 46.664626 -119.1006)
			(xy 46.674749 -119.101104) (xy 46.693464 -119.108833) (xy 46.707818 -119.123113) (xy 46.715643 -119.141787)
			(xy 46.716188 -119.151908) (xy 46.716188 -120.158256) (xy 49.968912 -120.158256) (xy 49.968912 -119.151908)
			(xy 49.969323 -119.141785) (xy 49.977071 -119.123079) (xy 49.991389 -119.108764) (xy 50.010096 -119.10102)
			(xy 50.02022 -119.1006) (xy 51.20132 -119.1006) (xy 51.21143 -119.101069) (xy 51.230109 -119.108813)
			(xy 51.244403 -119.123115) (xy 51.252137 -119.141798) (xy 51.252628 -119.151908) (xy 51.252628 -120.086374)
			(xy 53.639212 -120.086374) (xy 53.639212 -119.222774) (xy 53.639702 -119.192806) (xy 53.647525 -119.133384)
			(xy 53.663038 -119.075491) (xy 53.685974 -119.020118) (xy 53.715941 -118.968212) (xy 53.752428 -118.920662)
			(xy 53.794808 -118.878282) (xy 53.842358 -118.841795) (xy 53.894264 -118.811828) (xy 53.949637 -118.788892)
			(xy 54.00753 -118.773379) (xy 54.066952 -118.765556) (xy 54.126888 -118.765556) (xy 54.18631 -118.773379)
			(xy 54.244203 -118.788892) (xy 54.299576 -118.811828) (xy 54.351482 -118.841795) (xy 54.399032 -118.878282)
			(xy 54.441412 -118.920662) (xy 54.477899 -118.968212) (xy 54.507866 -119.020118) (xy 54.530802 -119.075491)
			(xy 54.546315 -119.133384) (xy 54.554138 -119.192806) (xy 54.554628 -119.222774) (xy 54.554628 -119.567198)
			(xy 66.599308 -119.567198) (xy 66.599308 -118.703598) (xy 66.599798 -118.673614) (xy 66.607626 -118.614158)
			(xy 66.623147 -118.556233) (xy 66.646096 -118.500829) (xy 66.67608 -118.448895) (xy 66.712586 -118.401319)
			(xy 66.754991 -118.358914) (xy 66.802567 -118.322408) (xy 66.854501 -118.292424) (xy 66.909905 -118.269475)
			(xy 66.96783 -118.253954) (xy 67.027286 -118.246126) (xy 67.087254 -118.246126) (xy 67.14671 -118.253954)
			(xy 67.204635 -118.269475) (xy 67.260039 -118.292424) (xy 67.311973 -118.322408) (xy 67.359549 -118.358914)
			(xy 67.401954 -118.401319) (xy 67.43846 -118.448895) (xy 67.468444 -118.500829) (xy 67.491393 -118.556233)
			(xy 67.506914 -118.614158) (xy 67.514742 -118.673614) (xy 67.515232 -118.703598) (xy 67.515232 -119.567198)
			(xy 67.514742 -119.597182) (xy 67.509359 -119.638064) (xy 68.047108 -119.638064) (xy 68.047108 -118.631716)
			(xy 68.047529 -118.621594) (xy 68.055274 -118.602889) (xy 68.069589 -118.588574) (xy 68.088294 -118.580829)
			(xy 68.098416 -118.580408) (xy 69.27977 -118.580408) (xy 69.289891 -118.58095) (xy 69.308605 -118.588662)
			(xy 69.322962 -118.602931) (xy 69.330788 -118.621598) (xy 69.331332 -118.631716) (xy 69.331332 -119.638064)
			(xy 72.584056 -119.638064) (xy 72.584056 -118.631716) (xy 72.584597 -118.621614) (xy 72.592321 -118.602944)
			(xy 72.606601 -118.58865) (xy 72.625262 -118.580907) (xy 72.635364 -118.580408) (xy 73.816464 -118.580408)
			(xy 73.826585 -118.580846) (xy 73.845289 -118.588584) (xy 73.859605 -118.602894) (xy 73.86735 -118.621595)
			(xy 73.867772 -118.631716) (xy 73.867772 -119.638064) (xy 73.867354 -119.648188) (xy 73.859612 -119.666896)
			(xy 73.845296 -119.681212) (xy 73.826588 -119.688954) (xy 73.816464 -119.689372) (xy 72.635364 -119.689372)
			(xy 72.625249 -119.688944) (xy 72.606565 -119.681189) (xy 72.592271 -119.666874) (xy 72.584542 -119.648179)
			(xy 72.584056 -119.638064) (xy 69.331332 -119.638064) (xy 69.330855 -119.64818) (xy 69.323125 -119.666877)
			(xy 69.308827 -119.681191) (xy 69.29014 -119.688943) (xy 69.280024 -119.689372) (xy 68.09867 -119.689372)
			(xy 68.088543 -119.688898) (xy 68.069823 -119.681163) (xy 68.055468 -119.666873) (xy 68.047648 -119.648189)
			(xy 68.047108 -119.638064) (xy 67.509359 -119.638064) (xy 67.506914 -119.656638) (xy 67.491393 -119.714563)
			(xy 67.487203 -119.724678) (xy 79.599536 -119.724678) (xy 79.599536 -119.481854) (xy 79.744316 -119.261128)
			(xy 79.793592 -119.18569) (xy 79.813404 -119.155464) (xy 79.818378 -119.147015) (xy 79.822104 -119.127781)
			(xy 79.818364 -119.108551) (xy 79.813404 -119.100092) (xy 79.66837 -118.87708) (xy 79.612744 -118.791736)
			(xy 79.608426 -118.78564) (xy 79.605124 -118.780052) (xy 79.604616 -118.779036) (xy 79.599536 -118.771162)
			(xy 79.599536 -118.528338) (xy 79.599995 -118.518169) (xy 79.607767 -118.499376) (xy 79.622142 -118.48499)
			(xy 79.640929 -118.477203) (xy 79.651098 -118.476776) (xy 80.387698 -118.476776) (xy 80.397874 -118.477166)
			(xy 80.416676 -118.484958) (xy 80.431062 -118.499354) (xy 80.438841 -118.518161) (xy 80.43926 -118.528338)
			(xy 80.43926 -118.771162) (xy 80.22336 -119.101616) (xy 80.219309 -119.109824) (xy 80.216779 -119.127943)
			(xy 80.220735 -119.145804) (xy 80.225392 -119.153686) (xy 80.25765 -119.20347) (xy 80.273144 -119.227092)
			(xy 80.43926 -119.480584) (xy 80.43926 -119.55907) (xy 81.07426 -119.55907) (xy 81.07426 -118.69547)
			(xy 81.07475 -118.665486) (xy 81.082578 -118.60603) (xy 81.098099 -118.548105) (xy 81.121048 -118.492701)
			(xy 81.151032 -118.440767) (xy 81.187538 -118.393191) (xy 81.229943 -118.350786) (xy 81.277519 -118.31428)
			(xy 81.329453 -118.284296) (xy 81.384857 -118.261347) (xy 81.442782 -118.245826) (xy 81.502238 -118.237998)
			(xy 81.562206 -118.237998) (xy 81.621662 -118.245826) (xy 81.679587 -118.261347) (xy 81.734991 -118.284296)
			(xy 81.786925 -118.31428) (xy 81.834501 -118.350786) (xy 81.876906 -118.393191) (xy 81.913412 -118.440767)
			(xy 81.943396 -118.492701) (xy 81.966345 -118.548105) (xy 81.981866 -118.60603) (xy 81.989694 -118.665486)
			(xy 81.990184 -118.69547) (xy 81.990184 -119.55907) (xy 81.989694 -119.589054) (xy 81.981866 -119.64851)
			(xy 81.966345 -119.706435) (xy 81.943396 -119.761839) (xy 81.913412 -119.813773) (xy 81.876906 -119.861349)
			(xy 81.834501 -119.903754) (xy 81.786925 -119.94026) (xy 81.734991 -119.970244) (xy 81.679587 -119.993193)
			(xy 81.621662 -120.008714) (xy 81.562206 -120.016542) (xy 81.502238 -120.016542) (xy 81.442782 -120.008714)
			(xy 81.384857 -119.993193) (xy 81.329453 -119.970244) (xy 81.277519 -119.94026) (xy 81.229943 -119.903754)
			(xy 81.187538 -119.861349) (xy 81.151032 -119.813773) (xy 81.121048 -119.761839) (xy 81.098099 -119.706435)
			(xy 81.082578 -119.64851) (xy 81.07475 -119.589054) (xy 81.07426 -119.55907) (xy 80.43926 -119.55907)
			(xy 80.43926 -119.724678) (xy 80.438818 -119.734848) (xy 80.43104 -119.753643) (xy 80.41666 -119.768029)
			(xy 80.397868 -119.775814) (xy 80.387698 -119.77624) (xy 79.651098 -119.77624) (xy 79.640924 -119.775837)
			(xy 79.622125 -119.768047) (xy 79.607739 -119.753655) (xy 79.599958 -119.734853) (xy 79.599536 -119.724678)
			(xy 67.487203 -119.724678) (xy 67.468444 -119.769967) (xy 67.43846 -119.821901) (xy 67.401954 -119.869477)
			(xy 67.359549 -119.911882) (xy 67.311973 -119.948388) (xy 67.260039 -119.978372) (xy 67.204635 -120.001321)
			(xy 67.14671 -120.016842) (xy 67.087254 -120.02467) (xy 67.027286 -120.02467) (xy 66.96783 -120.016842)
			(xy 66.909905 -120.001321) (xy 66.854501 -119.978372) (xy 66.802567 -119.948388) (xy 66.754991 -119.911882)
			(xy 66.712586 -119.869477) (xy 66.67608 -119.821901) (xy 66.646096 -119.769967) (xy 66.623147 -119.714563)
			(xy 66.607626 -119.656638) (xy 66.599798 -119.597182) (xy 66.599308 -119.567198) (xy 54.554628 -119.567198)
			(xy 54.554628 -120.086374) (xy 54.554138 -120.116342) (xy 54.546315 -120.175764) (xy 54.530802 -120.233657)
			(xy 54.507866 -120.28903) (xy 54.477899 -120.340936) (xy 54.441412 -120.388486) (xy 54.399032 -120.430866)
			(xy 54.351482 -120.467353) (xy 54.299576 -120.49732) (xy 54.244203 -120.520256) (xy 54.18631 -120.535769)
			(xy 54.126888 -120.543592) (xy 54.066952 -120.543592) (xy 54.00753 -120.535769) (xy 53.949637 -120.520256)
			(xy 53.894264 -120.49732) (xy 53.842358 -120.467353) (xy 53.794808 -120.430866) (xy 53.752428 -120.388486)
			(xy 53.715941 -120.340936) (xy 53.685974 -120.28903) (xy 53.663038 -120.233657) (xy 53.647525 -120.175764)
			(xy 53.639702 -120.116342) (xy 53.639212 -120.086374) (xy 51.252628 -120.086374) (xy 51.252628 -120.158256)
			(xy 51.252149 -120.168372) (xy 51.24442 -120.187069) (xy 51.230123 -120.201384) (xy 51.211436 -120.209136)
			(xy 51.20132 -120.209564) (xy 50.02022 -120.209564) (xy 50.010094 -120.209167) (xy 49.991384 -120.201419)
			(xy 49.977068 -120.187096) (xy 49.969328 -120.168382) (xy 49.968912 -120.158256) (xy 46.716188 -120.158256)
			(xy 46.715742 -120.168409) (xy 46.707959 -120.187162) (xy 46.693569 -120.201488) (xy 46.674781 -120.209187)
			(xy 46.664626 -120.209564) (xy 45.483526 -120.209564) (xy 45.473401 -120.209052) (xy 45.454682 -120.201334)
			(xy 45.440324 -120.187055) (xy 45.432504 -120.168378) (xy 45.431964 -120.158256) (xy 37.0586 -120.158256)
			(xy 37.0586 -120.253252) (xy 37.058149 -120.263473) (xy 37.050338 -120.282362) (xy 37.035889 -120.29682)
			(xy 37.017004 -120.304642) (xy 37.006784 -120.305068) (xy 36.270184 -120.305068) (xy 36.259955 -120.3047)
			(xy 36.241058 -120.296862) (xy 36.226602 -120.282388) (xy 36.218787 -120.263481) (xy 36.218368 -120.253252)
			(xy 35.552057 -120.253252) (xy 35.536606 -120.290554) (xy 35.506639 -120.34246) (xy 35.470152 -120.39001)
			(xy 35.427772 -120.43239) (xy 35.380222 -120.468877) (xy 35.328316 -120.498844) (xy 35.272943 -120.52178)
			(xy 35.21505 -120.537293) (xy 35.155628 -120.545116) (xy 35.095692 -120.545116) (xy 35.03627 -120.537293)
			(xy 34.978377 -120.52178) (xy 34.923004 -120.498844) (xy 34.871098 -120.468877) (xy 34.823548 -120.43239)
			(xy 34.781168 -120.39001) (xy 34.744681 -120.34246) (xy 34.714714 -120.290554) (xy 34.691778 -120.235181)
			(xy 34.676265 -120.177288) (xy 34.668442 -120.117866) (xy 34.667952 -120.087898) (xy 4.30911 -120.087898)
			(xy 4.30911 -121.894346) (xy 37.31006 -121.894346) (xy 37.31006 -121.030746) (xy 37.31055 -121.000778)
			(xy 37.318373 -120.941356) (xy 37.333886 -120.883463) (xy 37.356822 -120.82809) (xy 37.386789 -120.776184)
			(xy 37.423276 -120.728634) (xy 37.465656 -120.686254) (xy 37.513206 -120.649767) (xy 37.565112 -120.6198)
			(xy 37.620485 -120.596864) (xy 37.678378 -120.581351) (xy 37.7378 -120.573528) (xy 37.797736 -120.573528)
			(xy 37.857158 -120.581351) (xy 37.915051 -120.596864) (xy 37.970424 -120.6198) (xy 38.02233 -120.649767)
			(xy 38.06988 -120.686254) (xy 38.11226 -120.728634) (xy 38.148747 -120.776184) (xy 38.178714 -120.82809)
			(xy 38.20165 -120.883463) (xy 38.217163 -120.941356) (xy 38.224986 -121.000778) (xy 38.225476 -121.030746)
			(xy 38.225476 -121.894346) (xy 38.224986 -121.924314) (xy 38.217163 -121.983736) (xy 38.20165 -122.041629)
			(xy 38.194165 -122.0597) (xy 38.860476 -122.0597) (xy 38.860476 -121.832116) (xy 38.86073 -121.828052)
			(xy 38.860984 -121.825512) (xy 38.860984 -121.816876) (xy 38.866572 -121.80824) (xy 38.867842 -121.806208)
			(xy 38.868858 -121.804176) (xy 39.078662 -121.48439) (xy 39.080948 -121.476262) (xy 39.083387 -121.465612)
			(xy 39.080114 -121.444035) (xy 39.074598 -121.434606) (xy 38.868604 -121.118884) (xy 38.866318 -121.115074)
			(xy 38.866064 -121.114566) (xy 38.865048 -121.112788) (xy 38.860984 -121.106184) (xy 38.860984 -121.098056)
			(xy 38.86073 -121.095516) (xy 38.860476 -121.091452) (xy 38.860476 -120.86336) (xy 38.860949 -120.853151)
			(xy 38.868773 -120.83429) (xy 38.883217 -120.819855) (xy 38.902082 -120.812043) (xy 38.912292 -120.811544)
			(xy 39.648892 -120.811544) (xy 39.659094 -120.812087) (xy 39.677948 -120.81989) (xy 39.692383 -120.834312)
			(xy 39.700203 -120.853158) (xy 39.700708 -120.86336) (xy 39.700708 -121.090944) (xy 39.700454 -121.095008)
			(xy 39.7002 -121.097548) (xy 39.7002 -121.106184) (xy 39.694358 -121.115582) (xy 39.693596 -121.116852)
			(xy 39.692326 -121.118884) (xy 39.486586 -121.43359) (xy 39.481507 -121.442098) (xy 39.477696 -121.461525)
			(xy 39.481526 -121.480949) (xy 39.486586 -121.48947) (xy 39.692326 -121.802906) (xy 39.693342 -121.804938)
			(xy 39.694612 -121.80697) (xy 39.7002 -121.815606) (xy 39.7002 -121.824242) (xy 39.700454 -121.826782)
			(xy 39.700708 -121.830846) (xy 39.700708 -121.958354) (xy 45.431964 -121.958354) (xy 45.431964 -120.952006)
			(xy 45.432369 -120.941832) (xy 45.440157 -120.923032) (xy 45.454549 -120.908646) (xy 45.473351 -120.900865)
			(xy 45.483526 -120.900444) (xy 46.664626 -120.900444) (xy 46.674786 -120.900912) (xy 46.693557 -120.908696)
			(xy 46.707922 -120.92307) (xy 46.715694 -120.941845) (xy 46.716188 -120.952006) (xy 46.716188 -121.958354)
			(xy 46.716176 -121.958608) (xy 49.968912 -121.958608) (xy 49.968912 -120.952006) (xy 49.969431 -120.941883)
			(xy 49.977151 -120.923167) (xy 49.991427 -120.908812) (xy 50.0101 -120.900988) (xy 50.02022 -120.900444)
			(xy 51.20132 -120.900444) (xy 51.211423 -120.900967) (xy 51.230091 -120.908701) (xy 51.244383 -120.922985)
			(xy 51.252127 -120.941649) (xy 51.252628 -120.951752) (xy 51.252628 -121.886472) (xy 51.785012 -121.886472)
			(xy 51.785012 -121.022872) (xy 51.785502 -120.992904) (xy 51.793325 -120.933482) (xy 51.808838 -120.875589)
			(xy 51.831774 -120.820216) (xy 51.861741 -120.76831) (xy 51.898228 -120.72076) (xy 51.940608 -120.67838)
			(xy 51.988158 -120.641893) (xy 52.040064 -120.611926) (xy 52.095437 -120.58899) (xy 52.15333 -120.573477)
			(xy 52.212752 -120.565654) (xy 52.272688 -120.565654) (xy 52.33211 -120.573477) (xy 52.390003 -120.58899)
			(xy 52.445376 -120.611926) (xy 52.497282 -120.641893) (xy 52.544832 -120.67838) (xy 52.587212 -120.72076)
			(xy 52.623699 -120.76831) (xy 52.653666 -120.820216) (xy 52.676602 -120.875589) (xy 52.692115 -120.933482)
			(xy 52.699938 -120.992904) (xy 52.700428 -121.022872) (xy 52.700428 -121.367296) (xy 64.745108 -121.367296)
			(xy 64.745108 -120.503696) (xy 64.745598 -120.473712) (xy 64.753426 -120.414256) (xy 64.768947 -120.356331)
			(xy 64.791896 -120.300927) (xy 64.82188 -120.248993) (xy 64.858386 -120.201417) (xy 64.900791 -120.159012)
			(xy 64.948367 -120.122506) (xy 65.000301 -120.092522) (xy 65.055705 -120.069573) (xy 65.11363 -120.054052)
			(xy 65.173086 -120.046224) (xy 65.233054 -120.046224) (xy 65.29251 -120.054052) (xy 65.350435 -120.069573)
			(xy 65.405839 -120.092522) (xy 65.457773 -120.122506) (xy 65.505349 -120.159012) (xy 65.547754 -120.201417)
			(xy 65.58426 -120.248993) (xy 65.614244 -120.300927) (xy 65.637193 -120.356331) (xy 65.652714 -120.414256)
			(xy 65.660542 -120.473712) (xy 65.661032 -120.503696) (xy 65.661032 -121.367296) (xy 65.660542 -121.39728)
			(xy 65.655159 -121.438162) (xy 68.047108 -121.438162) (xy 68.047108 -120.431814) (xy 68.047644 -120.421661)
			(xy 68.055408 -120.402898) (xy 68.069761 -120.388533) (xy 68.088517 -120.380753) (xy 68.09867 -120.380252)
			(xy 69.27977 -120.380252) (xy 69.289941 -120.380689) (xy 69.308738 -120.388467) (xy 69.323124 -120.402849)
			(xy 69.330908 -120.421643) (xy 69.331332 -120.431814) (xy 69.331332 -121.438162) (xy 72.584056 -121.438162)
			(xy 72.584056 -120.431814) (xy 72.584538 -120.421686) (xy 72.592265 -120.402962) (xy 72.606552 -120.388605)
			(xy 72.625239 -120.380788) (xy 72.635364 -120.380252) (xy 73.816464 -120.380252) (xy 73.82661 -120.38075)
			(xy 73.845352 -120.388525) (xy 73.859675 -120.402898) (xy 73.867384 -120.421667) (xy 73.867772 -120.431814)
			(xy 73.867772 -121.438162) (xy 73.867242 -121.448285) (xy 73.859529 -121.467003) (xy 73.845256 -121.48136)
			(xy 73.826584 -121.489182) (xy 73.816464 -121.489724) (xy 72.635364 -121.489724) (xy 72.625211 -121.489308)
			(xy 72.606462 -121.481505) (xy 72.592141 -121.467108) (xy 72.584438 -121.448318) (xy 72.584056 -121.438162)
			(xy 69.331332 -121.438162) (xy 69.330904 -121.448335) (xy 69.323126 -121.467134) (xy 69.308741 -121.481522)
			(xy 69.289943 -121.489303) (xy 69.27977 -121.489724) (xy 68.09867 -121.489724) (xy 68.088492 -121.48936)
			(xy 68.069689 -121.481558) (xy 68.055304 -121.467154) (xy 68.047527 -121.448341) (xy 68.047108 -121.438162)
			(xy 65.655159 -121.438162) (xy 65.652714 -121.456736) (xy 65.637193 -121.514661) (xy 65.630373 -121.531126)
			(xy 82.241644 -121.531126) (xy 82.241644 -121.288302) (xy 82.360516 -121.106946) (xy 82.423 -121.011442)
			(xy 82.44713 -120.974612) (xy 82.451004 -120.968287) (xy 82.455261 -120.954085) (xy 82.455512 -120.946672)
			(xy 82.455512 -120.920764) (xy 82.455337 -120.914613) (xy 82.452372 -120.902672) (xy 82.44967 -120.897142)
			(xy 82.336132 -120.723152) (xy 82.316066 -120.692164) (xy 82.310478 -120.683528) (xy 82.250026 -120.590818)
			(xy 82.249518 -120.590056) (xy 82.24901 -120.589294) (xy 82.248756 -120.588786) (xy 82.248248 -120.588024)
			(xy 82.241644 -120.57761) (xy 82.241644 -120.334786) (xy 82.242122 -120.324627) (xy 82.249902 -120.305856)
			(xy 82.264273 -120.291491) (xy 82.283046 -120.283718) (xy 82.293206 -120.283224) (xy 83.029806 -120.283224)
			(xy 83.039962 -120.283728) (xy 83.058729 -120.291502) (xy 83.073093 -120.305864) (xy 83.08087 -120.32463)
			(xy 83.081368 -120.334786) (xy 83.081368 -120.57761) (xy 82.865468 -120.908064) (xy 82.861457 -120.916289)
			(xy 82.858912 -120.934396) (xy 82.862851 -120.952252) (xy 82.8675 -120.960134) (xy 82.899758 -121.009918)
			(xy 83.081368 -121.287032) (xy 83.081368 -121.365772) (xy 83.716368 -121.365772) (xy 83.716368 -120.502172)
			(xy 83.716858 -120.472188) (xy 83.724686 -120.412732) (xy 83.740207 -120.354807) (xy 83.763156 -120.299403)
			(xy 83.79314 -120.247469) (xy 83.829646 -120.199893) (xy 83.872051 -120.157488) (xy 83.919627 -120.120982)
			(xy 83.971561 -120.090998) (xy 84.026965 -120.068049) (xy 84.08489 -120.052528) (xy 84.144346 -120.0447)
			(xy 84.204314 -120.0447) (xy 84.26377 -120.052528) (xy 84.321695 -120.068049) (xy 84.369615 -120.087898)
			(xy 150.767796 -120.087898) (xy 150.767796 -119.224298) (xy 150.768286 -119.194314) (xy 150.776114 -119.134858)
			(xy 150.791635 -119.076933) (xy 150.814584 -119.021529) (xy 150.844568 -118.969595) (xy 150.881074 -118.922019)
			(xy 150.923479 -118.879614) (xy 150.971055 -118.843108) (xy 151.022989 -118.813124) (xy 151.078393 -118.790175)
			(xy 151.136318 -118.774654) (xy 151.195774 -118.766826) (xy 151.255742 -118.766826) (xy 151.315198 -118.774654)
			(xy 151.373123 -118.790175) (xy 151.428527 -118.813124) (xy 151.480461 -118.843108) (xy 151.528037 -118.879614)
			(xy 151.570442 -118.922019) (xy 151.606948 -118.969595) (xy 151.636932 -119.021529) (xy 151.659881 -119.076933)
			(xy 151.675402 -119.134858) (xy 151.68323 -119.194314) (xy 151.68372 -119.224298) (xy 151.68372 -120.087898)
			(xy 151.68323 -120.117882) (xy 151.675402 -120.177338) (xy 151.659881 -120.235263) (xy 151.65243 -120.253252)
			(xy 152.318212 -120.253252) (xy 152.318212 -120.025668) (xy 152.318466 -120.021604) (xy 152.31872 -120.019064)
			(xy 152.31872 -120.010428) (xy 152.324308 -120.001792) (xy 152.325578 -119.99976) (xy 152.326594 -119.997728)
			(xy 152.523952 -119.696738) (xy 152.527818 -119.690409) (xy 152.53208 -119.67621) (xy 152.532334 -119.668798)
			(xy 152.532334 -119.643144) (xy 152.532132 -119.63581) (xy 152.528 -119.621738) (xy 152.524206 -119.615458)
			(xy 152.32634 -119.312436) (xy 152.324054 -119.308626) (xy 152.3238 -119.308118) (xy 152.322784 -119.30634)
			(xy 152.31872 -119.299736) (xy 152.31872 -119.291608) (xy 152.318466 -119.289068) (xy 152.318212 -119.285004)
			(xy 152.318212 -119.056912) (xy 152.318623 -119.046688) (xy 152.326447 -119.027795) (xy 152.340909 -119.013338)
			(xy 152.359803 -119.005519) (xy 152.370028 -119.005096) (xy 153.106628 -119.005096) (xy 153.116839 -119.005559)
			(xy 153.135704 -119.013383) (xy 153.150139 -119.02783) (xy 153.157949 -119.0467) (xy 153.158444 -119.056912)
			(xy 153.158444 -119.284496) (xy 153.15819 -119.28856) (xy 153.157936 -119.2911) (xy 153.157936 -119.299736)
			(xy 153.152094 -119.309134) (xy 153.151332 -119.310404) (xy 153.150062 -119.312436) (xy 152.944322 -119.627142)
			(xy 152.93928 -119.635669) (xy 152.935453 -119.655085) (xy 152.939268 -119.674503) (xy 152.944322 -119.683022)
			(xy 153.150062 -119.996458) (xy 153.151078 -119.99849) (xy 153.152348 -120.000522) (xy 153.157936 -120.009158)
			(xy 153.157936 -120.017794) (xy 153.15819 -120.020334) (xy 153.158444 -120.024398) (xy 153.158444 -120.158256)
			(xy 161.531808 -120.158256) (xy 161.531808 -119.151908) (xy 161.532228 -119.141753) (xy 161.540023 -119.123)
			(xy 161.55442 -119.108676) (xy 161.573213 -119.100977) (xy 161.58337 -119.1006) (xy 162.76447 -119.1006)
			(xy 162.77459 -119.10115) (xy 162.793303 -119.10886) (xy 162.807659 -119.123127) (xy 162.815486 -119.141791)
			(xy 162.816032 -119.151908) (xy 162.816032 -120.158256) (xy 166.068756 -120.158256) (xy 166.068756 -119.151908)
			(xy 166.069291 -119.141805) (xy 166.077017 -119.123136) (xy 166.091299 -119.108842) (xy 166.109962 -119.101099)
			(xy 166.120064 -119.1006) (xy 167.301164 -119.1006) (xy 167.311284 -119.101046) (xy 167.329987 -119.108782)
			(xy 167.344302 -119.12309) (xy 167.352049 -119.141788) (xy 167.352472 -119.151908) (xy 167.352472 -120.086374)
			(xy 169.739056 -120.086374) (xy 169.739056 -119.222774) (xy 169.739546 -119.19279) (xy 169.747374 -119.133334)
			(xy 169.762895 -119.075409) (xy 169.785844 -119.020005) (xy 169.815828 -118.968071) (xy 169.852334 -118.920495)
			(xy 169.894739 -118.87809) (xy 169.942315 -118.841584) (xy 169.994249 -118.8116) (xy 170.049653 -118.788651)
			(xy 170.107578 -118.77313) (xy 170.167034 -118.765302) (xy 170.227002 -118.765302) (xy 170.286458 -118.77313)
			(xy 170.344383 -118.788651) (xy 170.399787 -118.8116) (xy 170.451721 -118.841584) (xy 170.499297 -118.87809)
			(xy 170.541702 -118.920495) (xy 170.578208 -118.968071) (xy 170.608192 -119.020005) (xy 170.631141 -119.075409)
			(xy 170.646662 -119.133334) (xy 170.65449 -119.19279) (xy 170.65498 -119.222774) (xy 170.65498 -119.567198)
			(xy 182.69966 -119.567198) (xy 182.69966 -118.703598) (xy 182.70015 -118.67363) (xy 182.707973 -118.614208)
			(xy 182.723486 -118.556315) (xy 182.746422 -118.500942) (xy 182.776389 -118.449036) (xy 182.812876 -118.401486)
			(xy 182.855256 -118.359106) (xy 182.902806 -118.322619) (xy 182.954712 -118.292652) (xy 183.010085 -118.269716)
			(xy 183.067978 -118.254203) (xy 183.1274 -118.24638) (xy 183.187336 -118.24638) (xy 183.246758 -118.254203)
			(xy 183.304651 -118.269716) (xy 183.360024 -118.292652) (xy 183.41193 -118.322619) (xy 183.45948 -118.359106)
			(xy 183.50186 -118.401486) (xy 183.538347 -118.449036) (xy 183.568314 -118.500942) (xy 183.59125 -118.556315)
			(xy 183.606763 -118.614208) (xy 183.614586 -118.67363) (xy 183.615076 -118.703598) (xy 183.615076 -119.567198)
			(xy 183.614586 -119.597166) (xy 183.609202 -119.638064) (xy 184.146952 -119.638064) (xy 184.146952 -118.631716)
			(xy 184.147497 -118.621614) (xy 184.15522 -118.602945) (xy 184.169498 -118.588652) (xy 184.188159 -118.580908)
			(xy 184.19826 -118.580408) (xy 185.379614 -118.580408) (xy 185.389738 -118.580914) (xy 185.408453 -118.588641)
			(xy 185.422808 -118.60292) (xy 185.430632 -118.621595) (xy 185.431176 -118.631716) (xy 185.431176 -119.638064)
			(xy 188.6839 -119.638064) (xy 188.6839 -118.631716) (xy 188.684329 -118.621595) (xy 188.692072 -118.602891)
			(xy 188.706385 -118.588576) (xy 188.725087 -118.580831) (xy 188.735208 -118.580408) (xy 189.916308 -118.580408)
			(xy 189.926432 -118.58081) (xy 189.945137 -118.588562) (xy 189.959451 -118.602883) (xy 189.967195 -118.621592)
			(xy 189.967616 -118.631716) (xy 189.967616 -119.638064) (xy 189.967155 -119.648182) (xy 189.959421 -119.666882)
			(xy 189.945119 -119.681197) (xy 189.926426 -119.688946) (xy 189.916308 -119.689372) (xy 188.735208 -119.689372)
			(xy 188.725083 -119.688977) (xy 188.706374 -119.681226) (xy 188.692058 -119.666903) (xy 188.684318 -119.64819)
			(xy 188.6839 -119.638064) (xy 185.431176 -119.638064) (xy 185.430754 -119.648187) (xy 185.423013 -119.666894)
			(xy 185.408698 -119.681211) (xy 185.389991 -119.688953) (xy 185.379868 -119.689372) (xy 184.198514 -119.689372)
			(xy 184.18839 -119.688862) (xy 184.169671 -119.681141) (xy 184.155315 -119.666862) (xy 184.147493 -119.648186)
			(xy 184.146952 -119.638064) (xy 183.609202 -119.638064) (xy 183.606763 -119.656588) (xy 183.59125 -119.714481)
			(xy 183.587026 -119.724678) (xy 195.69938 -119.724678) (xy 195.69938 -119.481854) (xy 195.818252 -119.300498)
			(xy 195.880736 -119.204994) (xy 195.904866 -119.168164) (xy 195.908724 -119.16183) (xy 195.91299 -119.147635)
			(xy 195.913248 -119.140224) (xy 195.913248 -119.114316) (xy 195.913051 -119.108166) (xy 195.9101 -119.096226)
			(xy 195.907406 -119.090694) (xy 195.793868 -118.916704) (xy 195.773802 -118.885716) (xy 195.768214 -118.87708)
			(xy 195.707762 -118.78437) (xy 195.707254 -118.783608) (xy 195.706746 -118.782846) (xy 195.706492 -118.782338)
			(xy 195.705984 -118.781576) (xy 195.69938 -118.771162) (xy 195.69938 -118.528338) (xy 195.699796 -118.518164)
			(xy 195.707576 -118.499362) (xy 195.721965 -118.484974) (xy 195.740768 -118.477195) (xy 195.750942 -118.476776)
			(xy 196.487542 -118.476776) (xy 196.497707 -118.4772) (xy 196.516485 -118.484995) (xy 196.53085 -118.499383)
			(xy 196.538616 -118.518172) (xy 196.539104 -118.528338) (xy 196.539104 -118.771162) (xy 196.323204 -119.101616)
			(xy 196.319148 -119.109823) (xy 196.316616 -119.127943) (xy 196.320576 -119.145805) (xy 196.325236 -119.153686)
			(xy 196.357494 -119.20347) (xy 196.539104 -119.480584) (xy 196.539104 -119.559324) (xy 197.174612 -119.559324)
			(xy 197.174612 -118.695724) (xy 197.175102 -118.665756) (xy 197.182925 -118.606334) (xy 197.198438 -118.548441)
			(xy 197.221374 -118.493068) (xy 197.251341 -118.441162) (xy 197.287828 -118.393612) (xy 197.330208 -118.351232)
			(xy 197.377758 -118.314745) (xy 197.429664 -118.284778) (xy 197.485037 -118.261842) (xy 197.54293 -118.246329)
			(xy 197.602352 -118.238506) (xy 197.662288 -118.238506) (xy 197.72171 -118.246329) (xy 197.779603 -118.261842)
			(xy 197.834976 -118.284778) (xy 197.886882 -118.314745) (xy 197.934432 -118.351232) (xy 197.976812 -118.393612)
			(xy 198.013299 -118.441162) (xy 198.043266 -118.493068) (xy 198.066202 -118.548441) (xy 198.081715 -118.606334)
			(xy 198.089538 -118.665756) (xy 198.090028 -118.695724) (xy 198.090028 -119.559324) (xy 198.089538 -119.589292)
			(xy 198.081715 -119.648714) (xy 198.066202 -119.706607) (xy 198.043266 -119.76198) (xy 198.013299 -119.813886)
			(xy 197.976812 -119.861436) (xy 197.934432 -119.903816) (xy 197.886882 -119.940303) (xy 197.834976 -119.97027)
			(xy 197.779603 -119.993206) (xy 197.72171 -120.008719) (xy 197.662288 -120.016542) (xy 197.602352 -120.016542)
			(xy 197.54293 -120.008719) (xy 197.485037 -119.993206) (xy 197.429664 -119.97027) (xy 197.377758 -119.940303)
			(xy 197.330208 -119.903816) (xy 197.287828 -119.861436) (xy 197.251341 -119.813886) (xy 197.221374 -119.76198)
			(xy 197.198438 -119.706607) (xy 197.182925 -119.648714) (xy 197.175102 -119.589292) (xy 197.174612 -119.559324)
			(xy 196.539104 -119.559324) (xy 196.539104 -119.724678) (xy 196.53855 -119.734829) (xy 196.53079 -119.75359)
			(xy 196.516444 -119.767954) (xy 196.497693 -119.775737) (xy 196.487542 -119.77624) (xy 195.750942 -119.77624)
			(xy 195.74077 -119.775801) (xy 195.721972 -119.768026) (xy 195.707585 -119.753644) (xy 195.699803 -119.734849)
			(xy 195.69938 -119.724678) (xy 183.587026 -119.724678) (xy 183.568314 -119.769854) (xy 183.538347 -119.82176)
			(xy 183.50186 -119.86931) (xy 183.45948 -119.91169) (xy 183.41193 -119.948177) (xy 183.360024 -119.978144)
			(xy 183.304651 -120.00108) (xy 183.246758 -120.016593) (xy 183.187336 -120.024416) (xy 183.1274 -120.024416)
			(xy 183.067978 -120.016593) (xy 183.010085 -120.00108) (xy 182.954712 -119.978144) (xy 182.902806 -119.948177)
			(xy 182.855256 -119.91169) (xy 182.812876 -119.86931) (xy 182.776389 -119.82176) (xy 182.746422 -119.769854)
			(xy 182.723486 -119.714481) (xy 182.707973 -119.656588) (xy 182.70015 -119.597166) (xy 182.69966 -119.567198)
			(xy 170.65498 -119.567198) (xy 170.65498 -120.086374) (xy 170.65449 -120.116358) (xy 170.646662 -120.175814)
			(xy 170.631141 -120.233739) (xy 170.608192 -120.289143) (xy 170.578208 -120.341077) (xy 170.541702 -120.388653)
			(xy 170.499297 -120.431058) (xy 170.451721 -120.467564) (xy 170.399787 -120.497548) (xy 170.344383 -120.520497)
			(xy 170.286458 -120.536018) (xy 170.227002 -120.543846) (xy 170.167034 -120.543846) (xy 170.107578 -120.536018)
			(xy 170.049653 -120.520497) (xy 169.994249 -120.497548) (xy 169.942315 -120.467564) (xy 169.894739 -120.431058)
			(xy 169.852334 -120.388653) (xy 169.815828 -120.341077) (xy 169.785844 -120.289143) (xy 169.762895 -120.233739)
			(xy 169.747374 -120.175814) (xy 169.739546 -120.116358) (xy 169.739056 -120.086374) (xy 167.352472 -120.086374)
			(xy 167.352472 -120.158256) (xy 167.352047 -120.168379) (xy 167.344308 -120.187087) (xy 167.329994 -120.201404)
			(xy 167.311287 -120.209146) (xy 167.301164 -120.209564) (xy 166.120064 -120.209564) (xy 166.109935 -120.209213)
			(xy 166.091223 -120.201446) (xy 166.076909 -120.187109) (xy 166.069172 -120.168386) (xy 166.068756 -120.158256)
			(xy 162.816032 -120.158256) (xy 162.815543 -120.168403) (xy 162.807768 -120.187149) (xy 162.793392 -120.201472)
			(xy 162.774619 -120.209179) (xy 162.76447 -120.209564) (xy 161.58337 -120.209564) (xy 161.573242 -120.209098)
			(xy 161.554521 -120.201361) (xy 161.540166 -120.187069) (xy 161.532347 -120.168382) (xy 161.531808 -120.158256)
			(xy 153.158444 -120.158256) (xy 153.158444 -120.253252) (xy 153.15795 -120.263467) (xy 153.150147 -120.282348)
			(xy 153.135712 -120.296805) (xy 153.116843 -120.304635) (xy 153.106628 -120.305068) (xy 152.370028 -120.305068)
			(xy 152.359802 -120.304664) (xy 152.340906 -120.296841) (xy 152.326448 -120.282377) (xy 152.318632 -120.263478)
			(xy 152.318212 -120.253252) (xy 151.65243 -120.253252) (xy 151.636932 -120.290667) (xy 151.606948 -120.342601)
			(xy 151.570442 -120.390177) (xy 151.528037 -120.432582) (xy 151.480461 -120.469088) (xy 151.428527 -120.499072)
			(xy 151.373123 -120.522021) (xy 151.315198 -120.537542) (xy 151.255742 -120.54537) (xy 151.195774 -120.54537)
			(xy 151.136318 -120.537542) (xy 151.078393 -120.522021) (xy 151.022989 -120.499072) (xy 150.971055 -120.469088)
			(xy 150.923479 -120.432582) (xy 150.881074 -120.390177) (xy 150.844568 -120.342601) (xy 150.814584 -120.290667)
			(xy 150.791635 -120.235263) (xy 150.776114 -120.177338) (xy 150.768286 -120.117882) (xy 150.767796 -120.087898)
			(xy 84.369615 -120.087898) (xy 84.377099 -120.090998) (xy 84.429033 -120.120982) (xy 84.476609 -120.157488)
			(xy 84.519014 -120.199893) (xy 84.55552 -120.247469) (xy 84.585504 -120.299403) (xy 84.608453 -120.354807)
			(xy 84.623974 -120.412732) (xy 84.631802 -120.472188) (xy 84.632292 -120.502172) (xy 84.632292 -121.365772)
			(xy 84.631802 -121.395756) (xy 84.623974 -121.455212) (xy 84.608453 -121.513137) (xy 84.585504 -121.568541)
			(xy 84.55552 -121.620475) (xy 84.519014 -121.668051) (xy 84.476609 -121.710456) (xy 84.429033 -121.746962)
			(xy 84.377099 -121.776946) (xy 84.321695 -121.799895) (xy 84.26377 -121.815416) (xy 84.204314 -121.823244)
			(xy 84.144346 -121.823244) (xy 84.08489 -121.815416) (xy 84.026965 -121.799895) (xy 83.971561 -121.776946)
			(xy 83.919627 -121.746962) (xy 83.872051 -121.710456) (xy 83.829646 -121.668051) (xy 83.79314 -121.620475)
			(xy 83.763156 -121.568541) (xy 83.740207 -121.513137) (xy 83.724686 -121.455212) (xy 83.716858 -121.395756)
			(xy 83.716368 -121.365772) (xy 83.081368 -121.365772) (xy 83.081368 -121.531126) (xy 83.080888 -121.541285)
			(xy 83.073106 -121.560053) (xy 83.058737 -121.574418) (xy 83.039965 -121.582192) (xy 83.029806 -121.582688)
			(xy 82.293206 -121.582688) (xy 82.283052 -121.582162) (xy 82.264288 -121.574395) (xy 82.249923 -121.560039)
			(xy 82.242144 -121.54128) (xy 82.241644 -121.531126) (xy 65.630373 -121.531126) (xy 65.614244 -121.570065)
			(xy 65.58426 -121.621999) (xy 65.547754 -121.669575) (xy 65.505349 -121.71198) (xy 65.457773 -121.748486)
			(xy 65.405839 -121.77847) (xy 65.350435 -121.801419) (xy 65.29251 -121.81694) (xy 65.233054 -121.824768)
			(xy 65.173086 -121.824768) (xy 65.11363 -121.81694) (xy 65.055705 -121.801419) (xy 65.000301 -121.77847)
			(xy 64.948367 -121.748486) (xy 64.900791 -121.71198) (xy 64.858386 -121.669575) (xy 64.82188 -121.621999)
			(xy 64.791896 -121.570065) (xy 64.768947 -121.514661) (xy 64.753426 -121.456736) (xy 64.745598 -121.39728)
			(xy 64.745108 -121.367296) (xy 52.700428 -121.367296) (xy 52.700428 -121.886472) (xy 52.699938 -121.91644)
			(xy 52.692115 -121.975862) (xy 52.676602 -122.033755) (xy 52.653666 -122.089128) (xy 52.623699 -122.141034)
			(xy 52.587212 -122.188584) (xy 52.544832 -122.230964) (xy 52.497282 -122.267451) (xy 52.445376 -122.297418)
			(xy 52.390003 -122.320354) (xy 52.33211 -122.335867) (xy 52.272688 -122.34369) (xy 52.212752 -122.34369)
			(xy 52.15333 -122.335867) (xy 52.095437 -122.320354) (xy 52.040064 -122.297418) (xy 51.988158 -122.267451)
			(xy 51.940608 -122.230964) (xy 51.898228 -122.188584) (xy 51.861741 -122.141034) (xy 51.831774 -122.089128)
			(xy 51.808838 -122.033755) (xy 51.793325 -121.975862) (xy 51.785502 -121.91644) (xy 51.785012 -121.886472)
			(xy 51.252628 -121.886472) (xy 51.252628 -121.958354) (xy 51.252135 -121.968482) (xy 51.244416 -121.987208)
			(xy 51.230131 -122.001567) (xy 51.211445 -122.009382) (xy 51.20132 -122.009916) (xy 50.02022 -122.009916)
			(xy 50.010101 -122.009468) (xy 49.991401 -122.00173) (xy 49.977086 -121.987423) (xy 49.969337 -121.968727)
			(xy 49.968912 -121.958608) (xy 46.716176 -121.958608) (xy 46.715699 -121.968519) (xy 46.707934 -121.987308)
			(xy 46.693569 -122.001694) (xy 46.674791 -122.009485) (xy 46.664626 -122.009916) (xy 45.483526 -122.009916)
			(xy 45.47335 -122.009514) (xy 45.454548 -122.001729) (xy 45.44016 -121.987336) (xy 45.432383 -121.96853)
			(xy 45.431964 -121.958354) (xy 39.700708 -121.958354) (xy 39.700708 -122.0597) (xy 39.700288 -122.069923)
			(xy 39.692463 -122.088812) (xy 39.678005 -122.103268) (xy 39.659115 -122.11109) (xy 39.648892 -122.111516)
			(xy 38.912292 -122.111516) (xy 38.902084 -122.111025) (xy 38.883222 -122.103209) (xy 38.868786 -122.088771)
			(xy 38.860974 -122.069908) (xy 38.860476 -122.0597) (xy 38.194165 -122.0597) (xy 38.178714 -122.097002)
			(xy 38.148747 -122.148908) (xy 38.11226 -122.196458) (xy 38.06988 -122.238838) (xy 38.02233 -122.275325)
			(xy 37.970424 -122.305292) (xy 37.915051 -122.328228) (xy 37.857158 -122.343741) (xy 37.797736 -122.351564)
			(xy 37.7378 -122.351564) (xy 37.678378 -122.343741) (xy 37.620485 -122.328228) (xy 37.565112 -122.305292)
			(xy 37.513206 -122.275325) (xy 37.465656 -122.238838) (xy 37.423276 -122.196458) (xy 37.386789 -122.148908)
			(xy 37.356822 -122.097002) (xy 37.333886 -122.041629) (xy 37.318373 -121.983736) (xy 37.31055 -121.924314)
			(xy 37.31006 -121.894346) (xy 4.30911 -121.894346) (xy 4.30911 -123.68784) (xy 34.667952 -123.68784)
			(xy 34.667952 -122.82424) (xy 34.668442 -122.794272) (xy 34.676265 -122.73485) (xy 34.691778 -122.676957)
			(xy 34.714714 -122.621584) (xy 34.744681 -122.569678) (xy 34.781168 -122.522128) (xy 34.823548 -122.479748)
			(xy 34.871098 -122.443261) (xy 34.923004 -122.413294) (xy 34.978377 -122.390358) (xy 35.03627 -122.374845)
			(xy 35.095692 -122.367022) (xy 35.155628 -122.367022) (xy 35.21505 -122.374845) (xy 35.272943 -122.390358)
			(xy 35.328316 -122.413294) (xy 35.380222 -122.443261) (xy 35.427772 -122.479748) (xy 35.470152 -122.522128)
			(xy 35.506639 -122.569678) (xy 35.536606 -122.621584) (xy 35.559542 -122.676957) (xy 35.575055 -122.73485)
			(xy 35.582878 -122.794272) (xy 35.583368 -122.82424) (xy 35.583368 -123.68784) (xy 35.582878 -123.717808)
			(xy 35.575055 -123.77723) (xy 35.559542 -123.835123) (xy 35.552057 -123.853194) (xy 36.218368 -123.853194)
			(xy 36.218368 -123.62561) (xy 36.218622 -123.621546) (xy 36.218876 -123.619006) (xy 36.218876 -123.61037)
			(xy 36.224464 -123.601734) (xy 36.225734 -123.599702) (xy 36.22675 -123.59767) (xy 36.436554 -123.277884)
			(xy 36.43884 -123.269756) (xy 36.441284 -123.259107) (xy 36.438008 -123.237529) (xy 36.43249 -123.2281)
			(xy 36.226496 -122.912378) (xy 36.22421 -122.908568) (xy 36.223956 -122.90806) (xy 36.22294 -122.906282)
			(xy 36.218876 -122.899678) (xy 36.218876 -122.89155) (xy 36.218622 -122.88901) (xy 36.218368 -122.884946)
			(xy 36.218368 -122.656854) (xy 36.218797 -122.64669) (xy 36.226592 -122.627914) (xy 36.240978 -122.613549)
			(xy 36.259765 -122.605782) (xy 36.26993 -122.605292) (xy 37.006784 -122.605292) (xy 37.01696 -122.605788)
			(xy 37.035775 -122.61355) (xy 37.050203 -122.627905) (xy 37.05806 -122.64668) (xy 37.0586 -122.656854)
			(xy 37.0586 -122.884438) (xy 37.058346 -122.888502) (xy 37.058092 -122.891042) (xy 37.058092 -122.899678)
			(xy 37.05225 -122.909076) (xy 37.051488 -122.910346) (xy 37.050218 -122.912378) (xy 36.844478 -123.227084)
			(xy 36.839404 -123.235594) (xy 36.835593 -123.25502) (xy 36.83942 -123.274443) (xy 36.844478 -123.282964)
			(xy 37.050218 -123.5964) (xy 37.051234 -123.598432) (xy 37.052504 -123.600464) (xy 37.058092 -123.6091)
			(xy 37.058092 -123.617736) (xy 37.058346 -123.620276) (xy 37.0586 -123.62434) (xy 37.0586 -123.758452)
			(xy 45.431964 -123.758452) (xy 45.431964 -122.752104) (xy 45.432424 -122.741955) (xy 45.440212 -122.723209)
			(xy 45.454596 -122.708887) (xy 45.473375 -122.701181) (xy 45.483526 -122.700796) (xy 46.664626 -122.700796)
			(xy 46.674749 -122.701304) (xy 46.693462 -122.709032) (xy 46.707816 -122.723311) (xy 46.715642 -122.741984)
			(xy 46.716188 -122.752104) (xy 46.716188 -123.758452) (xy 49.968912 -123.758452) (xy 49.968912 -122.752104)
			(xy 49.96932 -122.74198) (xy 49.977069 -122.723274) (xy 49.991388 -122.70896) (xy 50.010096 -122.701216)
			(xy 50.02022 -122.700796) (xy 51.20132 -122.700796) (xy 51.21143 -122.701268) (xy 51.230108 -122.709012)
			(xy 51.244402 -122.723313) (xy 51.252136 -122.741994) (xy 51.252628 -122.752104) (xy 51.252628 -123.686316)
			(xy 53.639212 -123.686316) (xy 53.639212 -122.822716) (xy 53.639702 -122.792748) (xy 53.647525 -122.733326)
			(xy 53.663038 -122.675433) (xy 53.685974 -122.62006) (xy 53.715941 -122.568154) (xy 53.752428 -122.520604)
			(xy 53.794808 -122.478224) (xy 53.842358 -122.441737) (xy 53.894264 -122.41177) (xy 53.949637 -122.388834)
			(xy 54.00753 -122.373321) (xy 54.066952 -122.365498) (xy 54.126888 -122.365498) (xy 54.18631 -122.373321)
			(xy 54.244203 -122.388834) (xy 54.299576 -122.41177) (xy 54.351482 -122.441737) (xy 54.399032 -122.478224)
			(xy 54.441412 -122.520604) (xy 54.477899 -122.568154) (xy 54.507866 -122.62006) (xy 54.530802 -122.675433)
			(xy 54.546315 -122.733326) (xy 54.554138 -122.792748) (xy 54.554628 -122.822716) (xy 54.554628 -123.16714)
			(xy 66.599308 -123.16714) (xy 66.599308 -122.30354) (xy 66.599798 -122.273556) (xy 66.607626 -122.2141)
			(xy 66.623147 -122.156175) (xy 66.646096 -122.100771) (xy 66.67608 -122.048837) (xy 66.712586 -122.001261)
			(xy 66.754991 -121.958856) (xy 66.802567 -121.92235) (xy 66.854501 -121.892366) (xy 66.909905 -121.869417)
			(xy 66.96783 -121.853896) (xy 67.027286 -121.846068) (xy 67.087254 -121.846068) (xy 67.14671 -121.853896)
			(xy 67.204635 -121.869417) (xy 67.260039 -121.892366) (xy 67.311973 -121.92235) (xy 67.359549 -121.958856)
			(xy 67.401954 -122.001261) (xy 67.43846 -122.048837) (xy 67.468444 -122.100771) (xy 67.491393 -122.156175)
			(xy 67.506914 -122.2141) (xy 67.514742 -122.273556) (xy 67.515232 -122.30354) (xy 67.515232 -123.16714)
			(xy 67.514742 -123.197124) (xy 67.509326 -123.23826) (xy 68.047108 -123.23826) (xy 68.047108 -122.231912)
			(xy 68.047526 -122.221789) (xy 68.055272 -122.203084) (xy 68.069588 -122.188769) (xy 68.088293 -122.181025)
			(xy 68.098416 -122.180604) (xy 69.27977 -122.180604) (xy 69.28989 -122.18115) (xy 69.308604 -122.188861)
			(xy 69.32296 -122.203129) (xy 69.330787 -122.221795) (xy 69.331332 -122.231912) (xy 69.331332 -123.23826)
			(xy 72.584056 -123.23826) (xy 72.584056 -122.231912) (xy 72.584594 -122.221809) (xy 72.592319 -122.20314)
			(xy 72.6066 -122.188846) (xy 72.625262 -122.181103) (xy 72.635364 -122.180604) (xy 73.816464 -122.180604)
			(xy 73.826585 -122.181046) (xy 73.845288 -122.188783) (xy 73.859604 -122.203092) (xy 73.86735 -122.221792)
			(xy 73.867772 -122.231912) (xy 73.867772 -123.23826) (xy 73.86735 -123.248383) (xy 73.85961 -123.267091)
			(xy 73.845295 -123.281408) (xy 73.826587 -123.28915) (xy 73.816464 -123.289568) (xy 72.635364 -123.289568)
			(xy 72.625235 -123.289213) (xy 72.606525 -123.281447) (xy 72.592211 -123.267111) (xy 72.584472 -123.248389)
			(xy 72.584056 -123.23826) (xy 69.331332 -123.23826) (xy 69.330852 -123.248376) (xy 69.323123 -123.267072)
			(xy 69.308826 -123.281387) (xy 69.290139 -123.289139) (xy 69.280024 -123.289568) (xy 68.09867 -123.289568)
			(xy 68.088542 -123.289098) (xy 68.069822 -123.281362) (xy 68.055467 -123.267071) (xy 68.047647 -123.248385)
			(xy 68.047108 -123.23826) (xy 67.509326 -123.23826) (xy 67.506914 -123.25658) (xy 67.491393 -123.314505)
			(xy 67.487203 -123.32462) (xy 79.599536 -123.32462) (xy 79.599536 -123.081796) (xy 79.718408 -122.90044)
			(xy 79.780892 -122.804936) (xy 79.805022 -122.768106) (xy 79.808898 -122.761782) (xy 79.813154 -122.747579)
			(xy 79.813404 -122.740166) (xy 79.813404 -122.714258) (xy 79.813197 -122.708109) (xy 79.810253 -122.696168)
			(xy 79.807562 -122.690636) (xy 79.694024 -122.516646) (xy 79.673958 -122.485658) (xy 79.66837 -122.477022)
			(xy 79.607918 -122.384312) (xy 79.60741 -122.38355) (xy 79.606902 -122.382788) (xy 79.606648 -122.38228)
			(xy 79.60614 -122.381518) (xy 79.599536 -122.371104) (xy 79.599536 -122.12828) (xy 79.600169 -122.116727)
			(xy 79.610132 -122.095876) (xy 79.628078 -122.081316) (xy 79.63916 -122.077988) (xy 79.651098 -122.076464)
			(xy 80.387698 -122.076464) (xy 80.398459 -122.076959) (xy 80.418148 -122.085641) (xy 80.425798 -122.093228)
			(xy 80.431987 -122.100633) (xy 80.438906 -122.118636) (xy 80.43926 -122.12828) (xy 80.43926 -122.371104)
			(xy 80.22336 -122.701558) (xy 80.219354 -122.709785) (xy 80.216808 -122.727891) (xy 80.220745 -122.745746)
			(xy 80.225392 -122.753628) (xy 80.25765 -122.803412) (xy 80.43926 -123.080526) (xy 80.43926 -123.159266)
			(xy 81.07426 -123.159266) (xy 81.07426 -122.295666) (xy 81.07475 -122.265682) (xy 81.082578 -122.206226)
			(xy 81.098099 -122.148301) (xy 81.121048 -122.092897) (xy 81.151032 -122.040963) (xy 81.187538 -121.993387)
			(xy 81.229943 -121.950982) (xy 81.277519 -121.914476) (xy 81.329453 -121.884492) (xy 81.384857 -121.861543)
			(xy 81.442782 -121.846022) (xy 81.502238 -121.838194) (xy 81.562206 -121.838194) (xy 81.621662 -121.846022)
			(xy 81.679587 -121.861543) (xy 81.734991 -121.884492) (xy 81.752059 -121.894346) (xy 153.409904 -121.894346)
			(xy 153.409904 -121.030746) (xy 153.410394 -121.000762) (xy 153.418222 -120.941306) (xy 153.433743 -120.883381)
			(xy 153.456692 -120.827977) (xy 153.486676 -120.776043) (xy 153.523182 -120.728467) (xy 153.565587 -120.686062)
			(xy 153.613163 -120.649556) (xy 153.665097 -120.619572) (xy 153.720501 -120.596623) (xy 153.778426 -120.581102)
			(xy 153.837882 -120.573274) (xy 153.89785 -120.573274) (xy 153.957306 -120.581102) (xy 154.015231 -120.596623)
			(xy 154.070635 -120.619572) (xy 154.122569 -120.649556) (xy 154.170145 -120.686062) (xy 154.21255 -120.728467)
			(xy 154.249056 -120.776043) (xy 154.27904 -120.827977) (xy 154.301989 -120.883381) (xy 154.31751 -120.941306)
			(xy 154.325338 -121.000762) (xy 154.325828 -121.030746) (xy 154.325828 -121.894346) (xy 154.325338 -121.92433)
			(xy 154.31751 -121.983786) (xy 154.301989 -122.041711) (xy 154.294538 -122.0597) (xy 154.96032 -122.0597)
			(xy 154.96032 -121.832116) (xy 154.960574 -121.828052) (xy 154.960828 -121.825512) (xy 154.960828 -121.816876)
			(xy 154.966416 -121.80824) (xy 154.967686 -121.806208) (xy 154.968702 -121.804176) (xy 155.16606 -121.503186)
			(xy 155.169947 -121.496868) (xy 155.174195 -121.482661) (xy 155.174442 -121.475246) (xy 155.174442 -121.449592)
			(xy 155.17426 -121.442256) (xy 155.170114 -121.428185) (xy 155.166314 -121.421906) (xy 154.968448 -121.118884)
			(xy 154.966162 -121.115074) (xy 154.965908 -121.114566) (xy 154.964892 -121.112788) (xy 154.960828 -121.106184)
			(xy 154.960828 -121.098056) (xy 154.960574 -121.095516) (xy 154.96032 -121.091452) (xy 154.96032 -120.86336)
			(xy 154.96075 -120.853145) (xy 154.968583 -120.834276) (xy 154.98304 -120.81984) (xy 155.00192 -120.812035)
			(xy 155.012136 -120.811544) (xy 155.748736 -120.811544) (xy 155.758941 -120.812051) (xy 155.777796 -120.819868)
			(xy 155.792229 -120.834301) (xy 155.800048 -120.853155) (xy 155.800552 -120.86336) (xy 155.800552 -121.090944)
			(xy 155.800298 -121.095008) (xy 155.800044 -121.097548) (xy 155.800044 -121.106184) (xy 155.794202 -121.115582)
			(xy 155.79344 -121.116852) (xy 155.79217 -121.118884) (xy 155.58643 -121.43359) (xy 155.581347 -121.442096)
			(xy 155.577533 -121.461525) (xy 155.581366 -121.48095) (xy 155.58643 -121.48947) (xy 155.79217 -121.802906)
			(xy 155.793186 -121.804938) (xy 155.794456 -121.80697) (xy 155.800044 -121.815606) (xy 155.800044 -121.824242)
			(xy 155.800298 -121.826782) (xy 155.800552 -121.830846) (xy 155.800552 -121.958354) (xy 161.531808 -121.958354)
			(xy 161.531808 -120.952006) (xy 161.532338 -120.941852) (xy 161.540104 -120.923089) (xy 161.554459 -120.908725)
			(xy 161.573217 -120.900945) (xy 161.58337 -120.900444) (xy 162.76447 -120.900444) (xy 162.77464 -120.900889)
			(xy 162.793436 -120.908665) (xy 162.807822 -120.923044) (xy 162.815607 -120.941836) (xy 162.816032 -120.952006)
			(xy 162.816032 -121.958354) (xy 162.816021 -121.958608) (xy 166.068756 -121.958608) (xy 166.068756 -120.952006)
			(xy 166.069232 -120.941878) (xy 166.076961 -120.923154) (xy 166.091251 -120.908797) (xy 166.109938 -120.90098)
			(xy 166.120064 -120.900444) (xy 167.301164 -120.900444) (xy 167.311264 -120.901013) (xy 167.32993 -120.908729)
			(xy 167.344224 -120.922999) (xy 167.35197 -120.941653) (xy 167.352472 -120.951752) (xy 167.352472 -121.886472)
			(xy 167.884856 -121.886472) (xy 167.884856 -121.022872) (xy 167.885346 -120.992888) (xy 167.893174 -120.933432)
			(xy 167.908695 -120.875507) (xy 167.931644 -120.820103) (xy 167.961628 -120.768169) (xy 167.998134 -120.720593)
			(xy 168.040539 -120.678188) (xy 168.088115 -120.641682) (xy 168.140049 -120.611698) (xy 168.195453 -120.588749)
			(xy 168.253378 -120.573228) (xy 168.312834 -120.5654) (xy 168.372802 -120.5654) (xy 168.432258 -120.573228)
			(xy 168.490183 -120.588749) (xy 168.545587 -120.611698) (xy 168.597521 -120.641682) (xy 168.645097 -120.678188)
			(xy 168.687502 -120.720593) (xy 168.724008 -120.768169) (xy 168.753992 -120.820103) (xy 168.776941 -120.875507)
			(xy 168.792462 -120.933432) (xy 168.80029 -120.992888) (xy 168.80078 -121.022872) (xy 168.80078 -121.367296)
			(xy 180.84546 -121.367296) (xy 180.84546 -120.503696) (xy 180.84595 -120.473728) (xy 180.853773 -120.414306)
			(xy 180.869286 -120.356413) (xy 180.892222 -120.30104) (xy 180.922189 -120.249134) (xy 180.958676 -120.201584)
			(xy 181.001056 -120.159204) (xy 181.048606 -120.122717) (xy 181.100512 -120.09275) (xy 181.155885 -120.069814)
			(xy 181.213778 -120.054301) (xy 181.2732 -120.046478) (xy 181.333136 -120.046478) (xy 181.392558 -120.054301)
			(xy 181.450451 -120.069814) (xy 181.505824 -120.09275) (xy 181.55773 -120.122717) (xy 181.60528 -120.159204)
			(xy 181.64766 -120.201584) (xy 181.684147 -120.249134) (xy 181.714114 -120.30104) (xy 181.73705 -120.356413)
			(xy 181.752563 -120.414306) (xy 181.760386 -120.473728) (xy 181.760876 -120.503696) (xy 181.760876 -121.367296)
			(xy 181.760386 -121.397264) (xy 181.755002 -121.438162) (xy 184.146952 -121.438162) (xy 184.146952 -120.431814)
			(xy 184.147375 -120.421642) (xy 184.155159 -120.402844) (xy 184.169544 -120.388459) (xy 184.188342 -120.380675)
			(xy 184.198514 -120.380252) (xy 185.379614 -120.380252) (xy 185.389774 -120.380722) (xy 185.408546 -120.388504)
			(xy 185.422912 -120.402877) (xy 185.430683 -120.421653) (xy 185.431176 -120.431814) (xy 185.431176 -121.438162)
			(xy 188.6839 -121.438162) (xy 188.6839 -120.431814) (xy 188.684437 -120.421693) (xy 188.692153 -120.40298)
			(xy 188.706423 -120.388624) (xy 188.72509 -120.380798) (xy 188.735208 -120.380252) (xy 189.916308 -120.380252)
			(xy 189.926457 -120.380714) (xy 189.9452 -120.388503) (xy 189.959521 -120.402887) (xy 189.967229 -120.421664)
			(xy 189.967616 -120.431814) (xy 189.967616 -121.438162) (xy 189.967141 -121.448292) (xy 189.959417 -121.46702)
			(xy 189.945127 -121.481379) (xy 189.926435 -121.489192) (xy 189.916308 -121.489724) (xy 188.735208 -121.489724)
			(xy 188.725057 -121.489272) (xy 188.70631 -121.481484) (xy 188.691987 -121.467097) (xy 188.684283 -121.448314)
			(xy 188.6839 -121.438162) (xy 185.431176 -121.438162) (xy 185.430705 -121.448329) (xy 185.422935 -121.467121)
			(xy 185.408564 -121.481506) (xy 185.389781 -121.489295) (xy 185.379614 -121.489724) (xy 184.198514 -121.489724)
			(xy 184.188339 -121.489324) (xy 184.169537 -121.481536) (xy 184.15515 -121.467143) (xy 184.147371 -121.448338)
			(xy 184.146952 -121.438162) (xy 181.755002 -121.438162) (xy 181.752563 -121.456686) (xy 181.73705 -121.514579)
			(xy 181.730196 -121.531126) (xy 198.341488 -121.531126) (xy 198.341488 -121.288302) (xy 198.46036 -121.106946)
			(xy 198.522844 -121.011442) (xy 198.546974 -120.974612) (xy 198.550852 -120.968289) (xy 198.555105 -120.954086)
			(xy 198.555356 -120.946672) (xy 198.555356 -120.920764) (xy 198.555176 -120.914613) (xy 198.552213 -120.902672)
			(xy 198.549514 -120.897142) (xy 198.435976 -120.723152) (xy 198.41591 -120.692164) (xy 198.410322 -120.683528)
			(xy 198.34987 -120.590818) (xy 198.349362 -120.590056) (xy 198.348854 -120.589294) (xy 198.3486 -120.588786)
			(xy 198.348092 -120.588024) (xy 198.341488 -120.57761) (xy 198.341488 -120.334786) (xy 198.341854 -120.324607)
			(xy 198.349653 -120.305803) (xy 198.364057 -120.291417) (xy 198.382871 -120.283641) (xy 198.39305 -120.283224)
			(xy 199.12965 -120.283224) (xy 199.139817 -120.283704) (xy 199.158608 -120.29147) (xy 199.172994 -120.305839)
			(xy 199.180783 -120.32462) (xy 199.181212 -120.334786) (xy 199.181212 -120.57761) (xy 198.965312 -120.908064)
			(xy 198.961297 -120.916288) (xy 198.95875 -120.934396) (xy 198.962692 -120.952253) (xy 198.967344 -120.960134)
			(xy 198.999602 -121.009918) (xy 199.181212 -121.287032) (xy 199.181212 -121.365772) (xy 199.81672 -121.365772)
			(xy 199.81672 -120.502172) (xy 199.81721 -120.472204) (xy 199.825033 -120.412782) (xy 199.840546 -120.354889)
			(xy 199.863482 -120.299516) (xy 199.893449 -120.24761) (xy 199.929936 -120.20006) (xy 199.972316 -120.15768)
			(xy 200.019866 -120.121193) (xy 200.071772 -120.091226) (xy 200.127145 -120.06829) (xy 200.185038 -120.052777)
			(xy 200.24446 -120.044954) (xy 200.304396 -120.044954) (xy 200.363818 -120.052777) (xy 200.421711 -120.06829)
			(xy 200.469049 -120.087898) (xy 266.86764 -120.087898) (xy 266.86764 -119.224298) (xy 266.86813 -119.194314)
			(xy 266.875958 -119.134858) (xy 266.891479 -119.076933) (xy 266.914428 -119.021529) (xy 266.944412 -118.969595)
			(xy 266.980918 -118.922019) (xy 267.023323 -118.879614) (xy 267.070899 -118.843108) (xy 267.122833 -118.813124)
			(xy 267.178237 -118.790175) (xy 267.236162 -118.774654) (xy 267.295618 -118.766826) (xy 267.355586 -118.766826)
			(xy 267.415042 -118.774654) (xy 267.472967 -118.790175) (xy 267.528371 -118.813124) (xy 267.580305 -118.843108)
			(xy 267.627881 -118.879614) (xy 267.670286 -118.922019) (xy 267.706792 -118.969595) (xy 267.736776 -119.021529)
			(xy 267.759725 -119.076933) (xy 267.775246 -119.134858) (xy 267.783074 -119.194314) (xy 267.783564 -119.224298)
			(xy 267.783564 -120.087898) (xy 267.783074 -120.117882) (xy 267.775246 -120.177338) (xy 267.759725 -120.235263)
			(xy 267.752274 -120.253252) (xy 268.418564 -120.253252) (xy 268.418564 -120.010428) (xy 268.537436 -119.829072)
			(xy 268.59992 -119.733568) (xy 268.62405 -119.696738) (xy 268.627916 -119.690409) (xy 268.632177 -119.67621)
			(xy 268.632432 -119.668798) (xy 268.632432 -119.64289) (xy 268.632246 -119.63674) (xy 268.629288 -119.624799)
			(xy 268.62659 -119.619268) (xy 268.513052 -119.445278) (xy 268.492986 -119.41429) (xy 268.487398 -119.405654)
			(xy 268.426946 -119.312944) (xy 268.426438 -119.312182) (xy 268.42593 -119.31142) (xy 268.425676 -119.310912)
			(xy 268.425168 -119.31015) (xy 268.418564 -119.299736) (xy 268.418564 -119.056912) (xy 268.419198 -119.045361)
			(xy 268.429171 -119.024518) (xy 268.44711 -119.009956) (xy 268.458188 -119.00662) (xy 268.470126 -119.005096)
			(xy 269.206726 -119.005096) (xy 269.217479 -119.00565) (xy 269.237169 -119.014293) (xy 269.244826 -119.02186)
			(xy 269.25102 -119.029262) (xy 269.257938 -119.047267) (xy 269.258288 -119.056912) (xy 269.258288 -119.299736)
			(xy 269.042388 -119.63019) (xy 269.038354 -119.638406) (xy 269.035816 -119.65652) (xy 269.039765 -119.674379)
			(xy 269.04442 -119.68226) (xy 269.076678 -119.732044) (xy 269.258288 -120.009158) (xy 269.258288 -120.158256)
			(xy 277.63216 -120.158256) (xy 277.63216 -119.151908) (xy 277.632691 -119.141805) (xy 277.640418 -119.123134)
			(xy 277.654701 -119.108841) (xy 277.673365 -119.101099) (xy 277.683468 -119.1006) (xy 278.864568 -119.1006)
			(xy 278.874688 -119.101042) (xy 278.893391 -119.10878) (xy 278.907707 -119.123088) (xy 278.915453 -119.141788)
			(xy 278.915876 -119.151908) (xy 278.915876 -120.158256) (xy 282.1686 -120.158256) (xy 282.1686 -119.151908)
			(xy 282.169023 -119.141786) (xy 282.176768 -119.123083) (xy 282.191083 -119.108768) (xy 282.209786 -119.101023)
			(xy 282.219908 -119.1006) (xy 283.401262 -119.1006) (xy 283.411381 -119.101157) (xy 283.430094 -119.108865)
			(xy 283.44445 -119.123129) (xy 283.452278 -119.141792) (xy 283.452824 -119.151908) (xy 283.452824 -120.086374)
			(xy 285.8389 -120.086374) (xy 285.8389 -119.222774) (xy 285.83939 -119.19279) (xy 285.847218 -119.133334)
			(xy 285.862739 -119.075409) (xy 285.885688 -119.020005) (xy 285.915672 -118.968071) (xy 285.952178 -118.920495)
			(xy 285.994583 -118.87809) (xy 286.042159 -118.841584) (xy 286.094093 -118.8116) (xy 286.149497 -118.788651)
			(xy 286.207422 -118.77313) (xy 286.266878 -118.765302) (xy 286.326846 -118.765302) (xy 286.386302 -118.77313)
			(xy 286.444227 -118.788651) (xy 286.499631 -118.8116) (xy 286.551565 -118.841584) (xy 286.599141 -118.87809)
			(xy 286.641546 -118.920495) (xy 286.678052 -118.968071) (xy 286.708036 -119.020005) (xy 286.730985 -119.075409)
			(xy 286.746506 -119.133334) (xy 286.754334 -119.19279) (xy 286.754824 -119.222774) (xy 286.754824 -119.567198)
			(xy 298.799504 -119.567198) (xy 298.799504 -118.703598) (xy 298.799994 -118.67363) (xy 298.807817 -118.614208)
			(xy 298.82333 -118.556315) (xy 298.846266 -118.500942) (xy 298.876233 -118.449036) (xy 298.91272 -118.401486)
			(xy 298.9551 -118.359106) (xy 299.00265 -118.322619) (xy 299.054556 -118.292652) (xy 299.109929 -118.269716)
			(xy 299.167822 -118.254203) (xy 299.227244 -118.24638) (xy 299.28718 -118.24638) (xy 299.346602 -118.254203)
			(xy 299.404495 -118.269716) (xy 299.459868 -118.292652) (xy 299.511774 -118.322619) (xy 299.559324 -118.359106)
			(xy 299.601704 -118.401486) (xy 299.638191 -118.449036) (xy 299.668158 -118.500942) (xy 299.691094 -118.556315)
			(xy 299.706607 -118.614208) (xy 299.71443 -118.67363) (xy 299.71492 -118.703598) (xy 299.71492 -119.567198)
			(xy 299.71443 -119.597166) (xy 299.709046 -119.638064) (xy 300.247304 -119.638064) (xy 300.247304 -118.631716)
			(xy 300.247729 -118.621594) (xy 300.255473 -118.60289) (xy 300.269787 -118.588575) (xy 300.28849 -118.58083)
			(xy 300.298612 -118.580408) (xy 301.479712 -118.580408) (xy 301.489836 -118.580806) (xy 301.508542 -118.58856)
			(xy 301.522856 -118.602882) (xy 301.530599 -118.621591) (xy 301.53102 -118.631716) (xy 301.53102 -119.638064)
			(xy 304.783744 -119.638064) (xy 304.783744 -118.631716) (xy 304.784233 -118.62157) (xy 304.792013 -118.602829)
			(xy 304.806388 -118.588507) (xy 304.825158 -118.580796) (xy 304.835306 -118.580408) (xy 306.016406 -118.580408)
			(xy 306.026529 -118.580921) (xy 306.045244 -118.588645) (xy 306.059599 -118.602922) (xy 306.067424 -118.621596)
			(xy 306.067968 -118.631716) (xy 306.067968 -119.638064) (xy 306.067548 -119.64822) (xy 306.059758 -119.666977)
			(xy 306.04536 -119.681303) (xy 306.026564 -119.688998) (xy 306.016406 -119.689372) (xy 304.835306 -119.689372)
			(xy 304.825181 -119.688869) (xy 304.806462 -119.681145) (xy 304.792106 -119.666864) (xy 304.784285 -119.648186)
			(xy 304.783744 -119.638064) (xy 301.53102 -119.638064) (xy 301.530555 -119.648182) (xy 301.522822 -119.666881)
			(xy 301.508521 -119.681195) (xy 301.489829 -119.688945) (xy 301.479712 -119.689372) (xy 300.298612 -119.689372)
			(xy 300.288487 -119.688974) (xy 300.269778 -119.681224) (xy 300.255462 -119.666902) (xy 300.247722 -119.648189)
			(xy 300.247304 -119.638064) (xy 299.709046 -119.638064) (xy 299.706607 -119.656588) (xy 299.691094 -119.714481)
			(xy 299.68687 -119.724678) (xy 311.799224 -119.724678) (xy 311.799224 -119.497094) (xy 311.799478 -119.49303)
			(xy 311.799732 -119.49049) (xy 311.799732 -119.481854) (xy 311.80532 -119.473218) (xy 311.80659 -119.471186)
			(xy 311.807606 -119.469154) (xy 312.004964 -119.168164) (xy 312.008822 -119.16183) (xy 312.013088 -119.147635)
			(xy 312.013346 -119.140224) (xy 312.013346 -119.11457) (xy 312.013131 -119.107237) (xy 312.009008 -119.093165)
			(xy 312.005218 -119.086884) (xy 311.807352 -118.783862) (xy 311.805066 -118.780052) (xy 311.804812 -118.779544)
			(xy 311.803796 -118.777766) (xy 311.799732 -118.771162) (xy 311.799732 -118.763034) (xy 311.799478 -118.760494)
			(xy 311.799224 -118.75643) (xy 311.799224 -118.528338) (xy 311.799695 -118.518171) (xy 311.807465 -118.499379)
			(xy 311.821836 -118.484994) (xy 311.840619 -118.477205) (xy 311.850786 -118.476776) (xy 312.58764 -118.476776)
			(xy 312.597818 -118.477242) (xy 312.616631 -118.485019) (xy 312.631056 -118.499383) (xy 312.638914 -118.518162)
			(xy 312.639456 -118.528338) (xy 312.639456 -118.755922) (xy 312.639202 -118.759986) (xy 312.638948 -118.762526)
			(xy 312.638948 -118.771162) (xy 312.633106 -118.78056) (xy 312.632344 -118.78183) (xy 312.631074 -118.783862)
			(xy 312.425334 -119.098568) (xy 312.420277 -119.107086) (xy 312.416464 -119.126507) (xy 312.420282 -119.145926)
			(xy 312.425334 -119.154448) (xy 312.631074 -119.467884) (xy 312.63209 -119.469916) (xy 312.63336 -119.471948)
			(xy 312.638948 -119.480584) (xy 312.638948 -119.48922) (xy 312.639202 -119.49176) (xy 312.639456 -119.495824)
			(xy 312.639456 -119.559324) (xy 313.274456 -119.559324) (xy 313.274456 -118.695724) (xy 313.274946 -118.665756)
			(xy 313.282769 -118.606334) (xy 313.298282 -118.548441) (xy 313.321218 -118.493068) (xy 313.351185 -118.441162)
			(xy 313.387672 -118.393612) (xy 313.430052 -118.351232) (xy 313.477602 -118.314745) (xy 313.529508 -118.284778)
			(xy 313.584881 -118.261842) (xy 313.642774 -118.246329) (xy 313.702196 -118.238506) (xy 313.762132 -118.238506)
			(xy 313.821554 -118.246329) (xy 313.879447 -118.261842) (xy 313.93482 -118.284778) (xy 313.986726 -118.314745)
			(xy 314.034276 -118.351232) (xy 314.076656 -118.393612) (xy 314.113143 -118.441162) (xy 314.14311 -118.493068)
			(xy 314.166046 -118.548441) (xy 314.181559 -118.606334) (xy 314.189382 -118.665756) (xy 314.189872 -118.695724)
			(xy 314.189872 -119.559324) (xy 314.189382 -119.589292) (xy 314.181559 -119.648714) (xy 314.166046 -119.706607)
			(xy 314.14311 -119.76198) (xy 314.113143 -119.813886) (xy 314.076656 -119.861436) (xy 314.034276 -119.903816)
			(xy 313.986726 -119.940303) (xy 313.93482 -119.97027) (xy 313.879447 -119.993206) (xy 313.821554 -120.008719)
			(xy 313.762132 -120.016542) (xy 313.702196 -120.016542) (xy 313.642774 -120.008719) (xy 313.584881 -119.993206)
			(xy 313.529508 -119.97027) (xy 313.477602 -119.940303) (xy 313.430052 -119.903816) (xy 313.387672 -119.861436)
			(xy 313.351185 -119.813886) (xy 313.321218 -119.76198) (xy 313.298282 -119.706607) (xy 313.282769 -119.648714)
			(xy 313.274946 -119.589292) (xy 313.274456 -119.559324) (xy 312.639456 -119.559324) (xy 312.639456 -119.724678)
			(xy 312.639018 -119.734849) (xy 312.631239 -119.753644) (xy 312.616858 -119.76803) (xy 312.598065 -119.775815)
			(xy 312.587894 -119.77624) (xy 311.85104 -119.77624) (xy 311.840869 -119.775693) (xy 311.822061 -119.767945)
			(xy 311.807634 -119.753606) (xy 311.79977 -119.734846) (xy 311.799224 -119.724678) (xy 299.68687 -119.724678)
			(xy 299.668158 -119.769854) (xy 299.638191 -119.82176) (xy 299.601704 -119.86931) (xy 299.559324 -119.91169)
			(xy 299.511774 -119.948177) (xy 299.459868 -119.978144) (xy 299.404495 -120.00108) (xy 299.346602 -120.016593)
			(xy 299.28718 -120.024416) (xy 299.227244 -120.024416) (xy 299.167822 -120.016593) (xy 299.109929 -120.00108)
			(xy 299.054556 -119.978144) (xy 299.00265 -119.948177) (xy 298.9551 -119.91169) (xy 298.91272 -119.86931)
			(xy 298.876233 -119.82176) (xy 298.846266 -119.769854) (xy 298.82333 -119.714481) (xy 298.807817 -119.656588)
			(xy 298.799994 -119.597166) (xy 298.799504 -119.567198) (xy 286.754824 -119.567198) (xy 286.754824 -120.086374)
			(xy 286.754334 -120.116358) (xy 286.746506 -120.175814) (xy 286.730985 -120.233739) (xy 286.708036 -120.289143)
			(xy 286.678052 -120.341077) (xy 286.641546 -120.388653) (xy 286.599141 -120.431058) (xy 286.551565 -120.467564)
			(xy 286.499631 -120.497548) (xy 286.444227 -120.520497) (xy 286.386302 -120.536018) (xy 286.326846 -120.543846)
			(xy 286.266878 -120.543846) (xy 286.207422 -120.536018) (xy 286.149497 -120.520497) (xy 286.094093 -120.497548)
			(xy 286.042159 -120.467564) (xy 285.994583 -120.431058) (xy 285.952178 -120.388653) (xy 285.915672 -120.341077)
			(xy 285.885688 -120.289143) (xy 285.862739 -120.233739) (xy 285.847218 -120.175814) (xy 285.83939 -120.116358)
			(xy 285.8389 -120.086374) (xy 283.452824 -120.086374) (xy 283.452824 -120.158256) (xy 283.452348 -120.168373)
			(xy 283.444619 -120.187071) (xy 283.430321 -120.201386) (xy 283.411632 -120.209137) (xy 283.401516 -120.209564)
			(xy 282.220162 -120.209564) (xy 282.210033 -120.209105) (xy 282.191312 -120.201365) (xy 282.176957 -120.187071)
			(xy 282.169139 -120.168382) (xy 282.1686 -120.158256) (xy 278.915876 -120.158256) (xy 278.915447 -120.168379)
			(xy 278.907709 -120.187086) (xy 278.893396 -120.201402) (xy 278.87469 -120.209145) (xy 278.864568 -120.209564)
			(xy 277.683468 -120.209564) (xy 277.673339 -120.209209) (xy 277.654628 -120.201444) (xy 277.640313 -120.187108)
			(xy 277.632576 -120.168386) (xy 277.63216 -120.158256) (xy 269.258288 -120.158256) (xy 269.258288 -120.253252)
			(xy 269.257662 -120.264805) (xy 269.247692 -120.285654) (xy 269.229746 -120.300214) (xy 269.218664 -120.303544)
			(xy 269.206726 -120.305068) (xy 268.470126 -120.305068) (xy 268.459368 -120.30455) (xy 268.439679 -120.295883)
			(xy 268.432026 -120.288304) (xy 268.42581 -120.280918) (xy 268.418906 -120.262901) (xy 268.418564 -120.253252)
			(xy 267.752274 -120.253252) (xy 267.736776 -120.290667) (xy 267.706792 -120.342601) (xy 267.670286 -120.390177)
			(xy 267.627881 -120.432582) (xy 267.580305 -120.469088) (xy 267.528371 -120.499072) (xy 267.472967 -120.522021)
			(xy 267.415042 -120.537542) (xy 267.355586 -120.54537) (xy 267.295618 -120.54537) (xy 267.236162 -120.537542)
			(xy 267.178237 -120.522021) (xy 267.122833 -120.499072) (xy 267.070899 -120.469088) (xy 267.023323 -120.432582)
			(xy 266.980918 -120.390177) (xy 266.944412 -120.342601) (xy 266.914428 -120.290667) (xy 266.891479 -120.235263)
			(xy 266.875958 -120.177338) (xy 266.86813 -120.117882) (xy 266.86764 -120.087898) (xy 200.469049 -120.087898)
			(xy 200.477084 -120.091226) (xy 200.52899 -120.121193) (xy 200.57654 -120.15768) (xy 200.61892 -120.20006)
			(xy 200.655407 -120.24761) (xy 200.685374 -120.299516) (xy 200.70831 -120.354889) (xy 200.723823 -120.412782)
			(xy 200.731646 -120.472204) (xy 200.732136 -120.502172) (xy 200.732136 -121.365772) (xy 200.731646 -121.39574)
			(xy 200.723823 -121.455162) (xy 200.70831 -121.513055) (xy 200.685374 -121.568428) (xy 200.655407 -121.620334)
			(xy 200.61892 -121.667884) (xy 200.57654 -121.710264) (xy 200.52899 -121.746751) (xy 200.477084 -121.776718)
			(xy 200.421711 -121.799654) (xy 200.363818 -121.815167) (xy 200.304396 -121.82299) (xy 200.24446 -121.82299)
			(xy 200.185038 -121.815167) (xy 200.127145 -121.799654) (xy 200.071772 -121.776718) (xy 200.019866 -121.746751)
			(xy 199.972316 -121.710264) (xy 199.929936 -121.667884) (xy 199.893449 -121.620334) (xy 199.863482 -121.568428)
			(xy 199.840546 -121.513055) (xy 199.825033 -121.455162) (xy 199.81721 -121.39574) (xy 199.81672 -121.365772)
			(xy 199.181212 -121.365772) (xy 199.181212 -121.531126) (xy 199.180856 -121.541306) (xy 199.173054 -121.56011)
			(xy 199.158647 -121.574496) (xy 199.13983 -121.582271) (xy 199.12965 -121.582688) (xy 198.39305 -121.582688)
			(xy 198.382885 -121.582196) (xy 198.364096 -121.574432) (xy 198.34971 -121.560068) (xy 198.341919 -121.541291)
			(xy 198.341488 -121.531126) (xy 181.730196 -121.531126) (xy 181.714114 -121.569952) (xy 181.684147 -121.621858)
			(xy 181.64766 -121.669408) (xy 181.60528 -121.711788) (xy 181.55773 -121.748275) (xy 181.505824 -121.778242)
			(xy 181.450451 -121.801178) (xy 181.392558 -121.816691) (xy 181.333136 -121.824514) (xy 181.2732 -121.824514)
			(xy 181.213778 -121.816691) (xy 181.155885 -121.801178) (xy 181.100512 -121.778242) (xy 181.048606 -121.748275)
			(xy 181.001056 -121.711788) (xy 180.958676 -121.669408) (xy 180.922189 -121.621858) (xy 180.892222 -121.569952)
			(xy 180.869286 -121.514579) (xy 180.853773 -121.456686) (xy 180.84595 -121.397264) (xy 180.84546 -121.367296)
			(xy 168.80078 -121.367296) (xy 168.80078 -121.886472) (xy 168.80029 -121.916456) (xy 168.792462 -121.975912)
			(xy 168.776941 -122.033837) (xy 168.753992 -122.089241) (xy 168.724008 -122.141175) (xy 168.687502 -122.188751)
			(xy 168.645097 -122.231156) (xy 168.597521 -122.267662) (xy 168.545587 -122.297646) (xy 168.490183 -122.320595)
			(xy 168.432258 -122.336116) (xy 168.372802 -122.343944) (xy 168.312834 -122.343944) (xy 168.253378 -122.336116)
			(xy 168.195453 -122.320595) (xy 168.140049 -122.297646) (xy 168.088115 -122.267662) (xy 168.040539 -122.231156)
			(xy 167.998134 -122.188751) (xy 167.961628 -122.141175) (xy 167.931644 -122.089241) (xy 167.908695 -122.033837)
			(xy 167.893174 -121.975912) (xy 167.885346 -121.916456) (xy 167.884856 -121.886472) (xy 167.352472 -121.886472)
			(xy 167.352472 -121.958354) (xy 167.351936 -121.968476) (xy 167.344226 -121.987194) (xy 167.329954 -122.001552)
			(xy 167.311283 -122.009374) (xy 167.301164 -122.009916) (xy 166.120064 -122.009916) (xy 166.109955 -122.009445)
			(xy 166.091279 -122.001698) (xy 166.076986 -121.987398) (xy 166.06925 -121.968717) (xy 166.068756 -121.958608)
			(xy 162.816021 -121.958608) (xy 162.815598 -121.968526) (xy 162.807822 -121.987326) (xy 162.793439 -122.001713)
			(xy 162.774642 -122.009495) (xy 162.76447 -122.009916) (xy 161.58337 -122.009916) (xy 161.573191 -122.00956)
			(xy 161.554386 -122.001756) (xy 161.540001 -121.98735) (xy 161.532225 -121.968534) (xy 161.531808 -121.958354)
			(xy 155.800552 -121.958354) (xy 155.800552 -122.0597) (xy 155.800019 -122.069903) (xy 155.792213 -122.088758)
			(xy 155.777788 -122.103193) (xy 155.758939 -122.111012) (xy 155.748736 -122.111516) (xy 155.012136 -122.111516)
			(xy 155.001917 -122.111059) (xy 154.98303 -122.103247) (xy 154.968573 -122.0888) (xy 154.960748 -122.069919)
			(xy 154.96032 -122.0597) (xy 154.294538 -122.0597) (xy 154.27904 -122.097115) (xy 154.249056 -122.149049)
			(xy 154.21255 -122.196625) (xy 154.170145 -122.23903) (xy 154.122569 -122.275536) (xy 154.070635 -122.30552)
			(xy 154.015231 -122.328469) (xy 153.957306 -122.34399) (xy 153.89785 -122.351818) (xy 153.837882 -122.351818)
			(xy 153.778426 -122.34399) (xy 153.720501 -122.328469) (xy 153.665097 -122.30552) (xy 153.613163 -122.275536)
			(xy 153.565587 -122.23903) (xy 153.523182 -122.196625) (xy 153.486676 -122.149049) (xy 153.456692 -122.097115)
			(xy 153.433743 -122.041711) (xy 153.418222 -121.983786) (xy 153.410394 -121.92433) (xy 153.409904 -121.894346)
			(xy 81.752059 -121.894346) (xy 81.786925 -121.914476) (xy 81.834501 -121.950982) (xy 81.876906 -121.993387)
			(xy 81.913412 -122.040963) (xy 81.943396 -122.092897) (xy 81.966345 -122.148301) (xy 81.981866 -122.206226)
			(xy 81.989694 -122.265682) (xy 81.990184 -122.295666) (xy 81.990184 -123.159266) (xy 81.989694 -123.18925)
			(xy 81.981866 -123.248706) (xy 81.966345 -123.306631) (xy 81.943396 -123.362035) (xy 81.913412 -123.413969)
			(xy 81.876906 -123.461545) (xy 81.834501 -123.50395) (xy 81.786925 -123.540456) (xy 81.734991 -123.57044)
			(xy 81.679587 -123.593389) (xy 81.621662 -123.60891) (xy 81.562206 -123.616738) (xy 81.502238 -123.616738)
			(xy 81.442782 -123.60891) (xy 81.384857 -123.593389) (xy 81.329453 -123.57044) (xy 81.277519 -123.540456)
			(xy 81.229943 -123.50395) (xy 81.187538 -123.461545) (xy 81.151032 -123.413969) (xy 81.121048 -123.362035)
			(xy 81.098099 -123.306631) (xy 81.082578 -123.248706) (xy 81.07475 -123.18925) (xy 81.07426 -123.159266)
			(xy 80.43926 -123.159266) (xy 80.43926 -123.32462) (xy 80.43863 -123.336174) (xy 80.428666 -123.357025)
			(xy 80.410719 -123.371585) (xy 80.399636 -123.374912) (xy 80.387698 -123.376436) (xy 79.651098 -123.376436)
			(xy 79.640337 -123.375943) (xy 79.620647 -123.367259) (xy 79.612998 -123.359672) (xy 79.606808 -123.352267)
			(xy 79.59989 -123.334264) (xy 79.599536 -123.32462) (xy 67.487203 -123.32462) (xy 67.468444 -123.369909)
			(xy 67.43846 -123.421843) (xy 67.401954 -123.469419) (xy 67.359549 -123.511824) (xy 67.311973 -123.54833)
			(xy 67.260039 -123.578314) (xy 67.204635 -123.601263) (xy 67.14671 -123.616784) (xy 67.087254 -123.624612)
			(xy 67.027286 -123.624612) (xy 66.96783 -123.616784) (xy 66.909905 -123.601263) (xy 66.854501 -123.578314)
			(xy 66.802567 -123.54833) (xy 66.754991 -123.511824) (xy 66.712586 -123.469419) (xy 66.67608 -123.421843)
			(xy 66.646096 -123.369909) (xy 66.623147 -123.314505) (xy 66.607626 -123.25658) (xy 66.599798 -123.197124)
			(xy 66.599308 -123.16714) (xy 54.554628 -123.16714) (xy 54.554628 -123.686316) (xy 54.554138 -123.716284)
			(xy 54.546315 -123.775706) (xy 54.530802 -123.833599) (xy 54.507866 -123.888972) (xy 54.477899 -123.940878)
			(xy 54.441412 -123.988428) (xy 54.399032 -124.030808) (xy 54.351482 -124.067295) (xy 54.299576 -124.097262)
			(xy 54.244203 -124.120198) (xy 54.18631 -124.135711) (xy 54.126888 -124.143534) (xy 54.066952 -124.143534)
			(xy 54.00753 -124.135711) (xy 53.949637 -124.120198) (xy 53.894264 -124.097262) (xy 53.842358 -124.067295)
			(xy 53.794808 -124.030808) (xy 53.752428 -123.988428) (xy 53.715941 -123.940878) (xy 53.685974 -123.888972)
			(xy 53.663038 -123.833599) (xy 53.647525 -123.775706) (xy 53.639702 -123.716284) (xy 53.639212 -123.686316)
			(xy 51.252628 -123.686316) (xy 51.252628 -123.758452) (xy 51.252145 -123.768568) (xy 51.244418 -123.787265)
			(xy 51.230122 -123.80158) (xy 51.211435 -123.809332) (xy 51.20132 -123.80976) (xy 50.02022 -123.80976)
			(xy 50.010094 -123.809367) (xy 49.991383 -123.801618) (xy 49.977067 -123.787294) (xy 49.969328 -123.768578)
			(xy 49.968912 -123.758452) (xy 46.716188 -123.758452) (xy 46.715739 -123.768604) (xy 46.707957 -123.787358)
			(xy 46.693568 -123.801684) (xy 46.67478 -123.809383) (xy 46.664626 -123.80976) (xy 45.483526 -123.80976)
			(xy 45.473401 -123.809252) (xy 45.45468 -123.801533) (xy 45.440323 -123.787253) (xy 45.432503 -123.768574)
			(xy 45.431964 -123.758452) (xy 37.0586 -123.758452) (xy 37.0586 -123.853194) (xy 37.058063 -123.863347)
			(xy 37.050297 -123.882108) (xy 37.035945 -123.896473) (xy 37.01719 -123.904254) (xy 37.007038 -123.904756)
			(xy 36.270184 -123.904756) (xy 36.260011 -123.904239) (xy 36.241205 -123.896476) (xy 36.226781 -123.882128)
			(xy 36.218916 -123.863364) (xy 36.218368 -123.853194) (xy 35.552057 -123.853194) (xy 35.536606 -123.890496)
			(xy 35.506639 -123.942402) (xy 35.470152 -123.989952) (xy 35.427772 -124.032332) (xy 35.380222 -124.068819)
			(xy 35.328316 -124.098786) (xy 35.272943 -124.121722) (xy 35.21505 -124.137235) (xy 35.155628 -124.145058)
			(xy 35.095692 -124.145058) (xy 35.03627 -124.137235) (xy 34.978377 -124.121722) (xy 34.923004 -124.098786)
			(xy 34.871098 -124.068819) (xy 34.823548 -124.032332) (xy 34.781168 -123.989952) (xy 34.744681 -123.942402)
			(xy 34.714714 -123.890496) (xy 34.691778 -123.835123) (xy 34.676265 -123.77723) (xy 34.668442 -123.717808)
			(xy 34.667952 -123.68784) (xy 4.30911 -123.68784) (xy 4.30911 -125.494542) (xy 37.31006 -125.494542)
			(xy 37.31006 -124.630942) (xy 37.31055 -124.600974) (xy 37.318373 -124.541552) (xy 37.333886 -124.483659)
			(xy 37.356822 -124.428286) (xy 37.386789 -124.37638) (xy 37.423276 -124.32883) (xy 37.465656 -124.28645)
			(xy 37.513206 -124.249963) (xy 37.565112 -124.219996) (xy 37.620485 -124.19706) (xy 37.678378 -124.181547)
			(xy 37.7378 -124.173724) (xy 37.797736 -124.173724) (xy 37.857158 -124.181547) (xy 37.915051 -124.19706)
			(xy 37.970424 -124.219996) (xy 38.02233 -124.249963) (xy 38.06988 -124.28645) (xy 38.11226 -124.32883)
			(xy 38.148747 -124.37638) (xy 38.178714 -124.428286) (xy 38.20165 -124.483659) (xy 38.217163 -124.541552)
			(xy 38.224986 -124.600974) (xy 38.225476 -124.630942) (xy 38.225476 -125.494542) (xy 38.224986 -125.52451)
			(xy 38.217163 -125.583932) (xy 38.20165 -125.641825) (xy 38.194165 -125.659896) (xy 38.860476 -125.659896)
			(xy 38.860476 -125.432312) (xy 38.86073 -125.428248) (xy 38.860984 -125.425708) (xy 38.860984 -125.417072)
			(xy 38.866572 -125.408436) (xy 38.867842 -125.406404) (xy 38.868858 -125.404372) (xy 39.066216 -125.103382)
			(xy 39.0701 -125.097063) (xy 39.074351 -125.082856) (xy 39.074598 -125.075442) (xy 39.074598 -125.049788)
			(xy 39.074368 -125.042456) (xy 39.070254 -125.028385) (xy 39.06647 -125.022102) (xy 38.868604 -124.71908)
			(xy 38.866318 -124.71527) (xy 38.866064 -124.714762) (xy 38.865048 -124.712984) (xy 38.860984 -124.70638)
			(xy 38.860984 -124.698252) (xy 38.86073 -124.695712) (xy 38.860476 -124.691648) (xy 38.860476 -124.463556)
			(xy 38.860946 -124.453346) (xy 38.868771 -124.434485) (xy 38.883216 -124.420051) (xy 38.902082 -124.412239)
			(xy 38.912292 -124.41174) (xy 39.648892 -124.41174) (xy 39.659094 -124.412287) (xy 39.677947 -124.420089)
			(xy 39.692382 -124.434509) (xy 39.700202 -124.453355) (xy 39.700708 -124.463556) (xy 39.700708 -124.69114)
			(xy 39.700454 -124.695204) (xy 39.7002 -124.697744) (xy 39.7002 -124.70638) (xy 39.694358 -124.715778)
			(xy 39.693596 -124.717048) (xy 39.692326 -124.71908) (xy 39.486586 -125.033786) (xy 39.48151 -125.042295)
			(xy 39.477699 -125.061722) (xy 39.481527 -125.081145) (xy 39.486586 -125.089666) (xy 39.692326 -125.403102)
			(xy 39.693342 -125.405134) (xy 39.694612 -125.407166) (xy 39.7002 -125.415802) (xy 39.7002 -125.424438)
			(xy 39.700454 -125.426978) (xy 39.700708 -125.431042) (xy 39.700708 -125.558296) (xy 45.431964 -125.558296)
			(xy 45.431964 -124.551948) (xy 45.43246 -124.541801) (xy 45.440233 -124.523057) (xy 45.454607 -124.508733)
			(xy 45.473378 -124.501025) (xy 45.483526 -124.50064) (xy 46.664626 -124.50064) (xy 46.674754 -124.501105)
			(xy 46.693476 -124.508841) (xy 46.707832 -124.523134) (xy 46.71565 -124.541822) (xy 46.716188 -124.551948)
			(xy 46.716188 -125.558296) (xy 49.968912 -125.558296) (xy 49.968912 -124.551948) (xy 49.969356 -124.541827)
			(xy 49.97709 -124.523122) (xy 49.991399 -124.508806) (xy 50.010099 -124.501061) (xy 50.02022 -124.50064)
			(xy 51.20132 -124.50064) (xy 51.211449 -124.501) (xy 51.230161 -124.508763) (xy 51.244476 -124.523097)
			(xy 51.252213 -124.541819) (xy 51.252628 -124.551948) (xy 51.252628 -125.486414) (xy 51.785012 -125.486414)
			(xy 51.785012 -124.622814) (xy 51.785502 -124.592846) (xy 51.793325 -124.533424) (xy 51.808838 -124.475531)
			(xy 51.831774 -124.420158) (xy 51.861741 -124.368252) (xy 51.898228 -124.320702) (xy 51.940608 -124.278322)
			(xy 51.988158 -124.241835) (xy 52.040064 -124.211868) (xy 52.095437 -124.188932) (xy 52.15333 -124.173419)
			(xy 52.212752 -124.165596) (xy 52.272688 -124.165596) (xy 52.33211 -124.173419) (xy 52.390003 -124.188932)
			(xy 52.445376 -124.211868) (xy 52.497282 -124.241835) (xy 52.544832 -124.278322) (xy 52.587212 -124.320702)
			(xy 52.623699 -124.368252) (xy 52.653666 -124.420158) (xy 52.676602 -124.475531) (xy 52.692115 -124.533424)
			(xy 52.699938 -124.592846) (xy 52.700428 -124.622814) (xy 52.700428 -124.967238) (xy 64.745108 -124.967238)
			(xy 64.745108 -124.103638) (xy 64.745598 -124.073654) (xy 64.753426 -124.014198) (xy 64.768947 -123.956273)
			(xy 64.791896 -123.900869) (xy 64.82188 -123.848935) (xy 64.858386 -123.801359) (xy 64.900791 -123.758954)
			(xy 64.948367 -123.722448) (xy 65.000301 -123.692464) (xy 65.055705 -123.669515) (xy 65.11363 -123.653994)
			(xy 65.173086 -123.646166) (xy 65.233054 -123.646166) (xy 65.29251 -123.653994) (xy 65.350435 -123.669515)
			(xy 65.405839 -123.692464) (xy 65.457773 -123.722448) (xy 65.505349 -123.758954) (xy 65.547754 -123.801359)
			(xy 65.58426 -123.848935) (xy 65.614244 -123.900869) (xy 65.637193 -123.956273) (xy 65.652714 -124.014198)
			(xy 65.660542 -124.073654) (xy 65.661032 -124.103638) (xy 65.661032 -124.967238) (xy 65.660542 -124.997222)
			(xy 65.655159 -125.038104) (xy 68.047108 -125.038104) (xy 68.047108 -124.031756) (xy 68.047549 -124.021643)
			(xy 68.055303 -124.002963) (xy 68.069613 -123.988669) (xy 68.088303 -123.980938) (xy 68.098416 -123.980448)
			(xy 69.27977 -123.980448) (xy 69.289896 -123.980951) (xy 69.308618 -123.988671) (xy 69.322976 -124.002952)
			(xy 69.330794 -124.021633) (xy 69.331332 -124.031756) (xy 69.331332 -125.038104) (xy 72.584056 -125.038104)
			(xy 72.584056 -124.031756) (xy 72.584548 -124.02165) (xy 72.592292 -124.002979) (xy 72.606586 -123.988687)
			(xy 72.625258 -123.980946) (xy 72.635364 -123.980448) (xy 73.816464 -123.980448) (xy 73.826564 -123.981014)
			(xy 73.845231 -123.98873) (xy 73.859526 -124.003001) (xy 73.867271 -124.021657) (xy 73.867772 -124.031756)
			(xy 73.867772 -125.038104) (xy 73.867386 -125.04823) (xy 73.859632 -125.066939) (xy 73.845306 -125.081254)
			(xy 73.826591 -125.088994) (xy 73.816464 -125.089412) (xy 72.635364 -125.089412) (xy 72.625254 -125.088945)
			(xy 72.606578 -125.081197) (xy 72.592285 -125.066895) (xy 72.584549 -125.048214) (xy 72.584056 -125.038104)
			(xy 69.331332 -125.038104) (xy 69.330819 -125.048209) (xy 69.323086 -125.066881) (xy 69.308798 -125.081175)
			(xy 69.290129 -125.088915) (xy 69.280024 -125.089412) (xy 68.09867 -125.089412) (xy 68.088548 -125.0889)
			(xy 68.069836 -125.081172) (xy 68.055482 -125.066894) (xy 68.047655 -125.048223) (xy 68.047108 -125.038104)
			(xy 65.655159 -125.038104) (xy 65.652714 -125.056678) (xy 65.637193 -125.114603) (xy 65.630373 -125.131068)
			(xy 82.241644 -125.131068) (xy 82.241644 -124.888244) (xy 82.360516 -124.706888) (xy 82.423 -124.611384)
			(xy 82.44713 -124.574554) (xy 82.450989 -124.568221) (xy 82.455255 -124.554025) (xy 82.455512 -124.546614)
			(xy 82.455512 -124.520706) (xy 82.455323 -124.514556) (xy 82.452367 -124.502615) (xy 82.44967 -124.497084)
			(xy 82.336132 -124.323094) (xy 82.316066 -124.292106) (xy 82.310478 -124.28347) (xy 82.250026 -124.19076)
			(xy 82.249518 -124.189998) (xy 82.24901 -124.189236) (xy 82.248756 -124.188728) (xy 82.248248 -124.187966)
			(xy 82.241644 -124.177552) (xy 82.241644 -123.934728) (xy 82.242232 -123.92317) (xy 82.252216 -123.902317)
			(xy 82.270179 -123.88776) (xy 82.281268 -123.884436) (xy 82.293206 -123.882912) (xy 83.029806 -123.882912)
			(xy 83.040565 -123.883418) (xy 83.060254 -123.892094) (xy 83.067906 -123.899676) (xy 83.074117 -123.907066)
			(xy 83.081022 -123.92508) (xy 83.081368 -123.934728) (xy 83.081368 -124.177552) (xy 82.865468 -124.508006)
			(xy 82.861424 -124.516217) (xy 82.858891 -124.534334) (xy 82.862844 -124.552194) (xy 82.8675 -124.560076)
			(xy 82.899758 -124.60986) (xy 83.081368 -124.886974) (xy 83.081368 -124.965714) (xy 83.716368 -124.965714)
			(xy 83.716368 -124.102114) (xy 83.716858 -124.07213) (xy 83.724686 -124.012674) (xy 83.740207 -123.954749)
			(xy 83.763156 -123.899345) (xy 83.79314 -123.847411) (xy 83.829646 -123.799835) (xy 83.872051 -123.75743)
			(xy 83.919627 -123.720924) (xy 83.971561 -123.69094) (xy 84.026965 -123.667991) (xy 84.08489 -123.65247)
			(xy 84.144346 -123.644642) (xy 84.204314 -123.644642) (xy 84.26377 -123.65247) (xy 84.321695 -123.667991)
			(xy 84.369615 -123.68784) (xy 150.767796 -123.68784) (xy 150.767796 -122.82424) (xy 150.768286 -122.794256)
			(xy 150.776114 -122.7348) (xy 150.791635 -122.676875) (xy 150.814584 -122.621471) (xy 150.844568 -122.569537)
			(xy 150.881074 -122.521961) (xy 150.923479 -122.479556) (xy 150.971055 -122.44305) (xy 151.022989 -122.413066)
			(xy 151.078393 -122.390117) (xy 151.136318 -122.374596) (xy 151.195774 -122.366768) (xy 151.255742 -122.366768)
			(xy 151.315198 -122.374596) (xy 151.373123 -122.390117) (xy 151.428527 -122.413066) (xy 151.480461 -122.44305)
			(xy 151.528037 -122.479556) (xy 151.570442 -122.521961) (xy 151.606948 -122.569537) (xy 151.636932 -122.621471)
			(xy 151.659881 -122.676875) (xy 151.675402 -122.7348) (xy 151.68323 -122.794256) (xy 151.68372 -122.82424)
			(xy 151.68372 -123.68784) (xy 151.68323 -123.717824) (xy 151.675402 -123.77728) (xy 151.659881 -123.835205)
			(xy 151.65243 -123.853194) (xy 152.318212 -123.853194) (xy 152.318212 -123.62561) (xy 152.318466 -123.621546)
			(xy 152.31872 -123.619006) (xy 152.31872 -123.61037) (xy 152.324308 -123.601734) (xy 152.325578 -123.599702)
			(xy 152.326594 -123.59767) (xy 152.523952 -123.29668) (xy 152.52784 -123.290363) (xy 152.532088 -123.276155)
			(xy 152.532334 -123.26874) (xy 152.532334 -123.243086) (xy 152.532114 -123.235753) (xy 152.527994 -123.221682)
			(xy 152.524206 -123.2154) (xy 152.32634 -122.912378) (xy 152.324054 -122.908568) (xy 152.3238 -122.90806)
			(xy 152.322784 -122.906282) (xy 152.31872 -122.899678) (xy 152.31872 -122.89155) (xy 152.318466 -122.88901)
			(xy 152.318212 -122.884946) (xy 152.318212 -122.656854) (xy 152.318695 -122.646697) (xy 152.32648 -122.627931)
			(xy 152.340848 -122.613569) (xy 152.359616 -122.605791) (xy 152.369774 -122.605292) (xy 153.106628 -122.605292)
			(xy 153.116807 -122.605752) (xy 153.135623 -122.613529) (xy 153.150049 -122.627894) (xy 153.157905 -122.646677)
			(xy 153.158444 -122.656854) (xy 153.158444 -122.884438) (xy 153.15819 -122.888502) (xy 153.157936 -122.891042)
			(xy 153.157936 -122.899678) (xy 153.152094 -122.909076) (xy 153.151332 -122.910346) (xy 153.150062 -122.912378)
			(xy 152.944322 -123.227084) (xy 152.939245 -123.235593) (xy 152.93543 -123.25502) (xy 152.93926 -123.274444)
			(xy 152.944322 -123.282964) (xy 153.150062 -123.5964) (xy 153.151078 -123.598432) (xy 153.152348 -123.600464)
			(xy 153.157936 -123.6091) (xy 153.157936 -123.617736) (xy 153.15819 -123.620276) (xy 153.158444 -123.62434)
			(xy 153.158444 -123.758452) (xy 161.531808 -123.758452) (xy 161.531808 -122.752104) (xy 161.532225 -122.741949)
			(xy 161.540021 -122.723195) (xy 161.554419 -122.708872) (xy 161.573213 -122.701173) (xy 161.58337 -122.700796)
			(xy 162.76447 -122.700796) (xy 162.774589 -122.70135) (xy 162.793302 -122.709059) (xy 162.807657 -122.723325)
			(xy 162.815486 -122.741988) (xy 162.816032 -122.752104) (xy 162.816032 -123.758452) (xy 166.068756 -123.758452)
			(xy 166.068756 -122.752104) (xy 166.069287 -122.742001) (xy 166.077015 -122.723331) (xy 166.091298 -122.709038)
			(xy 166.109961 -122.701295) (xy 166.120064 -122.700796) (xy 167.301164 -122.700796) (xy 167.311284 -122.701246)
			(xy 167.329986 -122.708981) (xy 167.344301 -122.723287) (xy 167.352048 -122.741985) (xy 167.352472 -122.752104)
			(xy 167.352472 -123.686316) (xy 169.739056 -123.686316) (xy 169.739056 -122.822716) (xy 169.739546 -122.792732)
			(xy 169.747374 -122.733276) (xy 169.762895 -122.675351) (xy 169.785844 -122.619947) (xy 169.815828 -122.568013)
			(xy 169.852334 -122.520437) (xy 169.894739 -122.478032) (xy 169.942315 -122.441526) (xy 169.994249 -122.411542)
			(xy 170.049653 -122.388593) (xy 170.107578 -122.373072) (xy 170.167034 -122.365244) (xy 170.227002 -122.365244)
			(xy 170.286458 -122.373072) (xy 170.344383 -122.388593) (xy 170.399787 -122.411542) (xy 170.451721 -122.441526)
			(xy 170.499297 -122.478032) (xy 170.541702 -122.520437) (xy 170.578208 -122.568013) (xy 170.608192 -122.619947)
			(xy 170.631141 -122.675351) (xy 170.646662 -122.733276) (xy 170.65449 -122.792732) (xy 170.65498 -122.822716)
			(xy 170.65498 -123.16714) (xy 182.69966 -123.16714) (xy 182.69966 -122.30354) (xy 182.70015 -122.273572)
			(xy 182.707973 -122.21415) (xy 182.723486 -122.156257) (xy 182.746422 -122.100884) (xy 182.776389 -122.048978)
			(xy 182.812876 -122.001428) (xy 182.855256 -121.959048) (xy 182.902806 -121.922561) (xy 182.954712 -121.892594)
			(xy 183.010085 -121.869658) (xy 183.067978 -121.854145) (xy 183.1274 -121.846322) (xy 183.187336 -121.846322)
			(xy 183.246758 -121.854145) (xy 183.304651 -121.869658) (xy 183.360024 -121.892594) (xy 183.41193 -121.922561)
			(xy 183.45948 -121.959048) (xy 183.50186 -122.001428) (xy 183.538347 -122.048978) (xy 183.568314 -122.100884)
			(xy 183.59125 -122.156257) (xy 183.606763 -122.21415) (xy 183.614586 -122.273572) (xy 183.615076 -122.30354)
			(xy 183.615076 -123.16714) (xy 183.614586 -123.197108) (xy 183.609168 -123.23826) (xy 184.146952 -123.23826)
			(xy 184.146952 -122.231912) (xy 184.147494 -122.22181) (xy 184.155218 -122.203141) (xy 184.169498 -122.188848)
			(xy 184.188158 -122.181104) (xy 184.19826 -122.180604) (xy 185.379614 -122.180604) (xy 185.389737 -122.181114)
			(xy 185.408452 -122.18884) (xy 185.422806 -122.203118) (xy 185.430631 -122.221792) (xy 185.431176 -122.231912)
			(xy 185.431176 -123.23826) (xy 188.6839 -123.23826) (xy 188.6839 -122.231912) (xy 188.684326 -122.22179)
			(xy 188.69207 -122.203087) (xy 188.706384 -122.188772) (xy 188.725086 -122.181027) (xy 188.735208 -122.180604)
			(xy 189.916308 -122.180604) (xy 189.926431 -122.18101) (xy 189.945136 -122.188761) (xy 189.95945 -122.203081)
			(xy 189.967194 -122.221788) (xy 189.967616 -122.231912) (xy 189.967616 -123.23826) (xy 189.967151 -123.248378)
			(xy 189.95942 -123.267078) (xy 189.945118 -123.281393) (xy 189.926425 -123.289142) (xy 189.916308 -123.289568)
			(xy 188.735208 -123.289568) (xy 188.725082 -123.289177) (xy 188.706372 -123.281425) (xy 188.692057 -123.267101)
			(xy 188.684317 -123.248386) (xy 188.6839 -123.23826) (xy 185.431176 -123.23826) (xy 185.430751 -123.248383)
			(xy 185.423011 -123.26709) (xy 185.408697 -123.281407) (xy 185.389991 -123.289149) (xy 185.379868 -123.289568)
			(xy 184.198514 -123.289568) (xy 184.188389 -123.289062) (xy 184.16967 -123.281341) (xy 184.155313 -123.26706)
			(xy 184.147492 -123.248382) (xy 184.146952 -123.23826) (xy 183.609168 -123.23826) (xy 183.606763 -123.25653)
			(xy 183.59125 -123.314423) (xy 183.587026 -123.32462) (xy 195.69938 -123.32462) (xy 195.69938 -123.081796)
			(xy 195.818252 -122.90044) (xy 195.880736 -122.804936) (xy 195.904866 -122.768106) (xy 195.908746 -122.761784)
			(xy 195.912998 -122.74758) (xy 195.913248 -122.740166) (xy 195.913248 -122.714258) (xy 195.913037 -122.708109)
			(xy 195.910096 -122.696168) (xy 195.907406 -122.690636) (xy 195.793868 -122.516646) (xy 195.773802 -122.485658)
			(xy 195.768214 -122.477022) (xy 195.707762 -122.384312) (xy 195.707254 -122.38355) (xy 195.706746 -122.382788)
			(xy 195.706492 -122.38228) (xy 195.705984 -122.381518) (xy 195.69938 -122.371104) (xy 195.69938 -122.12828)
			(xy 195.700054 -122.116733) (xy 195.710005 -122.095889) (xy 195.727931 -122.081324) (xy 195.739004 -122.077988)
			(xy 195.750942 -122.076464) (xy 196.487542 -122.076464) (xy 196.498299 -122.07699) (xy 196.517989 -122.08565)
			(xy 196.525642 -122.093228) (xy 196.531824 -122.100639) (xy 196.538749 -122.118637) (xy 196.539104 -122.12828)
			(xy 196.539104 -122.371104) (xy 196.323204 -122.701558) (xy 196.319194 -122.709784) (xy 196.316646 -122.727891)
			(xy 196.320586 -122.745747) (xy 196.325236 -122.753628) (xy 196.357494 -122.803412) (xy 196.539104 -123.080526)
			(xy 196.539104 -123.159266) (xy 197.174612 -123.159266) (xy 197.174612 -122.295666) (xy 197.175102 -122.265698)
			(xy 197.182925 -122.206276) (xy 197.198438 -122.148383) (xy 197.221374 -122.09301) (xy 197.251341 -122.041104)
			(xy 197.287828 -121.993554) (xy 197.330208 -121.951174) (xy 197.377758 -121.914687) (xy 197.429664 -121.88472)
			(xy 197.485037 -121.861784) (xy 197.54293 -121.846271) (xy 197.602352 -121.838448) (xy 197.662288 -121.838448)
			(xy 197.72171 -121.846271) (xy 197.779603 -121.861784) (xy 197.834976 -121.88472) (xy 197.851649 -121.894346)
			(xy 269.509748 -121.894346) (xy 269.509748 -121.030746) (xy 269.510238 -121.000762) (xy 269.518066 -120.941306)
			(xy 269.533587 -120.883381) (xy 269.556536 -120.827977) (xy 269.58652 -120.776043) (xy 269.623026 -120.728467)
			(xy 269.665431 -120.686062) (xy 269.713007 -120.649556) (xy 269.764941 -120.619572) (xy 269.820345 -120.596623)
			(xy 269.87827 -120.581102) (xy 269.937726 -120.573274) (xy 269.997694 -120.573274) (xy 270.05715 -120.581102)
			(xy 270.115075 -120.596623) (xy 270.170479 -120.619572) (xy 270.222413 -120.649556) (xy 270.269989 -120.686062)
			(xy 270.312394 -120.728467) (xy 270.3489 -120.776043) (xy 270.378884 -120.827977) (xy 270.401833 -120.883381)
			(xy 270.417354 -120.941306) (xy 270.425182 -121.000762) (xy 270.425672 -121.030746) (xy 270.425672 -121.894346)
			(xy 270.425182 -121.92433) (xy 270.417354 -121.983786) (xy 270.401833 -122.041711) (xy 270.394382 -122.0597)
			(xy 271.060672 -122.0597) (xy 271.060672 -121.816876) (xy 271.179544 -121.63552) (xy 271.242028 -121.540016)
			(xy 271.266158 -121.503186) (xy 271.270044 -121.496868) (xy 271.274293 -121.482661) (xy 271.27454 -121.475246)
			(xy 271.27454 -121.449338) (xy 271.274337 -121.443189) (xy 271.27139 -121.431248) (xy 271.268698 -121.425716)
			(xy 271.15516 -121.251726) (xy 271.135094 -121.220738) (xy 271.129506 -121.212102) (xy 271.069054 -121.119392)
			(xy 271.068546 -121.11863) (xy 271.068038 -121.117868) (xy 271.067784 -121.11736) (xy 271.067276 -121.116598)
			(xy 271.060672 -121.106184) (xy 271.060672 -120.86336) (xy 271.061337 -120.851812) (xy 271.071293 -120.830969)
			(xy 271.089222 -120.816405) (xy 271.100296 -120.813068) (xy 271.112234 -120.811544) (xy 271.848834 -120.811544)
			(xy 271.85959 -120.81208) (xy 271.87928 -120.820734) (xy 271.886934 -120.828308) (xy 271.893107 -120.835726)
			(xy 271.900037 -120.853718) (xy 271.900396 -120.86336) (xy 271.900396 -121.106184) (xy 271.684496 -121.436638)
			(xy 271.680503 -121.444871) (xy 271.677949 -121.462973) (xy 271.681882 -121.480827) (xy 271.686528 -121.488708)
			(xy 271.718786 -121.538492) (xy 271.900396 -121.815606) (xy 271.900396 -121.958354) (xy 277.63216 -121.958354)
			(xy 277.63216 -120.952006) (xy 277.632632 -120.941877) (xy 277.640362 -120.923152) (xy 277.654653 -120.908795)
			(xy 277.673342 -120.900979) (xy 277.683468 -120.900444) (xy 278.864568 -120.900444) (xy 278.874713 -120.900946)
			(xy 278.893454 -120.908721) (xy 278.907777 -120.923092) (xy 278.915488 -120.94186) (xy 278.915876 -120.952006)
			(xy 278.915876 -121.958354) (xy 282.1686 -121.958354) (xy 282.1686 -120.952006) (xy 282.169137 -120.941853)
			(xy 282.176903 -120.923092) (xy 282.191255 -120.908727) (xy 282.21001 -120.900946) (xy 282.220162 -120.900444)
			(xy 283.401262 -120.900444) (xy 283.411432 -120.900895) (xy 283.430227 -120.908669) (xy 283.444613 -120.923046)
			(xy 283.452399 -120.941836) (xy 283.452824 -120.952006) (xy 283.452824 -121.886472) (xy 283.9847 -121.886472)
			(xy 283.9847 -121.022872) (xy 283.98519 -120.992888) (xy 283.993018 -120.933432) (xy 284.008539 -120.875507)
			(xy 284.031488 -120.820103) (xy 284.061472 -120.768169) (xy 284.097978 -120.720593) (xy 284.140383 -120.678188)
			(xy 284.187959 -120.641682) (xy 284.239893 -120.611698) (xy 284.295297 -120.588749) (xy 284.353222 -120.573228)
			(xy 284.412678 -120.5654) (xy 284.472646 -120.5654) (xy 284.532102 -120.573228) (xy 284.590027 -120.588749)
			(xy 284.645431 -120.611698) (xy 284.697365 -120.641682) (xy 284.744941 -120.678188) (xy 284.787346 -120.720593)
			(xy 284.823852 -120.768169) (xy 284.853836 -120.820103) (xy 284.876785 -120.875507) (xy 284.892306 -120.933432)
			(xy 284.900134 -120.992888) (xy 284.900624 -121.022872) (xy 284.900624 -121.367296) (xy 296.945304 -121.367296)
			(xy 296.945304 -120.503696) (xy 296.945794 -120.473728) (xy 296.953617 -120.414306) (xy 296.96913 -120.356413)
			(xy 296.992066 -120.30104) (xy 297.022033 -120.249134) (xy 297.05852 -120.201584) (xy 297.1009 -120.159204)
			(xy 297.14845 -120.122717) (xy 297.200356 -120.09275) (xy 297.255729 -120.069814) (xy 297.313622 -120.054301)
			(xy 297.373044 -120.046478) (xy 297.43298 -120.046478) (xy 297.492402 -120.054301) (xy 297.550295 -120.069814)
			(xy 297.605668 -120.09275) (xy 297.657574 -120.122717) (xy 297.705124 -120.159204) (xy 297.747504 -120.201584)
			(xy 297.783991 -120.249134) (xy 297.813958 -120.30104) (xy 297.836894 -120.356413) (xy 297.852407 -120.414306)
			(xy 297.86023 -120.473728) (xy 297.86072 -120.503696) (xy 297.86072 -121.367296) (xy 297.86023 -121.397264)
			(xy 297.854812 -121.438416) (xy 300.247304 -121.438416) (xy 300.247304 -120.431814) (xy 300.247837 -120.421693)
			(xy 300.255553 -120.402979) (xy 300.269825 -120.388623) (xy 300.288494 -120.380797) (xy 300.298612 -120.380252)
			(xy 301.479712 -120.380252) (xy 301.489816 -120.380774) (xy 301.508485 -120.388507) (xy 301.522777 -120.402792)
			(xy 301.53052 -120.421457) (xy 301.53102 -120.43156) (xy 301.53102 -121.438162) (xy 304.783744 -121.438162)
			(xy 304.783744 -120.431814) (xy 304.784175 -120.421643) (xy 304.791957 -120.402847) (xy 304.80634 -120.388461)
			(xy 304.825135 -120.380677) (xy 304.835306 -120.380252) (xy 306.016406 -120.380252) (xy 306.02658 -120.380659)
			(xy 306.045377 -120.388449) (xy 306.059762 -120.40284) (xy 306.067545 -120.42164) (xy 306.067968 -120.431814)
			(xy 306.067968 -121.438162) (xy 306.067505 -121.44833) (xy 306.059734 -121.467123) (xy 306.04536 -121.481509)
			(xy 306.026574 -121.489296) (xy 306.016406 -121.489724) (xy 304.835306 -121.489724) (xy 304.82513 -121.48933)
			(xy 304.806328 -121.48154) (xy 304.791942 -121.467145) (xy 304.784163 -121.448338) (xy 304.783744 -121.438162)
			(xy 301.53102 -121.438162) (xy 301.530541 -121.448291) (xy 301.522818 -121.467019) (xy 301.508529 -121.481378)
			(xy 301.489839 -121.489191) (xy 301.479712 -121.489724) (xy 300.298612 -121.489724) (xy 300.288507 -121.489206)
			(xy 300.269834 -121.481476) (xy 300.255539 -121.46719) (xy 300.2478 -121.448521) (xy 300.247304 -121.438416)
			(xy 297.854812 -121.438416) (xy 297.852407 -121.456686) (xy 297.836894 -121.514579) (xy 297.83004 -121.531126)
			(xy 314.441332 -121.531126) (xy 314.441332 -121.303542) (xy 314.441586 -121.299478) (xy 314.44184 -121.296938)
			(xy 314.44184 -121.288302) (xy 314.447428 -121.279666) (xy 314.448698 -121.277634) (xy 314.449714 -121.275602)
			(xy 314.647072 -120.974612) (xy 314.65095 -120.968289) (xy 314.655203 -120.954086) (xy 314.655454 -120.946672)
			(xy 314.655454 -120.921018) (xy 314.65526 -120.913683) (xy 314.651122 -120.899612) (xy 314.647326 -120.893332)
			(xy 314.44946 -120.59031) (xy 314.447174 -120.5865) (xy 314.44692 -120.585992) (xy 314.445904 -120.584214)
			(xy 314.44184 -120.57761) (xy 314.44184 -120.569482) (xy 314.441586 -120.566942) (xy 314.441332 -120.562878)
			(xy 314.441332 -120.334786) (xy 314.441822 -120.324628) (xy 314.4496 -120.30586) (xy 314.463967 -120.291495)
			(xy 314.482736 -120.28372) (xy 314.492894 -120.283224) (xy 315.229748 -120.283224) (xy 315.239933 -120.283637)
			(xy 315.258754 -120.291426) (xy 315.273181 -120.305806) (xy 315.28103 -120.324603) (xy 315.281564 -120.334786)
			(xy 315.281564 -120.56237) (xy 315.28131 -120.566434) (xy 315.281056 -120.568974) (xy 315.281056 -120.57761)
			(xy 315.275214 -120.587008) (xy 315.274452 -120.588278) (xy 315.273182 -120.59031) (xy 315.067442 -120.905016)
			(xy 315.062428 -120.913556) (xy 315.0586 -120.932963) (xy 315.0624 -120.952375) (xy 315.067442 -120.960896)
			(xy 315.273182 -121.274332) (xy 315.274198 -121.276364) (xy 315.275468 -121.278396) (xy 315.281056 -121.287032)
			(xy 315.281056 -121.295668) (xy 315.28131 -121.298208) (xy 315.281564 -121.302272) (xy 315.281564 -121.365772)
			(xy 315.916564 -121.365772) (xy 315.916564 -120.502172) (xy 315.917054 -120.472204) (xy 315.924877 -120.412782)
			(xy 315.94039 -120.354889) (xy 315.963326 -120.299516) (xy 315.993293 -120.24761) (xy 316.02978 -120.20006)
			(xy 316.07216 -120.15768) (xy 316.11971 -120.121193) (xy 316.171616 -120.091226) (xy 316.226989 -120.06829)
			(xy 316.284882 -120.052777) (xy 316.344304 -120.044954) (xy 316.40424 -120.044954) (xy 316.463662 -120.052777)
			(xy 316.521555 -120.06829) (xy 316.568893 -120.087898) (xy 382.967992 -120.087898) (xy 382.967992 -119.224298)
			(xy 382.968482 -119.19433) (xy 382.976305 -119.134908) (xy 382.991818 -119.077015) (xy 383.014754 -119.021642)
			(xy 383.044721 -118.969736) (xy 383.081208 -118.922186) (xy 383.123588 -118.879806) (xy 383.171138 -118.843319)
			(xy 383.223044 -118.813352) (xy 383.278417 -118.790416) (xy 383.33631 -118.774903) (xy 383.395732 -118.76708)
			(xy 383.455668 -118.76708) (xy 383.51509 -118.774903) (xy 383.572983 -118.790416) (xy 383.628356 -118.813352)
			(xy 383.680262 -118.843319) (xy 383.727812 -118.879806) (xy 383.770192 -118.922186) (xy 383.806679 -118.969736)
			(xy 383.836646 -119.021642) (xy 383.859582 -119.077015) (xy 383.875095 -119.134908) (xy 383.882918 -119.19433)
			(xy 383.883408 -119.224298) (xy 383.883408 -120.087898) (xy 383.882918 -120.117866) (xy 383.875095 -120.177288)
			(xy 383.859582 -120.235181) (xy 383.852097 -120.253252) (xy 384.518408 -120.253252) (xy 384.518408 -120.010428)
			(xy 384.523996 -120.002046) (xy 384.52425 -120.001538) (xy 384.526282 -119.99849) (xy 384.526536 -119.997982)
			(xy 384.732276 -119.684038) (xy 384.737307 -119.675621) (xy 384.741116 -119.656399) (xy 384.737456 -119.637147)
			(xy 384.73253 -119.628666) (xy 384.646678 -119.496586) (xy 384.63728 -119.482108) (xy 384.525012 -119.31015)
			(xy 384.524504 -119.309134) (xy 384.522472 -119.306086) (xy 384.522218 -119.305578) (xy 384.518408 -119.299736)
			(xy 384.518408 -119.056912) (xy 384.518823 -119.046688) (xy 384.526646 -119.027797) (xy 384.541107 -119.01334)
			(xy 384.56 -119.00552) (xy 384.570224 -119.005096) (xy 385.306824 -119.005096) (xy 385.317035 -119.005562)
			(xy 385.335899 -119.013385) (xy 385.350335 -119.027831) (xy 385.358145 -119.046701) (xy 385.35864 -119.056912)
			(xy 385.35864 -119.299736) (xy 385.35483 -119.305578) (xy 385.354576 -119.306086) (xy 385.350512 -119.312182)
			(xy 385.350258 -119.312436) (xy 385.212336 -119.52351) (xy 385.15925 -119.60479) (xy 385.146804 -119.62384)
			(xy 385.144772 -119.626634) (xy 385.143502 -119.628666) (xy 385.139321 -119.636092) (xy 385.135601 -119.652709)
			(xy 385.137552 -119.669626) (xy 385.140962 -119.677434) (xy 385.32816 -119.96293) (xy 385.3307 -119.96674)
			(xy 385.350512 -119.996712) (xy 385.350766 -119.99722) (xy 385.352036 -119.999252) (xy 385.353814 -120.001792)
			(xy 385.35864 -120.009158) (xy 385.35864 -120.158256) (xy 393.732004 -120.158256) (xy 393.732004 -119.151908)
			(xy 393.732428 -119.141754) (xy 393.740222 -119.123001) (xy 393.754618 -119.108677) (xy 393.77341 -119.100978)
			(xy 393.783566 -119.1006) (xy 394.964666 -119.1006) (xy 394.974786 -119.101153) (xy 394.993498 -119.108863)
			(xy 395.007854 -119.123128) (xy 395.015682 -119.141792) (xy 395.016228 -119.151908) (xy 395.016228 -120.158256)
			(xy 398.268952 -120.158256) (xy 398.268952 -119.151908) (xy 398.26949 -119.141806) (xy 398.277217 -119.123137)
			(xy 398.291497 -119.108843) (xy 398.310158 -119.1011) (xy 398.32026 -119.1006) (xy 399.50136 -119.1006)
			(xy 399.51148 -119.101049) (xy 399.530183 -119.108784) (xy 399.544498 -119.123091) (xy 399.552245 -119.141788)
			(xy 399.552668 -119.151908) (xy 399.552668 -120.086374) (xy 401.939252 -120.086374) (xy 401.939252 -119.222774)
			(xy 401.939742 -119.192806) (xy 401.947565 -119.133384) (xy 401.963078 -119.075491) (xy 401.986014 -119.020118)
			(xy 402.015981 -118.968212) (xy 402.052468 -118.920662) (xy 402.094848 -118.878282) (xy 402.142398 -118.841795)
			(xy 402.194304 -118.811828) (xy 402.249677 -118.788892) (xy 402.30757 -118.773379) (xy 402.366992 -118.765556)
			(xy 402.426928 -118.765556) (xy 402.48635 -118.773379) (xy 402.544243 -118.788892) (xy 402.599616 -118.811828)
			(xy 402.651522 -118.841795) (xy 402.699072 -118.878282) (xy 402.741452 -118.920662) (xy 402.777939 -118.968212)
			(xy 402.807906 -119.020118) (xy 402.830842 -119.075491) (xy 402.846355 -119.133384) (xy 402.854178 -119.192806)
			(xy 402.854668 -119.222774) (xy 402.854668 -119.567198) (xy 414.899348 -119.567198) (xy 414.899348 -118.703598)
			(xy 414.899838 -118.673614) (xy 414.907666 -118.614158) (xy 414.923187 -118.556233) (xy 414.946136 -118.500829)
			(xy 414.97612 -118.448895) (xy 415.012626 -118.401319) (xy 415.055031 -118.358914) (xy 415.102607 -118.322408)
			(xy 415.154541 -118.292424) (xy 415.209945 -118.269475) (xy 415.26787 -118.253954) (xy 415.327326 -118.246126)
			(xy 415.387294 -118.246126) (xy 415.44675 -118.253954) (xy 415.504675 -118.269475) (xy 415.560079 -118.292424)
			(xy 415.612013 -118.322408) (xy 415.659589 -118.358914) (xy 415.701994 -118.401319) (xy 415.7385 -118.448895)
			(xy 415.768484 -118.500829) (xy 415.791433 -118.556233) (xy 415.806954 -118.614158) (xy 415.814782 -118.673614)
			(xy 415.815272 -118.703598) (xy 415.815272 -119.567198) (xy 415.814782 -119.597182) (xy 415.809399 -119.638064)
			(xy 416.347148 -119.638064) (xy 416.347148 -118.631716) (xy 416.347697 -118.621615) (xy 416.35542 -118.602947)
			(xy 416.369696 -118.588653) (xy 416.388355 -118.580909) (xy 416.398456 -118.580408) (xy 417.57981 -118.580408)
			(xy 417.589933 -118.580918) (xy 417.608649 -118.588643) (xy 417.623003 -118.602921) (xy 417.630828 -118.621595)
			(xy 417.631372 -118.631716) (xy 417.631372 -119.638064) (xy 420.884096 -119.638064) (xy 420.884096 -118.631716)
			(xy 420.884529 -118.621595) (xy 420.892271 -118.602892) (xy 420.906582 -118.588578) (xy 420.925283 -118.580831)
			(xy 420.935404 -118.580408) (xy 422.116504 -118.580408) (xy 422.126628 -118.580813) (xy 422.145333 -118.588564)
			(xy 422.159647 -118.602884) (xy 422.167391 -118.621592) (xy 422.167812 -118.631716) (xy 422.167812 -119.638064)
			(xy 422.167355 -119.648183) (xy 422.159621 -119.666883) (xy 422.145317 -119.681198) (xy 422.126622 -119.688947)
			(xy 422.116504 -119.689372) (xy 420.935404 -119.689372) (xy 420.925278 -119.68898) (xy 420.906569 -119.681228)
			(xy 420.892254 -119.666904) (xy 420.884514 -119.64819) (xy 420.884096 -119.638064) (xy 417.631372 -119.638064)
			(xy 417.630954 -119.648188) (xy 417.623212 -119.666896) (xy 417.608896 -119.681212) (xy 417.590188 -119.688954)
			(xy 417.580064 -119.689372) (xy 416.39871 -119.689372) (xy 416.388585 -119.688866) (xy 416.369867 -119.681143)
			(xy 416.355511 -119.666863) (xy 416.347689 -119.648186) (xy 416.347148 -119.638064) (xy 415.809399 -119.638064)
			(xy 415.806954 -119.656638) (xy 415.791433 -119.714563) (xy 415.787243 -119.724678) (xy 427.899576 -119.724678)
			(xy 427.899576 -119.481854) (xy 428.044356 -119.261128) (xy 428.093632 -119.18569) (xy 428.113444 -119.155464)
			(xy 428.118422 -119.147016) (xy 428.122153 -119.127781) (xy 428.118408 -119.108549) (xy 428.113444 -119.100092)
			(xy 427.96841 -118.87708) (xy 427.912784 -118.791736) (xy 427.908466 -118.78564) (xy 427.905164 -118.780052)
			(xy 427.904656 -118.779036) (xy 427.899576 -118.771162) (xy 427.899576 -118.528338) (xy 427.899996 -118.518164)
			(xy 427.907776 -118.499363) (xy 427.922163 -118.484976) (xy 427.940964 -118.477196) (xy 427.951138 -118.476776)
			(xy 428.687738 -118.476776) (xy 428.697903 -118.477203) (xy 428.71668 -118.484997) (xy 428.731045 -118.499384)
			(xy 428.738812 -118.518172) (xy 428.7393 -118.528338) (xy 428.7393 -118.771162) (xy 428.5234 -119.101616)
			(xy 428.519344 -119.109823) (xy 428.516813 -119.127943) (xy 428.520772 -119.145805) (xy 428.525432 -119.153686)
			(xy 428.55769 -119.20347) (xy 428.573184 -119.227092) (xy 428.7393 -119.480584) (xy 428.7393 -119.559324)
			(xy 429.3743 -119.559324) (xy 429.3743 -118.695724) (xy 429.37479 -118.66574) (xy 429.382618 -118.606284)
			(xy 429.398139 -118.548359) (xy 429.421088 -118.492955) (xy 429.451072 -118.441021) (xy 429.487578 -118.393445)
			(xy 429.529983 -118.35104) (xy 429.577559 -118.314534) (xy 429.629493 -118.28455) (xy 429.684897 -118.261601)
			(xy 429.742822 -118.24608) (xy 429.802278 -118.238252) (xy 429.862246 -118.238252) (xy 429.921702 -118.24608)
			(xy 429.979627 -118.261601) (xy 430.035031 -118.28455) (xy 430.086965 -118.314534) (xy 430.134541 -118.35104)
			(xy 430.176946 -118.393445) (xy 430.213452 -118.441021) (xy 430.243436 -118.492955) (xy 430.266385 -118.548359)
			(xy 430.281906 -118.606284) (xy 430.289734 -118.66574) (xy 430.290224 -118.695724) (xy 430.290224 -119.559324)
			(xy 430.289734 -119.589308) (xy 430.281906 -119.648764) (xy 430.266385 -119.706689) (xy 430.243436 -119.762093)
			(xy 430.213452 -119.814027) (xy 430.176946 -119.861603) (xy 430.134541 -119.904008) (xy 430.086965 -119.940514)
			(xy 430.035031 -119.970498) (xy 429.979627 -119.993447) (xy 429.921702 -120.008968) (xy 429.862246 -120.016796)
			(xy 429.802278 -120.016796) (xy 429.742822 -120.008968) (xy 429.684897 -119.993447) (xy 429.629493 -119.970498)
			(xy 429.577559 -119.940514) (xy 429.529983 -119.904008) (xy 429.487578 -119.861603) (xy 429.451072 -119.814027)
			(xy 429.421088 -119.762093) (xy 429.398139 -119.706689) (xy 429.382618 -119.648764) (xy 429.37479 -119.589308)
			(xy 429.3743 -119.559324) (xy 428.7393 -119.559324) (xy 428.7393 -119.724678) (xy 428.73875 -119.73483)
			(xy 428.73099 -119.753591) (xy 428.716642 -119.767956) (xy 428.697889 -119.775738) (xy 428.687738 -119.77624)
			(xy 427.951138 -119.77624) (xy 427.940966 -119.775804) (xy 427.922168 -119.768028) (xy 427.907781 -119.753645)
			(xy 427.899999 -119.73485) (xy 427.899576 -119.724678) (xy 415.787243 -119.724678) (xy 415.768484 -119.769967)
			(xy 415.7385 -119.821901) (xy 415.701994 -119.869477) (xy 415.659589 -119.911882) (xy 415.612013 -119.948388)
			(xy 415.560079 -119.978372) (xy 415.504675 -120.001321) (xy 415.44675 -120.016842) (xy 415.387294 -120.02467)
			(xy 415.327326 -120.02467) (xy 415.26787 -120.016842) (xy 415.209945 -120.001321) (xy 415.154541 -119.978372)
			(xy 415.102607 -119.948388) (xy 415.055031 -119.911882) (xy 415.012626 -119.869477) (xy 414.97612 -119.821901)
			(xy 414.946136 -119.769967) (xy 414.923187 -119.714563) (xy 414.907666 -119.656638) (xy 414.899838 -119.597182)
			(xy 414.899348 -119.567198) (xy 402.854668 -119.567198) (xy 402.854668 -120.086374) (xy 402.854178 -120.116342)
			(xy 402.846355 -120.175764) (xy 402.830842 -120.233657) (xy 402.807906 -120.28903) (xy 402.777939 -120.340936)
			(xy 402.741452 -120.388486) (xy 402.699072 -120.430866) (xy 402.651522 -120.467353) (xy 402.599616 -120.49732)
			(xy 402.544243 -120.520256) (xy 402.48635 -120.535769) (xy 402.426928 -120.543592) (xy 402.366992 -120.543592)
			(xy 402.30757 -120.535769) (xy 402.249677 -120.520256) (xy 402.194304 -120.49732) (xy 402.142398 -120.467353)
			(xy 402.094848 -120.430866) (xy 402.052468 -120.388486) (xy 402.015981 -120.340936) (xy 401.986014 -120.28903)
			(xy 401.963078 -120.233657) (xy 401.947565 -120.175764) (xy 401.939742 -120.116342) (xy 401.939252 -120.086374)
			(xy 399.552668 -120.086374) (xy 399.552668 -120.158256) (xy 399.552247 -120.16838) (xy 399.544508 -120.187088)
			(xy 399.530192 -120.201405) (xy 399.511484 -120.209146) (xy 399.50136 -120.209564) (xy 398.32026 -120.209564)
			(xy 398.31013 -120.209216) (xy 398.291419 -120.201448) (xy 398.277105 -120.18711) (xy 398.269368 -120.168386)
			(xy 398.268952 -120.158256) (xy 395.016228 -120.158256) (xy 395.015743 -120.168404) (xy 395.007967 -120.18715)
			(xy 394.99359 -120.201474) (xy 394.974815 -120.20918) (xy 394.964666 -120.209564) (xy 393.783566 -120.209564)
			(xy 393.773438 -120.209101) (xy 393.754716 -120.201363) (xy 393.740361 -120.18707) (xy 393.732543 -120.168382)
			(xy 393.732004 -120.158256) (xy 385.35864 -120.158256) (xy 385.35864 -120.253252) (xy 385.35815 -120.263468)
			(xy 385.350346 -120.282349) (xy 385.33591 -120.296806) (xy 385.317039 -120.304635) (xy 385.306824 -120.305068)
			(xy 384.570224 -120.305068) (xy 384.559998 -120.304667) (xy 384.541102 -120.296843) (xy 384.526644 -120.282378)
			(xy 384.518828 -120.263478) (xy 384.518408 -120.253252) (xy 383.852097 -120.253252) (xy 383.836646 -120.290554)
			(xy 383.806679 -120.34246) (xy 383.770192 -120.39001) (xy 383.727812 -120.43239) (xy 383.680262 -120.468877)
			(xy 383.628356 -120.498844) (xy 383.572983 -120.52178) (xy 383.51509 -120.537293) (xy 383.455668 -120.545116)
			(xy 383.395732 -120.545116) (xy 383.33631 -120.537293) (xy 383.278417 -120.52178) (xy 383.223044 -120.498844)
			(xy 383.171138 -120.468877) (xy 383.123588 -120.43239) (xy 383.081208 -120.39001) (xy 383.044721 -120.34246)
			(xy 383.014754 -120.290554) (xy 382.991818 -120.235181) (xy 382.976305 -120.177288) (xy 382.968482 -120.117866)
			(xy 382.967992 -120.087898) (xy 316.568893 -120.087898) (xy 316.576928 -120.091226) (xy 316.628834 -120.121193)
			(xy 316.676384 -120.15768) (xy 316.718764 -120.20006) (xy 316.755251 -120.24761) (xy 316.785218 -120.299516)
			(xy 316.808154 -120.354889) (xy 316.823667 -120.412782) (xy 316.83149 -120.472204) (xy 316.83198 -120.502172)
			(xy 316.83198 -121.365772) (xy 316.83149 -121.39574) (xy 316.823667 -121.455162) (xy 316.808154 -121.513055)
			(xy 316.785218 -121.568428) (xy 316.755251 -121.620334) (xy 316.718764 -121.667884) (xy 316.676384 -121.710264)
			(xy 316.628834 -121.746751) (xy 316.576928 -121.776718) (xy 316.521555 -121.799654) (xy 316.463662 -121.815167)
			(xy 316.40424 -121.82299) (xy 316.344304 -121.82299) (xy 316.284882 -121.815167) (xy 316.226989 -121.799654)
			(xy 316.171616 -121.776718) (xy 316.11971 -121.746751) (xy 316.07216 -121.710264) (xy 316.02978 -121.667884)
			(xy 315.993293 -121.620334) (xy 315.963326 -121.568428) (xy 315.94039 -121.513055) (xy 315.924877 -121.455162)
			(xy 315.917054 -121.39574) (xy 315.916564 -121.365772) (xy 315.281564 -121.365772) (xy 315.281564 -121.531126)
			(xy 315.281088 -121.541285) (xy 315.273305 -121.560055) (xy 315.258934 -121.574419) (xy 315.240161 -121.582193)
			(xy 315.230002 -121.582688) (xy 314.493148 -121.582688) (xy 314.482971 -121.582185) (xy 314.464154 -121.57443)
			(xy 314.449724 -121.560076) (xy 314.44187 -121.5413) (xy 314.441332 -121.531126) (xy 297.83004 -121.531126)
			(xy 297.813958 -121.569952) (xy 297.783991 -121.621858) (xy 297.747504 -121.669408) (xy 297.705124 -121.711788)
			(xy 297.657574 -121.748275) (xy 297.605668 -121.778242) (xy 297.550295 -121.801178) (xy 297.492402 -121.816691)
			(xy 297.43298 -121.824514) (xy 297.373044 -121.824514) (xy 297.313622 -121.816691) (xy 297.255729 -121.801178)
			(xy 297.200356 -121.778242) (xy 297.14845 -121.748275) (xy 297.1009 -121.711788) (xy 297.05852 -121.669408)
			(xy 297.022033 -121.621858) (xy 296.992066 -121.569952) (xy 296.96913 -121.514579) (xy 296.953617 -121.456686)
			(xy 296.945794 -121.397264) (xy 296.945304 -121.367296) (xy 284.900624 -121.367296) (xy 284.900624 -121.886472)
			(xy 284.900134 -121.916456) (xy 284.892306 -121.975912) (xy 284.876785 -122.033837) (xy 284.853836 -122.089241)
			(xy 284.823852 -122.141175) (xy 284.787346 -122.188751) (xy 284.744941 -122.231156) (xy 284.697365 -122.267662)
			(xy 284.645431 -122.297646) (xy 284.590027 -122.320595) (xy 284.532102 -122.336116) (xy 284.472646 -122.343944)
			(xy 284.412678 -122.343944) (xy 284.353222 -122.336116) (xy 284.295297 -122.320595) (xy 284.239893 -122.297646)
			(xy 284.187959 -122.267662) (xy 284.140383 -122.231156) (xy 284.097978 -122.188751) (xy 284.061472 -122.141175)
			(xy 284.031488 -122.089241) (xy 284.008539 -122.033837) (xy 283.993018 -121.975912) (xy 283.98519 -121.916456)
			(xy 283.9847 -121.886472) (xy 283.452824 -121.886472) (xy 283.452824 -121.958354) (xy 283.452398 -121.968527)
			(xy 283.444621 -121.987328) (xy 283.430235 -122.001716) (xy 283.411435 -122.009496) (xy 283.401262 -122.009916)
			(xy 282.220162 -122.009916) (xy 282.209982 -122.009566) (xy 282.191178 -122.00176) (xy 282.176793 -121.987352)
			(xy 282.169017 -121.968534) (xy 282.1686 -121.958354) (xy 278.915876 -121.958354) (xy 278.915336 -121.968476)
			(xy 278.907626 -121.987193) (xy 278.893356 -122.00155) (xy 278.874687 -122.009374) (xy 278.864568 -122.009916)
			(xy 277.683468 -122.009916) (xy 277.673314 -122.009505) (xy 277.654564 -122.001702) (xy 277.640242 -121.987302)
			(xy 277.632541 -121.96851) (xy 277.63216 -121.958354) (xy 271.900396 -121.958354) (xy 271.900396 -122.0597)
			(xy 271.899724 -122.071248) (xy 271.889776 -122.092095) (xy 271.871847 -122.106659) (xy 271.860772 -122.109992)
			(xy 271.848834 -122.111516) (xy 271.112234 -122.111516) (xy 271.101479 -122.110979) (xy 271.08179 -122.102324)
			(xy 271.074134 -122.094752) (xy 271.06794 -122.08735) (xy 271.061023 -122.069345) (xy 271.060672 -122.0597)
			(xy 270.394382 -122.0597) (xy 270.378884 -122.097115) (xy 270.3489 -122.149049) (xy 270.312394 -122.196625)
			(xy 270.269989 -122.23903) (xy 270.222413 -122.275536) (xy 270.170479 -122.30552) (xy 270.115075 -122.328469)
			(xy 270.05715 -122.34399) (xy 269.997694 -122.351818) (xy 269.937726 -122.351818) (xy 269.87827 -122.34399)
			(xy 269.820345 -122.328469) (xy 269.764941 -122.30552) (xy 269.713007 -122.275536) (xy 269.665431 -122.23903)
			(xy 269.623026 -122.196625) (xy 269.58652 -122.149049) (xy 269.556536 -122.097115) (xy 269.533587 -122.041711)
			(xy 269.518066 -121.983786) (xy 269.510238 -121.92433) (xy 269.509748 -121.894346) (xy 197.851649 -121.894346)
			(xy 197.886882 -121.914687) (xy 197.934432 -121.951174) (xy 197.976812 -121.993554) (xy 198.013299 -122.041104)
			(xy 198.043266 -122.09301) (xy 198.066202 -122.148383) (xy 198.081715 -122.206276) (xy 198.089538 -122.265698)
			(xy 198.090028 -122.295666) (xy 198.090028 -123.159266) (xy 198.089538 -123.189234) (xy 198.081715 -123.248656)
			(xy 198.066202 -123.306549) (xy 198.043266 -123.361922) (xy 198.013299 -123.413828) (xy 197.976812 -123.461378)
			(xy 197.934432 -123.503758) (xy 197.886882 -123.540245) (xy 197.834976 -123.570212) (xy 197.779603 -123.593148)
			(xy 197.72171 -123.608661) (xy 197.662288 -123.616484) (xy 197.602352 -123.616484) (xy 197.54293 -123.608661)
			(xy 197.485037 -123.593148) (xy 197.429664 -123.570212) (xy 197.377758 -123.540245) (xy 197.330208 -123.503758)
			(xy 197.287828 -123.461378) (xy 197.251341 -123.413828) (xy 197.221374 -123.361922) (xy 197.198438 -123.306549)
			(xy 197.182925 -123.248656) (xy 197.175102 -123.189234) (xy 197.174612 -123.159266) (xy 196.539104 -123.159266)
			(xy 196.539104 -123.32462) (xy 196.538441 -123.336169) (xy 196.528487 -123.357015) (xy 196.510556 -123.371578)
			(xy 196.49948 -123.374912) (xy 196.487542 -123.376436) (xy 195.750942 -123.376436) (xy 195.740184 -123.375919)
			(xy 195.720494 -123.367252) (xy 195.712842 -123.359672) (xy 195.706658 -123.352263) (xy 195.699735 -123.334264)
			(xy 195.69938 -123.32462) (xy 183.587026 -123.32462) (xy 183.568314 -123.369796) (xy 183.538347 -123.421702)
			(xy 183.50186 -123.469252) (xy 183.45948 -123.511632) (xy 183.41193 -123.548119) (xy 183.360024 -123.578086)
			(xy 183.304651 -123.601022) (xy 183.246758 -123.616535) (xy 183.187336 -123.624358) (xy 183.1274 -123.624358)
			(xy 183.067978 -123.616535) (xy 183.010085 -123.601022) (xy 182.954712 -123.578086) (xy 182.902806 -123.548119)
			(xy 182.855256 -123.511632) (xy 182.812876 -123.469252) (xy 182.776389 -123.421702) (xy 182.746422 -123.369796)
			(xy 182.723486 -123.314423) (xy 182.707973 -123.25653) (xy 182.70015 -123.197108) (xy 182.69966 -123.16714)
			(xy 170.65498 -123.16714) (xy 170.65498 -123.686316) (xy 170.65449 -123.7163) (xy 170.646662 -123.775756)
			(xy 170.631141 -123.833681) (xy 170.608192 -123.889085) (xy 170.578208 -123.941019) (xy 170.541702 -123.988595)
			(xy 170.499297 -124.031) (xy 170.451721 -124.067506) (xy 170.399787 -124.09749) (xy 170.344383 -124.120439)
			(xy 170.286458 -124.13596) (xy 170.227002 -124.143788) (xy 170.167034 -124.143788) (xy 170.107578 -124.13596)
			(xy 170.049653 -124.120439) (xy 169.994249 -124.09749) (xy 169.942315 -124.067506) (xy 169.894739 -124.031)
			(xy 169.852334 -123.988595) (xy 169.815828 -123.941019) (xy 169.785844 -123.889085) (xy 169.762895 -123.833681)
			(xy 169.747374 -123.775756) (xy 169.739546 -123.7163) (xy 169.739056 -123.686316) (xy 167.352472 -123.686316)
			(xy 167.352472 -123.758452) (xy 167.352044 -123.768575) (xy 167.344306 -123.787283) (xy 167.329993 -123.8016)
			(xy 167.311287 -123.809342) (xy 167.301164 -123.80976) (xy 166.120064 -123.80976) (xy 166.109934 -123.809413)
			(xy 166.091222 -123.801645) (xy 166.076908 -123.787307) (xy 166.069171 -123.768582) (xy 166.068756 -123.758452)
			(xy 162.816032 -123.758452) (xy 162.81554 -123.768599) (xy 162.807766 -123.787344) (xy 162.793391 -123.801668)
			(xy 162.774618 -123.809375) (xy 162.76447 -123.80976) (xy 161.58337 -123.80976) (xy 161.573241 -123.809298)
			(xy 161.554519 -123.80156) (xy 161.540164 -123.787267) (xy 161.532346 -123.768578) (xy 161.531808 -123.758452)
			(xy 153.158444 -123.758452) (xy 153.158444 -123.853194) (xy 153.158031 -123.863367) (xy 153.150244 -123.882166)
			(xy 153.135855 -123.896551) (xy 153.117056 -123.904333) (xy 153.106882 -123.904756) (xy 152.370028 -123.904756)
			(xy 152.359858 -123.904203) (xy 152.341053 -123.896454) (xy 152.326626 -123.882117) (xy 152.318761 -123.863361)
			(xy 152.318212 -123.853194) (xy 151.65243 -123.853194) (xy 151.636932 -123.890609) (xy 151.606948 -123.942543)
			(xy 151.570442 -123.990119) (xy 151.528037 -124.032524) (xy 151.480461 -124.06903) (xy 151.428527 -124.099014)
			(xy 151.373123 -124.121963) (xy 151.315198 -124.137484) (xy 151.255742 -124.145312) (xy 151.195774 -124.145312)
			(xy 151.136318 -124.137484) (xy 151.078393 -124.121963) (xy 151.022989 -124.099014) (xy 150.971055 -124.06903)
			(xy 150.923479 -124.032524) (xy 150.881074 -123.990119) (xy 150.844568 -123.942543) (xy 150.814584 -123.890609)
			(xy 150.791635 -123.835205) (xy 150.776114 -123.77728) (xy 150.768286 -123.717824) (xy 150.767796 -123.68784)
			(xy 84.369615 -123.68784) (xy 84.377099 -123.69094) (xy 84.429033 -123.720924) (xy 84.476609 -123.75743)
			(xy 84.519014 -123.799835) (xy 84.55552 -123.847411) (xy 84.585504 -123.899345) (xy 84.608453 -123.954749)
			(xy 84.623974 -124.012674) (xy 84.631802 -124.07213) (xy 84.632292 -124.102114) (xy 84.632292 -124.965714)
			(xy 84.631802 -124.995698) (xy 84.623974 -125.055154) (xy 84.608453 -125.113079) (xy 84.585504 -125.168483)
			(xy 84.55552 -125.220417) (xy 84.519014 -125.267993) (xy 84.476609 -125.310398) (xy 84.429033 -125.346904)
			(xy 84.377099 -125.376888) (xy 84.321695 -125.399837) (xy 84.26377 -125.415358) (xy 84.204314 -125.423186)
			(xy 84.144346 -125.423186) (xy 84.08489 -125.415358) (xy 84.026965 -125.399837) (xy 83.971561 -125.376888)
			(xy 83.919627 -125.346904) (xy 83.872051 -125.310398) (xy 83.829646 -125.267993) (xy 83.79314 -125.220417)
			(xy 83.763156 -125.168483) (xy 83.740207 -125.113079) (xy 83.724686 -125.055154) (xy 83.716858 -124.995698)
			(xy 83.716368 -124.965714) (xy 83.081368 -124.965714) (xy 83.081368 -125.131068) (xy 83.080768 -125.142625)
			(xy 83.070788 -125.163476) (xy 83.052831 -125.178034) (xy 83.041744 -125.18136) (xy 83.029806 -125.182884)
			(xy 82.293206 -125.182884) (xy 82.282448 -125.182372) (xy 82.262759 -125.1737) (xy 82.255106 -125.16612)
			(xy 82.248895 -125.15873) (xy 82.241989 -125.140716) (xy 82.241644 -125.131068) (xy 65.630373 -125.131068)
			(xy 65.614244 -125.170007) (xy 65.58426 -125.221941) (xy 65.547754 -125.269517) (xy 65.505349 -125.311922)
			(xy 65.457773 -125.348428) (xy 65.405839 -125.378412) (xy 65.350435 -125.401361) (xy 65.29251 -125.416882)
			(xy 65.233054 -125.42471) (xy 65.173086 -125.42471) (xy 65.11363 -125.416882) (xy 65.055705 -125.401361)
			(xy 65.000301 -125.378412) (xy 64.948367 -125.348428) (xy 64.900791 -125.311922) (xy 64.858386 -125.269517)
			(xy 64.82188 -125.221941) (xy 64.791896 -125.170007) (xy 64.768947 -125.114603) (xy 64.753426 -125.056678)
			(xy 64.745598 -124.997222) (xy 64.745108 -124.967238) (xy 52.700428 -124.967238) (xy 52.700428 -125.486414)
			(xy 52.700295 -125.494542) (xy 153.409904 -125.494542) (xy 153.409904 -124.630942) (xy 153.410394 -124.600958)
			(xy 153.418222 -124.541502) (xy 153.433743 -124.483577) (xy 153.456692 -124.428173) (xy 153.486676 -124.376239)
			(xy 153.523182 -124.328663) (xy 153.565587 -124.286258) (xy 153.613163 -124.249752) (xy 153.665097 -124.219768)
			(xy 153.720501 -124.196819) (xy 153.778426 -124.181298) (xy 153.837882 -124.17347) (xy 153.89785 -124.17347)
			(xy 153.957306 -124.181298) (xy 154.015231 -124.196819) (xy 154.070635 -124.219768) (xy 154.122569 -124.249752)
			(xy 154.170145 -124.286258) (xy 154.21255 -124.328663) (xy 154.249056 -124.376239) (xy 154.27904 -124.428173)
			(xy 154.301989 -124.483577) (xy 154.31751 -124.541502) (xy 154.325338 -124.600958) (xy 154.325828 -124.630942)
			(xy 154.325828 -125.494542) (xy 154.325338 -125.524526) (xy 154.31751 -125.583982) (xy 154.301989 -125.641907)
			(xy 154.294538 -125.659896) (xy 154.96032 -125.659896) (xy 154.96032 -125.417072) (xy 154.965908 -125.40869)
			(xy 154.966162 -125.408182) (xy 154.968194 -125.405134) (xy 154.968448 -125.404626) (xy 155.174188 -125.090682)
			(xy 155.179181 -125.082246) (xy 155.183001 -125.063036) (xy 155.179358 -125.043791) (xy 155.174442 -125.03531)
			(xy 155.08859 -124.90323) (xy 155.079192 -124.888752) (xy 154.966924 -124.716794) (xy 154.966416 -124.715778)
			(xy 154.964384 -124.71273) (xy 154.96413 -124.712222) (xy 154.96032 -124.70638) (xy 154.96032 -124.463556)
			(xy 154.960747 -124.453341) (xy 154.968581 -124.434471) (xy 154.983039 -124.420036) (xy 155.00192 -124.412231)
			(xy 155.012136 -124.41174) (xy 155.748736 -124.41174) (xy 155.758941 -124.412251) (xy 155.777795 -124.420068)
			(xy 155.792228 -124.434499) (xy 155.800047 -124.453351) (xy 155.800552 -124.463556) (xy 155.800552 -124.70638)
			(xy 155.796742 -124.712222) (xy 155.796488 -124.71273) (xy 155.792424 -124.718826) (xy 155.79217 -124.71908)
			(xy 155.654248 -124.930154) (xy 155.601162 -125.011434) (xy 155.588716 -125.030484) (xy 155.586684 -125.033278)
			(xy 155.585414 -125.03531) (xy 155.581201 -125.04272) (xy 155.577491 -125.059347) (xy 155.579456 -125.076269)
			(xy 155.582874 -125.084078) (xy 155.770072 -125.369574) (xy 155.772612 -125.373384) (xy 155.792424 -125.403356)
			(xy 155.792678 -125.403864) (xy 155.793948 -125.405896) (xy 155.795726 -125.408436) (xy 155.800552 -125.415802)
			(xy 155.800552 -125.558296) (xy 161.531808 -125.558296) (xy 161.531808 -124.551948) (xy 161.532261 -124.541796)
			(xy 161.540042 -124.523043) (xy 161.55443 -124.508718) (xy 161.573216 -124.501018) (xy 161.58337 -124.50064)
			(xy 162.76447 -124.50064) (xy 162.774595 -124.501151) (xy 162.793315 -124.508869) (xy 162.807673 -124.523148)
			(xy 162.815493 -124.541826) (xy 162.816032 -124.551948) (xy 162.816032 -125.558296) (xy 166.068756 -125.558296)
			(xy 166.068756 -124.551948) (xy 166.069254 -124.541834) (xy 166.076978 -124.52314) (xy 166.091269 -124.508826)
			(xy 166.109951 -124.501071) (xy 166.120064 -124.50064) (xy 167.301164 -124.50064) (xy 167.311289 -124.501047)
			(xy 167.329999 -124.50879) (xy 167.344316 -124.523111) (xy 167.352056 -124.541823) (xy 167.352472 -124.551948)
			(xy 167.352472 -125.486414) (xy 167.884856 -125.486414) (xy 167.884856 -124.622814) (xy 167.885346 -124.59283)
			(xy 167.893174 -124.533374) (xy 167.908695 -124.475449) (xy 167.931644 -124.420045) (xy 167.961628 -124.368111)
			(xy 167.998134 -124.320535) (xy 168.040539 -124.27813) (xy 168.088115 -124.241624) (xy 168.140049 -124.21164)
			(xy 168.195453 -124.188691) (xy 168.253378 -124.17317) (xy 168.312834 -124.165342) (xy 168.372802 -124.165342)
			(xy 168.432258 -124.17317) (xy 168.490183 -124.188691) (xy 168.545587 -124.21164) (xy 168.597521 -124.241624)
			(xy 168.645097 -124.27813) (xy 168.687502 -124.320535) (xy 168.724008 -124.368111) (xy 168.753992 -124.420045)
			(xy 168.776941 -124.475449) (xy 168.792462 -124.533374) (xy 168.80029 -124.59283) (xy 168.80078 -124.622814)
			(xy 168.80078 -124.967238) (xy 180.84546 -124.967238) (xy 180.84546 -124.103638) (xy 180.84595 -124.07367)
			(xy 180.853773 -124.014248) (xy 180.869286 -123.956355) (xy 180.892222 -123.900982) (xy 180.922189 -123.849076)
			(xy 180.958676 -123.801526) (xy 181.001056 -123.759146) (xy 181.048606 -123.722659) (xy 181.100512 -123.692692)
			(xy 181.155885 -123.669756) (xy 181.213778 -123.654243) (xy 181.2732 -123.64642) (xy 181.333136 -123.64642)
			(xy 181.392558 -123.654243) (xy 181.450451 -123.669756) (xy 181.505824 -123.692692) (xy 181.55773 -123.722659)
			(xy 181.60528 -123.759146) (xy 181.64766 -123.801526) (xy 181.684147 -123.849076) (xy 181.714114 -123.900982)
			(xy 181.73705 -123.956355) (xy 181.752563 -124.014248) (xy 181.760386 -124.07367) (xy 181.760876 -124.103638)
			(xy 181.760876 -124.967238) (xy 181.760386 -124.997206) (xy 181.755002 -125.038104) (xy 184.146952 -125.038104)
			(xy 184.146952 -124.031756) (xy 184.147448 -124.02165) (xy 184.155191 -124.00298) (xy 184.169484 -123.988689)
			(xy 184.188154 -123.980947) (xy 184.19826 -123.980448) (xy 185.379614 -123.980448) (xy 185.389743 -123.980916)
			(xy 185.408465 -123.988649) (xy 185.422821 -124.002942) (xy 185.430639 -124.02163) (xy 185.431176 -124.031756)
			(xy 185.431176 -125.038104) (xy 188.6839 -125.038104) (xy 188.6839 -124.031756) (xy 188.684349 -124.021644)
			(xy 188.692101 -124.002965) (xy 188.706409 -123.988672) (xy 188.725096 -123.980939) (xy 188.735208 -123.980448)
			(xy 189.916308 -123.980448) (xy 189.926411 -123.980977) (xy 189.945079 -123.988708) (xy 189.959372 -124.002991)
			(xy 189.967115 -124.021654) (xy 189.967616 -124.031756) (xy 189.967616 -125.038104) (xy 189.967118 -125.048211)
			(xy 189.959382 -125.066886) (xy 189.94509 -125.08118) (xy 189.926415 -125.088918) (xy 189.916308 -125.089412)
			(xy 188.735208 -125.089412) (xy 188.725088 -125.088978) (xy 188.706386 -125.081234) (xy 188.692072 -125.066924)
			(xy 188.684325 -125.048224) (xy 188.6839 -125.038104) (xy 185.431176 -125.038104) (xy 185.430787 -125.04823)
			(xy 185.423033 -125.066938) (xy 185.408708 -125.081253) (xy 185.389994 -125.088994) (xy 185.379868 -125.089412)
			(xy 184.198514 -125.089412) (xy 184.188395 -125.088864) (xy 184.169684 -125.08115) (xy 184.155329 -125.066883)
			(xy 184.1475 -125.04822) (xy 184.146952 -125.038104) (xy 181.755002 -125.038104) (xy 181.752563 -125.056628)
			(xy 181.73705 -125.114521) (xy 181.730196 -125.131068) (xy 198.341488 -125.131068) (xy 198.341488 -124.888244)
			(xy 198.46036 -124.706888) (xy 198.522844 -124.611384) (xy 198.546974 -124.574554) (xy 198.550836 -124.568223)
			(xy 198.555099 -124.554026) (xy 198.555356 -124.546614) (xy 198.555356 -124.520706) (xy 198.555162 -124.514556)
			(xy 198.552209 -124.502615) (xy 198.549514 -124.497084) (xy 198.435976 -124.323094) (xy 198.41591 -124.292106)
			(xy 198.410322 -124.28347) (xy 198.34987 -124.19076) (xy 198.349362 -124.189998) (xy 198.348854 -124.189236)
			(xy 198.3486 -124.188728) (xy 198.348092 -124.187966) (xy 198.341488 -124.177552) (xy 198.341488 -123.934728)
			(xy 198.342117 -123.923176) (xy 198.352089 -123.90233) (xy 198.370032 -123.887769) (xy 198.381112 -123.884436)
			(xy 198.39305 -123.882912) (xy 199.12965 -123.882912) (xy 199.140405 -123.883449) (xy 199.160095 -123.892103)
			(xy 199.16775 -123.899676) (xy 199.173954 -123.907071) (xy 199.180865 -123.925081) (xy 199.181212 -123.934728)
			(xy 199.181212 -124.177552) (xy 198.965312 -124.508006) (xy 198.961263 -124.516216) (xy 198.958728 -124.534334)
			(xy 198.962685 -124.552195) (xy 198.967344 -124.560076) (xy 198.999602 -124.60986) (xy 199.181212 -124.886974)
			(xy 199.181212 -124.965714) (xy 199.81672 -124.965714) (xy 199.81672 -124.102114) (xy 199.81721 -124.072146)
			(xy 199.825033 -124.012724) (xy 199.840546 -123.954831) (xy 199.863482 -123.899458) (xy 199.893449 -123.847552)
			(xy 199.929936 -123.800002) (xy 199.972316 -123.757622) (xy 200.019866 -123.721135) (xy 200.071772 -123.691168)
			(xy 200.127145 -123.668232) (xy 200.185038 -123.652719) (xy 200.24446 -123.644896) (xy 200.304396 -123.644896)
			(xy 200.363818 -123.652719) (xy 200.421711 -123.668232) (xy 200.469049 -123.68784) (xy 266.86764 -123.68784)
			(xy 266.86764 -122.82424) (xy 266.86813 -122.794256) (xy 266.875958 -122.7348) (xy 266.891479 -122.676875)
			(xy 266.914428 -122.621471) (xy 266.944412 -122.569537) (xy 266.980918 -122.521961) (xy 267.023323 -122.479556)
			(xy 267.070899 -122.44305) (xy 267.122833 -122.413066) (xy 267.178237 -122.390117) (xy 267.236162 -122.374596)
			(xy 267.295618 -122.366768) (xy 267.355586 -122.366768) (xy 267.415042 -122.374596) (xy 267.472967 -122.390117)
			(xy 267.528371 -122.413066) (xy 267.580305 -122.44305) (xy 267.627881 -122.479556) (xy 267.670286 -122.521961)
			(xy 267.706792 -122.569537) (xy 267.736776 -122.621471) (xy 267.759725 -122.676875) (xy 267.775246 -122.7348)
			(xy 267.783074 -122.794256) (xy 267.783564 -122.82424) (xy 267.783564 -123.68784) (xy 267.783074 -123.717824)
			(xy 267.775246 -123.77728) (xy 267.759725 -123.835205) (xy 267.752274 -123.853194) (xy 268.418564 -123.853194)
			(xy 268.418564 -123.61037) (xy 268.537436 -123.429014) (xy 268.59992 -123.33351) (xy 268.62405 -123.29668)
			(xy 268.627938 -123.290363) (xy 268.632186 -123.276155) (xy 268.632432 -123.26874) (xy 268.632432 -123.242832)
			(xy 268.632232 -123.236683) (xy 268.629283 -123.224742) (xy 268.62659 -123.21921) (xy 268.513052 -123.04522)
			(xy 268.492986 -123.014232) (xy 268.487398 -123.005596) (xy 268.426946 -122.912886) (xy 268.426438 -122.912124)
			(xy 268.42593 -122.911362) (xy 268.425676 -122.910854) (xy 268.425168 -122.910092) (xy 268.418564 -122.899678)
			(xy 268.418564 -122.656854) (xy 268.418996 -122.64669) (xy 268.426791 -122.627915) (xy 268.441175 -122.61355)
			(xy 268.459961 -122.605782) (xy 268.470126 -122.605292) (xy 269.206726 -122.605292) (xy 269.21688 -122.605811)
			(xy 269.235641 -122.613585) (xy 269.250004 -122.627942) (xy 269.257785 -122.6467) (xy 269.258288 -122.656854)
			(xy 269.258288 -122.899678) (xy 269.042388 -123.230132) (xy 269.038401 -123.238367) (xy 269.035846 -123.256468)
			(xy 269.039776 -123.274321) (xy 269.04442 -123.282202) (xy 269.076678 -123.331986) (xy 269.258288 -123.6091)
			(xy 269.258288 -123.758452) (xy 277.63216 -123.758452) (xy 277.63216 -122.752104) (xy 277.632687 -122.742)
			(xy 277.640416 -122.72333) (xy 277.6547 -122.709037) (xy 277.673365 -122.701295) (xy 277.683468 -122.700796)
			(xy 278.864568 -122.700796) (xy 278.874688 -122.701242) (xy 278.89339 -122.708979) (xy 278.907706 -122.723286)
			(xy 278.915453 -122.741984) (xy 278.915876 -122.752104) (xy 278.915876 -123.758452) (xy 282.1686 -123.758452)
			(xy 282.1686 -122.752104) (xy 282.169019 -122.741982) (xy 282.176766 -122.723278) (xy 282.191082 -122.708964)
			(xy 282.209786 -122.701219) (xy 282.219908 -122.700796) (xy 283.401262 -122.700796) (xy 283.411381 -122.701357)
			(xy 283.430093 -122.709064) (xy 283.444449 -122.723327) (xy 283.452277 -122.741989) (xy 283.452824 -122.752104)
			(xy 283.452824 -123.686316) (xy 285.8389 -123.686316) (xy 285.8389 -122.822716) (xy 285.83939 -122.792732)
			(xy 285.847218 -122.733276) (xy 285.862739 -122.675351) (xy 285.885688 -122.619947) (xy 285.915672 -122.568013)
			(xy 285.952178 -122.520437) (xy 285.994583 -122.478032) (xy 286.042159 -122.441526) (xy 286.094093 -122.411542)
			(xy 286.149497 -122.388593) (xy 286.207422 -122.373072) (xy 286.266878 -122.365244) (xy 286.326846 -122.365244)
			(xy 286.386302 -122.373072) (xy 286.444227 -122.388593) (xy 286.499631 -122.411542) (xy 286.551565 -122.441526)
			(xy 286.599141 -122.478032) (xy 286.641546 -122.520437) (xy 286.678052 -122.568013) (xy 286.708036 -122.619947)
			(xy 286.730985 -122.675351) (xy 286.746506 -122.733276) (xy 286.754334 -122.792732) (xy 286.754824 -122.822716)
			(xy 286.754824 -123.16714) (xy 298.799504 -123.16714) (xy 298.799504 -122.30354) (xy 298.799994 -122.273572)
			(xy 298.807817 -122.21415) (xy 298.82333 -122.156257) (xy 298.846266 -122.100884) (xy 298.876233 -122.048978)
			(xy 298.91272 -122.001428) (xy 298.9551 -121.959048) (xy 299.00265 -121.922561) (xy 299.054556 -121.892594)
			(xy 299.109929 -121.869658) (xy 299.167822 -121.854145) (xy 299.227244 -121.846322) (xy 299.28718 -121.846322)
			(xy 299.346602 -121.854145) (xy 299.404495 -121.869658) (xy 299.459868 -121.892594) (xy 299.511774 -121.922561)
			(xy 299.559324 -121.959048) (xy 299.601704 -122.001428) (xy 299.638191 -122.048978) (xy 299.668158 -122.100884)
			(xy 299.691094 -122.156257) (xy 299.706607 -122.21415) (xy 299.71443 -122.273572) (xy 299.71492 -122.30354)
			(xy 299.71492 -123.16714) (xy 299.71443 -123.197108) (xy 299.709012 -123.23826) (xy 300.247304 -123.23826)
			(xy 300.247304 -122.231912) (xy 300.247726 -122.22179) (xy 300.255471 -122.203086) (xy 300.269786 -122.188771)
			(xy 300.28849 -122.181026) (xy 300.298612 -122.180604) (xy 301.479712 -122.180604) (xy 301.489822 -122.181076)
			(xy 301.508501 -122.188818) (xy 301.522796 -122.203119) (xy 301.530529 -122.221802) (xy 301.53102 -122.231912)
			(xy 301.53102 -123.23826) (xy 304.783744 -123.23826) (xy 304.783744 -122.231912) (xy 304.78423 -122.221766)
			(xy 304.792011 -122.203024) (xy 304.806387 -122.188702) (xy 304.825158 -122.180992) (xy 304.835306 -122.180604)
			(xy 306.016406 -122.180604) (xy 306.026529 -122.181121) (xy 306.045243 -122.188844) (xy 306.059598 -122.20312)
			(xy 306.067423 -122.221792) (xy 306.067968 -122.231912) (xy 306.067968 -123.23826) (xy 306.067545 -123.248415)
			(xy 306.059757 -123.267173) (xy 306.045359 -123.281499) (xy 306.026563 -123.289194) (xy 306.016406 -123.289568)
			(xy 304.835306 -123.289568) (xy 304.825181 -123.289069) (xy 304.806461 -123.281344) (xy 304.792105 -123.267062)
			(xy 304.784284 -123.248383) (xy 304.783744 -123.23826) (xy 301.53102 -123.23826) (xy 301.530552 -123.248377)
			(xy 301.52282 -123.267076) (xy 301.50852 -123.281391) (xy 301.489829 -123.289141) (xy 301.479712 -123.289568)
			(xy 300.298612 -123.289568) (xy 300.288486 -123.289173) (xy 300.269777 -123.281423) (xy 300.255461 -123.2671)
			(xy 300.247721 -123.248386) (xy 300.247304 -123.23826) (xy 299.709012 -123.23826) (xy 299.706607 -123.25653)
			(xy 299.691094 -123.314423) (xy 299.68687 -123.32462) (xy 311.799224 -123.32462) (xy 311.799224 -123.097036)
			(xy 311.799478 -123.092972) (xy 311.799732 -123.090432) (xy 311.799732 -123.081796) (xy 311.80532 -123.07316)
			(xy 311.80659 -123.071128) (xy 311.807606 -123.069096) (xy 312.004964 -122.768106) (xy 312.008843 -122.761784)
			(xy 312.013096 -122.74758) (xy 312.013346 -122.740166) (xy 312.013346 -122.714512) (xy 312.013155 -122.707177)
			(xy 312.009015 -122.693106) (xy 312.005218 -122.686826) (xy 311.807352 -122.383804) (xy 311.805066 -122.379994)
			(xy 311.804812 -122.379486) (xy 311.803796 -122.377708) (xy 311.799732 -122.371104) (xy 311.799732 -122.362976)
			(xy 311.799478 -122.360436) (xy 311.799224 -122.356372) (xy 311.799224 -122.12828) (xy 311.799597 -122.118052)
			(xy 311.807434 -122.099157) (xy 311.821907 -122.0847) (xy 311.840812 -122.076885) (xy 311.85104 -122.076464)
			(xy 312.58764 -122.076464) (xy 312.597848 -122.076949) (xy 312.616707 -122.084771) (xy 312.63114 -122.09921)
			(xy 312.638955 -122.118072) (xy 312.639456 -122.12828) (xy 312.639456 -122.355864) (xy 312.639202 -122.359928)
			(xy 312.638948 -122.362468) (xy 312.638948 -122.371104) (xy 312.633106 -122.380502) (xy 312.632344 -122.381772)
			(xy 312.631074 -122.383804) (xy 312.425334 -122.69851) (xy 312.420325 -122.707053) (xy 312.416497 -122.726458)
			(xy 312.420294 -122.745869) (xy 312.425334 -122.75439) (xy 312.631074 -123.067826) (xy 312.63209 -123.069858)
			(xy 312.63336 -123.07189) (xy 312.638948 -123.080526) (xy 312.638948 -123.089162) (xy 312.639202 -123.091702)
			(xy 312.639456 -123.095766) (xy 312.639456 -123.159266) (xy 313.274456 -123.159266) (xy 313.274456 -122.295666)
			(xy 313.274946 -122.265698) (xy 313.282769 -122.206276) (xy 313.298282 -122.148383) (xy 313.321218 -122.09301)
			(xy 313.351185 -122.041104) (xy 313.387672 -121.993554) (xy 313.430052 -121.951174) (xy 313.477602 -121.914687)
			(xy 313.529508 -121.88472) (xy 313.584881 -121.861784) (xy 313.642774 -121.846271) (xy 313.702196 -121.838448)
			(xy 313.762132 -121.838448) (xy 313.821554 -121.846271) (xy 313.879447 -121.861784) (xy 313.93482 -121.88472)
			(xy 313.951493 -121.894346) (xy 385.6101 -121.894346) (xy 385.6101 -121.030746) (xy 385.61059 -121.000778)
			(xy 385.618413 -120.941356) (xy 385.633926 -120.883463) (xy 385.656862 -120.82809) (xy 385.686829 -120.776184)
			(xy 385.723316 -120.728634) (xy 385.765696 -120.686254) (xy 385.813246 -120.649767) (xy 385.865152 -120.6198)
			(xy 385.920525 -120.596864) (xy 385.978418 -120.581351) (xy 386.03784 -120.573528) (xy 386.097776 -120.573528)
			(xy 386.157198 -120.581351) (xy 386.215091 -120.596864) (xy 386.270464 -120.6198) (xy 386.32237 -120.649767)
			(xy 386.36992 -120.686254) (xy 386.4123 -120.728634) (xy 386.448787 -120.776184) (xy 386.478754 -120.82809)
			(xy 386.50169 -120.883463) (xy 386.517203 -120.941356) (xy 386.525026 -121.000778) (xy 386.525516 -121.030746)
			(xy 386.525516 -121.894346) (xy 386.525026 -121.924314) (xy 386.517203 -121.983736) (xy 386.50169 -122.041629)
			(xy 386.494205 -122.0597) (xy 387.160516 -122.0597) (xy 387.160516 -121.832116) (xy 387.16077 -121.828052)
			(xy 387.161024 -121.825512) (xy 387.161024 -121.816876) (xy 387.166612 -121.80824) (xy 387.167882 -121.806208)
			(xy 387.168898 -121.804176) (xy 387.366256 -121.503186) (xy 387.370142 -121.496868) (xy 387.374391 -121.482661)
			(xy 387.374638 -121.475246) (xy 387.374638 -121.449592) (xy 387.374457 -121.442256) (xy 387.37031 -121.428185)
			(xy 387.36651 -121.421906) (xy 387.168644 -121.118884) (xy 387.166358 -121.115074) (xy 387.166104 -121.114566)
			(xy 387.165088 -121.112788) (xy 387.161024 -121.106184) (xy 387.161024 -121.098056) (xy 387.16077 -121.095516)
			(xy 387.160516 -121.091452) (xy 387.160516 -120.86336) (xy 387.16095 -120.853146) (xy 387.168782 -120.834277)
			(xy 387.183238 -120.819841) (xy 387.202117 -120.812036) (xy 387.212332 -120.811544) (xy 387.948932 -120.811544)
			(xy 387.959137 -120.812055) (xy 387.977992 -120.81987) (xy 387.992425 -120.834302) (xy 388.000244 -120.853155)
			(xy 388.000748 -120.86336) (xy 388.000748 -121.090944) (xy 388.000494 -121.095008) (xy 388.00024 -121.097548)
			(xy 388.00024 -121.106184) (xy 387.994398 -121.115582) (xy 387.993636 -121.116852) (xy 387.992366 -121.118884)
			(xy 387.786626 -121.43359) (xy 387.781543 -121.442096) (xy 387.77773 -121.461525) (xy 387.781562 -121.48095)
			(xy 387.786626 -121.48947) (xy 387.992366 -121.802906) (xy 387.993382 -121.804938) (xy 387.994652 -121.80697)
			(xy 388.00024 -121.815606) (xy 388.00024 -121.824242) (xy 388.000494 -121.826782) (xy 388.000748 -121.830846)
			(xy 388.000748 -121.958354) (xy 393.732004 -121.958354) (xy 393.732004 -120.952006) (xy 393.732537 -120.941853)
			(xy 393.740304 -120.92309) (xy 393.754657 -120.908726) (xy 393.773413 -120.900945) (xy 393.783566 -120.900444)
			(xy 394.964666 -120.900444) (xy 394.974836 -120.900892) (xy 394.993631 -120.908667) (xy 395.008017 -120.923045)
			(xy 395.015803 -120.941836) (xy 395.016228 -120.952006) (xy 395.016228 -121.958354) (xy 395.016217 -121.958608)
			(xy 398.268952 -121.958608) (xy 398.268952 -120.952006) (xy 398.269432 -120.941878) (xy 398.27716 -120.923155)
			(xy 398.291448 -120.908798) (xy 398.310135 -120.900981) (xy 398.32026 -120.900444) (xy 399.50136 -120.900444)
			(xy 399.511459 -120.901017) (xy 399.530126 -120.908731) (xy 399.54442 -120.923) (xy 399.552166 -120.941654)
			(xy 399.552668 -120.951752) (xy 399.552668 -121.886472) (xy 400.085052 -121.886472) (xy 400.085052 -121.022872)
			(xy 400.085542 -120.992904) (xy 400.093365 -120.933482) (xy 400.108878 -120.875589) (xy 400.131814 -120.820216)
			(xy 400.161781 -120.76831) (xy 400.198268 -120.72076) (xy 400.240648 -120.67838) (xy 400.288198 -120.641893)
			(xy 400.340104 -120.611926) (xy 400.395477 -120.58899) (xy 400.45337 -120.573477) (xy 400.512792 -120.565654)
			(xy 400.572728 -120.565654) (xy 400.63215 -120.573477) (xy 400.690043 -120.58899) (xy 400.745416 -120.611926)
			(xy 400.797322 -120.641893) (xy 400.844872 -120.67838) (xy 400.887252 -120.72076) (xy 400.923739 -120.76831)
			(xy 400.953706 -120.820216) (xy 400.976642 -120.875589) (xy 400.992155 -120.933482) (xy 400.999978 -120.992904)
			(xy 401.000468 -121.022872) (xy 401.000468 -121.367296) (xy 413.045148 -121.367296) (xy 413.045148 -120.503696)
			(xy 413.045638 -120.473712) (xy 413.053466 -120.414256) (xy 413.068987 -120.356331) (xy 413.091936 -120.300927)
			(xy 413.12192 -120.248993) (xy 413.158426 -120.201417) (xy 413.200831 -120.159012) (xy 413.248407 -120.122506)
			(xy 413.300341 -120.092522) (xy 413.355745 -120.069573) (xy 413.41367 -120.054052) (xy 413.473126 -120.046224)
			(xy 413.533094 -120.046224) (xy 413.59255 -120.054052) (xy 413.650475 -120.069573) (xy 413.705879 -120.092522)
			(xy 413.757813 -120.122506) (xy 413.805389 -120.159012) (xy 413.847794 -120.201417) (xy 413.8843 -120.248993)
			(xy 413.914284 -120.300927) (xy 413.937233 -120.356331) (xy 413.952754 -120.414256) (xy 413.960582 -120.473712)
			(xy 413.961072 -120.503696) (xy 413.961072 -121.367296) (xy 413.960582 -121.39728) (xy 413.955199 -121.438162)
			(xy 416.347148 -121.438162) (xy 416.347148 -120.431814) (xy 416.347575 -120.421642) (xy 416.355358 -120.402846)
			(xy 416.369742 -120.38846) (xy 416.388538 -120.380676) (xy 416.39871 -120.380252) (xy 417.57981 -120.380252)
			(xy 417.589984 -120.380656) (xy 417.608782 -120.388447) (xy 417.623167 -120.402839) (xy 417.630949 -120.42164)
			(xy 417.631372 -120.431814) (xy 417.631372 -121.438162) (xy 420.884096 -121.438162) (xy 420.884096 -120.431814)
			(xy 420.884637 -120.421694) (xy 420.892352 -120.402981) (xy 420.906621 -120.388626) (xy 420.925287 -120.380798)
			(xy 420.935404 -120.380252) (xy 422.116504 -120.380252) (xy 422.126652 -120.380717) (xy 422.145396 -120.388505)
			(xy 422.159717 -120.402888) (xy 422.167425 -120.421664) (xy 422.167812 -120.431814) (xy 422.167812 -121.438162)
			(xy 422.167244 -121.44828) (xy 422.159538 -121.46699) (xy 422.145277 -121.481346) (xy 422.126618 -121.489176)
			(xy 422.116504 -121.489724) (xy 420.935404 -121.489724) (xy 420.925253 -121.489276) (xy 420.906505 -121.481486)
			(xy 420.892183 -121.467098) (xy 420.884479 -121.448315) (xy 420.884096 -121.438162) (xy 417.631372 -121.438162)
			(xy 417.630905 -121.44833) (xy 417.623135 -121.467122) (xy 417.608762 -121.481508) (xy 417.589977 -121.489296)
			(xy 417.57981 -121.489724) (xy 416.39871 -121.489724) (xy 416.388534 -121.489327) (xy 416.369733 -121.481538)
			(xy 416.355346 -121.467144) (xy 416.347567 -121.448338) (xy 416.347148 -121.438162) (xy 413.955199 -121.438162)
			(xy 413.952754 -121.456736) (xy 413.937233 -121.514661) (xy 413.930413 -121.531126) (xy 430.541684 -121.531126)
			(xy 430.541684 -121.288302) (xy 430.660556 -121.106946) (xy 430.72304 -121.011442) (xy 430.74717 -120.974612)
			(xy 430.751048 -120.968289) (xy 430.755301 -120.954086) (xy 430.755552 -120.946672) (xy 430.755552 -120.920764)
			(xy 430.755373 -120.914613) (xy 430.75241 -120.902672) (xy 430.74971 -120.897142) (xy 430.636172 -120.723152)
			(xy 430.616106 -120.692164) (xy 430.610518 -120.683528) (xy 430.550066 -120.590818) (xy 430.549558 -120.590056)
			(xy 430.54905 -120.589294) (xy 430.548796 -120.588786) (xy 430.548288 -120.588024) (xy 430.541684 -120.57761)
			(xy 430.541684 -120.334786) (xy 430.542054 -120.324608) (xy 430.549852 -120.305804) (xy 430.564254 -120.291418)
			(xy 430.583067 -120.283642) (xy 430.593246 -120.283224) (xy 431.329846 -120.283224) (xy 431.340005 -120.283695)
			(xy 431.358772 -120.291482) (xy 431.373136 -120.305854) (xy 431.380911 -120.324627) (xy 431.381408 -120.334786)
			(xy 431.381408 -120.57761) (xy 431.165508 -120.908064) (xy 431.161493 -120.916288) (xy 431.158946 -120.934396)
			(xy 431.162889 -120.952253) (xy 431.16754 -120.960134) (xy 431.199798 -121.009918) (xy 431.381408 -121.287032)
			(xy 431.381408 -121.365772) (xy 432.016408 -121.365772) (xy 432.016408 -120.502172) (xy 432.016898 -120.472188)
			(xy 432.024726 -120.412732) (xy 432.040247 -120.354807) (xy 432.063196 -120.299403) (xy 432.09318 -120.247469)
			(xy 432.129686 -120.199893) (xy 432.172091 -120.157488) (xy 432.219667 -120.120982) (xy 432.271601 -120.090998)
			(xy 432.327005 -120.068049) (xy 432.38493 -120.052528) (xy 432.444386 -120.0447) (xy 432.504354 -120.0447)
			(xy 432.56381 -120.052528) (xy 432.621735 -120.068049) (xy 432.677139 -120.090998) (xy 432.729073 -120.120982)
			(xy 432.776649 -120.157488) (xy 432.819054 -120.199893) (xy 432.85556 -120.247469) (xy 432.885544 -120.299403)
			(xy 432.908493 -120.354807) (xy 432.924014 -120.412732) (xy 432.931842 -120.472188) (xy 432.932332 -120.502172)
			(xy 432.932332 -121.365772) (xy 432.931842 -121.395756) (xy 432.924014 -121.455212) (xy 432.908493 -121.513137)
			(xy 432.885544 -121.568541) (xy 432.85556 -121.620475) (xy 432.819054 -121.668051) (xy 432.776649 -121.710456)
			(xy 432.729073 -121.746962) (xy 432.677139 -121.776946) (xy 432.621735 -121.799895) (xy 432.56381 -121.815416)
			(xy 432.504354 -121.823244) (xy 432.444386 -121.823244) (xy 432.38493 -121.815416) (xy 432.327005 -121.799895)
			(xy 432.271601 -121.776946) (xy 432.219667 -121.746962) (xy 432.172091 -121.710456) (xy 432.129686 -121.668051)
			(xy 432.09318 -121.620475) (xy 432.063196 -121.568541) (xy 432.040247 -121.513137) (xy 432.024726 -121.455212)
			(xy 432.016898 -121.395756) (xy 432.016408 -121.365772) (xy 431.381408 -121.365772) (xy 431.381408 -121.531126)
			(xy 431.380889 -121.54128) (xy 431.373115 -121.560041) (xy 431.358758 -121.574404) (xy 431.34 -121.582185)
			(xy 431.329846 -121.582688) (xy 430.593246 -121.582688) (xy 430.583081 -121.582199) (xy 430.564292 -121.574434)
			(xy 430.549906 -121.560069) (xy 430.542115 -121.541291) (xy 430.541684 -121.531126) (xy 413.930413 -121.531126)
			(xy 413.914284 -121.570065) (xy 413.8843 -121.621999) (xy 413.847794 -121.669575) (xy 413.805389 -121.71198)
			(xy 413.757813 -121.748486) (xy 413.705879 -121.77847) (xy 413.650475 -121.801419) (xy 413.59255 -121.81694)
			(xy 413.533094 -121.824768) (xy 413.473126 -121.824768) (xy 413.41367 -121.81694) (xy 413.355745 -121.801419)
			(xy 413.300341 -121.77847) (xy 413.248407 -121.748486) (xy 413.200831 -121.71198) (xy 413.158426 -121.669575)
			(xy 413.12192 -121.621999) (xy 413.091936 -121.570065) (xy 413.068987 -121.514661) (xy 413.053466 -121.456736)
			(xy 413.045638 -121.39728) (xy 413.045148 -121.367296) (xy 401.000468 -121.367296) (xy 401.000468 -121.886472)
			(xy 400.999978 -121.91644) (xy 400.992155 -121.975862) (xy 400.976642 -122.033755) (xy 400.953706 -122.089128)
			(xy 400.923739 -122.141034) (xy 400.887252 -122.188584) (xy 400.844872 -122.230964) (xy 400.797322 -122.267451)
			(xy 400.745416 -122.297418) (xy 400.690043 -122.320354) (xy 400.63215 -122.335867) (xy 400.572728 -122.34369)
			(xy 400.512792 -122.34369) (xy 400.45337 -122.335867) (xy 400.395477 -122.320354) (xy 400.340104 -122.297418)
			(xy 400.288198 -122.267451) (xy 400.240648 -122.230964) (xy 400.198268 -122.188584) (xy 400.161781 -122.141034)
			(xy 400.131814 -122.089128) (xy 400.108878 -122.033755) (xy 400.093365 -121.975862) (xy 400.085542 -121.91644)
			(xy 400.085052 -121.886472) (xy 399.552668 -121.886472) (xy 399.552668 -121.958354) (xy 399.552136 -121.968477)
			(xy 399.544425 -121.987195) (xy 399.530152 -122.001553) (xy 399.51148 -122.009375) (xy 399.50136 -122.009916)
			(xy 398.32026 -122.009916) (xy 398.310151 -122.009448) (xy 398.291475 -122.0017) (xy 398.277182 -121.987398)
			(xy 398.269446 -121.968718) (xy 398.268952 -121.958608) (xy 395.016217 -121.958608) (xy 395.015798 -121.968527)
			(xy 395.008021 -121.987327) (xy 394.993637 -122.001715) (xy 394.974839 -122.009495) (xy 394.964666 -122.009916)
			(xy 393.783566 -122.009916) (xy 393.773386 -122.009563) (xy 393.754582 -122.001758) (xy 393.740197 -121.987351)
			(xy 393.732421 -121.968534) (xy 393.732004 -121.958354) (xy 388.000748 -121.958354) (xy 388.000748 -122.0597)
			(xy 388.000219 -122.069904) (xy 387.992412 -122.088759) (xy 387.977986 -122.103194) (xy 387.959136 -122.111013)
			(xy 387.948932 -122.111516) (xy 387.212332 -122.111516) (xy 387.202112 -122.111062) (xy 387.183226 -122.103249)
			(xy 387.168769 -122.088801) (xy 387.160944 -122.069919) (xy 387.160516 -122.0597) (xy 386.494205 -122.0597)
			(xy 386.478754 -122.097002) (xy 386.448787 -122.148908) (xy 386.4123 -122.196458) (xy 386.36992 -122.238838)
			(xy 386.32237 -122.275325) (xy 386.270464 -122.305292) (xy 386.215091 -122.328228) (xy 386.157198 -122.343741)
			(xy 386.097776 -122.351564) (xy 386.03784 -122.351564) (xy 385.978418 -122.343741) (xy 385.920525 -122.328228)
			(xy 385.865152 -122.305292) (xy 385.813246 -122.275325) (xy 385.765696 -122.238838) (xy 385.723316 -122.196458)
			(xy 385.686829 -122.148908) (xy 385.656862 -122.097002) (xy 385.633926 -122.041629) (xy 385.618413 -121.983736)
			(xy 385.61059 -121.924314) (xy 385.6101 -121.894346) (xy 313.951493 -121.894346) (xy 313.986726 -121.914687)
			(xy 314.034276 -121.951174) (xy 314.076656 -121.993554) (xy 314.113143 -122.041104) (xy 314.14311 -122.09301)
			(xy 314.166046 -122.148383) (xy 314.181559 -122.206276) (xy 314.189382 -122.265698) (xy 314.189872 -122.295666)
			(xy 314.189872 -123.159266) (xy 314.189382 -123.189234) (xy 314.181559 -123.248656) (xy 314.166046 -123.306549)
			(xy 314.14311 -123.361922) (xy 314.113143 -123.413828) (xy 314.076656 -123.461378) (xy 314.034276 -123.503758)
			(xy 313.986726 -123.540245) (xy 313.93482 -123.570212) (xy 313.879447 -123.593148) (xy 313.821554 -123.608661)
			(xy 313.762132 -123.616484) (xy 313.702196 -123.616484) (xy 313.642774 -123.608661) (xy 313.584881 -123.593148)
			(xy 313.529508 -123.570212) (xy 313.477602 -123.540245) (xy 313.430052 -123.503758) (xy 313.387672 -123.461378)
			(xy 313.351185 -123.413828) (xy 313.321218 -123.361922) (xy 313.298282 -123.306549) (xy 313.282769 -123.248656)
			(xy 313.274946 -123.189234) (xy 313.274456 -123.159266) (xy 312.639456 -123.159266) (xy 312.639456 -123.32462)
			(xy 312.638936 -123.334824) (xy 312.631124 -123.353679) (xy 312.616695 -123.368113) (xy 312.597844 -123.375932)
			(xy 312.58764 -123.376436) (xy 311.85104 -123.376436) (xy 311.840823 -123.375956) (xy 311.821941 -123.368149)
			(xy 311.807484 -123.35371) (xy 311.799656 -123.334836) (xy 311.799224 -123.32462) (xy 299.68687 -123.32462)
			(xy 299.668158 -123.369796) (xy 299.638191 -123.421702) (xy 299.601704 -123.469252) (xy 299.559324 -123.511632)
			(xy 299.511774 -123.548119) (xy 299.459868 -123.578086) (xy 299.404495 -123.601022) (xy 299.346602 -123.616535)
			(xy 299.28718 -123.624358) (xy 299.227244 -123.624358) (xy 299.167822 -123.616535) (xy 299.109929 -123.601022)
			(xy 299.054556 -123.578086) (xy 299.00265 -123.548119) (xy 298.9551 -123.511632) (xy 298.91272 -123.469252)
			(xy 298.876233 -123.421702) (xy 298.846266 -123.369796) (xy 298.82333 -123.314423) (xy 298.807817 -123.25653)
			(xy 298.799994 -123.197108) (xy 298.799504 -123.16714) (xy 286.754824 -123.16714) (xy 286.754824 -123.686316)
			(xy 286.754334 -123.7163) (xy 286.746506 -123.775756) (xy 286.730985 -123.833681) (xy 286.708036 -123.889085)
			(xy 286.678052 -123.941019) (xy 286.641546 -123.988595) (xy 286.599141 -124.031) (xy 286.551565 -124.067506)
			(xy 286.499631 -124.09749) (xy 286.444227 -124.120439) (xy 286.386302 -124.13596) (xy 286.326846 -124.143788)
			(xy 286.266878 -124.143788) (xy 286.207422 -124.13596) (xy 286.149497 -124.120439) (xy 286.094093 -124.09749)
			(xy 286.042159 -124.067506) (xy 285.994583 -124.031) (xy 285.952178 -123.988595) (xy 285.915672 -123.941019)
			(xy 285.885688 -123.889085) (xy 285.862739 -123.833681) (xy 285.847218 -123.775756) (xy 285.83939 -123.7163)
			(xy 285.8389 -123.686316) (xy 283.452824 -123.686316) (xy 283.452824 -123.758452) (xy 283.452345 -123.768568)
			(xy 283.444617 -123.787266) (xy 283.43032 -123.801581) (xy 283.411632 -123.809333) (xy 283.401516 -123.80976)
			(xy 282.220162 -123.80976) (xy 282.210033 -123.809305) (xy 282.191311 -123.801564) (xy 282.176956 -123.787269)
			(xy 282.169138 -123.768579) (xy 282.1686 -123.758452) (xy 278.915876 -123.758452) (xy 278.915444 -123.768574)
			(xy 278.907707 -123.787281) (xy 278.893395 -123.801598) (xy 278.87469 -123.809341) (xy 278.864568 -123.80976)
			(xy 277.683468 -123.80976) (xy 277.673338 -123.809409) (xy 277.654626 -123.801643) (xy 277.640312 -123.787306)
			(xy 277.632575 -123.768582) (xy 277.63216 -123.758452) (xy 269.258288 -123.758452) (xy 269.258288 -123.853194)
			(xy 269.257762 -123.863348) (xy 269.249995 -123.882112) (xy 269.235639 -123.896477) (xy 269.21688 -123.904256)
			(xy 269.206726 -123.904756) (xy 268.470126 -123.904756) (xy 268.459955 -123.904315) (xy 268.44116 -123.896537)
			(xy 268.426774 -123.882157) (xy 268.418989 -123.863364) (xy 268.418564 -123.853194) (xy 267.752274 -123.853194)
			(xy 267.736776 -123.890609) (xy 267.706792 -123.942543) (xy 267.670286 -123.990119) (xy 267.627881 -124.032524)
			(xy 267.580305 -124.06903) (xy 267.528371 -124.099014) (xy 267.472967 -124.121963) (xy 267.415042 -124.137484)
			(xy 267.355586 -124.145312) (xy 267.295618 -124.145312) (xy 267.236162 -124.137484) (xy 267.178237 -124.121963)
			(xy 267.122833 -124.099014) (xy 267.070899 -124.06903) (xy 267.023323 -124.032524) (xy 266.980918 -123.990119)
			(xy 266.944412 -123.942543) (xy 266.914428 -123.890609) (xy 266.891479 -123.835205) (xy 266.875958 -123.77728)
			(xy 266.86813 -123.717824) (xy 266.86764 -123.68784) (xy 200.469049 -123.68784) (xy 200.477084 -123.691168)
			(xy 200.52899 -123.721135) (xy 200.57654 -123.757622) (xy 200.61892 -123.800002) (xy 200.655407 -123.847552)
			(xy 200.685374 -123.899458) (xy 200.70831 -123.954831) (xy 200.723823 -124.012724) (xy 200.731646 -124.072146)
			(xy 200.732136 -124.102114) (xy 200.732136 -124.965714) (xy 200.731646 -124.995682) (xy 200.723823 -125.055104)
			(xy 200.70831 -125.112997) (xy 200.685374 -125.16837) (xy 200.655407 -125.220276) (xy 200.61892 -125.267826)
			(xy 200.57654 -125.310206) (xy 200.52899 -125.346693) (xy 200.477084 -125.37666) (xy 200.421711 -125.399596)
			(xy 200.363818 -125.415109) (xy 200.304396 -125.422932) (xy 200.24446 -125.422932) (xy 200.185038 -125.415109)
			(xy 200.127145 -125.399596) (xy 200.071772 -125.37666) (xy 200.019866 -125.346693) (xy 199.972316 -125.310206)
			(xy 199.929936 -125.267826) (xy 199.893449 -125.220276) (xy 199.863482 -125.16837) (xy 199.840546 -125.112997)
			(xy 199.825033 -125.055104) (xy 199.81721 -124.995682) (xy 199.81672 -124.965714) (xy 199.181212 -124.965714)
			(xy 199.181212 -125.131068) (xy 199.18058 -125.14262) (xy 199.17061 -125.163466) (xy 199.152668 -125.178027)
			(xy 199.141588 -125.18136) (xy 199.12965 -125.182884) (xy 198.39305 -125.182884) (xy 198.382294 -125.182348)
			(xy 198.362605 -125.173693) (xy 198.35495 -125.16612) (xy 198.348744 -125.158726) (xy 198.341834 -125.140715)
			(xy 198.341488 -125.131068) (xy 181.730196 -125.131068) (xy 181.714114 -125.169894) (xy 181.684147 -125.2218)
			(xy 181.64766 -125.26935) (xy 181.60528 -125.31173) (xy 181.55773 -125.348217) (xy 181.505824 -125.378184)
			(xy 181.450451 -125.40112) (xy 181.392558 -125.416633) (xy 181.333136 -125.424456) (xy 181.2732 -125.424456)
			(xy 181.213778 -125.416633) (xy 181.155885 -125.40112) (xy 181.100512 -125.378184) (xy 181.048606 -125.348217)
			(xy 181.001056 -125.31173) (xy 180.958676 -125.26935) (xy 180.922189 -125.2218) (xy 180.892222 -125.169894)
			(xy 180.869286 -125.114521) (xy 180.853773 -125.056628) (xy 180.84595 -124.997206) (xy 180.84546 -124.967238)
			(xy 168.80078 -124.967238) (xy 168.80078 -125.486414) (xy 168.800647 -125.494542) (xy 269.509748 -125.494542)
			(xy 269.509748 -124.630942) (xy 269.510238 -124.600958) (xy 269.518066 -124.541502) (xy 269.533587 -124.483577)
			(xy 269.556536 -124.428173) (xy 269.58652 -124.376239) (xy 269.623026 -124.328663) (xy 269.665431 -124.286258)
			(xy 269.713007 -124.249752) (xy 269.764941 -124.219768) (xy 269.820345 -124.196819) (xy 269.87827 -124.181298)
			(xy 269.937726 -124.17347) (xy 269.997694 -124.17347) (xy 270.05715 -124.181298) (xy 270.115075 -124.196819)
			(xy 270.170479 -124.219768) (xy 270.222413 -124.249752) (xy 270.269989 -124.286258) (xy 270.312394 -124.328663)
			(xy 270.3489 -124.376239) (xy 270.378884 -124.428173) (xy 270.401833 -124.483577) (xy 270.417354 -124.541502)
			(xy 270.425182 -124.600958) (xy 270.425672 -124.630942) (xy 270.425672 -125.494542) (xy 270.425182 -125.524526)
			(xy 270.417354 -125.583982) (xy 270.401833 -125.641907) (xy 270.394382 -125.659896) (xy 271.060672 -125.659896)
			(xy 271.060672 -125.417072) (xy 271.179544 -125.235716) (xy 271.242028 -125.140212) (xy 271.266158 -125.103382)
			(xy 271.270046 -125.097065) (xy 271.274293 -125.082857) (xy 271.27454 -125.075442) (xy 271.27454 -125.049534)
			(xy 271.274338 -125.043385) (xy 271.271391 -125.031444) (xy 271.268698 -125.025912) (xy 271.15516 -124.851922)
			(xy 271.135094 -124.820934) (xy 271.129506 -124.812298) (xy 271.069054 -124.719588) (xy 271.068546 -124.718826)
			(xy 271.068038 -124.718064) (xy 271.067784 -124.717556) (xy 271.067276 -124.716794) (xy 271.060672 -124.70638)
			(xy 271.060672 -124.463556) (xy 271.061334 -124.452008) (xy 271.071292 -124.431165) (xy 271.089221 -124.4166)
			(xy 271.100296 -124.413264) (xy 271.112234 -124.41174) (xy 271.848834 -124.41174) (xy 271.85959 -124.412277)
			(xy 271.879279 -124.420931) (xy 271.886934 -124.428504) (xy 271.893148 -124.435892) (xy 271.900054 -124.453907)
			(xy 271.900396 -124.463556) (xy 271.900396 -124.70638) (xy 271.684496 -125.036834) (xy 271.680506 -125.045068)
			(xy 271.677951 -125.06317) (xy 271.681883 -125.081023) (xy 271.686528 -125.088904) (xy 271.718786 -125.138688)
			(xy 271.900396 -125.415802) (xy 271.900396 -125.558296) (xy 277.63216 -125.558296) (xy 277.63216 -124.551948)
			(xy 277.632654 -124.541834) (xy 277.640379 -124.523139) (xy 277.654671 -124.508824) (xy 277.673354 -124.50107)
			(xy 277.683468 -124.50064) (xy 278.864568 -124.50064) (xy 278.874693 -124.501043) (xy 278.893404 -124.508788)
			(xy 278.907721 -124.523109) (xy 278.91546 -124.541822) (xy 278.915876 -124.551948) (xy 278.915876 -125.558296)
			(xy 282.1686 -125.558296) (xy 282.1686 -124.551948) (xy 282.169055 -124.541829) (xy 282.176788 -124.523126)
			(xy 282.191092 -124.50881) (xy 282.209789 -124.501063) (xy 282.219908 -124.50064) (xy 283.401262 -124.50064)
			(xy 283.411386 -124.501158) (xy 283.430106 -124.508873) (xy 283.444464 -124.52315) (xy 283.452285 -124.541827)
			(xy 283.452824 -124.551948) (xy 283.452824 -125.486414) (xy 283.9847 -125.486414) (xy 283.9847 -124.622814)
			(xy 283.98519 -124.59283) (xy 283.993018 -124.533374) (xy 284.008539 -124.475449) (xy 284.031488 -124.420045)
			(xy 284.061472 -124.368111) (xy 284.097978 -124.320535) (xy 284.140383 -124.27813) (xy 284.187959 -124.241624)
			(xy 284.239893 -124.21164) (xy 284.295297 -124.188691) (xy 284.353222 -124.17317) (xy 284.412678 -124.165342)
			(xy 284.472646 -124.165342) (xy 284.532102 -124.17317) (xy 284.590027 -124.188691) (xy 284.645431 -124.21164)
			(xy 284.697365 -124.241624) (xy 284.744941 -124.27813) (xy 284.787346 -124.320535) (xy 284.823852 -124.368111)
			(xy 284.853836 -124.420045) (xy 284.876785 -124.475449) (xy 284.892306 -124.533374) (xy 284.900134 -124.59283)
			(xy 284.900624 -124.622814) (xy 284.900624 -124.967238) (xy 296.945304 -124.967238) (xy 296.945304 -124.103638)
			(xy 296.945794 -124.07367) (xy 296.953617 -124.014248) (xy 296.96913 -123.956355) (xy 296.992066 -123.900982)
			(xy 297.022033 -123.849076) (xy 297.05852 -123.801526) (xy 297.1009 -123.759146) (xy 297.14845 -123.722659)
			(xy 297.200356 -123.692692) (xy 297.255729 -123.669756) (xy 297.313622 -123.654243) (xy 297.373044 -123.64642)
			(xy 297.43298 -123.64642) (xy 297.492402 -123.654243) (xy 297.550295 -123.669756) (xy 297.605668 -123.692692)
			(xy 297.657574 -123.722659) (xy 297.705124 -123.759146) (xy 297.747504 -123.801526) (xy 297.783991 -123.849076)
			(xy 297.813958 -123.900982) (xy 297.836894 -123.956355) (xy 297.852407 -124.014248) (xy 297.86023 -124.07367)
			(xy 297.86072 -124.103638) (xy 297.86072 -124.967238) (xy 297.86023 -124.997206) (xy 297.854846 -125.038104)
			(xy 300.247304 -125.038104) (xy 300.247304 -124.031756) (xy 300.247749 -124.021644) (xy 300.255502 -124.002964)
			(xy 300.269811 -123.988671) (xy 300.288499 -123.980938) (xy 300.298612 -123.980448) (xy 301.479712 -123.980448)
			(xy 301.489815 -123.980974) (xy 301.508483 -123.988706) (xy 301.522776 -124.00299) (xy 301.530519 -124.021653)
			(xy 301.53102 -124.031756) (xy 301.53102 -125.038104) (xy 304.783744 -125.038104) (xy 304.783744 -124.031756)
			(xy 304.784185 -124.021606) (xy 304.791984 -124.002864) (xy 304.806374 -123.988544) (xy 304.825154 -123.980836)
			(xy 304.835306 -123.980448) (xy 306.016406 -123.980448) (xy 306.026534 -123.980922) (xy 306.045257 -123.988653)
			(xy 306.059613 -124.002943) (xy 306.067431 -124.02163) (xy 306.067968 -124.031756) (xy 306.067968 -125.038104)
			(xy 306.067581 -125.048262) (xy 306.059778 -125.067021) (xy 306.04537 -125.081345) (xy 306.026567 -125.089039)
			(xy 306.016406 -125.089412) (xy 304.835306 -125.089412) (xy 304.825186 -125.08887) (xy 304.806475 -125.081154)
			(xy 304.79212 -125.066885) (xy 304.784292 -125.048221) (xy 304.783744 -125.038104) (xy 301.53102 -125.038104)
			(xy 301.530519 -125.04821) (xy 301.522783 -125.066885) (xy 301.508492 -125.081179) (xy 301.489818 -125.088917)
			(xy 301.479712 -125.089412) (xy 300.298612 -125.089412) (xy 300.288492 -125.088975) (xy 300.269791 -125.081233)
			(xy 300.255476 -125.066923) (xy 300.247729 -125.048224) (xy 300.247304 -125.038104) (xy 297.854846 -125.038104)
			(xy 297.852407 -125.056628) (xy 297.836894 -125.114521) (xy 297.83004 -125.131068) (xy 314.441332 -125.131068)
			(xy 314.441332 -124.903484) (xy 314.441586 -124.89942) (xy 314.44184 -124.89688) (xy 314.44184 -124.888244)
			(xy 314.447428 -124.879608) (xy 314.448698 -124.877576) (xy 314.449714 -124.875544) (xy 314.647072 -124.574554)
			(xy 314.650934 -124.568223) (xy 314.655197 -124.554026) (xy 314.655454 -124.546614) (xy 314.655454 -124.52096)
			(xy 314.655242 -124.513626) (xy 314.651116 -124.499555) (xy 314.647326 -124.493274) (xy 314.44946 -124.190252)
			(xy 314.447174 -124.186442) (xy 314.44692 -124.185934) (xy 314.445904 -124.184156) (xy 314.44184 -124.177552)
			(xy 314.44184 -124.169424) (xy 314.441586 -124.166884) (xy 314.441332 -124.16282) (xy 314.441332 -123.934728)
			(xy 314.441736 -123.924502) (xy 314.449559 -123.905606) (xy 314.464023 -123.891148) (xy 314.482922 -123.883332)
			(xy 314.493148 -123.882912) (xy 315.229748 -123.882912) (xy 315.239962 -123.883343) (xy 315.25883 -123.891177)
			(xy 315.273266 -123.905634) (xy 315.281072 -123.924513) (xy 315.281564 -123.934728) (xy 315.281564 -124.162312)
			(xy 315.28131 -124.166376) (xy 315.281056 -124.168916) (xy 315.281056 -124.177552) (xy 315.275214 -124.18695)
			(xy 315.274452 -124.18822) (xy 315.273182 -124.190252) (xy 315.067442 -124.504958) (xy 315.062393 -124.51348)
			(xy 315.058577 -124.532898) (xy 315.062391 -124.552317) (xy 315.067442 -124.560838) (xy 315.273182 -124.874274)
			(xy 315.274198 -124.876306) (xy 315.275468 -124.878338) (xy 315.281056 -124.886974) (xy 315.281056 -124.89561)
			(xy 315.28131 -124.89815) (xy 315.281564 -124.902214) (xy 315.281564 -124.965714) (xy 315.916564 -124.965714)
			(xy 315.916564 -124.102114) (xy 315.917054 -124.072146) (xy 315.924877 -124.012724) (xy 315.94039 -123.954831)
			(xy 315.963326 -123.899458) (xy 315.993293 -123.847552) (xy 316.02978 -123.800002) (xy 316.07216 -123.757622)
			(xy 316.11971 -123.721135) (xy 316.171616 -123.691168) (xy 316.226989 -123.668232) (xy 316.284882 -123.652719)
			(xy 316.344304 -123.644896) (xy 316.40424 -123.644896) (xy 316.463662 -123.652719) (xy 316.521555 -123.668232)
			(xy 316.568893 -123.68784) (xy 382.967992 -123.68784) (xy 382.967992 -122.82424) (xy 382.968482 -122.794272)
			(xy 382.976305 -122.73485) (xy 382.991818 -122.676957) (xy 383.014754 -122.621584) (xy 383.044721 -122.569678)
			(xy 383.081208 -122.522128) (xy 383.123588 -122.479748) (xy 383.171138 -122.443261) (xy 383.223044 -122.413294)
			(xy 383.278417 -122.390358) (xy 383.33631 -122.374845) (xy 383.395732 -122.367022) (xy 383.455668 -122.367022)
			(xy 383.51509 -122.374845) (xy 383.572983 -122.390358) (xy 383.628356 -122.413294) (xy 383.680262 -122.443261)
			(xy 383.727812 -122.479748) (xy 383.770192 -122.522128) (xy 383.806679 -122.569678) (xy 383.836646 -122.621584)
			(xy 383.859582 -122.676957) (xy 383.875095 -122.73485) (xy 383.882918 -122.794272) (xy 383.883408 -122.82424)
			(xy 383.883408 -123.68784) (xy 383.882918 -123.717808) (xy 383.875095 -123.77723) (xy 383.859582 -123.835123)
			(xy 383.852097 -123.853194) (xy 384.518408 -123.853194) (xy 384.518408 -123.61037) (xy 384.523996 -123.601988)
			(xy 384.52425 -123.60148) (xy 384.526282 -123.598432) (xy 384.526536 -123.597924) (xy 384.732276 -123.28398)
			(xy 384.737272 -123.275545) (xy 384.741092 -123.256334) (xy 384.737447 -123.237089) (xy 384.73253 -123.228608)
			(xy 384.646678 -123.096528) (xy 384.63728 -123.08205) (xy 384.525012 -122.910092) (xy 384.524504 -122.909076)
			(xy 384.522472 -122.906028) (xy 384.522218 -122.90552) (xy 384.518408 -122.899678) (xy 384.518408 -122.656854)
			(xy 384.51863 -122.65048) (xy 384.521845 -122.638144) (xy 384.524758 -122.63247) (xy 384.529525 -122.624478)
			(xy 384.543525 -122.612241) (xy 384.560928 -122.605693) (xy 384.570224 -122.605292) (xy 385.306824 -122.605292)
			(xy 385.318348 -122.605889) (xy 385.339171 -122.615772) (xy 385.353754 -122.633621) (xy 385.357116 -122.644662)
			(xy 385.357116 -122.644916) (xy 385.35864 -122.656854) (xy 385.35864 -122.899678) (xy 385.35483 -122.90552)
			(xy 385.354576 -122.906028) (xy 385.350512 -122.912124) (xy 385.350258 -122.912378) (xy 385.212336 -123.123452)
			(xy 385.15925 -123.204732) (xy 385.146804 -123.223782) (xy 385.144772 -123.226576) (xy 385.143502 -123.228608)
			(xy 385.13929 -123.236019) (xy 385.135581 -123.252645) (xy 385.137545 -123.269567) (xy 385.140962 -123.277376)
			(xy 385.32816 -123.562872) (xy 385.3307 -123.566682) (xy 385.350512 -123.596654) (xy 385.350766 -123.597162)
			(xy 385.352036 -123.599194) (xy 385.353814 -123.601734) (xy 385.35864 -123.6091) (xy 385.35864 -123.758452)
			(xy 393.732004 -123.758452) (xy 393.732004 -122.752104) (xy 393.732425 -122.74195) (xy 393.74022 -122.723197)
			(xy 393.754617 -122.708873) (xy 393.77341 -122.701174) (xy 393.783566 -122.700796) (xy 394.964666 -122.700796)
			(xy 394.974785 -122.701353) (xy 394.993497 -122.709062) (xy 395.007853 -122.723326) (xy 395.015681 -122.741988)
			(xy 395.016228 -122.752104) (xy 395.016228 -123.758452) (xy 398.268952 -123.758452) (xy 398.268952 -122.752104)
			(xy 398.269487 -122.742001) (xy 398.277215 -122.723333) (xy 398.291496 -122.709039) (xy 398.310158 -122.701296)
			(xy 398.32026 -122.700796) (xy 399.50136 -122.700796) (xy 399.511479 -122.701249) (xy 399.530181 -122.708983)
			(xy 399.544497 -122.723288) (xy 399.552244 -122.741985) (xy 399.552668 -122.752104) (xy 399.552668 -123.686316)
			(xy 401.939252 -123.686316) (xy 401.939252 -122.822716) (xy 401.939742 -122.792748) (xy 401.947565 -122.733326)
			(xy 401.963078 -122.675433) (xy 401.986014 -122.62006) (xy 402.015981 -122.568154) (xy 402.052468 -122.520604)
			(xy 402.094848 -122.478224) (xy 402.142398 -122.441737) (xy 402.194304 -122.41177) (xy 402.249677 -122.388834)
			(xy 402.30757 -122.373321) (xy 402.366992 -122.365498) (xy 402.426928 -122.365498) (xy 402.48635 -122.373321)
			(xy 402.544243 -122.388834) (xy 402.599616 -122.41177) (xy 402.651522 -122.441737) (xy 402.699072 -122.478224)
			(xy 402.741452 -122.520604) (xy 402.777939 -122.568154) (xy 402.807906 -122.62006) (xy 402.830842 -122.675433)
			(xy 402.846355 -122.733326) (xy 402.854178 -122.792748) (xy 402.854668 -122.822716) (xy 402.854668 -123.16714)
			(xy 414.899348 -123.16714) (xy 414.899348 -122.30354) (xy 414.899838 -122.273556) (xy 414.907666 -122.2141)
			(xy 414.923187 -122.156175) (xy 414.946136 -122.100771) (xy 414.97612 -122.048837) (xy 415.012626 -122.001261)
			(xy 415.055031 -121.958856) (xy 415.102607 -121.92235) (xy 415.154541 -121.892366) (xy 415.209945 -121.869417)
			(xy 415.26787 -121.853896) (xy 415.327326 -121.846068) (xy 415.387294 -121.846068) (xy 415.44675 -121.853896)
			(xy 415.504675 -121.869417) (xy 415.560079 -121.892366) (xy 415.612013 -121.92235) (xy 415.659589 -121.958856)
			(xy 415.701994 -122.001261) (xy 415.7385 -122.048837) (xy 415.768484 -122.100771) (xy 415.791433 -122.156175)
			(xy 415.806954 -122.2141) (xy 415.814782 -122.273556) (xy 415.815272 -122.30354) (xy 415.815272 -123.16714)
			(xy 415.814782 -123.197124) (xy 415.809366 -123.23826) (xy 416.347148 -123.23826) (xy 416.347148 -122.231912)
			(xy 416.347694 -122.22181) (xy 416.355418 -122.203142) (xy 416.369695 -122.188849) (xy 416.388355 -122.181105)
			(xy 416.398456 -122.180604) (xy 417.57981 -122.180604) (xy 417.589933 -122.181117) (xy 417.608647 -122.188842)
			(xy 417.623002 -122.203119) (xy 417.630827 -122.221792) (xy 417.631372 -122.231912) (xy 417.631372 -123.23826)
			(xy 420.884096 -123.23826) (xy 420.884096 -122.231912) (xy 420.884526 -122.221791) (xy 420.892269 -122.203088)
			(xy 420.906581 -122.188774) (xy 420.925283 -122.181027) (xy 420.935404 -122.180604) (xy 422.116504 -122.180604)
			(xy 422.126627 -122.181013) (xy 422.145332 -122.188763) (xy 422.159646 -122.203082) (xy 422.16739 -122.221789)
			(xy 422.167812 -122.231912) (xy 422.167812 -123.23826) (xy 422.167351 -123.248378) (xy 422.159619 -123.267079)
			(xy 422.145316 -123.281394) (xy 422.126622 -123.289143) (xy 422.116504 -123.289568) (xy 420.935404 -123.289568)
			(xy 420.925278 -123.28918) (xy 420.906568 -123.281427) (xy 420.892253 -123.267102) (xy 420.884513 -123.248386)
			(xy 420.884096 -123.23826) (xy 417.631372 -123.23826) (xy 417.63095 -123.248383) (xy 417.62321 -123.267091)
			(xy 417.608895 -123.281408) (xy 417.590187 -123.28915) (xy 417.580064 -123.289568) (xy 416.39871 -123.289568)
			(xy 416.388585 -123.289065) (xy 416.369865 -123.281342) (xy 416.355509 -123.267061) (xy 416.347688 -123.248382)
			(xy 416.347148 -123.23826) (xy 415.809366 -123.23826) (xy 415.806954 -123.25658) (xy 415.791433 -123.314505)
			(xy 415.787243 -123.32462) (xy 427.899576 -123.32462) (xy 427.899576 -123.081796) (xy 428.018448 -122.90044)
			(xy 428.080932 -122.804936) (xy 428.105062 -122.768106) (xy 428.108941 -122.761784) (xy 428.113194 -122.74758)
			(xy 428.113444 -122.740166) (xy 428.113444 -122.714258) (xy 428.113234 -122.708109) (xy 428.110292 -122.696168)
			(xy 428.107602 -122.690636) (xy 427.994064 -122.516646) (xy 427.973998 -122.485658) (xy 427.96841 -122.477022)
			(xy 427.907958 -122.384312) (xy 427.90745 -122.38355) (xy 427.906942 -122.382788) (xy 427.906688 -122.38228)
			(xy 427.90618 -122.381518) (xy 427.899576 -122.371104) (xy 427.899576 -122.12828) (xy 427.900253 -122.116733)
			(xy 427.910203 -122.09589) (xy 427.928127 -122.081325) (xy 427.9392 -122.077988) (xy 427.951138 -122.076464)
			(xy 428.687738 -122.076464) (xy 428.698495 -122.076992) (xy 428.718185 -122.085651) (xy 428.725838 -122.093228)
			(xy 428.73202 -122.100639) (xy 428.738945 -122.118637) (xy 428.7393 -122.12828) (xy 428.7393 -122.371104)
			(xy 428.5234 -122.701558) (xy 428.519391 -122.709784) (xy 428.516843 -122.727891) (xy 428.520782 -122.745747)
			(xy 428.525432 -122.753628) (xy 428.55769 -122.803412) (xy 428.7393 -123.080526) (xy 428.7393 -123.159266)
			(xy 429.3743 -123.159266) (xy 429.3743 -122.295666) (xy 429.37479 -122.265682) (xy 429.382618 -122.206226)
			(xy 429.398139 -122.148301) (xy 429.421088 -122.092897) (xy 429.451072 -122.040963) (xy 429.487578 -121.993387)
			(xy 429.529983 -121.950982) (xy 429.577559 -121.914476) (xy 429.629493 -121.884492) (xy 429.684897 -121.861543)
			(xy 429.742822 -121.846022) (xy 429.802278 -121.838194) (xy 429.862246 -121.838194) (xy 429.921702 -121.846022)
			(xy 429.979627 -121.861543) (xy 430.035031 -121.884492) (xy 430.086965 -121.914476) (xy 430.134541 -121.950982)
			(xy 430.176946 -121.993387) (xy 430.213452 -122.040963) (xy 430.243436 -122.092897) (xy 430.266385 -122.148301)
			(xy 430.281906 -122.206226) (xy 430.289734 -122.265682) (xy 430.290224 -122.295666) (xy 430.290224 -123.159266)
			(xy 430.289734 -123.18925) (xy 430.281906 -123.248706) (xy 430.266385 -123.306631) (xy 430.243436 -123.362035)
			(xy 430.213452 -123.413969) (xy 430.176946 -123.461545) (xy 430.134541 -123.50395) (xy 430.086965 -123.540456)
			(xy 430.035031 -123.57044) (xy 429.979627 -123.593389) (xy 429.921702 -123.60891) (xy 429.862246 -123.616738)
			(xy 429.802278 -123.616738) (xy 429.742822 -123.60891) (xy 429.684897 -123.593389) (xy 429.629493 -123.57044)
			(xy 429.577559 -123.540456) (xy 429.529983 -123.50395) (xy 429.487578 -123.461545) (xy 429.451072 -123.413969)
			(xy 429.421088 -123.362035) (xy 429.398139 -123.306631) (xy 429.382618 -123.248706) (xy 429.37479 -123.18925)
			(xy 429.3743 -123.159266) (xy 428.7393 -123.159266) (xy 428.7393 -123.32462) (xy 428.73864 -123.336169)
			(xy 428.728685 -123.357015) (xy 428.710752 -123.371579) (xy 428.699676 -123.374912) (xy 428.687738 -123.376436)
			(xy 427.951138 -123.376436) (xy 427.94038 -123.375921) (xy 427.92069 -123.367253) (xy 427.913038 -123.359672)
			(xy 427.906853 -123.352263) (xy 427.899931 -123.334264) (xy 427.899576 -123.32462) (xy 415.787243 -123.32462)
			(xy 415.768484 -123.369909) (xy 415.7385 -123.421843) (xy 415.701994 -123.469419) (xy 415.659589 -123.511824)
			(xy 415.612013 -123.54833) (xy 415.560079 -123.578314) (xy 415.504675 -123.601263) (xy 415.44675 -123.616784)
			(xy 415.387294 -123.624612) (xy 415.327326 -123.624612) (xy 415.26787 -123.616784) (xy 415.209945 -123.601263)
			(xy 415.154541 -123.578314) (xy 415.102607 -123.54833) (xy 415.055031 -123.511824) (xy 415.012626 -123.469419)
			(xy 414.97612 -123.421843) (xy 414.946136 -123.369909) (xy 414.923187 -123.314505) (xy 414.907666 -123.25658)
			(xy 414.899838 -123.197124) (xy 414.899348 -123.16714) (xy 402.854668 -123.16714) (xy 402.854668 -123.686316)
			(xy 402.854178 -123.716284) (xy 402.846355 -123.775706) (xy 402.830842 -123.833599) (xy 402.807906 -123.888972)
			(xy 402.777939 -123.940878) (xy 402.741452 -123.988428) (xy 402.699072 -124.030808) (xy 402.651522 -124.067295)
			(xy 402.599616 -124.097262) (xy 402.544243 -124.120198) (xy 402.48635 -124.135711) (xy 402.426928 -124.143534)
			(xy 402.366992 -124.143534) (xy 402.30757 -124.135711) (xy 402.249677 -124.120198) (xy 402.194304 -124.097262)
			(xy 402.142398 -124.067295) (xy 402.094848 -124.030808) (xy 402.052468 -123.988428) (xy 402.015981 -123.940878)
			(xy 401.986014 -123.888972) (xy 401.963078 -123.833599) (xy 401.947565 -123.775706) (xy 401.939742 -123.716284)
			(xy 401.939252 -123.686316) (xy 399.552668 -123.686316) (xy 399.552668 -123.758452) (xy 399.552244 -123.768575)
			(xy 399.544506 -123.787284) (xy 399.530191 -123.801601) (xy 399.511483 -123.809342) (xy 399.50136 -123.80976)
			(xy 398.32026 -123.80976) (xy 398.31013 -123.809416) (xy 398.291418 -123.801647) (xy 398.277104 -123.787308)
			(xy 398.269367 -123.768583) (xy 398.268952 -123.758452) (xy 395.016228 -123.758452) (xy 395.01574 -123.7686)
			(xy 395.007965 -123.787345) (xy 394.993589 -123.80167) (xy 394.974815 -123.809376) (xy 394.964666 -123.80976)
			(xy 393.783566 -123.80976) (xy 393.773437 -123.809301) (xy 393.754715 -123.801562) (xy 393.74036 -123.787268)
			(xy 393.732542 -123.768579) (xy 393.732004 -123.758452) (xy 385.35864 -123.758452) (xy 385.35864 -123.853194)
			(xy 385.358405 -123.859567) (xy 385.355199 -123.871904) (xy 385.35229 -123.877578) (xy 385.347539 -123.885582)
			(xy 385.333535 -123.897822) (xy 385.316123 -123.904363) (xy 385.306824 -123.904756) (xy 384.570224 -123.904756)
			(xy 384.558709 -123.904087) (xy 384.537893 -123.894233) (xy 384.523303 -123.876414) (xy 384.519932 -123.865386)
			(xy 384.519932 -123.865132) (xy 384.518408 -123.853194) (xy 383.852097 -123.853194) (xy 383.836646 -123.890496)
			(xy 383.806679 -123.942402) (xy 383.770192 -123.989952) (xy 383.727812 -124.032332) (xy 383.680262 -124.068819)
			(xy 383.628356 -124.098786) (xy 383.572983 -124.121722) (xy 383.51509 -124.137235) (xy 383.455668 -124.145058)
			(xy 383.395732 -124.145058) (xy 383.33631 -124.137235) (xy 383.278417 -124.121722) (xy 383.223044 -124.098786)
			(xy 383.171138 -124.068819) (xy 383.123588 -124.032332) (xy 383.081208 -123.989952) (xy 383.044721 -123.942402)
			(xy 383.014754 -123.890496) (xy 382.991818 -123.835123) (xy 382.976305 -123.77723) (xy 382.968482 -123.717808)
			(xy 382.967992 -123.68784) (xy 316.568893 -123.68784) (xy 316.576928 -123.691168) (xy 316.628834 -123.721135)
			(xy 316.676384 -123.757622) (xy 316.718764 -123.800002) (xy 316.755251 -123.847552) (xy 316.785218 -123.899458)
			(xy 316.808154 -123.954831) (xy 316.823667 -124.012724) (xy 316.83149 -124.072146) (xy 316.83198 -124.102114)
			(xy 316.83198 -124.965714) (xy 316.83149 -124.995682) (xy 316.823667 -125.055104) (xy 316.808154 -125.112997)
			(xy 316.785218 -125.16837) (xy 316.755251 -125.220276) (xy 316.718764 -125.267826) (xy 316.676384 -125.310206)
			(xy 316.628834 -125.346693) (xy 316.576928 -125.37666) (xy 316.521555 -125.399596) (xy 316.463662 -125.415109)
			(xy 316.40424 -125.422932) (xy 316.344304 -125.422932) (xy 316.284882 -125.415109) (xy 316.226989 -125.399596)
			(xy 316.171616 -125.37666) (xy 316.11971 -125.346693) (xy 316.07216 -125.310206) (xy 316.02978 -125.267826)
			(xy 315.993293 -125.220276) (xy 315.963326 -125.16837) (xy 315.94039 -125.112997) (xy 315.924877 -125.055104)
			(xy 315.917054 -124.995682) (xy 315.916564 -124.965714) (xy 315.281564 -124.965714) (xy 315.281564 -125.131068)
			(xy 315.280993 -125.141268) (xy 315.2732 -125.16012) (xy 315.258787 -125.174555) (xy 315.239947 -125.182378)
			(xy 315.229748 -125.182884) (xy 314.493148 -125.182884) (xy 314.482925 -125.182448) (xy 314.464033 -125.174635)
			(xy 314.449574 -125.16018) (xy 314.441755 -125.14129) (xy 314.441332 -125.131068) (xy 297.83004 -125.131068)
			(xy 297.813958 -125.169894) (xy 297.783991 -125.2218) (xy 297.747504 -125.26935) (xy 297.705124 -125.31173)
			(xy 297.657574 -125.348217) (xy 297.605668 -125.378184) (xy 297.550295 -125.40112) (xy 297.492402 -125.416633)
			(xy 297.43298 -125.424456) (xy 297.373044 -125.424456) (xy 297.313622 -125.416633) (xy 297.255729 -125.40112)
			(xy 297.200356 -125.378184) (xy 297.14845 -125.348217) (xy 297.1009 -125.31173) (xy 297.05852 -125.26935)
			(xy 297.022033 -125.2218) (xy 296.992066 -125.169894) (xy 296.96913 -125.114521) (xy 296.953617 -125.056628)
			(xy 296.945794 -124.997206) (xy 296.945304 -124.967238) (xy 284.900624 -124.967238) (xy 284.900624 -125.486414)
			(xy 284.900491 -125.494542) (xy 385.6101 -125.494542) (xy 385.6101 -124.630942) (xy 385.61059 -124.600974)
			(xy 385.618413 -124.541552) (xy 385.633926 -124.483659) (xy 385.656862 -124.428286) (xy 385.686829 -124.37638)
			(xy 385.723316 -124.32883) (xy 385.765696 -124.28645) (xy 385.813246 -124.249963) (xy 385.865152 -124.219996)
			(xy 385.920525 -124.19706) (xy 385.978418 -124.181547) (xy 386.03784 -124.173724) (xy 386.097776 -124.173724)
			(xy 386.157198 -124.181547) (xy 386.215091 -124.19706) (xy 386.270464 -124.219996) (xy 386.32237 -124.249963)
			(xy 386.36992 -124.28645) (xy 386.4123 -124.32883) (xy 386.448787 -124.37638) (xy 386.478754 -124.428286)
			(xy 386.50169 -124.483659) (xy 386.517203 -124.541552) (xy 386.525026 -124.600974) (xy 386.525516 -124.630942)
			(xy 386.525516 -125.494542) (xy 386.525026 -125.52451) (xy 386.517203 -125.583932) (xy 386.50169 -125.641825)
			(xy 386.494205 -125.659896) (xy 387.160516 -125.659896) (xy 387.160516 -125.432312) (xy 387.16077 -125.428248)
			(xy 387.161024 -125.425708) (xy 387.161024 -125.417072) (xy 387.166612 -125.408436) (xy 387.167882 -125.406404)
			(xy 387.168898 -125.404372) (xy 387.366256 -125.103382) (xy 387.370144 -125.097064) (xy 387.374391 -125.082857)
			(xy 387.374638 -125.075442) (xy 387.374638 -125.049788) (xy 387.374417 -125.042455) (xy 387.370298 -125.028384)
			(xy 387.36651 -125.022102) (xy 387.168644 -124.71908) (xy 387.166358 -124.71527) (xy 387.166104 -124.714762)
			(xy 387.165088 -124.712984) (xy 387.161024 -124.70638) (xy 387.161024 -124.698252) (xy 387.16077 -124.695712)
			(xy 387.160516 -124.691648) (xy 387.160516 -124.463556) (xy 387.160947 -124.453341) (xy 387.16878 -124.434473)
			(xy 387.183237 -124.420037) (xy 387.202117 -124.412232) (xy 387.212332 -124.41174) (xy 387.948932 -124.41174)
			(xy 387.959136 -124.412254) (xy 387.97799 -124.42007) (xy 387.992424 -124.4345) (xy 388.000243 -124.453352)
			(xy 388.000748 -124.463556) (xy 388.000748 -124.69114) (xy 388.000494 -124.695204) (xy 388.00024 -124.697744)
			(xy 388.00024 -124.70638) (xy 387.994398 -124.715778) (xy 387.993636 -124.717048) (xy 387.992366 -124.71908)
			(xy 387.786626 -125.033786) (xy 387.781547 -125.042294) (xy 387.777732 -125.061722) (xy 387.781563 -125.081146)
			(xy 387.786626 -125.089666) (xy 387.992366 -125.403102) (xy 387.993382 -125.405134) (xy 387.994652 -125.407166)
			(xy 388.00024 -125.415802) (xy 388.00024 -125.424438) (xy 388.000494 -125.426978) (xy 388.000748 -125.431042)
			(xy 388.000748 -125.558296) (xy 393.732004 -125.558296) (xy 393.732004 -124.551948) (xy 393.732461 -124.541796)
			(xy 393.740242 -124.523044) (xy 393.754628 -124.508719) (xy 393.773413 -124.501019) (xy 393.783566 -124.50064)
			(xy 394.964666 -124.50064) (xy 394.974791 -124.501155) (xy 394.993511 -124.508871) (xy 395.007868 -124.523149)
			(xy 395.015689 -124.541826) (xy 395.016228 -124.551948) (xy 395.016228 -125.558296) (xy 398.268952 -125.558296)
			(xy 398.268952 -124.551948) (xy 398.269454 -124.541835) (xy 398.277178 -124.523141) (xy 398.291467 -124.508827)
			(xy 398.310147 -124.501072) (xy 398.32026 -124.50064) (xy 399.50136 -124.50064) (xy 399.511485 -124.50105)
			(xy 399.530195 -124.508792) (xy 399.544512 -124.523112) (xy 399.552252 -124.541823) (xy 399.552668 -124.551948)
			(xy 399.552668 -125.486414) (xy 400.085052 -125.486414) (xy 400.085052 -124.622814) (xy 400.085542 -124.592846)
			(xy 400.093365 -124.533424) (xy 400.108878 -124.475531) (xy 400.131814 -124.420158) (xy 400.161781 -124.368252)
			(xy 400.198268 -124.320702) (xy 400.240648 -124.278322) (xy 400.288198 -124.241835) (xy 400.340104 -124.211868)
			(xy 400.395477 -124.188932) (xy 400.45337 -124.173419) (xy 400.512792 -124.165596) (xy 400.572728 -124.165596)
			(xy 400.63215 -124.173419) (xy 400.690043 -124.188932) (xy 400.745416 -124.211868) (xy 400.797322 -124.241835)
			(xy 400.844872 -124.278322) (xy 400.887252 -124.320702) (xy 400.923739 -124.368252) (xy 400.953706 -124.420158)
			(xy 400.976642 -124.475531) (xy 400.992155 -124.533424) (xy 400.999978 -124.592846) (xy 401.000468 -124.622814)
			(xy 401.000468 -124.967238) (xy 413.045148 -124.967238) (xy 413.045148 -124.103638) (xy 413.045638 -124.073654)
			(xy 413.053466 -124.014198) (xy 413.068987 -123.956273) (xy 413.091936 -123.900869) (xy 413.12192 -123.848935)
			(xy 413.158426 -123.801359) (xy 413.200831 -123.758954) (xy 413.248407 -123.722448) (xy 413.300341 -123.692464)
			(xy 413.355745 -123.669515) (xy 413.41367 -123.653994) (xy 413.473126 -123.646166) (xy 413.533094 -123.646166)
			(xy 413.59255 -123.653994) (xy 413.650475 -123.669515) (xy 413.705879 -123.692464) (xy 413.757813 -123.722448)
			(xy 413.805389 -123.758954) (xy 413.847794 -123.801359) (xy 413.8843 -123.848935) (xy 413.914284 -123.900869)
			(xy 413.937233 -123.956273) (xy 413.952754 -124.014198) (xy 413.960582 -124.073654) (xy 413.961072 -124.103638)
			(xy 413.961072 -124.967238) (xy 413.960582 -124.997222) (xy 413.955199 -125.038104) (xy 416.347148 -125.038104)
			(xy 416.347148 -124.031756) (xy 416.347648 -124.021651) (xy 416.35539 -124.002982) (xy 416.369682 -123.98869)
			(xy 416.388351 -123.980948) (xy 416.398456 -123.980448) (xy 417.57981 -123.980448) (xy 417.589938 -123.980919)
			(xy 417.608661 -123.988651) (xy 417.623017 -124.002942) (xy 417.630835 -124.02163) (xy 417.631372 -124.031756)
			(xy 417.631372 -125.038104) (xy 420.884096 -125.038104) (xy 420.884096 -124.031756) (xy 420.884549 -124.021645)
			(xy 420.8923 -124.002967) (xy 420.906607 -123.988673) (xy 420.925293 -123.98094) (xy 420.935404 -123.980448)
			(xy 422.116504 -123.980448) (xy 422.126607 -123.980981) (xy 422.145275 -123.98871) (xy 422.159568 -124.002992)
			(xy 422.167311 -124.021654) (xy 422.167812 -124.031756) (xy 422.167812 -125.038104) (xy 422.167318 -125.048211)
			(xy 422.159582 -125.066887) (xy 422.145287 -125.081182) (xy 422.126611 -125.088918) (xy 422.116504 -125.089412)
			(xy 420.935404 -125.089412) (xy 420.925297 -125.088912) (xy 420.906621 -125.081178) (xy 420.892327 -125.066886)
			(xy 420.88459 -125.048211) (xy 420.884096 -125.038104) (xy 417.631372 -125.038104) (xy 417.630986 -125.04823)
			(xy 417.623232 -125.066939) (xy 417.608906 -125.081254) (xy 417.590191 -125.088994) (xy 417.580064 -125.089412)
			(xy 416.39871 -125.089412) (xy 416.38859 -125.088867) (xy 416.369879 -125.081152) (xy 416.355524 -125.066884)
			(xy 416.347696 -125.048221) (xy 416.347148 -125.038104) (xy 413.955199 -125.038104) (xy 413.952754 -125.056678)
			(xy 413.937233 -125.114603) (xy 413.930413 -125.131068) (xy 430.541684 -125.131068) (xy 430.541684 -124.888244)
			(xy 430.686464 -124.667518) (xy 430.73574 -124.59208) (xy 430.755552 -124.561854) (xy 430.760538 -124.55341)
			(xy 430.764266 -124.534173) (xy 430.760518 -124.514939) (xy 430.755552 -124.506482) (xy 430.610518 -124.28347)
			(xy 430.554892 -124.198126) (xy 430.550574 -124.19203) (xy 430.547272 -124.186442) (xy 430.546764 -124.185426)
			(xy 430.541684 -124.177552) (xy 430.541684 -123.934728) (xy 430.542326 -123.923209) (xy 430.552188 -123.902388)
			(xy 430.57002 -123.887801) (xy 430.581054 -123.884436) (xy 430.581308 -123.884436) (xy 430.593246 -123.882912)
			(xy 431.329846 -123.882912) (xy 431.33622 -123.883133) (xy 431.348556 -123.886349) (xy 431.35423 -123.889262)
			(xy 431.362224 -123.894027) (xy 431.37446 -123.908028) (xy 431.381008 -123.925431) (xy 431.381408 -123.934728)
			(xy 431.381408 -124.177552) (xy 431.165508 -124.508006) (xy 431.161459 -124.516216) (xy 431.158924 -124.534334)
			(xy 431.162881 -124.552195) (xy 431.16754 -124.560076) (xy 431.199798 -124.60986) (xy 431.215292 -124.633482)
			(xy 431.381408 -124.886974) (xy 431.381408 -124.965714) (xy 432.016408 -124.965714) (xy 432.016408 -124.102114)
			(xy 432.016898 -124.07213) (xy 432.024726 -124.012674) (xy 432.040247 -123.954749) (xy 432.063196 -123.899345)
			(xy 432.09318 -123.847411) (xy 432.129686 -123.799835) (xy 432.172091 -123.75743) (xy 432.219667 -123.720924)
			(xy 432.271601 -123.69094) (xy 432.327005 -123.667991) (xy 432.38493 -123.65247) (xy 432.444386 -123.644642)
			(xy 432.504354 -123.644642) (xy 432.56381 -123.65247) (xy 432.621735 -123.667991) (xy 432.677139 -123.69094)
			(xy 432.729073 -123.720924) (xy 432.776649 -123.75743) (xy 432.819054 -123.799835) (xy 432.85556 -123.847411)
			(xy 432.885544 -123.899345) (xy 432.908493 -123.954749) (xy 432.924014 -124.012674) (xy 432.931842 -124.07213)
			(xy 432.932332 -124.102114) (xy 432.932332 -124.965714) (xy 432.931842 -124.995698) (xy 432.924014 -125.055154)
			(xy 432.908493 -125.113079) (xy 432.885544 -125.168483) (xy 432.85556 -125.220417) (xy 432.819054 -125.267993)
			(xy 432.776649 -125.310398) (xy 432.729073 -125.346904) (xy 432.677139 -125.376888) (xy 432.621735 -125.399837)
			(xy 432.56381 -125.415358) (xy 432.504354 -125.423186) (xy 432.444386 -125.423186) (xy 432.38493 -125.415358)
			(xy 432.327005 -125.399837) (xy 432.271601 -125.376888) (xy 432.219667 -125.346904) (xy 432.172091 -125.310398)
			(xy 432.129686 -125.267993) (xy 432.09318 -125.220417) (xy 432.063196 -125.168483) (xy 432.040247 -125.113079)
			(xy 432.024726 -125.055154) (xy 432.016898 -124.995698) (xy 432.016408 -124.965714) (xy 431.381408 -124.965714)
			(xy 431.381408 -125.131068) (xy 431.380768 -125.142588) (xy 431.370907 -125.16341) (xy 431.353073 -125.177996)
			(xy 431.342038 -125.18136) (xy 431.341784 -125.18136) (xy 431.329846 -125.182884) (xy 430.593246 -125.182884)
			(xy 430.586872 -125.182666) (xy 430.574535 -125.179448) (xy 430.568862 -125.176534) (xy 430.560865 -125.171774)
			(xy 430.548629 -125.157771) (xy 430.542084 -125.140365) (xy 430.541684 -125.131068) (xy 413.930413 -125.131068)
			(xy 413.914284 -125.170007) (xy 413.8843 -125.221941) (xy 413.847794 -125.269517) (xy 413.805389 -125.311922)
			(xy 413.757813 -125.348428) (xy 413.705879 -125.378412) (xy 413.650475 -125.401361) (xy 413.59255 -125.416882)
			(xy 413.533094 -125.42471) (xy 413.473126 -125.42471) (xy 413.41367 -125.416882) (xy 413.355745 -125.401361)
			(xy 413.300341 -125.378412) (xy 413.248407 -125.348428) (xy 413.200831 -125.311922) (xy 413.158426 -125.269517)
			(xy 413.12192 -125.221941) (xy 413.091936 -125.170007) (xy 413.068987 -125.114603) (xy 413.053466 -125.056678)
			(xy 413.045638 -124.997222) (xy 413.045148 -124.967238) (xy 401.000468 -124.967238) (xy 401.000468 -125.486414)
			(xy 400.999978 -125.516382) (xy 400.992155 -125.575804) (xy 400.976642 -125.633697) (xy 400.953706 -125.68907)
			(xy 400.923739 -125.740976) (xy 400.887252 -125.788526) (xy 400.844872 -125.830906) (xy 400.797322 -125.867393)
			(xy 400.745416 -125.89736) (xy 400.690043 -125.920296) (xy 400.63215 -125.935809) (xy 400.572728 -125.943632)
			(xy 400.512792 -125.943632) (xy 400.45337 -125.935809) (xy 400.395477 -125.920296) (xy 400.340104 -125.89736)
			(xy 400.288198 -125.867393) (xy 400.240648 -125.830906) (xy 400.198268 -125.788526) (xy 400.161781 -125.740976)
			(xy 400.131814 -125.68907) (xy 400.108878 -125.633697) (xy 400.093365 -125.575804) (xy 400.085542 -125.516382)
			(xy 400.085052 -125.486414) (xy 399.552668 -125.486414) (xy 399.552668 -125.558296) (xy 399.55228 -125.568422)
			(xy 399.544527 -125.587132) (xy 399.530202 -125.601447) (xy 399.511486 -125.609187) (xy 399.50136 -125.609604)
			(xy 398.32026 -125.609604) (xy 398.310149 -125.609148) (xy 398.291471 -125.601398) (xy 398.277178 -125.587092)
			(xy 398.269444 -125.568407) (xy 398.268952 -125.558296) (xy 395.016228 -125.558296) (xy 395.015776 -125.568446)
			(xy 395.007987 -125.587193) (xy 394.9936 -125.601516) (xy 394.974818 -125.609221) (xy 394.964666 -125.609604)
			(xy 393.783566 -125.609604) (xy 393.773443 -125.609103) (xy 393.754729 -125.601372) (xy 393.740375 -125.587091)
			(xy 393.73255 -125.568417) (xy 393.732004 -125.558296) (xy 388.000748 -125.558296) (xy 388.000748 -125.659896)
			(xy 388.000216 -125.6701) (xy 387.99241 -125.688955) (xy 387.977985 -125.70339) (xy 387.959135 -125.711209)
			(xy 387.948932 -125.711712) (xy 387.212332 -125.711712) (xy 387.202112 -125.711262) (xy 387.183225 -125.703448)
			(xy 387.168768 -125.688999) (xy 387.160944 -125.670116) (xy 387.160516 -125.659896) (xy 386.494205 -125.659896)
			(xy 386.478754 -125.697198) (xy 386.448787 -125.749104) (xy 386.4123 -125.796654) (xy 386.36992 -125.839034)
			(xy 386.32237 -125.875521) (xy 386.270464 -125.905488) (xy 386.215091 -125.928424) (xy 386.157198 -125.943937)
			(xy 386.097776 -125.95176) (xy 386.03784 -125.95176) (xy 385.978418 -125.943937) (xy 385.920525 -125.928424)
			(xy 385.865152 -125.905488) (xy 385.813246 -125.875521) (xy 385.765696 -125.839034) (xy 385.723316 -125.796654)
			(xy 385.686829 -125.749104) (xy 385.656862 -125.697198) (xy 385.633926 -125.641825) (xy 385.618413 -125.583932)
			(xy 385.61059 -125.52451) (xy 385.6101 -125.494542) (xy 284.900491 -125.494542) (xy 284.900134 -125.516398)
			(xy 284.892306 -125.575854) (xy 284.876785 -125.633779) (xy 284.853836 -125.689183) (xy 284.823852 -125.741117)
			(xy 284.787346 -125.788693) (xy 284.744941 -125.831098) (xy 284.697365 -125.867604) (xy 284.645431 -125.897588)
			(xy 284.590027 -125.920537) (xy 284.532102 -125.936058) (xy 284.472646 -125.943886) (xy 284.412678 -125.943886)
			(xy 284.353222 -125.936058) (xy 284.295297 -125.920537) (xy 284.239893 -125.897588) (xy 284.187959 -125.867604)
			(xy 284.140383 -125.831098) (xy 284.097978 -125.788693) (xy 284.061472 -125.741117) (xy 284.031488 -125.689183)
			(xy 284.008539 -125.633779) (xy 283.993018 -125.575854) (xy 283.98519 -125.516398) (xy 283.9847 -125.486414)
			(xy 283.452824 -125.486414) (xy 283.452824 -125.558296) (xy 283.452312 -125.568402) (xy 283.44458 -125.587075)
			(xy 283.430292 -125.601369) (xy 283.411621 -125.609108) (xy 283.401516 -125.609604) (xy 282.220162 -125.609604)
			(xy 282.210038 -125.609106) (xy 282.191325 -125.601374) (xy 282.176971 -125.587092) (xy 282.169146 -125.568417)
			(xy 282.1686 -125.558296) (xy 278.915876 -125.558296) (xy 278.91548 -125.568421) (xy 278.907729 -125.587129)
			(xy 278.893406 -125.601445) (xy 278.874693 -125.609186) (xy 278.864568 -125.609604) (xy 277.683468 -125.609604)
			(xy 277.673358 -125.609141) (xy 277.65468 -125.601394) (xy 277.640386 -125.58709) (xy 277.632652 -125.568407)
			(xy 277.63216 -125.558296) (xy 271.900396 -125.558296) (xy 271.900396 -125.659896) (xy 271.899721 -125.671444)
			(xy 271.889774 -125.69229) (xy 271.871847 -125.706854) (xy 271.860772 -125.710188) (xy 271.848834 -125.711712)
			(xy 271.112234 -125.711712) (xy 271.101479 -125.711177) (xy 271.08179 -125.70252) (xy 271.074134 -125.694948)
			(xy 271.067939 -125.687547) (xy 271.061023 -125.669541) (xy 271.060672 -125.659896) (xy 270.394382 -125.659896)
			(xy 270.378884 -125.697311) (xy 270.3489 -125.749245) (xy 270.312394 -125.796821) (xy 270.269989 -125.839226)
			(xy 270.222413 -125.875732) (xy 270.170479 -125.905716) (xy 270.115075 -125.928665) (xy 270.05715 -125.944186)
			(xy 269.997694 -125.952014) (xy 269.937726 -125.952014) (xy 269.87827 -125.944186) (xy 269.820345 -125.928665)
			(xy 269.764941 -125.905716) (xy 269.713007 -125.875732) (xy 269.665431 -125.839226) (xy 269.623026 -125.796821)
			(xy 269.58652 -125.749245) (xy 269.556536 -125.697311) (xy 269.533587 -125.641907) (xy 269.518066 -125.583982)
			(xy 269.510238 -125.524526) (xy 269.509748 -125.494542) (xy 168.800647 -125.494542) (xy 168.80029 -125.516398)
			(xy 168.792462 -125.575854) (xy 168.776941 -125.633779) (xy 168.753992 -125.689183) (xy 168.724008 -125.741117)
			(xy 168.687502 -125.788693) (xy 168.645097 -125.831098) (xy 168.597521 -125.867604) (xy 168.545587 -125.897588)
			(xy 168.490183 -125.920537) (xy 168.432258 -125.936058) (xy 168.372802 -125.943886) (xy 168.312834 -125.943886)
			(xy 168.253378 -125.936058) (xy 168.195453 -125.920537) (xy 168.140049 -125.897588) (xy 168.088115 -125.867604)
			(xy 168.040539 -125.831098) (xy 167.998134 -125.788693) (xy 167.961628 -125.741117) (xy 167.931644 -125.689183)
			(xy 167.908695 -125.633779) (xy 167.893174 -125.575854) (xy 167.885346 -125.516398) (xy 167.884856 -125.486414)
			(xy 167.352472 -125.486414) (xy 167.352472 -125.558296) (xy 167.35208 -125.568422) (xy 167.344328 -125.587131)
			(xy 167.330004 -125.601446) (xy 167.31129 -125.609186) (xy 167.301164 -125.609604) (xy 166.120064 -125.609604)
			(xy 166.109953 -125.609144) (xy 166.091275 -125.601396) (xy 166.076982 -125.587091) (xy 166.069248 -125.568407)
			(xy 166.068756 -125.558296) (xy 162.816032 -125.558296) (xy 162.815576 -125.568446) (xy 162.807787 -125.587192)
			(xy 162.793402 -125.601514) (xy 162.774622 -125.60922) (xy 162.76447 -125.609604) (xy 161.58337 -125.609604)
			(xy 161.573247 -125.609099) (xy 161.554533 -125.60137) (xy 161.54018 -125.58709) (xy 161.532354 -125.568417)
			(xy 161.531808 -125.558296) (xy 155.800552 -125.558296) (xy 155.800552 -125.659896) (xy 155.800016 -125.670099)
			(xy 155.792211 -125.688954) (xy 155.777787 -125.703389) (xy 155.758939 -125.711208) (xy 155.748736 -125.711712)
			(xy 155.012136 -125.711712) (xy 155.001916 -125.711259) (xy 154.983029 -125.703446) (xy 154.968572 -125.688998)
			(xy 154.960748 -125.670116) (xy 154.96032 -125.659896) (xy 154.294538 -125.659896) (xy 154.27904 -125.697311)
			(xy 154.249056 -125.749245) (xy 154.21255 -125.796821) (xy 154.170145 -125.839226) (xy 154.122569 -125.875732)
			(xy 154.070635 -125.905716) (xy 154.015231 -125.928665) (xy 153.957306 -125.944186) (xy 153.89785 -125.952014)
			(xy 153.837882 -125.952014) (xy 153.778426 -125.944186) (xy 153.720501 -125.928665) (xy 153.665097 -125.905716)
			(xy 153.613163 -125.875732) (xy 153.565587 -125.839226) (xy 153.523182 -125.796821) (xy 153.486676 -125.749245)
			(xy 153.456692 -125.697311) (xy 153.433743 -125.641907) (xy 153.418222 -125.583982) (xy 153.410394 -125.524526)
			(xy 153.409904 -125.494542) (xy 52.700295 -125.494542) (xy 52.699938 -125.516382) (xy 52.692115 -125.575804)
			(xy 52.676602 -125.633697) (xy 52.653666 -125.68907) (xy 52.623699 -125.740976) (xy 52.587212 -125.788526)
			(xy 52.544832 -125.830906) (xy 52.497282 -125.867393) (xy 52.445376 -125.89736) (xy 52.390003 -125.920296)
			(xy 52.33211 -125.935809) (xy 52.272688 -125.943632) (xy 52.212752 -125.943632) (xy 52.15333 -125.935809)
			(xy 52.095437 -125.920296) (xy 52.040064 -125.89736) (xy 51.988158 -125.867393) (xy 51.940608 -125.830906)
			(xy 51.898228 -125.788526) (xy 51.861741 -125.740976) (xy 51.831774 -125.68907) (xy 51.808838 -125.633697)
			(xy 51.793325 -125.575804) (xy 51.785502 -125.516382) (xy 51.785012 -125.486414) (xy 51.252628 -125.486414)
			(xy 51.252628 -125.558296) (xy 51.252112 -125.568401) (xy 51.244381 -125.587074) (xy 51.230094 -125.601368)
			(xy 51.211425 -125.609108) (xy 51.20132 -125.609604) (xy 50.02022 -125.609604) (xy 50.010099 -125.609168)
			(xy 49.991397 -125.601427) (xy 49.977082 -125.587117) (xy 49.969335 -125.568417) (xy 49.968912 -125.558296)
			(xy 46.716188 -125.558296) (xy 46.715775 -125.568451) (xy 46.707978 -125.587206) (xy 46.693579 -125.60153)
			(xy 46.674783 -125.609228) (xy 46.664626 -125.609604) (xy 45.483526 -125.609604) (xy 45.473406 -125.609054)
			(xy 45.454694 -125.601342) (xy 45.440338 -125.587076) (xy 45.43251 -125.568412) (xy 45.431964 -125.558296)
			(xy 39.700708 -125.558296) (xy 39.700708 -125.659896) (xy 39.700285 -125.670118) (xy 39.692461 -125.689007)
			(xy 39.678004 -125.703463) (xy 39.659115 -125.711286) (xy 39.648892 -125.711712) (xy 38.912292 -125.711712)
			(xy 38.902083 -125.711224) (xy 38.883221 -125.703408) (xy 38.868785 -125.688969) (xy 38.860973 -125.670105)
			(xy 38.860476 -125.659896) (xy 38.194165 -125.659896) (xy 38.178714 -125.697198) (xy 38.148747 -125.749104)
			(xy 38.11226 -125.796654) (xy 38.06988 -125.839034) (xy 38.02233 -125.875521) (xy 37.970424 -125.905488)
			(xy 37.915051 -125.928424) (xy 37.857158 -125.943937) (xy 37.797736 -125.95176) (xy 37.7378 -125.95176)
			(xy 37.678378 -125.943937) (xy 37.620485 -125.928424) (xy 37.565112 -125.905488) (xy 37.513206 -125.875521)
			(xy 37.465656 -125.839034) (xy 37.423276 -125.796654) (xy 37.386789 -125.749104) (xy 37.356822 -125.697198)
			(xy 37.333886 -125.641825) (xy 37.318373 -125.583932) (xy 37.31055 -125.52451) (xy 37.31006 -125.494542)
			(xy 4.30911 -125.494542) (xy 4.30911 -131.297934) (xy 34.667952 -131.297934) (xy 34.667952 -130.434334)
			(xy 34.668442 -130.404366) (xy 34.676265 -130.344944) (xy 34.691778 -130.287051) (xy 34.714714 -130.231678)
			(xy 34.744681 -130.179772) (xy 34.781168 -130.132222) (xy 34.823548 -130.089842) (xy 34.871098 -130.053355)
			(xy 34.923004 -130.023388) (xy 34.978377 -130.000452) (xy 35.03627 -129.984939) (xy 35.095692 -129.977116)
			(xy 35.155628 -129.977116) (xy 35.21505 -129.984939) (xy 35.272943 -130.000452) (xy 35.328316 -130.023388)
			(xy 35.380222 -130.053355) (xy 35.427772 -130.089842) (xy 35.470152 -130.132222) (xy 35.506639 -130.179772)
			(xy 35.536606 -130.231678) (xy 35.559542 -130.287051) (xy 35.575055 -130.344944) (xy 35.582878 -130.404366)
			(xy 35.583368 -130.434334) (xy 35.583368 -131.297934) (xy 35.582878 -131.327902) (xy 35.575055 -131.387324)
			(xy 35.559542 -131.445217) (xy 35.552057 -131.463288) (xy 36.218368 -131.463288) (xy 36.218368 -131.235704)
			(xy 36.218622 -131.23164) (xy 36.218876 -131.2291) (xy 36.218876 -131.220464) (xy 36.224464 -131.211828)
			(xy 36.225734 -131.209796) (xy 36.22675 -131.207764) (xy 36.424108 -130.906774) (xy 36.427957 -130.900436)
			(xy 36.43223 -130.886244) (xy 36.43249 -130.878834) (xy 36.43249 -130.85318) (xy 36.432264 -130.845848)
			(xy 36.428147 -130.831777) (xy 36.424362 -130.825494) (xy 36.226496 -130.522472) (xy 36.22421 -130.518662)
			(xy 36.223956 -130.518154) (xy 36.22294 -130.516376) (xy 36.218876 -130.509772) (xy 36.218876 -130.501644)
			(xy 36.218622 -130.499104) (xy 36.218368 -130.49504) (xy 36.218368 -130.266948) (xy 36.218851 -130.256731)
			(xy 36.226655 -130.237848) (xy 36.241094 -130.223391) (xy 36.259968 -130.215563) (xy 36.270184 -130.215132)
			(xy 37.006784 -130.215132) (xy 37.017011 -130.215526) (xy 37.035907 -130.223353) (xy 37.050365 -130.23782)
			(xy 37.05818 -130.256721) (xy 37.0586 -130.266948) (xy 37.0586 -130.494532) (xy 37.058346 -130.498596)
			(xy 37.058092 -130.501136) (xy 37.058092 -130.509772) (xy 37.05225 -130.51917) (xy 37.051488 -130.52044)
			(xy 37.050218 -130.522472) (xy 36.844478 -130.837178) (xy 36.839409 -130.845691) (xy 36.835596 -130.865115)
			(xy 36.839421 -130.884537) (xy 36.844478 -130.893058) (xy 37.050218 -131.206494) (xy 37.051234 -131.208526)
			(xy 37.052504 -131.210558) (xy 37.058092 -131.219194) (xy 37.058092 -131.22783) (xy 37.058346 -131.23037)
			(xy 37.0586 -131.234434) (xy 37.0586 -131.368292) (xy 45.431964 -131.368292) (xy 45.431964 -130.361944)
			(xy 45.432457 -130.351797) (xy 45.440231 -130.333053) (xy 45.454606 -130.318729) (xy 45.473378 -130.311021)
			(xy 45.483526 -130.310636) (xy 46.664626 -130.310636) (xy 46.674754 -130.311105) (xy 46.693475 -130.318841)
			(xy 46.70783 -130.333132) (xy 46.715649 -130.351818) (xy 46.716188 -130.361944) (xy 46.716188 -131.368292)
			(xy 49.968912 -131.368292) (xy 49.968912 -130.361944) (xy 49.969352 -130.351823) (xy 49.977088 -130.333118)
			(xy 49.991398 -130.318802) (xy 50.010099 -130.311057) (xy 50.02022 -130.310636) (xy 51.20132 -130.310636)
			(xy 51.211448 -130.311) (xy 51.230159 -130.318762) (xy 51.244474 -130.333095) (xy 51.252212 -130.351815)
			(xy 51.252628 -130.361944) (xy 51.252628 -131.29641) (xy 53.639212 -131.29641) (xy 53.639212 -130.43281)
			(xy 53.639702 -130.402842) (xy 53.647525 -130.34342) (xy 53.663038 -130.285527) (xy 53.685974 -130.230154)
			(xy 53.715941 -130.178248) (xy 53.752428 -130.130698) (xy 53.794808 -130.088318) (xy 53.842358 -130.051831)
			(xy 53.894264 -130.021864) (xy 53.949637 -129.998928) (xy 54.00753 -129.983415) (xy 54.066952 -129.975592)
			(xy 54.126888 -129.975592) (xy 54.18631 -129.983415) (xy 54.244203 -129.998928) (xy 54.299576 -130.021864)
			(xy 54.351482 -130.051831) (xy 54.399032 -130.088318) (xy 54.441412 -130.130698) (xy 54.477899 -130.178248)
			(xy 54.507866 -130.230154) (xy 54.530802 -130.285527) (xy 54.546315 -130.34342) (xy 54.554138 -130.402842)
			(xy 54.554628 -130.43281) (xy 54.554628 -130.777234) (xy 66.599308 -130.777234) (xy 66.599308 -129.913634)
			(xy 66.599798 -129.88365) (xy 66.607626 -129.824194) (xy 66.623147 -129.766269) (xy 66.646096 -129.710865)
			(xy 66.67608 -129.658931) (xy 66.712586 -129.611355) (xy 66.754991 -129.56895) (xy 66.802567 -129.532444)
			(xy 66.854501 -129.50246) (xy 66.909905 -129.479511) (xy 66.96783 -129.46399) (xy 67.027286 -129.456162)
			(xy 67.087254 -129.456162) (xy 67.14671 -129.46399) (xy 67.204635 -129.479511) (xy 67.260039 -129.50246)
			(xy 67.311973 -129.532444) (xy 67.359549 -129.56895) (xy 67.401954 -129.611355) (xy 67.43846 -129.658931)
			(xy 67.468444 -129.710865) (xy 67.491393 -129.766269) (xy 67.506914 -129.824194) (xy 67.514742 -129.88365)
			(xy 67.515232 -129.913634) (xy 67.515232 -130.777234) (xy 67.514742 -130.807218) (xy 67.509359 -130.8481)
			(xy 68.047108 -130.8481) (xy 68.047108 -129.841752) (xy 68.047546 -129.831639) (xy 68.055301 -129.812958)
			(xy 68.069612 -129.798665) (xy 68.088303 -129.790934) (xy 68.098416 -129.790444) (xy 69.27977 -129.790444)
			(xy 69.289895 -129.790951) (xy 69.308617 -129.79867) (xy 69.322974 -129.81295) (xy 69.330794 -129.831629)
			(xy 69.331332 -129.841752) (xy 69.331332 -130.8481) (xy 72.584056 -130.8481) (xy 72.584056 -129.841752)
			(xy 72.584545 -129.831646) (xy 72.59229 -129.812975) (xy 72.606585 -129.798683) (xy 72.625258 -129.790942)
			(xy 72.635364 -129.790444) (xy 73.816464 -129.790444) (xy 73.826564 -129.791013) (xy 73.84523 -129.798729)
			(xy 73.859524 -129.812999) (xy 73.86727 -129.831653) (xy 73.867772 -129.841752) (xy 73.867772 -130.8481)
			(xy 73.867383 -130.858226) (xy 73.85963 -130.876935) (xy 73.845305 -130.89125) (xy 73.82659 -130.89899)
			(xy 73.816464 -130.899408) (xy 72.635364 -130.899408) (xy 72.625254 -130.898945) (xy 72.606576 -130.891197)
			(xy 72.592283 -130.876893) (xy 72.584548 -130.85821) (xy 72.584056 -130.8481) (xy 69.331332 -130.8481)
			(xy 69.330816 -130.858205) (xy 69.323084 -130.876877) (xy 69.308797 -130.89117) (xy 69.290129 -130.898911)
			(xy 69.280024 -130.899408) (xy 68.09867 -130.899408) (xy 68.088547 -130.8989) (xy 68.069834 -130.891171)
			(xy 68.055481 -130.876892) (xy 68.047654 -130.85822) (xy 68.047108 -130.8481) (xy 67.509359 -130.8481)
			(xy 67.506914 -130.866674) (xy 67.491393 -130.924599) (xy 67.487308 -130.93446) (xy 79.599536 -130.93446)
			(xy 79.599536 -130.691636) (xy 79.718408 -130.51028) (xy 79.780892 -130.414776) (xy 79.805022 -130.377946)
			(xy 79.808883 -130.371614) (xy 79.813148 -130.357418) (xy 79.813404 -130.350006) (xy 79.813404 -130.324098)
			(xy 79.813218 -130.317947) (xy 79.81026 -130.306007) (xy 79.807562 -130.300476) (xy 79.694024 -130.126486)
			(xy 79.673958 -130.095498) (xy 79.66837 -130.086862) (xy 79.607918 -129.994152) (xy 79.60741 -129.99339)
			(xy 79.606902 -129.992628) (xy 79.606648 -129.99212) (xy 79.60614 -129.991358) (xy 79.599536 -129.980944)
			(xy 79.599536 -129.73812) (xy 79.600123 -129.726562) (xy 79.610109 -129.70571) (xy 79.628071 -129.691153)
			(xy 79.63916 -129.687828) (xy 79.651098 -129.686304) (xy 80.387698 -129.686304) (xy 80.398456 -129.686817)
			(xy 80.418145 -129.695489) (xy 80.425798 -129.703068) (xy 80.432004 -129.710461) (xy 80.438913 -129.728473)
			(xy 80.43926 -129.73812) (xy 80.43926 -129.980944) (xy 80.22336 -130.311398) (xy 80.219323 -130.319612)
			(xy 80.216788 -130.337727) (xy 80.220738 -130.355586) (xy 80.225392 -130.363468) (xy 80.25765 -130.413252)
			(xy 80.43926 -130.690366) (xy 80.43926 -130.769106) (xy 81.07426 -130.769106) (xy 81.07426 -129.905506)
			(xy 81.07475 -129.875522) (xy 81.082578 -129.816066) (xy 81.098099 -129.758141) (xy 81.121048 -129.702737)
			(xy 81.151032 -129.650803) (xy 81.187538 -129.603227) (xy 81.229943 -129.560822) (xy 81.277519 -129.524316)
			(xy 81.329453 -129.494332) (xy 81.384857 -129.471383) (xy 81.442782 -129.455862) (xy 81.502238 -129.448034)
			(xy 81.562206 -129.448034) (xy 81.621662 -129.455862) (xy 81.679587 -129.471383) (xy 81.734991 -129.494332)
			(xy 81.786925 -129.524316) (xy 81.834501 -129.560822) (xy 81.876906 -129.603227) (xy 81.913412 -129.650803)
			(xy 81.943396 -129.702737) (xy 81.966345 -129.758141) (xy 81.981866 -129.816066) (xy 81.989694 -129.875522)
			(xy 81.990184 -129.905506) (xy 81.990184 -130.769106) (xy 81.989694 -130.79909) (xy 81.981866 -130.858546)
			(xy 81.966345 -130.916471) (xy 81.943396 -130.971875) (xy 81.913412 -131.023809) (xy 81.876906 -131.071385)
			(xy 81.834501 -131.11379) (xy 81.786925 -131.150296) (xy 81.734991 -131.18028) (xy 81.679587 -131.203229)
			(xy 81.621662 -131.21875) (xy 81.562206 -131.226578) (xy 81.502238 -131.226578) (xy 81.442782 -131.21875)
			(xy 81.384857 -131.203229) (xy 81.329453 -131.18028) (xy 81.277519 -131.150296) (xy 81.229943 -131.11379)
			(xy 81.187538 -131.071385) (xy 81.151032 -131.023809) (xy 81.121048 -130.971875) (xy 81.098099 -130.916471)
			(xy 81.082578 -130.858546) (xy 81.07475 -130.79909) (xy 81.07426 -130.769106) (xy 80.43926 -130.769106)
			(xy 80.43926 -130.93446) (xy 80.43866 -130.946017) (xy 80.428681 -130.966869) (xy 80.410723 -130.981427)
			(xy 80.399636 -130.984752) (xy 80.387698 -130.986276) (xy 79.651098 -130.986276) (xy 79.640339 -130.985771)
			(xy 79.62065 -130.977094) (xy 79.612998 -130.969512) (xy 79.606782 -130.962126) (xy 79.59988 -130.944109)
			(xy 79.599536 -130.93446) (xy 67.487308 -130.93446) (xy 67.468444 -130.980003) (xy 67.43846 -131.031937)
			(xy 67.401954 -131.079513) (xy 67.359549 -131.121918) (xy 67.311973 -131.158424) (xy 67.260039 -131.188408)
			(xy 67.204635 -131.211357) (xy 67.14671 -131.226878) (xy 67.087254 -131.234706) (xy 67.027286 -131.234706)
			(xy 66.96783 -131.226878) (xy 66.909905 -131.211357) (xy 66.854501 -131.188408) (xy 66.802567 -131.158424)
			(xy 66.754991 -131.121918) (xy 66.712586 -131.079513) (xy 66.67608 -131.031937) (xy 66.646096 -130.980003)
			(xy 66.623147 -130.924599) (xy 66.607626 -130.866674) (xy 66.599798 -130.807218) (xy 66.599308 -130.777234)
			(xy 54.554628 -130.777234) (xy 54.554628 -131.29641) (xy 54.554138 -131.326378) (xy 54.546315 -131.3858)
			(xy 54.530802 -131.443693) (xy 54.507866 -131.499066) (xy 54.477899 -131.550972) (xy 54.441412 -131.598522)
			(xy 54.399032 -131.640902) (xy 54.351482 -131.677389) (xy 54.299576 -131.707356) (xy 54.244203 -131.730292)
			(xy 54.18631 -131.745805) (xy 54.126888 -131.753628) (xy 54.066952 -131.753628) (xy 54.00753 -131.745805)
			(xy 53.949637 -131.730292) (xy 53.894264 -131.707356) (xy 53.842358 -131.677389) (xy 53.794808 -131.640902)
			(xy 53.752428 -131.598522) (xy 53.715941 -131.550972) (xy 53.685974 -131.499066) (xy 53.663038 -131.443693)
			(xy 53.647525 -131.3858) (xy 53.639702 -131.326378) (xy 53.639212 -131.29641) (xy 51.252628 -131.29641)
			(xy 51.252628 -131.368292) (xy 51.252109 -131.378397) (xy 51.244379 -131.397069) (xy 51.230093 -131.411364)
			(xy 51.211424 -131.419103) (xy 51.20132 -131.4196) (xy 50.02022 -131.4196) (xy 50.010099 -131.419168)
			(xy 49.991396 -131.411426) (xy 49.977081 -131.397115) (xy 49.969335 -131.378413) (xy 49.968912 -131.368292)
			(xy 46.716188 -131.368292) (xy 46.715772 -131.378447) (xy 46.707976 -131.397202) (xy 46.693578 -131.411526)
			(xy 46.674783 -131.419224) (xy 46.664626 -131.4196) (xy 45.483526 -131.4196) (xy 45.473406 -131.419053)
			(xy 45.454693 -131.411342) (xy 45.440337 -131.397074) (xy 45.43251 -131.378409) (xy 45.431964 -131.368292)
			(xy 37.0586 -131.368292) (xy 37.0586 -131.463288) (xy 37.058178 -131.473511) (xy 37.050355 -131.492401)
			(xy 37.035898 -131.506858) (xy 37.017007 -131.514678) (xy 37.006784 -131.515104) (xy 36.270184 -131.515104)
			(xy 36.259974 -131.514631) (xy 36.24111 -131.506811) (xy 36.226674 -131.492367) (xy 36.218864 -131.473499)
			(xy 36.218368 -131.463288) (xy 35.552057 -131.463288) (xy 35.536606 -131.50059) (xy 35.506639 -131.552496)
			(xy 35.470152 -131.600046) (xy 35.427772 -131.642426) (xy 35.380222 -131.678913) (xy 35.328316 -131.70888)
			(xy 35.272943 -131.731816) (xy 35.21505 -131.747329) (xy 35.155628 -131.755152) (xy 35.095692 -131.755152)
			(xy 35.03627 -131.747329) (xy 34.978377 -131.731816) (xy 34.923004 -131.70888) (xy 34.871098 -131.678913)
			(xy 34.823548 -131.642426) (xy 34.781168 -131.600046) (xy 34.744681 -131.552496) (xy 34.714714 -131.50059)
			(xy 34.691778 -131.445217) (xy 34.676265 -131.387324) (xy 34.668442 -131.327902) (xy 34.667952 -131.297934)
			(xy 4.30911 -131.297934) (xy 4.30911 -133.104382) (xy 37.31006 -133.104382) (xy 37.31006 -132.240782)
			(xy 37.31055 -132.210814) (xy 37.318373 -132.151392) (xy 37.333886 -132.093499) (xy 37.356822 -132.038126)
			(xy 37.386789 -131.98622) (xy 37.423276 -131.93867) (xy 37.465656 -131.89629) (xy 37.513206 -131.859803)
			(xy 37.565112 -131.829836) (xy 37.620485 -131.8069) (xy 37.678378 -131.791387) (xy 37.7378 -131.783564)
			(xy 37.797736 -131.783564) (xy 37.857158 -131.791387) (xy 37.915051 -131.8069) (xy 37.970424 -131.829836)
			(xy 38.02233 -131.859803) (xy 38.06988 -131.89629) (xy 38.11226 -131.93867) (xy 38.148747 -131.98622)
			(xy 38.178714 -132.038126) (xy 38.20165 -132.093499) (xy 38.217163 -132.151392) (xy 38.224986 -132.210814)
			(xy 38.225476 -132.240782) (xy 38.225476 -133.104382) (xy 38.224986 -133.13435) (xy 38.217163 -133.193772)
			(xy 38.20165 -133.251665) (xy 38.194165 -133.269736) (xy 38.860476 -133.269736) (xy 38.860476 -133.042152)
			(xy 38.86073 -133.038088) (xy 38.860984 -133.035548) (xy 38.860984 -133.026912) (xy 38.866572 -133.018276)
			(xy 38.867842 -133.016244) (xy 38.868858 -133.014212) (xy 39.066216 -132.713222) (xy 39.070085 -132.706894)
			(xy 39.074345 -132.692695) (xy 39.074598 -132.685282) (xy 39.074598 -132.659628) (xy 39.074393 -132.652294)
			(xy 39.070262 -132.638223) (xy 39.06647 -132.631942) (xy 38.868604 -132.32892) (xy 38.866318 -132.32511)
			(xy 38.866064 -132.324602) (xy 38.865048 -132.322824) (xy 38.860984 -132.31622) (xy 38.860984 -132.308092)
			(xy 38.86073 -132.305552) (xy 38.860476 -132.301488) (xy 38.860476 -132.073396) (xy 38.860978 -132.063189)
			(xy 38.868791 -132.044329) (xy 38.883225 -132.029893) (xy 38.902085 -132.022079) (xy 38.912292 -132.02158)
			(xy 39.648892 -132.02158) (xy 39.659113 -132.022019) (xy 39.677999 -132.029839) (xy 39.692455 -132.044291)
			(xy 39.700279 -132.063175) (xy 39.700708 -132.073396) (xy 39.700708 -132.30098) (xy 39.700454 -132.305044)
			(xy 39.7002 -132.307584) (xy 39.7002 -132.31622) (xy 39.694358 -132.325618) (xy 39.693596 -132.326888)
			(xy 39.692326 -132.32892) (xy 39.486586 -132.643626) (xy 39.48156 -132.652161) (xy 39.477732 -132.671571)
			(xy 39.481538 -132.690986) (xy 39.486586 -132.699506) (xy 39.692326 -133.012942) (xy 39.693342 -133.014974)
			(xy 39.694612 -133.017006) (xy 39.7002 -133.025642) (xy 39.7002 -133.034278) (xy 39.700454 -133.036818)
			(xy 39.700708 -133.040882) (xy 39.700708 -133.16839) (xy 45.431964 -133.16839) (xy 45.431964 -132.162042)
			(xy 45.432399 -132.15187) (xy 45.440175 -132.133071) (xy 45.454558 -132.118684) (xy 45.473354 -132.110902)
			(xy 45.483526 -132.11048) (xy 46.664626 -132.11048) (xy 46.674805 -132.110843) (xy 46.693608 -132.118645)
			(xy 46.707993 -132.133049) (xy 46.71577 -132.151863) (xy 46.716188 -132.162042) (xy 46.716188 -133.16839)
			(xy 46.716175 -133.168644) (xy 49.968912 -133.168644) (xy 49.968912 -132.162042) (xy 49.96946 -132.151921)
			(xy 49.977169 -132.133207) (xy 49.991436 -132.11885) (xy 50.010103 -132.111024) (xy 50.02022 -132.11048)
			(xy 51.20132 -132.11048) (xy 51.211428 -132.110968) (xy 51.230102 -132.118709) (xy 51.244396 -132.133004)
			(xy 51.252134 -132.15168) (xy 51.252628 -132.161788) (xy 51.252628 -133.096508) (xy 51.785012 -133.096508)
			(xy 51.785012 -132.232908) (xy 51.785502 -132.20294) (xy 51.793325 -132.143518) (xy 51.808838 -132.085625)
			(xy 51.831774 -132.030252) (xy 51.861741 -131.978346) (xy 51.898228 -131.930796) (xy 51.940608 -131.888416)
			(xy 51.988158 -131.851929) (xy 52.040064 -131.821962) (xy 52.095437 -131.799026) (xy 52.15333 -131.783513)
			(xy 52.212752 -131.77569) (xy 52.272688 -131.77569) (xy 52.33211 -131.783513) (xy 52.390003 -131.799026)
			(xy 52.445376 -131.821962) (xy 52.497282 -131.851929) (xy 52.544832 -131.888416) (xy 52.587212 -131.930796)
			(xy 52.623699 -131.978346) (xy 52.653666 -132.030252) (xy 52.676602 -132.085625) (xy 52.692115 -132.143518)
			(xy 52.699938 -132.20294) (xy 52.700428 -132.232908) (xy 52.700428 -132.577332) (xy 64.745108 -132.577332)
			(xy 64.745108 -131.713732) (xy 64.745598 -131.683748) (xy 64.753426 -131.624292) (xy 64.768947 -131.566367)
			(xy 64.791896 -131.510963) (xy 64.82188 -131.459029) (xy 64.858386 -131.411453) (xy 64.900791 -131.369048)
			(xy 64.948367 -131.332542) (xy 65.000301 -131.302558) (xy 65.055705 -131.279609) (xy 65.11363 -131.264088)
			(xy 65.173086 -131.25626) (xy 65.233054 -131.25626) (xy 65.29251 -131.264088) (xy 65.350435 -131.279609)
			(xy 65.405839 -131.302558) (xy 65.457773 -131.332542) (xy 65.505349 -131.369048) (xy 65.547754 -131.411453)
			(xy 65.58426 -131.459029) (xy 65.614244 -131.510963) (xy 65.637193 -131.566367) (xy 65.652714 -131.624292)
			(xy 65.660542 -131.683748) (xy 65.661032 -131.713732) (xy 65.661032 -132.577332) (xy 65.660542 -132.607316)
			(xy 65.655159 -132.648198) (xy 68.047108 -132.648198) (xy 68.047108 -131.64185) (xy 68.047604 -131.631685)
			(xy 68.055367 -131.612897) (xy 68.06973 -131.598512) (xy 68.088506 -131.59072) (xy 68.09867 -131.590288)
			(xy 69.27977 -131.590288) (xy 69.289946 -131.59069) (xy 69.308749 -131.598474) (xy 69.323137 -131.612867)
			(xy 69.330914 -131.631674) (xy 69.331332 -131.64185) (xy 69.331332 -132.648198) (xy 72.584056 -132.648198)
			(xy 72.584056 -131.64185) (xy 72.584568 -131.631725) (xy 72.592282 -131.613001) (xy 72.606561 -131.598643)
			(xy 72.625241 -131.590825) (xy 72.635364 -131.590288) (xy 73.816464 -131.590288) (xy 73.826614 -131.590751)
			(xy 73.845363 -131.598532) (xy 73.859688 -131.612917) (xy 73.867391 -131.631698) (xy 73.867772 -131.64185)
			(xy 73.867772 -132.648198) (xy 73.867272 -132.658323) (xy 73.859547 -132.677042) (xy 73.845265 -132.691398)
			(xy 73.826586 -132.699219) (xy 73.816464 -132.69976) (xy 72.635364 -132.69976) (xy 72.625203 -132.699407)
			(xy 72.606442 -132.691592) (xy 72.592118 -132.677174) (xy 72.584427 -132.658362) (xy 72.584056 -132.648198)
			(xy 69.331332 -132.648198) (xy 69.330934 -132.658373) (xy 69.323144 -132.677174) (xy 69.30875 -132.69156)
			(xy 69.289945 -132.699339) (xy 69.27977 -132.69976) (xy 68.09867 -132.69976) (xy 68.08851 -132.699291)
			(xy 68.06974 -132.691507) (xy 68.055375 -132.677133) (xy 68.047602 -132.658358) (xy 68.047108 -132.648198)
			(xy 65.655159 -132.648198) (xy 65.652714 -132.666772) (xy 65.637193 -132.724697) (xy 65.630373 -132.741162)
			(xy 82.241644 -132.741162) (xy 82.241644 -132.498338) (xy 82.386424 -132.277612) (xy 82.4357 -132.202174)
			(xy 82.455512 -132.171948) (xy 82.460499 -132.163505) (xy 82.46422 -132.144268) (xy 82.460475 -132.125035)
			(xy 82.455512 -132.116576) (xy 82.310478 -131.893564) (xy 82.254852 -131.80822) (xy 82.250534 -131.802124)
			(xy 82.247232 -131.796536) (xy 82.246724 -131.79552) (xy 82.241644 -131.787646) (xy 82.241644 -131.544822)
			(xy 82.242082 -131.534651) (xy 82.249861 -131.515856) (xy 82.264242 -131.50147) (xy 82.283035 -131.493685)
			(xy 82.293206 -131.49326) (xy 83.029806 -131.49326) (xy 83.039981 -131.49366) (xy 83.05878 -131.501451)
			(xy 83.073165 -131.515844) (xy 83.080946 -131.534647) (xy 83.081368 -131.544822) (xy 83.081368 -131.787646)
			(xy 82.865468 -132.1181) (xy 82.861428 -132.126313) (xy 82.858894 -132.144428) (xy 82.862845 -132.162288)
			(xy 82.8675 -132.17017) (xy 82.899758 -132.219954) (xy 82.915252 -132.243576) (xy 83.081368 -132.497068)
			(xy 83.081368 -132.575808) (xy 83.716368 -132.575808) (xy 83.716368 -131.712208) (xy 83.716858 -131.682224)
			(xy 83.724686 -131.622768) (xy 83.740207 -131.564843) (xy 83.763156 -131.509439) (xy 83.79314 -131.457505)
			(xy 83.829646 -131.409929) (xy 83.872051 -131.367524) (xy 83.919627 -131.331018) (xy 83.971561 -131.301034)
			(xy 84.026965 -131.278085) (xy 84.08489 -131.262564) (xy 84.144346 -131.254736) (xy 84.204314 -131.254736)
			(xy 84.26377 -131.262564) (xy 84.321695 -131.278085) (xy 84.369615 -131.297934) (xy 150.767796 -131.297934)
			(xy 150.767796 -130.434334) (xy 150.768286 -130.40435) (xy 150.776114 -130.344894) (xy 150.791635 -130.286969)
			(xy 150.814584 -130.231565) (xy 150.844568 -130.179631) (xy 150.881074 -130.132055) (xy 150.923479 -130.08965)
			(xy 150.971055 -130.053144) (xy 151.022989 -130.02316) (xy 151.078393 -130.000211) (xy 151.136318 -129.98469)
			(xy 151.195774 -129.976862) (xy 151.255742 -129.976862) (xy 151.315198 -129.98469) (xy 151.373123 -130.000211)
			(xy 151.428527 -130.02316) (xy 151.480461 -130.053144) (xy 151.528037 -130.08965) (xy 151.570442 -130.132055)
			(xy 151.606948 -130.179631) (xy 151.636932 -130.231565) (xy 151.659881 -130.286969) (xy 151.675402 -130.344894)
			(xy 151.68323 -130.40435) (xy 151.68372 -130.434334) (xy 151.68372 -131.297934) (xy 151.68323 -131.327918)
			(xy 151.675402 -131.387374) (xy 151.659881 -131.445299) (xy 151.65243 -131.463288) (xy 152.318212 -131.463288)
			(xy 152.318212 -131.235704) (xy 152.318466 -131.23164) (xy 152.31872 -131.2291) (xy 152.31872 -131.220464)
			(xy 152.324308 -131.211828) (xy 152.325578 -131.209796) (xy 152.326594 -131.207764) (xy 152.523952 -130.906774)
			(xy 152.527805 -130.900438) (xy 152.532074 -130.886245) (xy 152.532334 -130.878834) (xy 152.532334 -130.85318)
			(xy 152.532117 -130.845847) (xy 152.527995 -130.831775) (xy 152.524206 -130.825494) (xy 152.32634 -130.522472)
			(xy 152.324054 -130.518662) (xy 152.3238 -130.518154) (xy 152.322784 -130.516376) (xy 152.31872 -130.509772)
			(xy 152.31872 -130.501644) (xy 152.318466 -130.499104) (xy 152.318212 -130.49504) (xy 152.318212 -130.266948)
			(xy 152.318652 -130.256726) (xy 152.326465 -130.237834) (xy 152.340917 -130.223376) (xy 152.359806 -130.215556)
			(xy 152.370028 -130.215132) (xy 153.106628 -130.215132) (xy 153.116858 -130.21549) (xy 153.135755 -130.223332)
			(xy 153.150211 -130.237809) (xy 153.158025 -130.256718) (xy 153.158444 -130.266948) (xy 153.158444 -130.494532)
			(xy 153.15819 -130.498596) (xy 153.157936 -130.501136) (xy 153.157936 -130.509772) (xy 153.152094 -130.51917)
			(xy 153.151332 -130.52044) (xy 153.150062 -130.522472) (xy 152.944322 -130.837178) (xy 152.93925 -130.84569)
			(xy 152.935433 -130.865115) (xy 152.939261 -130.884538) (xy 152.944322 -130.893058) (xy 153.150062 -131.206494)
			(xy 153.151078 -131.208526) (xy 153.152348 -131.210558) (xy 153.157936 -131.219194) (xy 153.157936 -131.22783)
			(xy 153.15819 -131.23037) (xy 153.158444 -131.234434) (xy 153.158444 -131.368292) (xy 161.531808 -131.368292)
			(xy 161.531808 -130.361944) (xy 161.532258 -130.351792) (xy 161.54004 -130.333039) (xy 161.554429 -130.318714)
			(xy 161.573216 -130.311014) (xy 161.58337 -130.310636) (xy 162.76447 -130.310636) (xy 162.774594 -130.311151)
			(xy 162.793314 -130.318868) (xy 162.807671 -130.333146) (xy 162.815492 -130.351822) (xy 162.816032 -130.361944)
			(xy 162.816032 -131.368292) (xy 166.068756 -131.368292) (xy 166.068756 -130.361944) (xy 166.069251 -130.35183)
			(xy 166.076977 -130.333136) (xy 166.091268 -130.318821) (xy 166.109951 -130.311067) (xy 166.120064 -130.310636)
			(xy 167.301164 -130.310636) (xy 167.311289 -130.311047) (xy 167.329998 -130.318789) (xy 167.344315 -130.333108)
			(xy 167.352055 -130.351819) (xy 167.352472 -130.361944) (xy 167.352472 -131.29641) (xy 169.739056 -131.29641)
			(xy 169.739056 -130.43281) (xy 169.739546 -130.402826) (xy 169.747374 -130.34337) (xy 169.762895 -130.285445)
			(xy 169.785844 -130.230041) (xy 169.815828 -130.178107) (xy 169.852334 -130.130531) (xy 169.894739 -130.088126)
			(xy 169.942315 -130.05162) (xy 169.994249 -130.021636) (xy 170.049653 -129.998687) (xy 170.107578 -129.983166)
			(xy 170.167034 -129.975338) (xy 170.227002 -129.975338) (xy 170.286458 -129.983166) (xy 170.344383 -129.998687)
			(xy 170.399787 -130.021636) (xy 170.451721 -130.05162) (xy 170.499297 -130.088126) (xy 170.541702 -130.130531)
			(xy 170.578208 -130.178107) (xy 170.608192 -130.230041) (xy 170.631141 -130.285445) (xy 170.646662 -130.34337)
			(xy 170.65449 -130.402826) (xy 170.65498 -130.43281) (xy 170.65498 -130.777234) (xy 182.69966 -130.777234)
			(xy 182.69966 -129.913634) (xy 182.70015 -129.883666) (xy 182.707973 -129.824244) (xy 182.723486 -129.766351)
			(xy 182.746422 -129.710978) (xy 182.776389 -129.659072) (xy 182.812876 -129.611522) (xy 182.855256 -129.569142)
			(xy 182.902806 -129.532655) (xy 182.954712 -129.502688) (xy 183.010085 -129.479752) (xy 183.067978 -129.464239)
			(xy 183.1274 -129.456416) (xy 183.187336 -129.456416) (xy 183.246758 -129.464239) (xy 183.304651 -129.479752)
			(xy 183.360024 -129.502688) (xy 183.41193 -129.532655) (xy 183.45948 -129.569142) (xy 183.50186 -129.611522)
			(xy 183.538347 -129.659072) (xy 183.568314 -129.710978) (xy 183.59125 -129.766351) (xy 183.606763 -129.824244)
			(xy 183.614586 -129.883666) (xy 183.615076 -129.913634) (xy 183.615076 -130.777234) (xy 183.614586 -130.807202)
			(xy 183.609202 -130.8481) (xy 184.146952 -130.8481) (xy 184.146952 -129.841752) (xy 184.147445 -129.831646)
			(xy 184.155189 -129.812976) (xy 184.169483 -129.798685) (xy 184.188154 -129.790943) (xy 184.19826 -129.790444)
			(xy 185.379614 -129.790444) (xy 185.389742 -129.790915) (xy 185.408464 -129.798649) (xy 185.42282 -129.812939)
			(xy 185.430638 -129.831626) (xy 185.431176 -129.841752) (xy 185.431176 -130.8481) (xy 188.6839 -130.8481)
			(xy 188.6839 -129.841752) (xy 188.684346 -129.83164) (xy 188.692099 -129.812961) (xy 188.706408 -129.798668)
			(xy 188.725096 -129.790935) (xy 188.735208 -129.790444) (xy 189.916308 -129.790444) (xy 189.92641 -129.790977)
			(xy 189.945078 -129.798707) (xy 189.95937 -129.812989) (xy 189.967115 -129.83165) (xy 189.967616 -129.841752)
			(xy 189.967616 -130.8481) (xy 189.967115 -130.858207) (xy 189.959381 -130.876882) (xy 189.945089 -130.891176)
			(xy 189.926415 -130.898914) (xy 189.916308 -130.899408) (xy 188.735208 -130.899408) (xy 188.725087 -130.898978)
			(xy 188.706385 -130.891234) (xy 188.692071 -130.876922) (xy 188.684324 -130.858221) (xy 188.6839 -130.8481)
			(xy 185.431176 -130.8481) (xy 185.430783 -130.858225) (xy 185.423031 -130.876934) (xy 185.408707 -130.891249)
			(xy 185.389994 -130.89899) (xy 185.379868 -130.899408) (xy 184.198514 -130.899408) (xy 184.188394 -130.898863)
			(xy 184.169682 -130.891149) (xy 184.155327 -130.876881) (xy 184.147499 -130.858217) (xy 184.146952 -130.8481)
			(xy 183.609202 -130.8481) (xy 183.606763 -130.866624) (xy 183.59125 -130.924517) (xy 183.587132 -130.93446)
			(xy 195.69938 -130.93446) (xy 195.69938 -130.691636) (xy 195.818252 -130.51028) (xy 195.880736 -130.414776)
			(xy 195.904866 -130.377946) (xy 195.908731 -130.371616) (xy 195.912993 -130.357418) (xy 195.913248 -130.350006)
			(xy 195.913248 -130.324098) (xy 195.913058 -130.317948) (xy 195.910102 -130.306007) (xy 195.907406 -130.300476)
			(xy 195.793868 -130.126486) (xy 195.773802 -130.095498) (xy 195.768214 -130.086862) (xy 195.707762 -129.994152)
			(xy 195.707254 -129.99339) (xy 195.706746 -129.992628) (xy 195.706492 -129.99212) (xy 195.705984 -129.991358)
			(xy 195.69938 -129.980944) (xy 195.69938 -129.73812) (xy 195.700008 -129.726568) (xy 195.709982 -129.705723)
			(xy 195.727924 -129.691162) (xy 195.739004 -129.687828) (xy 195.750942 -129.686304) (xy 196.487542 -129.686304)
			(xy 196.498297 -129.686847) (xy 196.517986 -129.695498) (xy 196.525642 -129.703068) (xy 196.531841 -129.710466)
			(xy 196.538756 -129.728474) (xy 196.539104 -129.73812) (xy 196.539104 -129.980944) (xy 196.323204 -130.311398)
			(xy 196.319162 -130.319611) (xy 196.316625 -130.337727) (xy 196.320579 -130.355587) (xy 196.325236 -130.363468)
			(xy 196.357494 -130.413252) (xy 196.539104 -130.690366) (xy 196.539104 -130.769106) (xy 197.174612 -130.769106)
			(xy 197.174612 -129.905506) (xy 197.175102 -129.875538) (xy 197.182925 -129.816116) (xy 197.198438 -129.758223)
			(xy 197.221374 -129.70285) (xy 197.251341 -129.650944) (xy 197.287828 -129.603394) (xy 197.330208 -129.561014)
			(xy 197.377758 -129.524527) (xy 197.429664 -129.49456) (xy 197.485037 -129.471624) (xy 197.54293 -129.456111)
			(xy 197.602352 -129.448288) (xy 197.662288 -129.448288) (xy 197.72171 -129.456111) (xy 197.779603 -129.471624)
			(xy 197.834976 -129.49456) (xy 197.886882 -129.524527) (xy 197.934432 -129.561014) (xy 197.976812 -129.603394)
			(xy 198.013299 -129.650944) (xy 198.043266 -129.70285) (xy 198.066202 -129.758223) (xy 198.081715 -129.816116)
			(xy 198.089538 -129.875538) (xy 198.090028 -129.905506) (xy 198.090028 -130.769106) (xy 198.089538 -130.799074)
			(xy 198.081715 -130.858496) (xy 198.066202 -130.916389) (xy 198.043266 -130.971762) (xy 198.013299 -131.023668)
			(xy 197.976812 -131.071218) (xy 197.934432 -131.113598) (xy 197.886882 -131.150085) (xy 197.834976 -131.180052)
			(xy 197.779603 -131.202988) (xy 197.72171 -131.218501) (xy 197.662288 -131.226324) (xy 197.602352 -131.226324)
			(xy 197.54293 -131.218501) (xy 197.485037 -131.202988) (xy 197.429664 -131.180052) (xy 197.377758 -131.150085)
			(xy 197.330208 -131.113598) (xy 197.287828 -131.071218) (xy 197.251341 -131.023668) (xy 197.221374 -130.971762)
			(xy 197.198438 -130.916389) (xy 197.182925 -130.858496) (xy 197.175102 -130.799074) (xy 197.174612 -130.769106)
			(xy 196.539104 -130.769106) (xy 196.539104 -130.93446) (xy 196.538472 -130.946012) (xy 196.528503 -130.966859)
			(xy 196.51056 -130.98142) (xy 196.49948 -130.984752) (xy 196.487542 -130.986276) (xy 195.750942 -130.986276)
			(xy 195.740186 -130.985747) (xy 195.720496 -130.977087) (xy 195.712842 -130.969512) (xy 195.706632 -130.962121)
			(xy 195.699725 -130.944108) (xy 195.69938 -130.93446) (xy 183.587132 -130.93446) (xy 183.568314 -130.97989)
			(xy 183.538347 -131.031796) (xy 183.50186 -131.079346) (xy 183.45948 -131.121726) (xy 183.41193 -131.158213)
			(xy 183.360024 -131.18818) (xy 183.304651 -131.211116) (xy 183.246758 -131.226629) (xy 183.187336 -131.234452)
			(xy 183.1274 -131.234452) (xy 183.067978 -131.226629) (xy 183.010085 -131.211116) (xy 182.954712 -131.18818)
			(xy 182.902806 -131.158213) (xy 182.855256 -131.121726) (xy 182.812876 -131.079346) (xy 182.776389 -131.031796)
			(xy 182.746422 -130.97989) (xy 182.723486 -130.924517) (xy 182.707973 -130.866624) (xy 182.70015 -130.807202)
			(xy 182.69966 -130.777234) (xy 170.65498 -130.777234) (xy 170.65498 -131.29641) (xy 170.65449 -131.326394)
			(xy 170.646662 -131.38585) (xy 170.631141 -131.443775) (xy 170.608192 -131.499179) (xy 170.578208 -131.551113)
			(xy 170.541702 -131.598689) (xy 170.499297 -131.641094) (xy 170.451721 -131.6776) (xy 170.399787 -131.707584)
			(xy 170.344383 -131.730533) (xy 170.286458 -131.746054) (xy 170.227002 -131.753882) (xy 170.167034 -131.753882)
			(xy 170.107578 -131.746054) (xy 170.049653 -131.730533) (xy 169.994249 -131.707584) (xy 169.942315 -131.6776)
			(xy 169.894739 -131.641094) (xy 169.852334 -131.598689) (xy 169.815828 -131.551113) (xy 169.785844 -131.499179)
			(xy 169.762895 -131.443775) (xy 169.747374 -131.38585) (xy 169.739546 -131.326394) (xy 169.739056 -131.29641)
			(xy 167.352472 -131.29641) (xy 167.352472 -131.368292) (xy 167.352077 -131.378417) (xy 167.344326 -131.397126)
			(xy 167.330003 -131.411442) (xy 167.31129 -131.419182) (xy 167.301164 -131.4196) (xy 166.120064 -131.4196)
			(xy 166.109953 -131.419144) (xy 166.091274 -131.411395) (xy 166.07698 -131.397089) (xy 166.069247 -131.378403)
			(xy 166.068756 -131.368292) (xy 162.816032 -131.368292) (xy 162.815572 -131.378442) (xy 162.807786 -131.397188)
			(xy 162.793401 -131.41151) (xy 162.774621 -131.419216) (xy 162.76447 -131.4196) (xy 161.58337 -131.4196)
			(xy 161.573246 -131.419099) (xy 161.554532 -131.411369) (xy 161.540178 -131.397088) (xy 161.532353 -131.378413)
			(xy 161.531808 -131.368292) (xy 153.158444 -131.368292) (xy 153.158444 -131.463288) (xy 153.157909 -131.473492)
			(xy 153.150106 -131.492348) (xy 153.135681 -131.506783) (xy 153.116831 -131.514601) (xy 153.106628 -131.515104)
			(xy 152.370028 -131.515104) (xy 152.359807 -131.514665) (xy 152.340918 -131.506848) (xy 152.326461 -131.492396)
			(xy 152.318638 -131.473509) (xy 152.318212 -131.463288) (xy 151.65243 -131.463288) (xy 151.636932 -131.500703)
			(xy 151.606948 -131.552637) (xy 151.570442 -131.600213) (xy 151.528037 -131.642618) (xy 151.480461 -131.679124)
			(xy 151.428527 -131.709108) (xy 151.373123 -131.732057) (xy 151.315198 -131.747578) (xy 151.255742 -131.755406)
			(xy 151.195774 -131.755406) (xy 151.136318 -131.747578) (xy 151.078393 -131.732057) (xy 151.022989 -131.709108)
			(xy 150.971055 -131.679124) (xy 150.923479 -131.642618) (xy 150.881074 -131.600213) (xy 150.844568 -131.552637)
			(xy 150.814584 -131.500703) (xy 150.791635 -131.445299) (xy 150.776114 -131.387374) (xy 150.768286 -131.327918)
			(xy 150.767796 -131.297934) (xy 84.369615 -131.297934) (xy 84.377099 -131.301034) (xy 84.429033 -131.331018)
			(xy 84.476609 -131.367524) (xy 84.519014 -131.409929) (xy 84.55552 -131.457505) (xy 84.585504 -131.509439)
			(xy 84.608453 -131.564843) (xy 84.623974 -131.622768) (xy 84.631802 -131.682224) (xy 84.632292 -131.712208)
			(xy 84.632292 -132.575808) (xy 84.631802 -132.605792) (xy 84.623974 -132.665248) (xy 84.608453 -132.723173)
			(xy 84.585504 -132.778577) (xy 84.55552 -132.830511) (xy 84.519014 -132.878087) (xy 84.476609 -132.920492)
			(xy 84.429033 -132.956998) (xy 84.377099 -132.986982) (xy 84.321695 -133.009931) (xy 84.26377 -133.025452)
			(xy 84.204314 -133.03328) (xy 84.144346 -133.03328) (xy 84.08489 -133.025452) (xy 84.026965 -133.009931)
			(xy 83.971561 -132.986982) (xy 83.919627 -132.956998) (xy 83.872051 -132.920492) (xy 83.829646 -132.878087)
			(xy 83.79314 -132.830511) (xy 83.763156 -132.778577) (xy 83.740207 -132.723173) (xy 83.724686 -132.665248)
			(xy 83.716858 -132.605792) (xy 83.716368 -132.575808) (xy 83.081368 -132.575808) (xy 83.081368 -132.741162)
			(xy 83.080905 -132.75133) (xy 83.073134 -132.770123) (xy 83.05876 -132.784509) (xy 83.039974 -132.792296)
			(xy 83.029806 -132.792724) (xy 82.293206 -132.792724) (xy 82.28303 -132.79233) (xy 82.264228 -132.78454)
			(xy 82.249842 -132.770145) (xy 82.242063 -132.751338) (xy 82.241644 -132.741162) (xy 65.630373 -132.741162)
			(xy 65.614244 -132.780101) (xy 65.58426 -132.832035) (xy 65.547754 -132.879611) (xy 65.505349 -132.922016)
			(xy 65.457773 -132.958522) (xy 65.405839 -132.988506) (xy 65.350435 -133.011455) (xy 65.29251 -133.026976)
			(xy 65.233054 -133.034804) (xy 65.173086 -133.034804) (xy 65.11363 -133.026976) (xy 65.055705 -133.011455)
			(xy 65.000301 -132.988506) (xy 64.948367 -132.958522) (xy 64.900791 -132.922016) (xy 64.858386 -132.879611)
			(xy 64.82188 -132.832035) (xy 64.791896 -132.780101) (xy 64.768947 -132.724697) (xy 64.753426 -132.666772)
			(xy 64.745598 -132.607316) (xy 64.745108 -132.577332) (xy 52.700428 -132.577332) (xy 52.700428 -133.096508)
			(xy 52.699938 -133.126476) (xy 52.692115 -133.185898) (xy 52.676602 -133.243791) (xy 52.653666 -133.299164)
			(xy 52.623699 -133.35107) (xy 52.587212 -133.39862) (xy 52.544832 -133.441) (xy 52.497282 -133.477487)
			(xy 52.445376 -133.507454) (xy 52.390003 -133.53039) (xy 52.33211 -133.545903) (xy 52.272688 -133.553726)
			(xy 52.212752 -133.553726) (xy 52.15333 -133.545903) (xy 52.095437 -133.53039) (xy 52.040064 -133.507454)
			(xy 51.988158 -133.477487) (xy 51.940608 -133.441) (xy 51.898228 -133.39862) (xy 51.861741 -133.35107)
			(xy 51.831774 -133.299164) (xy 51.808838 -133.243791) (xy 51.793325 -133.185898) (xy 51.785502 -133.126476)
			(xy 51.785012 -133.096508) (xy 51.252628 -133.096508) (xy 51.252628 -133.16839) (xy 51.252164 -133.17852)
			(xy 51.244434 -133.197247) (xy 51.23014 -133.211605) (xy 51.211448 -133.219419) (xy 51.20132 -133.219952)
			(xy 50.02022 -133.219952) (xy 50.010119 -133.2194) (xy 49.991451 -133.211678) (xy 49.977157 -133.197403)
			(xy 49.969413 -133.178744) (xy 49.968912 -133.168644) (xy 46.716175 -133.168644) (xy 46.715659 -133.178544)
			(xy 46.707893 -133.197308) (xy 46.693538 -133.211673) (xy 46.67478 -133.219452) (xy 46.664626 -133.219952)
			(xy 45.483526 -133.219952) (xy 45.473355 -133.219514) (xy 45.454559 -133.211736) (xy 45.440173 -133.197355)
			(xy 45.432389 -133.178561) (xy 45.431964 -133.16839) (xy 39.700708 -133.16839) (xy 39.700708 -133.269736)
			(xy 39.700247 -133.279947) (xy 39.692421 -133.298811) (xy 39.677974 -133.313246) (xy 39.659104 -133.321056)
			(xy 39.648892 -133.321552) (xy 38.912292 -133.321552) (xy 38.902088 -133.321025) (xy 38.883233 -133.313217)
			(xy 38.868799 -133.29879) (xy 38.86098 -133.27994) (xy 38.860476 -133.269736) (xy 38.194165 -133.269736)
			(xy 38.178714 -133.307038) (xy 38.148747 -133.358944) (xy 38.11226 -133.406494) (xy 38.06988 -133.448874)
			(xy 38.02233 -133.485361) (xy 37.970424 -133.515328) (xy 37.915051 -133.538264) (xy 37.857158 -133.553777)
			(xy 37.797736 -133.5616) (xy 37.7378 -133.5616) (xy 37.678378 -133.553777) (xy 37.620485 -133.538264)
			(xy 37.565112 -133.515328) (xy 37.513206 -133.485361) (xy 37.465656 -133.448874) (xy 37.423276 -133.406494)
			(xy 37.386789 -133.358944) (xy 37.356822 -133.307038) (xy 37.333886 -133.251665) (xy 37.318373 -133.193772)
			(xy 37.31055 -133.13435) (xy 37.31006 -133.104382) (xy 4.30911 -133.104382) (xy 4.30911 -134.897876)
			(xy 34.667952 -134.897876) (xy 34.667952 -134.034276) (xy 34.668442 -134.004308) (xy 34.676265 -133.944886)
			(xy 34.691778 -133.886993) (xy 34.714714 -133.83162) (xy 34.744681 -133.779714) (xy 34.781168 -133.732164)
			(xy 34.823548 -133.689784) (xy 34.871098 -133.653297) (xy 34.923004 -133.62333) (xy 34.978377 -133.600394)
			(xy 35.03627 -133.584881) (xy 35.095692 -133.577058) (xy 35.155628 -133.577058) (xy 35.21505 -133.584881)
			(xy 35.272943 -133.600394) (xy 35.328316 -133.62333) (xy 35.380222 -133.653297) (xy 35.427772 -133.689784)
			(xy 35.470152 -133.732164) (xy 35.506639 -133.779714) (xy 35.536606 -133.83162) (xy 35.559542 -133.886993)
			(xy 35.575055 -133.944886) (xy 35.582878 -134.004308) (xy 35.583368 -134.034276) (xy 35.583368 -134.897876)
			(xy 35.582878 -134.927844) (xy 35.575055 -134.987266) (xy 35.559542 -135.045159) (xy 35.552057 -135.06323)
			(xy 36.218368 -135.06323) (xy 36.218368 -134.835646) (xy 36.218622 -134.831582) (xy 36.218876 -134.829042)
			(xy 36.218876 -134.820406) (xy 36.224464 -134.81177) (xy 36.225734 -134.809738) (xy 36.22675 -134.807706)
			(xy 36.424108 -134.506716) (xy 36.427979 -134.500389) (xy 36.432238 -134.486189) (xy 36.43249 -134.478776)
			(xy 36.43249 -134.453122) (xy 36.432288 -134.445788) (xy 36.428155 -134.431717) (xy 36.424362 -134.425436)
			(xy 36.226496 -134.122414) (xy 36.22421 -134.118604) (xy 36.223956 -134.118096) (xy 36.22294 -134.116318)
			(xy 36.218876 -134.109714) (xy 36.218876 -134.101586) (xy 36.218622 -134.099046) (xy 36.218368 -134.094982)
			(xy 36.218368 -133.86689) (xy 36.218756 -133.856714) (xy 36.22655 -133.837913) (xy 36.240947 -133.823528)
			(xy 36.259754 -133.815749) (xy 36.26993 -133.815328) (xy 37.006784 -133.815328) (xy 37.016965 -133.815789)
			(xy 37.035786 -133.823558) (xy 37.050215 -133.837924) (xy 37.058066 -133.856711) (xy 37.0586 -133.86689)
			(xy 37.0586 -134.094474) (xy 37.058346 -134.098538) (xy 37.058092 -134.101078) (xy 37.058092 -134.109714)
			(xy 37.05225 -134.119112) (xy 37.051488 -134.120382) (xy 37.050218 -134.122414) (xy 36.844478 -134.43712)
			(xy 36.839457 -134.445658) (xy 36.835628 -134.465066) (xy 36.839432 -134.48448) (xy 36.844478 -134.493)
			(xy 37.050218 -134.806436) (xy 37.051234 -134.808468) (xy 37.052504 -134.8105) (xy 37.058092 -134.819136)
			(xy 37.058092 -134.827772) (xy 37.058346 -134.830312) (xy 37.0586 -134.834376) (xy 37.0586 -134.968488)
			(xy 45.431964 -134.968488) (xy 45.431964 -133.96214) (xy 45.432454 -133.951993) (xy 45.440229 -133.933248)
			(xy 45.454605 -133.918925) (xy 45.473378 -133.911217) (xy 45.483526 -133.910832) (xy 46.664626 -133.910832)
			(xy 46.674753 -133.911305) (xy 46.693474 -133.91904) (xy 46.707829 -133.93333) (xy 46.715649 -133.952015)
			(xy 46.716188 -133.96214) (xy 46.716188 -134.968488) (xy 49.968912 -134.968488) (xy 49.968912 -133.96214)
			(xy 49.969349 -133.952019) (xy 49.977086 -133.933314) (xy 49.991397 -133.918998) (xy 50.010099 -133.911253)
			(xy 50.02022 -133.910832) (xy 51.20132 -133.910832) (xy 51.211448 -133.9112) (xy 51.230158 -133.918961)
			(xy 51.244473 -133.933292) (xy 51.252212 -133.952012) (xy 51.252628 -133.96214) (xy 51.252628 -134.896352)
			(xy 53.639212 -134.896352) (xy 53.639212 -134.032752) (xy 53.639702 -134.002784) (xy 53.647525 -133.943362)
			(xy 53.663038 -133.885469) (xy 53.685974 -133.830096) (xy 53.715941 -133.77819) (xy 53.752428 -133.73064)
			(xy 53.794808 -133.68826) (xy 53.842358 -133.651773) (xy 53.894264 -133.621806) (xy 53.949637 -133.59887)
			(xy 54.00753 -133.583357) (xy 54.066952 -133.575534) (xy 54.126888 -133.575534) (xy 54.18631 -133.583357)
			(xy 54.244203 -133.59887) (xy 54.299576 -133.621806) (xy 54.351482 -133.651773) (xy 54.399032 -133.68826)
			(xy 54.441412 -133.73064) (xy 54.477899 -133.77819) (xy 54.507866 -133.830096) (xy 54.530802 -133.885469)
			(xy 54.546315 -133.943362) (xy 54.554138 -134.002784) (xy 54.554628 -134.032752) (xy 54.554628 -134.377176)
			(xy 66.599308 -134.377176) (xy 66.599308 -133.513576) (xy 66.599798 -133.483592) (xy 66.607626 -133.424136)
			(xy 66.623147 -133.366211) (xy 66.646096 -133.310807) (xy 66.67608 -133.258873) (xy 66.712586 -133.211297)
			(xy 66.754991 -133.168892) (xy 66.802567 -133.132386) (xy 66.854501 -133.102402) (xy 66.909905 -133.079453)
			(xy 66.96783 -133.063932) (xy 67.027286 -133.056104) (xy 67.087254 -133.056104) (xy 67.14671 -133.063932)
			(xy 67.204635 -133.079453) (xy 67.260039 -133.102402) (xy 67.311973 -133.132386) (xy 67.359549 -133.168892)
			(xy 67.401954 -133.211297) (xy 67.43846 -133.258873) (xy 67.468444 -133.310807) (xy 67.491393 -133.366211)
			(xy 67.506914 -133.424136) (xy 67.514742 -133.483592) (xy 67.515232 -133.513576) (xy 67.515232 -134.377176)
			(xy 67.514742 -134.40716) (xy 67.509326 -134.448296) (xy 68.047108 -134.448296) (xy 68.047108 -133.441948)
			(xy 68.047556 -133.431828) (xy 68.055289 -133.413124) (xy 68.069597 -133.398807) (xy 68.088296 -133.391062)
			(xy 68.098416 -133.39064) (xy 69.27977 -133.39064) (xy 69.289895 -133.391151) (xy 69.308615 -133.398869)
			(xy 69.322973 -133.413148) (xy 69.330793 -133.431826) (xy 69.331332 -133.441948) (xy 69.331332 -134.448296)
			(xy 72.584056 -134.448296) (xy 72.584056 -133.441948) (xy 72.584554 -133.431834) (xy 72.592278 -133.41314)
			(xy 72.606569 -133.398826) (xy 72.625251 -133.391071) (xy 72.635364 -133.39064) (xy 73.816464 -133.39064)
			(xy 73.826589 -133.391047) (xy 73.845299 -133.39879) (xy 73.859616 -133.413111) (xy 73.867356 -133.431823)
			(xy 73.867772 -133.441948) (xy 73.867772 -134.448296) (xy 73.86738 -134.458422) (xy 73.859628 -134.477131)
			(xy 73.845304 -134.491446) (xy 73.82659 -134.499186) (xy 73.816464 -134.499604) (xy 72.635364 -134.499604)
			(xy 72.625253 -134.499144) (xy 72.606575 -134.491396) (xy 72.592282 -134.477091) (xy 72.584548 -134.458407)
			(xy 72.584056 -134.448296) (xy 69.331332 -134.448296) (xy 69.330812 -134.458401) (xy 69.323082 -134.477072)
			(xy 69.308796 -134.491366) (xy 69.290128 -134.499107) (xy 69.280024 -134.499604) (xy 68.09867 -134.499604)
			(xy 68.088547 -134.499099) (xy 68.069833 -134.49137) (xy 68.05548 -134.47709) (xy 68.047654 -134.458417)
			(xy 68.047108 -134.448296) (xy 67.509326 -134.448296) (xy 67.506914 -134.466616) (xy 67.491393 -134.524541)
			(xy 67.487203 -134.534656) (xy 79.599536 -134.534656) (xy 79.599536 -134.291832) (xy 79.718408 -134.110476)
			(xy 79.780892 -134.014972) (xy 79.805022 -133.978142) (xy 79.808885 -133.971811) (xy 79.813149 -133.957614)
			(xy 79.813404 -133.950202) (xy 79.813404 -133.924294) (xy 79.81322 -133.918143) (xy 79.810261 -133.906202)
			(xy 79.807562 -133.900672) (xy 79.694024 -133.726682) (xy 79.673958 -133.695694) (xy 79.66837 -133.687058)
			(xy 79.607918 -133.594348) (xy 79.60741 -133.593586) (xy 79.606902 -133.592824) (xy 79.606648 -133.592316)
			(xy 79.60614 -133.591554) (xy 79.599536 -133.58114) (xy 79.599536 -133.338316) (xy 79.60012 -133.326758)
			(xy 79.610108 -133.305905) (xy 79.628071 -133.291349) (xy 79.63916 -133.288024) (xy 79.651098 -133.2865)
			(xy 80.387698 -133.2865) (xy 80.398456 -133.287014) (xy 80.418145 -133.295685) (xy 80.425798 -133.303264)
			(xy 80.432003 -133.310658) (xy 80.438912 -133.328669) (xy 80.43926 -133.338316) (xy 80.43926 -133.58114)
			(xy 80.22336 -133.911594) (xy 80.219326 -133.919809) (xy 80.21679 -133.937923) (xy 80.220739 -133.955782)
			(xy 80.225392 -133.963664) (xy 80.25765 -134.013448) (xy 80.43926 -134.290562) (xy 80.43926 -134.369302)
			(xy 81.07426 -134.369302) (xy 81.07426 -133.505702) (xy 81.07475 -133.475718) (xy 81.082578 -133.416262)
			(xy 81.098099 -133.358337) (xy 81.121048 -133.302933) (xy 81.151032 -133.250999) (xy 81.187538 -133.203423)
			(xy 81.229943 -133.161018) (xy 81.277519 -133.124512) (xy 81.329453 -133.094528) (xy 81.384857 -133.071579)
			(xy 81.442782 -133.056058) (xy 81.502238 -133.04823) (xy 81.562206 -133.04823) (xy 81.621662 -133.056058)
			(xy 81.679587 -133.071579) (xy 81.734991 -133.094528) (xy 81.752059 -133.104382) (xy 153.409904 -133.104382)
			(xy 153.409904 -132.240782) (xy 153.410394 -132.210798) (xy 153.418222 -132.151342) (xy 153.433743 -132.093417)
			(xy 153.456692 -132.038013) (xy 153.486676 -131.986079) (xy 153.523182 -131.938503) (xy 153.565587 -131.896098)
			(xy 153.613163 -131.859592) (xy 153.665097 -131.829608) (xy 153.720501 -131.806659) (xy 153.778426 -131.791138)
			(xy 153.837882 -131.78331) (xy 153.89785 -131.78331) (xy 153.957306 -131.791138) (xy 154.015231 -131.806659)
			(xy 154.070635 -131.829608) (xy 154.122569 -131.859592) (xy 154.170145 -131.896098) (xy 154.21255 -131.938503)
			(xy 154.249056 -131.986079) (xy 154.27904 -132.038013) (xy 154.301989 -132.093417) (xy 154.31751 -132.151342)
			(xy 154.325338 -132.210798) (xy 154.325828 -132.240782) (xy 154.325828 -133.104382) (xy 154.325338 -133.134366)
			(xy 154.31751 -133.193822) (xy 154.301989 -133.251747) (xy 154.294538 -133.269736) (xy 154.96032 -133.269736)
			(xy 154.96032 -133.042152) (xy 154.960574 -133.038088) (xy 154.960828 -133.035548) (xy 154.960828 -133.026912)
			(xy 154.966416 -133.018276) (xy 154.967686 -133.016244) (xy 154.968702 -133.014212) (xy 155.16606 -132.713222)
			(xy 155.169933 -132.706897) (xy 155.17419 -132.692695) (xy 155.174442 -132.685282) (xy 155.174442 -132.659628)
			(xy 155.174245 -132.652293) (xy 155.170109 -132.638222) (xy 155.166314 -132.631942) (xy 154.968448 -132.32892)
			(xy 154.966162 -132.32511) (xy 154.965908 -132.324602) (xy 154.964892 -132.322824) (xy 154.960828 -132.31622)
			(xy 154.960828 -132.308092) (xy 154.960574 -132.305552) (xy 154.96032 -132.301488) (xy 154.96032 -132.073396)
			(xy 154.960709 -132.06317) (xy 154.968541 -132.044275) (xy 154.983009 -132.029818) (xy 155.001909 -132.022002)
			(xy 155.012136 -132.02158) (xy 155.748736 -132.02158) (xy 155.758946 -132.022052) (xy 155.777807 -132.029876)
			(xy 155.792242 -132.04432) (xy 155.800054 -132.063186) (xy 155.800552 -132.073396) (xy 155.800552 -132.30098)
			(xy 155.800298 -132.305044) (xy 155.800044 -132.307584) (xy 155.800044 -132.31622) (xy 155.794202 -132.325618)
			(xy 155.79344 -132.326888) (xy 155.79217 -132.32892) (xy 155.58643 -132.643626) (xy 155.5814 -132.65216)
			(xy 155.577569 -132.671571) (xy 155.581379 -132.690987) (xy 155.58643 -132.699506) (xy 155.79217 -133.012942)
			(xy 155.793186 -133.014974) (xy 155.794456 -133.017006) (xy 155.800044 -133.025642) (xy 155.800044 -133.034278)
			(xy 155.800298 -133.036818) (xy 155.800552 -133.040882) (xy 155.800552 -133.16839) (xy 161.531808 -133.16839)
			(xy 161.531808 -132.162042) (xy 161.532298 -132.151877) (xy 161.540063 -132.133089) (xy 161.554428 -132.118704)
			(xy 161.573205 -132.110912) (xy 161.58337 -132.11048) (xy 162.76447 -132.11048) (xy 162.774645 -132.11089)
			(xy 162.793447 -132.118672) (xy 162.807834 -132.133063) (xy 162.815613 -132.151867) (xy 162.816032 -132.162042)
			(xy 162.816032 -133.16839) (xy 162.816022 -133.168644) (xy 166.068756 -133.168644) (xy 166.068756 -132.162042)
			(xy 166.069262 -132.151916) (xy 166.076978 -132.133193) (xy 166.09126 -132.118835) (xy 166.109941 -132.111017)
			(xy 166.120064 -132.11048) (xy 167.301164 -132.11048) (xy 167.311282 -132.110945) (xy 167.329981 -132.118678)
			(xy 167.344295 -132.132979) (xy 167.352045 -132.151671) (xy 167.352472 -132.161788) (xy 167.352472 -133.096508)
			(xy 167.884856 -133.096508) (xy 167.884856 -132.232908) (xy 167.885346 -132.202924) (xy 167.893174 -132.143468)
			(xy 167.908695 -132.085543) (xy 167.931644 -132.030139) (xy 167.961628 -131.978205) (xy 167.998134 -131.930629)
			(xy 168.040539 -131.888224) (xy 168.088115 -131.851718) (xy 168.140049 -131.821734) (xy 168.195453 -131.798785)
			(xy 168.253378 -131.783264) (xy 168.312834 -131.775436) (xy 168.372802 -131.775436) (xy 168.432258 -131.783264)
			(xy 168.490183 -131.798785) (xy 168.545587 -131.821734) (xy 168.597521 -131.851718) (xy 168.645097 -131.888224)
			(xy 168.687502 -131.930629) (xy 168.724008 -131.978205) (xy 168.753992 -132.030139) (xy 168.776941 -132.085543)
			(xy 168.792462 -132.143468) (xy 168.80029 -132.202924) (xy 168.80078 -132.232908) (xy 168.80078 -132.577332)
			(xy 180.84546 -132.577332) (xy 180.84546 -131.713732) (xy 180.84595 -131.683764) (xy 180.853773 -131.624342)
			(xy 180.869286 -131.566449) (xy 180.892222 -131.511076) (xy 180.922189 -131.45917) (xy 180.958676 -131.41162)
			(xy 181.001056 -131.36924) (xy 181.048606 -131.332753) (xy 181.100512 -131.302786) (xy 181.155885 -131.27985)
			(xy 181.213778 -131.264337) (xy 181.2732 -131.256514) (xy 181.333136 -131.256514) (xy 181.392558 -131.264337)
			(xy 181.450451 -131.27985) (xy 181.505824 -131.302786) (xy 181.55773 -131.332753) (xy 181.60528 -131.36924)
			(xy 181.64766 -131.41162) (xy 181.684147 -131.45917) (xy 181.714114 -131.511076) (xy 181.73705 -131.566449)
			(xy 181.752563 -131.624342) (xy 181.760386 -131.683764) (xy 181.760876 -131.713732) (xy 181.760876 -132.577332)
			(xy 181.760386 -132.6073) (xy 181.755002 -132.648198) (xy 184.146952 -132.648198) (xy 184.146952 -131.64185)
			(xy 184.147405 -131.63168) (xy 184.155176 -131.612884) (xy 184.169553 -131.598496) (xy 184.188344 -131.590712)
			(xy 184.198514 -131.590288) (xy 185.379614 -131.590288) (xy 185.389793 -131.590654) (xy 185.408597 -131.598453)
			(xy 185.422983 -131.612857) (xy 185.430759 -131.631671) (xy 185.431176 -131.64185) (xy 185.431176 -132.648198)
			(xy 188.6839 -132.648198) (xy 188.6839 -131.64185) (xy 188.684466 -131.631731) (xy 188.69217 -131.613019)
			(xy 188.706432 -131.598662) (xy 188.725093 -131.590834) (xy 188.735208 -131.590288) (xy 189.916308 -131.590288)
			(xy 189.926461 -131.590715) (xy 189.945211 -131.598511) (xy 189.959534 -131.612906) (xy 189.967235 -131.631695)
			(xy 189.967616 -131.64185) (xy 189.967616 -132.648198) (xy 189.96717 -132.65833) (xy 189.959435 -132.677059)
			(xy 189.945136 -132.691417) (xy 189.926438 -132.699229) (xy 189.916308 -132.69976) (xy 188.735208 -132.69976)
			(xy 188.725049 -132.699371) (xy 188.706289 -132.691571) (xy 188.691964 -132.677163) (xy 188.684272 -132.658359)
			(xy 188.6839 -132.648198) (xy 185.431176 -132.648198) (xy 185.430665 -132.658354) (xy 185.422894 -132.67712)
			(xy 185.408534 -132.691485) (xy 185.38977 -132.699262) (xy 185.379614 -132.69976) (xy 184.198514 -132.69976)
			(xy 184.188343 -132.699325) (xy 184.169548 -132.691544) (xy 184.155163 -132.677162) (xy 184.147378 -132.658369)
			(xy 184.146952 -132.648198) (xy 181.755002 -132.648198) (xy 181.752563 -132.666722) (xy 181.73705 -132.724615)
			(xy 181.730196 -132.741162) (xy 198.341488 -132.741162) (xy 198.341488 -132.498338) (xy 198.46036 -132.316982)
			(xy 198.522844 -132.221478) (xy 198.546974 -132.184648) (xy 198.550839 -132.178318) (xy 198.5551 -132.16412)
			(xy 198.555356 -132.156708) (xy 198.555356 -132.1308) (xy 198.555164 -132.12465) (xy 198.552209 -132.112709)
			(xy 198.549514 -132.107178) (xy 198.435976 -131.933188) (xy 198.41591 -131.9022) (xy 198.410322 -131.893564)
			(xy 198.34987 -131.800854) (xy 198.349362 -131.800092) (xy 198.348854 -131.79933) (xy 198.3486 -131.798822)
			(xy 198.348092 -131.79806) (xy 198.341488 -131.787646) (xy 198.341488 -131.544822) (xy 198.341883 -131.534646)
			(xy 198.34967 -131.515842) (xy 198.364066 -131.501455) (xy 198.382873 -131.493678) (xy 198.39305 -131.49326)
			(xy 199.12965 -131.49326) (xy 199.139821 -131.493705) (xy 199.158619 -131.501478) (xy 199.173006 -131.515858)
			(xy 199.180789 -131.534651) (xy 199.181212 -131.544822) (xy 199.181212 -131.787646) (xy 198.965312 -132.1181)
			(xy 198.961268 -132.126312) (xy 198.958731 -132.144428) (xy 198.962686 -132.162289) (xy 198.967344 -132.17017)
			(xy 198.999602 -132.219954) (xy 199.181212 -132.497068) (xy 199.181212 -132.575808) (xy 199.81672 -132.575808)
			(xy 199.81672 -131.712208) (xy 199.81721 -131.68224) (xy 199.825033 -131.622818) (xy 199.840546 -131.564925)
			(xy 199.863482 -131.509552) (xy 199.893449 -131.457646) (xy 199.929936 -131.410096) (xy 199.972316 -131.367716)
			(xy 200.019866 -131.331229) (xy 200.071772 -131.301262) (xy 200.127145 -131.278326) (xy 200.185038 -131.262813)
			(xy 200.24446 -131.25499) (xy 200.304396 -131.25499) (xy 200.363818 -131.262813) (xy 200.421711 -131.278326)
			(xy 200.469049 -131.297934) (xy 266.86764 -131.297934) (xy 266.86764 -130.434334) (xy 266.86813 -130.40435)
			(xy 266.875958 -130.344894) (xy 266.891479 -130.286969) (xy 266.914428 -130.231565) (xy 266.944412 -130.179631)
			(xy 266.980918 -130.132055) (xy 267.023323 -130.08965) (xy 267.070899 -130.053144) (xy 267.122833 -130.02316)
			(xy 267.178237 -130.000211) (xy 267.236162 -129.98469) (xy 267.295618 -129.976862) (xy 267.355586 -129.976862)
			(xy 267.415042 -129.98469) (xy 267.472967 -130.000211) (xy 267.528371 -130.02316) (xy 267.580305 -130.053144)
			(xy 267.627881 -130.08965) (xy 267.670286 -130.132055) (xy 267.706792 -130.179631) (xy 267.736776 -130.231565)
			(xy 267.759725 -130.286969) (xy 267.775246 -130.344894) (xy 267.783074 -130.40435) (xy 267.783564 -130.434334)
			(xy 267.783564 -131.297934) (xy 267.783074 -131.327918) (xy 267.775246 -131.387374) (xy 267.759725 -131.445299)
			(xy 267.752274 -131.463288) (xy 268.418564 -131.463288) (xy 268.418564 -131.220464) (xy 268.537436 -131.039108)
			(xy 268.59992 -130.943604) (xy 268.62405 -130.906774) (xy 268.627903 -130.900438) (xy 268.632172 -130.886244)
			(xy 268.632432 -130.878834) (xy 268.632432 -130.852926) (xy 268.632234 -130.846776) (xy 268.629284 -130.834836)
			(xy 268.62659 -130.829304) (xy 268.513052 -130.655314) (xy 268.492986 -130.624326) (xy 268.487398 -130.61569)
			(xy 268.426946 -130.52298) (xy 268.426438 -130.522218) (xy 268.42593 -130.521456) (xy 268.425676 -130.520948)
			(xy 268.425168 -130.520186) (xy 268.418564 -130.509772) (xy 268.418564 -130.266948) (xy 268.419226 -130.2554)
			(xy 268.429185 -130.234558) (xy 268.447114 -130.219993) (xy 268.458188 -130.216656) (xy 268.470126 -130.215132)
			(xy 269.206726 -130.215132) (xy 269.217481 -130.215676) (xy 269.23717 -130.224325) (xy 269.244826 -130.231896)
			(xy 269.251036 -130.239287) (xy 269.257944 -130.2573) (xy 269.258288 -130.266948) (xy 269.258288 -130.509772)
			(xy 269.042388 -130.840226) (xy 269.038326 -130.84843) (xy 269.035797 -130.866552) (xy 269.039759 -130.884415)
			(xy 269.04442 -130.892296) (xy 269.076678 -130.94208) (xy 269.258288 -131.219194) (xy 269.258288 -131.368292)
			(xy 277.63216 -131.368292) (xy 277.63216 -130.361944) (xy 277.632651 -130.351829) (xy 277.640377 -130.333134)
			(xy 277.654671 -130.31882) (xy 277.673354 -130.311066) (xy 277.683468 -130.310636) (xy 278.864568 -130.310636)
			(xy 278.874693 -130.311043) (xy 278.893403 -130.318787) (xy 278.90772 -130.333107) (xy 278.91546 -130.351819)
			(xy 278.915876 -130.361944) (xy 278.915876 -131.368292) (xy 282.1686 -131.368292) (xy 282.1686 -130.361944)
			(xy 282.169052 -130.351824) (xy 282.176786 -130.333122) (xy 282.191092 -130.318806) (xy 282.209789 -130.311059)
			(xy 282.219908 -130.310636) (xy 283.401262 -130.310636) (xy 283.411386 -130.311158) (xy 283.430105 -130.318872)
			(xy 283.444463 -130.333148) (xy 283.452284 -130.351823) (xy 283.452824 -130.361944) (xy 283.452824 -131.29641)
			(xy 285.8389 -131.29641) (xy 285.8389 -130.43281) (xy 285.83939 -130.402826) (xy 285.847218 -130.34337)
			(xy 285.862739 -130.285445) (xy 285.885688 -130.230041) (xy 285.915672 -130.178107) (xy 285.952178 -130.130531)
			(xy 285.994583 -130.088126) (xy 286.042159 -130.05162) (xy 286.094093 -130.021636) (xy 286.149497 -129.998687)
			(xy 286.207422 -129.983166) (xy 286.266878 -129.975338) (xy 286.326846 -129.975338) (xy 286.386302 -129.983166)
			(xy 286.444227 -129.998687) (xy 286.499631 -130.021636) (xy 286.551565 -130.05162) (xy 286.599141 -130.088126)
			(xy 286.641546 -130.130531) (xy 286.678052 -130.178107) (xy 286.708036 -130.230041) (xy 286.730985 -130.285445)
			(xy 286.746506 -130.34337) (xy 286.754334 -130.402826) (xy 286.754824 -130.43281) (xy 286.754824 -130.777234)
			(xy 298.799504 -130.777234) (xy 298.799504 -129.913634) (xy 298.799994 -129.883666) (xy 298.807817 -129.824244)
			(xy 298.82333 -129.766351) (xy 298.846266 -129.710978) (xy 298.876233 -129.659072) (xy 298.91272 -129.611522)
			(xy 298.9551 -129.569142) (xy 299.00265 -129.532655) (xy 299.054556 -129.502688) (xy 299.109929 -129.479752)
			(xy 299.167822 -129.464239) (xy 299.227244 -129.456416) (xy 299.28718 -129.456416) (xy 299.346602 -129.464239)
			(xy 299.404495 -129.479752) (xy 299.459868 -129.502688) (xy 299.511774 -129.532655) (xy 299.559324 -129.569142)
			(xy 299.601704 -129.611522) (xy 299.638191 -129.659072) (xy 299.668158 -129.710978) (xy 299.691094 -129.766351)
			(xy 299.706607 -129.824244) (xy 299.71443 -129.883666) (xy 299.71492 -129.913634) (xy 299.71492 -130.777234)
			(xy 299.71443 -130.807202) (xy 299.709046 -130.8481) (xy 300.247304 -130.8481) (xy 300.247304 -129.841752)
			(xy 300.247746 -129.83164) (xy 300.2555 -129.81296) (xy 300.26981 -129.798667) (xy 300.288499 -129.790934)
			(xy 300.298612 -129.790444) (xy 301.479712 -129.790444) (xy 301.489815 -129.790974) (xy 301.508482 -129.798705)
			(xy 301.522775 -129.812988) (xy 301.530519 -129.83165) (xy 301.53102 -129.841752) (xy 301.53102 -130.8481)
			(xy 304.783744 -130.8481) (xy 304.783744 -129.841752) (xy 304.784181 -129.831602) (xy 304.791982 -129.812859)
			(xy 304.806373 -129.79854) (xy 304.825154 -129.790831) (xy 304.835306 -129.790444) (xy 306.016406 -129.790444)
			(xy 306.026534 -129.790922) (xy 306.045256 -129.798652) (xy 306.059612 -129.812941) (xy 306.06743 -129.831627)
			(xy 306.067968 -129.841752) (xy 306.067968 -130.8481) (xy 306.067578 -130.858258) (xy 306.059776 -130.877017)
			(xy 306.045369 -130.891341) (xy 306.026566 -130.899035) (xy 306.016406 -130.899408) (xy 304.835306 -130.899408)
			(xy 304.825186 -130.89887) (xy 304.806474 -130.891153) (xy 304.792119 -130.876883) (xy 304.784291 -130.858217)
			(xy 304.783744 -130.8481) (xy 301.53102 -130.8481) (xy 301.530515 -130.858206) (xy 301.522781 -130.876881)
			(xy 301.508491 -130.891175) (xy 301.489818 -130.898913) (xy 301.479712 -130.899408) (xy 300.298612 -130.899408)
			(xy 300.288491 -130.898974) (xy 300.269789 -130.891232) (xy 300.255475 -130.876921) (xy 300.247728 -130.858221)
			(xy 300.247304 -130.8481) (xy 299.709046 -130.8481) (xy 299.706607 -130.866624) (xy 299.691094 -130.924517)
			(xy 299.686976 -130.93446) (xy 311.799224 -130.93446) (xy 311.799224 -130.706876) (xy 311.799478 -130.702812)
			(xy 311.799732 -130.700272) (xy 311.799732 -130.691636) (xy 311.80532 -130.683) (xy 311.80659 -130.680968)
			(xy 311.807606 -130.678936) (xy 312.004964 -130.377946) (xy 312.008828 -130.371616) (xy 312.013091 -130.357418)
			(xy 312.013346 -130.350006) (xy 312.013346 -130.324352) (xy 312.013138 -130.317018) (xy 312.00901 -130.302947)
			(xy 312.005218 -130.296666) (xy 311.807352 -129.993644) (xy 311.805066 -129.989834) (xy 311.804812 -129.989326)
			(xy 311.803796 -129.987548) (xy 311.799732 -129.980944) (xy 311.799732 -129.972816) (xy 311.799478 -129.970276)
			(xy 311.799224 -129.966212) (xy 311.799224 -129.73812) (xy 311.799629 -129.727895) (xy 311.807454 -129.709)
			(xy 311.821917 -129.694542) (xy 311.840814 -129.686725) (xy 311.85104 -129.686304) (xy 312.58764 -129.686304)
			(xy 312.597853 -129.68675) (xy 312.616719 -129.694579) (xy 312.631155 -129.709031) (xy 312.638962 -129.727907)
			(xy 312.639456 -129.73812) (xy 312.639456 -129.965704) (xy 312.639202 -129.969768) (xy 312.638948 -129.972308)
			(xy 312.638948 -129.980944) (xy 312.633106 -129.990342) (xy 312.632344 -129.991612) (xy 312.631074 -129.993644)
			(xy 312.425334 -130.30835) (xy 312.420292 -130.316876) (xy 312.416474 -130.336292) (xy 312.420286 -130.355709)
			(xy 312.425334 -130.36423) (xy 312.631074 -130.677666) (xy 312.63209 -130.679698) (xy 312.63336 -130.68173)
			(xy 312.638948 -130.690366) (xy 312.638948 -130.699002) (xy 312.639202 -130.701542) (xy 312.639456 -130.705606)
			(xy 312.639456 -130.769106) (xy 313.274456 -130.769106) (xy 313.274456 -129.905506) (xy 313.274946 -129.875538)
			(xy 313.282769 -129.816116) (xy 313.298282 -129.758223) (xy 313.321218 -129.70285) (xy 313.351185 -129.650944)
			(xy 313.387672 -129.603394) (xy 313.430052 -129.561014) (xy 313.477602 -129.524527) (xy 313.529508 -129.49456)
			(xy 313.584881 -129.471624) (xy 313.642774 -129.456111) (xy 313.702196 -129.448288) (xy 313.762132 -129.448288)
			(xy 313.821554 -129.456111) (xy 313.879447 -129.471624) (xy 313.93482 -129.49456) (xy 313.986726 -129.524527)
			(xy 314.034276 -129.561014) (xy 314.076656 -129.603394) (xy 314.113143 -129.650944) (xy 314.14311 -129.70285)
			(xy 314.166046 -129.758223) (xy 314.181559 -129.816116) (xy 314.189382 -129.875538) (xy 314.189872 -129.905506)
			(xy 314.189872 -130.769106) (xy 314.189382 -130.799074) (xy 314.181559 -130.858496) (xy 314.166046 -130.916389)
			(xy 314.14311 -130.971762) (xy 314.113143 -131.023668) (xy 314.076656 -131.071218) (xy 314.034276 -131.113598)
			(xy 313.986726 -131.150085) (xy 313.93482 -131.180052) (xy 313.879447 -131.202988) (xy 313.821554 -131.218501)
			(xy 313.762132 -131.226324) (xy 313.702196 -131.226324) (xy 313.642774 -131.218501) (xy 313.584881 -131.202988)
			(xy 313.529508 -131.180052) (xy 313.477602 -131.150085) (xy 313.430052 -131.113598) (xy 313.387672 -131.071218)
			(xy 313.351185 -131.023668) (xy 313.321218 -130.971762) (xy 313.298282 -130.916389) (xy 313.282769 -130.858496)
			(xy 313.274946 -130.799074) (xy 313.274456 -130.769106) (xy 312.639456 -130.769106) (xy 312.639456 -130.93446)
			(xy 312.638886 -130.94466) (xy 312.631094 -130.963513) (xy 312.61668 -130.977949) (xy 312.59784 -130.985771)
			(xy 312.58764 -130.986276) (xy 311.85104 -130.986276) (xy 311.840816 -130.985854) (xy 311.821922 -130.978037)
			(xy 311.807463 -130.963578) (xy 311.799646 -130.944684) (xy 311.799224 -130.93446) (xy 299.686976 -130.93446)
			(xy 299.668158 -130.97989) (xy 299.638191 -131.031796) (xy 299.601704 -131.079346) (xy 299.559324 -131.121726)
			(xy 299.511774 -131.158213) (xy 299.459868 -131.18818) (xy 299.404495 -131.211116) (xy 299.346602 -131.226629)
			(xy 299.28718 -131.234452) (xy 299.227244 -131.234452) (xy 299.167822 -131.226629) (xy 299.109929 -131.211116)
			(xy 299.054556 -131.18818) (xy 299.00265 -131.158213) (xy 298.9551 -131.121726) (xy 298.91272 -131.079346)
			(xy 298.876233 -131.031796) (xy 298.846266 -130.97989) (xy 298.82333 -130.924517) (xy 298.807817 -130.866624)
			(xy 298.799994 -130.807202) (xy 298.799504 -130.777234) (xy 286.754824 -130.777234) (xy 286.754824 -131.29641)
			(xy 286.754334 -131.326394) (xy 286.746506 -131.38585) (xy 286.730985 -131.443775) (xy 286.708036 -131.499179)
			(xy 286.678052 -131.551113) (xy 286.641546 -131.598689) (xy 286.599141 -131.641094) (xy 286.551565 -131.6776)
			(xy 286.499631 -131.707584) (xy 286.444227 -131.730533) (xy 286.386302 -131.746054) (xy 286.326846 -131.753882)
			(xy 286.266878 -131.753882) (xy 286.207422 -131.746054) (xy 286.149497 -131.730533) (xy 286.094093 -131.707584)
			(xy 286.042159 -131.6776) (xy 285.994583 -131.641094) (xy 285.952178 -131.598689) (xy 285.915672 -131.551113)
			(xy 285.885688 -131.499179) (xy 285.862739 -131.443775) (xy 285.847218 -131.38585) (xy 285.83939 -131.326394)
			(xy 285.8389 -131.29641) (xy 283.452824 -131.29641) (xy 283.452824 -131.368292) (xy 283.452309 -131.378397)
			(xy 283.444578 -131.397071) (xy 283.430291 -131.411365) (xy 283.411621 -131.419104) (xy 283.401516 -131.4196)
			(xy 282.220162 -131.4196) (xy 282.210038 -131.419106) (xy 282.191323 -131.411373) (xy 282.17697 -131.39709)
			(xy 282.169145 -131.378414) (xy 282.1686 -131.368292) (xy 278.915876 -131.368292) (xy 278.915477 -131.378417)
			(xy 278.907727 -131.397125) (xy 278.893405 -131.41144) (xy 278.874693 -131.419182) (xy 278.864568 -131.4196)
			(xy 277.683468 -131.4196) (xy 277.673357 -131.419141) (xy 277.654678 -131.411393) (xy 277.640385 -131.397088)
			(xy 277.632651 -131.378403) (xy 277.63216 -131.368292) (xy 269.258288 -131.368292) (xy 269.258288 -131.463288)
			(xy 269.257689 -131.474844) (xy 269.247706 -131.495693) (xy 269.22975 -131.510252) (xy 269.218664 -131.51358)
			(xy 269.206726 -131.515104) (xy 268.470126 -131.515104) (xy 268.45937 -131.514575) (xy 268.439681 -131.505914)
			(xy 268.432026 -131.49834) (xy 268.425826 -131.490942) (xy 268.418913 -131.472934) (xy 268.418564 -131.463288)
			(xy 267.752274 -131.463288) (xy 267.736776 -131.500703) (xy 267.706792 -131.552637) (xy 267.670286 -131.600213)
			(xy 267.627881 -131.642618) (xy 267.580305 -131.679124) (xy 267.528371 -131.709108) (xy 267.472967 -131.732057)
			(xy 267.415042 -131.747578) (xy 267.355586 -131.755406) (xy 267.295618 -131.755406) (xy 267.236162 -131.747578)
			(xy 267.178237 -131.732057) (xy 267.122833 -131.709108) (xy 267.070899 -131.679124) (xy 267.023323 -131.642618)
			(xy 266.980918 -131.600213) (xy 266.944412 -131.552637) (xy 266.914428 -131.500703) (xy 266.891479 -131.445299)
			(xy 266.875958 -131.387374) (xy 266.86813 -131.327918) (xy 266.86764 -131.297934) (xy 200.469049 -131.297934)
			(xy 200.477084 -131.301262) (xy 200.52899 -131.331229) (xy 200.57654 -131.367716) (xy 200.61892 -131.410096)
			(xy 200.655407 -131.457646) (xy 200.685374 -131.509552) (xy 200.70831 -131.564925) (xy 200.723823 -131.622818)
			(xy 200.731646 -131.68224) (xy 200.732136 -131.712208) (xy 200.732136 -132.575808) (xy 200.731646 -132.605776)
			(xy 200.723823 -132.665198) (xy 200.70831 -132.723091) (xy 200.685374 -132.778464) (xy 200.655407 -132.83037)
			(xy 200.61892 -132.87792) (xy 200.57654 -132.9203) (xy 200.52899 -132.956787) (xy 200.477084 -132.986754)
			(xy 200.421711 -133.00969) (xy 200.363818 -133.025203) (xy 200.304396 -133.033026) (xy 200.24446 -133.033026)
			(xy 200.185038 -133.025203) (xy 200.127145 -133.00969) (xy 200.071772 -132.986754) (xy 200.019866 -132.956787)
			(xy 199.972316 -132.9203) (xy 199.929936 -132.87792) (xy 199.893449 -132.83037) (xy 199.863482 -132.778464)
			(xy 199.840546 -132.723091) (xy 199.825033 -132.665198) (xy 199.81721 -132.605776) (xy 199.81672 -132.575808)
			(xy 199.181212 -132.575808) (xy 199.181212 -132.741162) (xy 199.180804 -132.751337) (xy 199.173022 -132.770141)
			(xy 199.158631 -132.784529) (xy 199.139825 -132.792306) (xy 199.12965 -132.792724) (xy 198.39305 -132.792724)
			(xy 198.382877 -132.792294) (xy 198.364076 -132.784519) (xy 198.349688 -132.770134) (xy 198.341908 -132.751335)
			(xy 198.341488 -132.741162) (xy 181.730196 -132.741162) (xy 181.714114 -132.779988) (xy 181.684147 -132.831894)
			(xy 181.64766 -132.879444) (xy 181.60528 -132.921824) (xy 181.55773 -132.958311) (xy 181.505824 -132.988278)
			(xy 181.450451 -133.011214) (xy 181.392558 -133.026727) (xy 181.333136 -133.03455) (xy 181.2732 -133.03455)
			(xy 181.213778 -133.026727) (xy 181.155885 -133.011214) (xy 181.100512 -132.988278) (xy 181.048606 -132.958311)
			(xy 181.001056 -132.921824) (xy 180.958676 -132.879444) (xy 180.922189 -132.831894) (xy 180.892222 -132.779988)
			(xy 180.869286 -132.724615) (xy 180.853773 -132.666722) (xy 180.84595 -132.6073) (xy 180.84546 -132.577332)
			(xy 168.80078 -132.577332) (xy 168.80078 -133.096508) (xy 168.80029 -133.126492) (xy 168.792462 -133.185948)
			(xy 168.776941 -133.243873) (xy 168.753992 -133.299277) (xy 168.724008 -133.351211) (xy 168.687502 -133.398787)
			(xy 168.645097 -133.441192) (xy 168.597521 -133.477698) (xy 168.545587 -133.507682) (xy 168.490183 -133.530631)
			(xy 168.432258 -133.546152) (xy 168.372802 -133.55398) (xy 168.312834 -133.55398) (xy 168.253378 -133.546152)
			(xy 168.195453 -133.530631) (xy 168.140049 -133.507682) (xy 168.088115 -133.477698) (xy 168.040539 -133.441192)
			(xy 167.998134 -133.398787) (xy 167.961628 -133.351211) (xy 167.931644 -133.299277) (xy 167.908695 -133.243873)
			(xy 167.893174 -133.185948) (xy 167.885346 -133.126492) (xy 167.884856 -133.096508) (xy 167.352472 -133.096508)
			(xy 167.352472 -133.16839) (xy 167.351966 -133.178515) (xy 167.344243 -133.197233) (xy 167.329963 -133.211589)
			(xy 167.311286 -133.219411) (xy 167.301164 -133.219952) (xy 166.120064 -133.219952) (xy 166.109959 -133.219446)
			(xy 166.09129 -133.211706) (xy 166.076999 -133.197416) (xy 166.069256 -133.178749) (xy 166.068756 -133.168644)
			(xy 162.816022 -133.168644) (xy 162.815627 -133.178565) (xy 162.80784 -133.197365) (xy 162.793448 -133.211751)
			(xy 162.774645 -133.219531) (xy 162.76447 -133.219952) (xy 161.58337 -133.219952) (xy 161.573209 -133.219491)
			(xy 161.554437 -133.211705) (xy 161.540073 -133.197329) (xy 161.532301 -133.178551) (xy 161.531808 -133.16839)
			(xy 155.800552 -133.16839) (xy 155.800552 -133.269736) (xy 155.800049 -133.279942) (xy 155.792231 -133.298797)
			(xy 155.777797 -133.313231) (xy 155.758942 -133.321049) (xy 155.748736 -133.321552) (xy 155.012136 -133.321552)
			(xy 155.001935 -133.320989) (xy 154.983081 -133.313195) (xy 154.968645 -133.298779) (xy 154.960825 -133.279936)
			(xy 154.96032 -133.269736) (xy 154.294538 -133.269736) (xy 154.27904 -133.307151) (xy 154.249056 -133.359085)
			(xy 154.21255 -133.406661) (xy 154.170145 -133.449066) (xy 154.122569 -133.485572) (xy 154.070635 -133.515556)
			(xy 154.015231 -133.538505) (xy 153.957306 -133.554026) (xy 153.89785 -133.561854) (xy 153.837882 -133.561854)
			(xy 153.778426 -133.554026) (xy 153.720501 -133.538505) (xy 153.665097 -133.515556) (xy 153.613163 -133.485572)
			(xy 153.565587 -133.449066) (xy 153.523182 -133.406661) (xy 153.486676 -133.359085) (xy 153.456692 -133.307151)
			(xy 153.433743 -133.251747) (xy 153.418222 -133.193822) (xy 153.410394 -133.134366) (xy 153.409904 -133.104382)
			(xy 81.752059 -133.104382) (xy 81.786925 -133.124512) (xy 81.834501 -133.161018) (xy 81.876906 -133.203423)
			(xy 81.913412 -133.250999) (xy 81.943396 -133.302933) (xy 81.966345 -133.358337) (xy 81.981866 -133.416262)
			(xy 81.989694 -133.475718) (xy 81.990184 -133.505702) (xy 81.990184 -134.369302) (xy 81.989694 -134.399286)
			(xy 81.981866 -134.458742) (xy 81.966345 -134.516667) (xy 81.943396 -134.572071) (xy 81.913412 -134.624005)
			(xy 81.876906 -134.671581) (xy 81.834501 -134.713986) (xy 81.786925 -134.750492) (xy 81.734991 -134.780476)
			(xy 81.679587 -134.803425) (xy 81.621662 -134.818946) (xy 81.562206 -134.826774) (xy 81.502238 -134.826774)
			(xy 81.442782 -134.818946) (xy 81.384857 -134.803425) (xy 81.329453 -134.780476) (xy 81.277519 -134.750492)
			(xy 81.229943 -134.713986) (xy 81.187538 -134.671581) (xy 81.151032 -134.624005) (xy 81.121048 -134.572071)
			(xy 81.098099 -134.516667) (xy 81.082578 -134.458742) (xy 81.07475 -134.399286) (xy 81.07426 -134.369302)
			(xy 80.43926 -134.369302) (xy 80.43926 -134.534656) (xy 80.438657 -134.546212) (xy 80.42868 -134.567065)
			(xy 80.410723 -134.581622) (xy 80.399636 -134.584948) (xy 80.387698 -134.586472) (xy 79.651098 -134.586472)
			(xy 79.640339 -134.585968) (xy 79.62065 -134.577291) (xy 79.612998 -134.569708) (xy 79.606781 -134.562323)
			(xy 79.599879 -134.544305) (xy 79.599536 -134.534656) (xy 67.487203 -134.534656) (xy 67.468444 -134.579945)
			(xy 67.43846 -134.631879) (xy 67.401954 -134.679455) (xy 67.359549 -134.72186) (xy 67.311973 -134.758366)
			(xy 67.260039 -134.78835) (xy 67.204635 -134.811299) (xy 67.14671 -134.82682) (xy 67.087254 -134.834648)
			(xy 67.027286 -134.834648) (xy 66.96783 -134.82682) (xy 66.909905 -134.811299) (xy 66.854501 -134.78835)
			(xy 66.802567 -134.758366) (xy 66.754991 -134.72186) (xy 66.712586 -134.679455) (xy 66.67608 -134.631879)
			(xy 66.646096 -134.579945) (xy 66.623147 -134.524541) (xy 66.607626 -134.466616) (xy 66.599798 -134.40716)
			(xy 66.599308 -134.377176) (xy 54.554628 -134.377176) (xy 54.554628 -134.896352) (xy 54.554138 -134.92632)
			(xy 54.546315 -134.985742) (xy 54.530802 -135.043635) (xy 54.507866 -135.099008) (xy 54.477899 -135.150914)
			(xy 54.441412 -135.198464) (xy 54.399032 -135.240844) (xy 54.351482 -135.277331) (xy 54.299576 -135.307298)
			(xy 54.244203 -135.330234) (xy 54.18631 -135.345747) (xy 54.126888 -135.35357) (xy 54.066952 -135.35357)
			(xy 54.00753 -135.345747) (xy 53.949637 -135.330234) (xy 53.894264 -135.307298) (xy 53.842358 -135.277331)
			(xy 53.794808 -135.240844) (xy 53.752428 -135.198464) (xy 53.715941 -135.150914) (xy 53.685974 -135.099008)
			(xy 53.663038 -135.043635) (xy 53.647525 -134.985742) (xy 53.639702 -134.92632) (xy 53.639212 -134.896352)
			(xy 51.252628 -134.896352) (xy 51.252628 -134.968488) (xy 51.252106 -134.978593) (xy 51.244377 -134.997265)
			(xy 51.230092 -135.011559) (xy 51.211424 -135.019299) (xy 51.20132 -135.019796) (xy 50.02022 -135.019796)
			(xy 50.010098 -135.019368) (xy 49.991394 -135.011625) (xy 49.977079 -134.997312) (xy 49.969334 -134.97861)
			(xy 49.968912 -134.968488) (xy 46.716188 -134.968488) (xy 46.715768 -134.978643) (xy 46.707975 -134.997397)
			(xy 46.693577 -135.011722) (xy 46.674783 -135.01942) (xy 46.664626 -135.019796) (xy 45.483526 -135.019796)
			(xy 45.473405 -135.019253) (xy 45.454692 -135.011541) (xy 45.440336 -134.997272) (xy 45.432509 -134.978606)
			(xy 45.431964 -134.968488) (xy 37.0586 -134.968488) (xy 37.0586 -135.06323) (xy 37.058092 -135.073385)
			(xy 37.050315 -135.092148) (xy 37.035954 -135.10651) (xy 37.017193 -135.114291) (xy 37.007038 -135.114792)
			(xy 36.270184 -135.114792) (xy 36.260004 -135.114337) (xy 36.241185 -135.106562) (xy 36.226758 -135.092194)
			(xy 36.218905 -135.073408) (xy 36.218368 -135.06323) (xy 35.552057 -135.06323) (xy 35.536606 -135.100532)
			(xy 35.506639 -135.152438) (xy 35.470152 -135.199988) (xy 35.427772 -135.242368) (xy 35.380222 -135.278855)
			(xy 35.328316 -135.308822) (xy 35.272943 -135.331758) (xy 35.21505 -135.347271) (xy 35.155628 -135.355094)
			(xy 35.095692 -135.355094) (xy 35.03627 -135.347271) (xy 34.978377 -135.331758) (xy 34.923004 -135.308822)
			(xy 34.871098 -135.278855) (xy 34.823548 -135.242368) (xy 34.781168 -135.199988) (xy 34.744681 -135.152438)
			(xy 34.714714 -135.100532) (xy 34.691778 -135.045159) (xy 34.676265 -134.987266) (xy 34.668442 -134.927844)
			(xy 34.667952 -134.897876) (xy 4.30911 -134.897876) (xy 4.30911 -136.704324) (xy 37.31006 -136.704324)
			(xy 37.31006 -135.840724) (xy 37.31055 -135.810756) (xy 37.318373 -135.751334) (xy 37.333886 -135.693441)
			(xy 37.356822 -135.638068) (xy 37.386789 -135.586162) (xy 37.423276 -135.538612) (xy 37.465656 -135.496232)
			(xy 37.513206 -135.459745) (xy 37.565112 -135.429778) (xy 37.620485 -135.406842) (xy 37.678378 -135.391329)
			(xy 37.7378 -135.383506) (xy 37.797736 -135.383506) (xy 37.857158 -135.391329) (xy 37.915051 -135.406842)
			(xy 37.970424 -135.429778) (xy 38.02233 -135.459745) (xy 38.06988 -135.496232) (xy 38.11226 -135.538612)
			(xy 38.148747 -135.586162) (xy 38.178714 -135.638068) (xy 38.20165 -135.693441) (xy 38.217163 -135.751334)
			(xy 38.224986 -135.810756) (xy 38.225476 -135.840724) (xy 38.225476 -136.704324) (xy 38.224986 -136.734292)
			(xy 38.217163 -136.793714) (xy 38.20165 -136.851607) (xy 38.194165 -136.869678) (xy 38.860476 -136.869678)
			(xy 38.860476 -136.642094) (xy 38.86073 -136.63803) (xy 38.860984 -136.63549) (xy 38.860984 -136.626854)
			(xy 38.866572 -136.618218) (xy 38.867842 -136.616186) (xy 38.868858 -136.614154) (xy 39.066216 -136.313164)
			(xy 39.07007 -136.306828) (xy 39.07434 -136.292635) (xy 39.074598 -136.285224) (xy 39.074598 -136.25957)
			(xy 39.074376 -136.252237) (xy 39.070256 -136.238166) (xy 39.06647 -136.231884) (xy 38.868604 -135.928862)
			(xy 38.866318 -135.925052) (xy 38.866064 -135.924544) (xy 38.865048 -135.922766) (xy 38.860984 -135.916162)
			(xy 38.860984 -135.908034) (xy 38.86073 -135.905494) (xy 38.860476 -135.90143) (xy 38.860476 -135.673338)
			(xy 38.860896 -135.663164) (xy 38.868676 -135.644363) (xy 38.883063 -135.629976) (xy 38.901864 -135.622196)
			(xy 38.912038 -135.621776) (xy 39.648892 -135.621776) (xy 39.659067 -135.622281) (xy 39.677879 -135.630043)
			(xy 39.692306 -135.644395) (xy 39.700165 -135.663166) (xy 39.700708 -135.673338) (xy 39.700708 -135.900922)
			(xy 39.700454 -135.904986) (xy 39.7002 -135.907526) (xy 39.7002 -135.916162) (xy 39.694358 -135.92556)
			(xy 39.693596 -135.92683) (xy 39.692326 -135.928862) (xy 39.486586 -136.243568) (xy 39.481525 -136.252085)
			(xy 39.477708 -136.271507) (xy 39.48153 -136.290928) (xy 39.486586 -136.299448) (xy 39.692326 -136.612884)
			(xy 39.693342 -136.614916) (xy 39.694612 -136.616948) (xy 39.7002 -136.625584) (xy 39.7002 -136.63422)
			(xy 39.700454 -136.63676) (xy 39.700708 -136.640824) (xy 39.700708 -136.768332) (xy 45.431964 -136.768332)
			(xy 45.431964 -135.761984) (xy 45.432408 -135.751833) (xy 45.440202 -135.733087) (xy 45.454591 -135.718766)
			(xy 45.473373 -135.71106) (xy 45.483526 -135.710676) (xy 46.664626 -135.710676) (xy 46.674759 -135.711106)
			(xy 46.693487 -135.718849) (xy 46.707844 -135.733153) (xy 46.715656 -135.751853) (xy 46.716188 -135.761984)
			(xy 46.716188 -136.768332) (xy 49.968912 -136.768332) (xy 49.968912 -135.761984) (xy 49.969303 -135.751859)
			(xy 49.977059 -135.733153) (xy 49.991383 -135.718838) (xy 50.010095 -135.711096) (xy 50.02022 -135.710676)
			(xy 51.20132 -135.710676) (xy 51.211427 -135.711168) (xy 51.230101 -135.718908) (xy 51.244395 -135.733202)
			(xy 51.252133 -135.751877) (xy 51.252628 -135.761984) (xy 51.252628 -136.69645) (xy 51.785012 -136.69645)
			(xy 51.785012 -135.83285) (xy 51.785502 -135.802882) (xy 51.793325 -135.74346) (xy 51.808838 -135.685567)
			(xy 51.831774 -135.630194) (xy 51.861741 -135.578288) (xy 51.898228 -135.530738) (xy 51.940608 -135.488358)
			(xy 51.988158 -135.451871) (xy 52.040064 -135.421904) (xy 52.095437 -135.398968) (xy 52.15333 -135.383455)
			(xy 52.212752 -135.375632) (xy 52.272688 -135.375632) (xy 52.33211 -135.383455) (xy 52.390003 -135.398968)
			(xy 52.445376 -135.421904) (xy 52.497282 -135.451871) (xy 52.544832 -135.488358) (xy 52.587212 -135.530738)
			(xy 52.623699 -135.578288) (xy 52.653666 -135.630194) (xy 52.676602 -135.685567) (xy 52.692115 -135.74346)
			(xy 52.699938 -135.802882) (xy 52.700428 -135.83285) (xy 52.700428 -136.177274) (xy 64.745108 -136.177274)
			(xy 64.745108 -135.313674) (xy 64.745598 -135.28369) (xy 64.753426 -135.224234) (xy 64.768947 -135.166309)
			(xy 64.791896 -135.110905) (xy 64.82188 -135.058971) (xy 64.858386 -135.011395) (xy 64.900791 -134.96899)
			(xy 64.948367 -134.932484) (xy 65.000301 -134.9025) (xy 65.055705 -134.879551) (xy 65.11363 -134.86403)
			(xy 65.173086 -134.856202) (xy 65.233054 -134.856202) (xy 65.29251 -134.86403) (xy 65.350435 -134.879551)
			(xy 65.405839 -134.9025) (xy 65.457773 -134.932484) (xy 65.505349 -134.96899) (xy 65.547754 -135.011395)
			(xy 65.58426 -135.058971) (xy 65.614244 -135.110905) (xy 65.637193 -135.166309) (xy 65.652714 -135.224234)
			(xy 65.660542 -135.28369) (xy 65.661032 -135.313674) (xy 65.661032 -136.177274) (xy 65.660542 -136.207258)
			(xy 65.655159 -136.24814) (xy 68.047108 -136.24814) (xy 68.047108 -135.241792) (xy 68.04751 -135.231668)
			(xy 68.055262 -135.212963) (xy 68.069583 -135.198649) (xy 68.088292 -135.190905) (xy 68.098416 -135.190484)
			(xy 69.27977 -135.190484) (xy 69.2899 -135.190952) (xy 69.308629 -135.198678) (xy 69.322988 -135.212971)
			(xy 69.330801 -135.231664) (xy 69.331332 -135.241792) (xy 69.331332 -136.24814) (xy 72.584056 -136.24814)
			(xy 72.584056 -135.241792) (xy 72.584578 -135.231688) (xy 72.59231 -135.213018) (xy 72.606595 -135.198725)
			(xy 72.625261 -135.190983) (xy 72.635364 -135.190484) (xy 73.816464 -135.190484) (xy 73.826582 -135.190945)
			(xy 73.845282 -135.198679) (xy 73.859597 -135.212981) (xy 73.867346 -135.231674) (xy 73.867772 -135.241792)
			(xy 73.867772 -136.24814) (xy 73.867347 -136.258255) (xy 73.859591 -136.276939) (xy 73.845275 -136.291234)
			(xy 73.826579 -136.298962) (xy 73.816464 -136.299448) (xy 72.635364 -136.299448) (xy 72.625259 -136.298946)
			(xy 72.606589 -136.291205) (xy 72.592297 -136.276914) (xy 72.584555 -136.258245) (xy 72.584056 -136.24814)
			(xy 69.331332 -136.24814) (xy 69.330848 -136.258247) (xy 69.323104 -136.27692) (xy 69.308807 -136.291213)
			(xy 69.290131 -136.298952) (xy 69.280024 -136.299448) (xy 68.09867 -136.299448) (xy 68.08854 -136.298998)
			(xy 68.069816 -136.291258) (xy 68.05546 -136.276961) (xy 68.047644 -136.258268) (xy 68.047108 -136.24814)
			(xy 65.655159 -136.24814) (xy 65.652714 -136.266714) (xy 65.637193 -136.324639) (xy 65.630373 -136.341104)
			(xy 82.241644 -136.341104) (xy 82.241644 -136.09828) (xy 82.386424 -135.877554) (xy 82.4357 -135.802116)
			(xy 82.455512 -135.77189) (xy 82.460464 -135.76343) (xy 82.464197 -135.744203) (xy 82.460466 -135.724977)
			(xy 82.455512 -135.716518) (xy 82.310478 -135.493506) (xy 82.254852 -135.408162) (xy 82.250534 -135.402066)
			(xy 82.247232 -135.396478) (xy 82.246724 -135.395462) (xy 82.241644 -135.387588) (xy 82.241644 -135.144764)
			(xy 82.242267 -135.133244) (xy 82.252144 -135.112427) (xy 82.26998 -135.097841) (xy 82.281014 -135.094472)
			(xy 82.281268 -135.094472) (xy 82.293206 -135.092948) (xy 83.029806 -135.092948) (xy 83.036179 -135.09318)
			(xy 83.048516 -135.096388) (xy 83.05419 -135.099298) (xy 83.062191 -135.104053) (xy 83.07443 -135.118056)
			(xy 83.080973 -135.135465) (xy 83.081368 -135.144764) (xy 83.081368 -135.387588) (xy 82.865468 -135.718042)
			(xy 82.861474 -135.726274) (xy 82.858923 -135.744377) (xy 82.862855 -135.76223) (xy 82.8675 -135.770112)
			(xy 82.899758 -135.819896) (xy 82.915252 -135.843518) (xy 83.081368 -136.09701) (xy 83.081368 -136.17575)
			(xy 83.716368 -136.17575) (xy 83.716368 -135.31215) (xy 83.716858 -135.282166) (xy 83.724686 -135.22271)
			(xy 83.740207 -135.164785) (xy 83.763156 -135.109381) (xy 83.79314 -135.057447) (xy 83.829646 -135.009871)
			(xy 83.872051 -134.967466) (xy 83.919627 -134.93096) (xy 83.971561 -134.900976) (xy 84.026965 -134.878027)
			(xy 84.08489 -134.862506) (xy 84.144346 -134.854678) (xy 84.204314 -134.854678) (xy 84.26377 -134.862506)
			(xy 84.321695 -134.878027) (xy 84.369615 -134.897876) (xy 150.767796 -134.897876) (xy 150.767796 -134.034276)
			(xy 150.768286 -134.004292) (xy 150.776114 -133.944836) (xy 150.791635 -133.886911) (xy 150.814584 -133.831507)
			(xy 150.844568 -133.779573) (xy 150.881074 -133.731997) (xy 150.923479 -133.689592) (xy 150.971055 -133.653086)
			(xy 151.022989 -133.623102) (xy 151.078393 -133.600153) (xy 151.136318 -133.584632) (xy 151.195774 -133.576804)
			(xy 151.255742 -133.576804) (xy 151.315198 -133.584632) (xy 151.373123 -133.600153) (xy 151.428527 -133.623102)
			(xy 151.480461 -133.653086) (xy 151.528037 -133.689592) (xy 151.570442 -133.731997) (xy 151.606948 -133.779573)
			(xy 151.636932 -133.831507) (xy 151.659881 -133.886911) (xy 151.675402 -133.944836) (xy 151.68323 -134.004292)
			(xy 151.68372 -134.034276) (xy 151.68372 -134.897876) (xy 151.68323 -134.92786) (xy 151.675402 -134.987316)
			(xy 151.659881 -135.045241) (xy 151.65243 -135.06323) (xy 152.318212 -135.06323) (xy 152.318212 -134.835646)
			(xy 152.318466 -134.831582) (xy 152.31872 -134.829042) (xy 152.31872 -134.820406) (xy 152.324308 -134.81177)
			(xy 152.325578 -134.809738) (xy 152.326594 -134.807706) (xy 152.523952 -134.506716) (xy 152.527827 -134.500391)
			(xy 152.532083 -134.486189) (xy 152.532334 -134.478776) (xy 152.532334 -134.453122) (xy 152.532141 -134.445787)
			(xy 152.528002 -134.431716) (xy 152.524206 -134.425436) (xy 152.32634 -134.122414) (xy 152.324054 -134.118604)
			(xy 152.3238 -134.118096) (xy 152.322784 -134.116318) (xy 152.31872 -134.109714) (xy 152.31872 -134.101586)
			(xy 152.318466 -134.099046) (xy 152.318212 -134.094982) (xy 152.318212 -133.86689) (xy 152.318725 -133.856735)
			(xy 152.326498 -133.837971) (xy 152.340857 -133.823607) (xy 152.359619 -133.815828) (xy 152.369774 -133.815328)
			(xy 153.106628 -133.815328) (xy 153.116812 -133.815753) (xy 153.135634 -133.823536) (xy 153.150062 -133.837913)
			(xy 153.157911 -133.856708) (xy 153.158444 -133.86689) (xy 153.158444 -134.094474) (xy 153.15819 -134.098538)
			(xy 153.157936 -134.101078) (xy 153.157936 -134.109714) (xy 153.152094 -134.119112) (xy 153.151332 -134.120382)
			(xy 153.150062 -134.122414) (xy 152.944322 -134.43712) (xy 152.939298 -134.445657) (xy 152.935465 -134.465066)
			(xy 152.939273 -134.484481) (xy 152.944322 -134.493) (xy 153.150062 -134.806436) (xy 153.151078 -134.808468)
			(xy 153.152348 -134.8105) (xy 153.157936 -134.819136) (xy 153.157936 -134.827772) (xy 153.15819 -134.830312)
			(xy 153.158444 -134.834376) (xy 153.158444 -134.968488) (xy 161.531808 -134.968488) (xy 161.531808 -133.96214)
			(xy 161.532255 -133.951988) (xy 161.540038 -133.933234) (xy 161.554428 -133.918909) (xy 161.573216 -133.91121)
			(xy 161.58337 -133.910832) (xy 162.76447 -133.910832) (xy 162.774594 -133.911351) (xy 162.793313 -133.919067)
			(xy 162.80767 -133.933344) (xy 162.815492 -133.952019) (xy 162.816032 -133.96214) (xy 162.816032 -134.968488)
			(xy 166.068756 -134.968488) (xy 166.068756 -133.96214) (xy 166.069248 -133.952026) (xy 166.076975 -133.933331)
			(xy 166.091267 -133.919017) (xy 166.10995 -133.911263) (xy 166.120064 -133.910832) (xy 167.301164 -133.910832)
			(xy 167.311288 -133.911246) (xy 167.329997 -133.918989) (xy 167.344314 -133.933306) (xy 167.352054 -133.952016)
			(xy 167.352472 -133.96214) (xy 167.352472 -134.896352) (xy 169.739056 -134.896352) (xy 169.739056 -134.032752)
			(xy 169.739546 -134.002768) (xy 169.747374 -133.943312) (xy 169.762895 -133.885387) (xy 169.785844 -133.829983)
			(xy 169.815828 -133.778049) (xy 169.852334 -133.730473) (xy 169.894739 -133.688068) (xy 169.942315 -133.651562)
			(xy 169.994249 -133.621578) (xy 170.049653 -133.598629) (xy 170.107578 -133.583108) (xy 170.167034 -133.57528)
			(xy 170.227002 -133.57528) (xy 170.286458 -133.583108) (xy 170.344383 -133.598629) (xy 170.399787 -133.621578)
			(xy 170.451721 -133.651562) (xy 170.499297 -133.688068) (xy 170.541702 -133.730473) (xy 170.578208 -133.778049)
			(xy 170.608192 -133.829983) (xy 170.631141 -133.885387) (xy 170.646662 -133.943312) (xy 170.65449 -134.002768)
			(xy 170.65498 -134.032752) (xy 170.65498 -134.377176) (xy 182.69966 -134.377176) (xy 182.69966 -133.513576)
			(xy 182.70015 -133.483608) (xy 182.707973 -133.424186) (xy 182.723486 -133.366293) (xy 182.746422 -133.31092)
			(xy 182.776389 -133.259014) (xy 182.812876 -133.211464) (xy 182.855256 -133.169084) (xy 182.902806 -133.132597)
			(xy 182.954712 -133.10263) (xy 183.010085 -133.079694) (xy 183.067978 -133.064181) (xy 183.1274 -133.056358)
			(xy 183.187336 -133.056358) (xy 183.246758 -133.064181) (xy 183.304651 -133.079694) (xy 183.360024 -133.10263)
			(xy 183.41193 -133.132597) (xy 183.45948 -133.169084) (xy 183.50186 -133.211464) (xy 183.538347 -133.259014)
			(xy 183.568314 -133.31092) (xy 183.59125 -133.366293) (xy 183.606763 -133.424186) (xy 183.614586 -133.483608)
			(xy 183.615076 -133.513576) (xy 183.615076 -134.377176) (xy 183.614586 -134.407144) (xy 183.609168 -134.448296)
			(xy 184.146952 -134.448296) (xy 184.146952 -133.441948) (xy 184.147454 -133.431835) (xy 184.155178 -133.413141)
			(xy 184.169467 -133.398827) (xy 184.188147 -133.391072) (xy 184.19826 -133.39064) (xy 185.379614 -133.39064)
			(xy 185.389742 -133.391115) (xy 185.408463 -133.398848) (xy 185.422819 -133.413137) (xy 185.430637 -133.431823)
			(xy 185.431176 -133.441948) (xy 185.431176 -134.448296) (xy 188.6839 -134.448296) (xy 188.6839 -133.441948)
			(xy 188.684355 -133.431829) (xy 188.692088 -133.413126) (xy 188.706392 -133.39881) (xy 188.725089 -133.391063)
			(xy 188.735208 -133.39064) (xy 189.916308 -133.39064) (xy 189.926436 -133.391011) (xy 189.945147 -133.398769)
			(xy 189.959463 -133.4131) (xy 189.9672 -133.43182) (xy 189.967616 -133.441948) (xy 189.967616 -134.448296)
			(xy 189.967112 -134.458402) (xy 189.959379 -134.477078) (xy 189.945088 -134.491372) (xy 189.926414 -134.49911)
			(xy 189.916308 -134.499604) (xy 188.735208 -134.499604) (xy 188.725087 -134.499178) (xy 188.706384 -134.491433)
			(xy 188.692069 -134.47712) (xy 188.684323 -134.458417) (xy 188.6839 -134.448296) (xy 185.431176 -134.448296)
			(xy 185.43078 -134.458421) (xy 185.423029 -134.477129) (xy 185.408706 -134.491445) (xy 185.389993 -134.499186)
			(xy 185.379868 -134.499604) (xy 184.198514 -134.499604) (xy 184.188394 -134.499063) (xy 184.169681 -134.491348)
			(xy 184.155326 -134.477079) (xy 184.147498 -134.458413) (xy 184.146952 -134.448296) (xy 183.609168 -134.448296)
			(xy 183.606763 -134.466566) (xy 183.59125 -134.524459) (xy 183.587026 -134.534656) (xy 195.69938 -134.534656)
			(xy 195.69938 -134.291832) (xy 195.818252 -134.110476) (xy 195.880736 -134.014972) (xy 195.904866 -133.978142)
			(xy 195.908732 -133.971813) (xy 195.912993 -133.957614) (xy 195.913248 -133.950202) (xy 195.913248 -133.924294)
			(xy 195.913059 -133.918144) (xy 195.910103 -133.906203) (xy 195.907406 -133.900672) (xy 195.793868 -133.726682)
			(xy 195.773802 -133.695694) (xy 195.768214 -133.687058) (xy 195.707762 -133.594348) (xy 195.707254 -133.593586)
			(xy 195.706746 -133.592824) (xy 195.706492 -133.592316) (xy 195.705984 -133.591554) (xy 195.69938 -133.58114)
			(xy 195.69938 -133.338316) (xy 195.700005 -133.326764) (xy 195.70998 -133.305919) (xy 195.727924 -133.291357)
			(xy 195.739004 -133.288024) (xy 195.750942 -133.2865) (xy 196.487542 -133.2865) (xy 196.498296 -133.287045)
			(xy 196.517986 -133.295694) (xy 196.525642 -133.303264) (xy 196.53184 -133.310664) (xy 196.538755 -133.32867)
			(xy 196.539104 -133.338316) (xy 196.539104 -133.58114) (xy 196.323204 -133.911594) (xy 196.319165 -133.919808)
			(xy 196.316627 -133.937923) (xy 196.320579 -133.955783) (xy 196.325236 -133.963664) (xy 196.357494 -134.013448)
			(xy 196.539104 -134.290562) (xy 196.539104 -134.369302) (xy 197.174612 -134.369302) (xy 197.174612 -133.505702)
			(xy 197.175102 -133.475734) (xy 197.182925 -133.416312) (xy 197.198438 -133.358419) (xy 197.221374 -133.303046)
			(xy 197.251341 -133.25114) (xy 197.287828 -133.20359) (xy 197.330208 -133.16121) (xy 197.377758 -133.124723)
			(xy 197.429664 -133.094756) (xy 197.485037 -133.07182) (xy 197.54293 -133.056307) (xy 197.602352 -133.048484)
			(xy 197.662288 -133.048484) (xy 197.72171 -133.056307) (xy 197.779603 -133.07182) (xy 197.834976 -133.094756)
			(xy 197.851649 -133.104382) (xy 269.509748 -133.104382) (xy 269.509748 -132.240782) (xy 269.510238 -132.210798)
			(xy 269.518066 -132.151342) (xy 269.533587 -132.093417) (xy 269.556536 -132.038013) (xy 269.58652 -131.986079)
			(xy 269.623026 -131.938503) (xy 269.665431 -131.896098) (xy 269.713007 -131.859592) (xy 269.764941 -131.829608)
			(xy 269.820345 -131.806659) (xy 269.87827 -131.791138) (xy 269.937726 -131.78331) (xy 269.997694 -131.78331)
			(xy 270.05715 -131.791138) (xy 270.115075 -131.806659) (xy 270.170479 -131.829608) (xy 270.222413 -131.859592)
			(xy 270.269989 -131.896098) (xy 270.312394 -131.938503) (xy 270.3489 -131.986079) (xy 270.378884 -132.038013)
			(xy 270.401833 -132.093417) (xy 270.417354 -132.151342) (xy 270.425182 -132.210798) (xy 270.425672 -132.240782)
			(xy 270.425672 -133.104382) (xy 270.425182 -133.134366) (xy 270.417354 -133.193822) (xy 270.401833 -133.251747)
			(xy 270.394382 -133.269736) (xy 271.060672 -133.269736) (xy 271.060672 -133.026912) (xy 271.205452 -132.806186)
			(xy 271.254728 -132.730748) (xy 271.27454 -132.700522) (xy 271.279471 -132.69205) (xy 271.283218 -132.67283)
			(xy 271.279494 -132.653607) (xy 271.27454 -132.64515) (xy 271.129506 -132.422138) (xy 271.07388 -132.336794)
			(xy 271.069562 -132.330698) (xy 271.06626 -132.32511) (xy 271.065752 -132.324094) (xy 271.060672 -132.31622)
			(xy 271.060672 -132.073396) (xy 271.061299 -132.061875) (xy 271.071169 -132.041055) (xy 271.089007 -132.02647)
			(xy 271.100042 -132.023104) (xy 271.100296 -132.023104) (xy 271.112234 -132.02158) (xy 271.848834 -132.02158)
			(xy 271.855208 -132.021798) (xy 271.867545 -132.025015) (xy 271.873218 -132.02793) (xy 271.881239 -132.032655)
			(xy 271.893473 -132.046673) (xy 271.900006 -132.064093) (xy 271.900396 -132.073396) (xy 271.900396 -132.31622)
			(xy 271.684496 -132.646674) (xy 271.680474 -132.654895) (xy 271.677931 -132.673005) (xy 271.681875 -132.690863)
			(xy 271.686528 -132.698744) (xy 271.718786 -132.748528) (xy 271.73428 -132.77215) (xy 271.900396 -133.025642)
			(xy 271.900396 -133.16839) (xy 277.63216 -133.16839) (xy 277.63216 -132.162042) (xy 277.632662 -132.151916)
			(xy 277.640379 -132.133192) (xy 277.654662 -132.118833) (xy 277.673344 -132.111016) (xy 277.683468 -132.11048)
			(xy 278.864568 -132.11048) (xy 278.874718 -132.110947) (xy 278.893466 -132.118728) (xy 278.907789 -132.133111)
			(xy 278.915494 -132.151891) (xy 278.915876 -132.162042) (xy 278.915876 -133.16839) (xy 282.1686 -133.16839)
			(xy 282.1686 -132.162042) (xy 282.169097 -132.151878) (xy 282.176861 -132.133091) (xy 282.191224 -132.118706)
			(xy 282.209998 -132.110913) (xy 282.220162 -132.11048) (xy 283.401262 -132.11048) (xy 283.411436 -132.110896)
			(xy 283.430238 -132.118676) (xy 283.444626 -132.133065) (xy 283.452405 -132.151868) (xy 283.452824 -132.162042)
			(xy 283.452824 -133.096508) (xy 283.9847 -133.096508) (xy 283.9847 -132.232908) (xy 283.98519 -132.202924)
			(xy 283.993018 -132.143468) (xy 284.008539 -132.085543) (xy 284.031488 -132.030139) (xy 284.061472 -131.978205)
			(xy 284.097978 -131.930629) (xy 284.140383 -131.888224) (xy 284.187959 -131.851718) (xy 284.239893 -131.821734)
			(xy 284.295297 -131.798785) (xy 284.353222 -131.783264) (xy 284.412678 -131.775436) (xy 284.472646 -131.775436)
			(xy 284.532102 -131.783264) (xy 284.590027 -131.798785) (xy 284.645431 -131.821734) (xy 284.697365 -131.851718)
			(xy 284.744941 -131.888224) (xy 284.787346 -131.930629) (xy 284.823852 -131.978205) (xy 284.853836 -132.030139)
			(xy 284.876785 -132.085543) (xy 284.892306 -132.143468) (xy 284.900134 -132.202924) (xy 284.900624 -132.232908)
			(xy 284.900624 -132.577332) (xy 296.945304 -132.577332) (xy 296.945304 -131.713732) (xy 296.945794 -131.683764)
			(xy 296.953617 -131.624342) (xy 296.96913 -131.566449) (xy 296.992066 -131.511076) (xy 297.022033 -131.45917)
			(xy 297.05852 -131.41162) (xy 297.1009 -131.36924) (xy 297.14845 -131.332753) (xy 297.200356 -131.302786)
			(xy 297.255729 -131.27985) (xy 297.313622 -131.264337) (xy 297.373044 -131.256514) (xy 297.43298 -131.256514)
			(xy 297.492402 -131.264337) (xy 297.550295 -131.27985) (xy 297.605668 -131.302786) (xy 297.657574 -131.332753)
			(xy 297.705124 -131.36924) (xy 297.747504 -131.41162) (xy 297.783991 -131.45917) (xy 297.813958 -131.511076)
			(xy 297.836894 -131.566449) (xy 297.852407 -131.624342) (xy 297.86023 -131.683764) (xy 297.86072 -131.713732)
			(xy 297.86072 -132.577332) (xy 297.86023 -132.6073) (xy 297.854812 -132.648452) (xy 300.247304 -132.648452)
			(xy 300.247304 -131.64185) (xy 300.247867 -131.631731) (xy 300.255571 -131.613018) (xy 300.269834 -131.598661)
			(xy 300.288496 -131.590834) (xy 300.298612 -131.590288) (xy 301.479712 -131.590288) (xy 301.48982 -131.590775)
			(xy 301.508496 -131.598515) (xy 301.52279 -131.612811) (xy 301.530526 -131.631488) (xy 301.53102 -131.641596)
			(xy 301.53102 -132.648198) (xy 304.783744 -132.648198) (xy 304.783744 -131.64185) (xy 304.784205 -131.631681)
			(xy 304.791975 -131.612886) (xy 304.806349 -131.598499) (xy 304.825137 -131.590714) (xy 304.835306 -131.590288)
			(xy 306.016406 -131.590288) (xy 306.026584 -131.59066) (xy 306.045389 -131.598456) (xy 306.059775 -131.612859)
			(xy 306.067551 -131.631671) (xy 306.067968 -131.64185) (xy 306.067968 -132.648198) (xy 306.067465 -132.658355)
			(xy 306.059692 -132.677123) (xy 306.04533 -132.691488) (xy 306.026563 -132.699264) (xy 306.016406 -132.69976)
			(xy 304.835306 -132.69976) (xy 304.825135 -132.699331) (xy 304.80634 -132.691548) (xy 304.791954 -132.677164)
			(xy 304.78417 -132.658369) (xy 304.783744 -132.648198) (xy 301.53102 -132.648198) (xy 301.530571 -132.658329)
			(xy 301.522836 -132.677058) (xy 301.508538 -132.691416) (xy 301.489841 -132.699228) (xy 301.479712 -132.69976)
			(xy 300.298612 -132.69976) (xy 300.288485 -132.699373) (xy 300.269774 -132.691622) (xy 300.255458 -132.677295)
			(xy 300.24772 -132.658579) (xy 300.247304 -132.648452) (xy 297.854812 -132.648452) (xy 297.852407 -132.666722)
			(xy 297.836894 -132.724615) (xy 297.83004 -132.741162) (xy 314.441332 -132.741162) (xy 314.441332 -132.513578)
			(xy 314.441586 -132.509514) (xy 314.44184 -132.506974) (xy 314.44184 -132.498338) (xy 314.447428 -132.489702)
			(xy 314.448698 -132.48767) (xy 314.449714 -132.485638) (xy 314.647072 -132.184648) (xy 314.650936 -132.178318)
			(xy 314.655198 -132.16412) (xy 314.655454 -132.156708) (xy 314.655454 -132.131054) (xy 314.655244 -132.12372)
			(xy 314.651117 -132.109649) (xy 314.647326 -132.103368) (xy 314.44946 -131.800346) (xy 314.447174 -131.796536)
			(xy 314.44692 -131.796028) (xy 314.445904 -131.79425) (xy 314.44184 -131.787646) (xy 314.44184 -131.779518)
			(xy 314.441586 -131.776978) (xy 314.441332 -131.772914) (xy 314.441332 -131.544822) (xy 314.441782 -131.534653)
			(xy 314.449559 -131.51586) (xy 314.463936 -131.501474) (xy 314.482725 -131.493687) (xy 314.492894 -131.49326)
			(xy 315.229748 -131.49326) (xy 315.239925 -131.493735) (xy 315.258734 -131.501512) (xy 315.273159 -131.515873)
			(xy 315.281019 -131.534648) (xy 315.281564 -131.544822) (xy 315.281564 -131.772406) (xy 315.28131 -131.77647)
			(xy 315.281056 -131.77901) (xy 315.281056 -131.787646) (xy 315.275214 -131.797044) (xy 315.274452 -131.798314)
			(xy 315.273182 -131.800346) (xy 315.067442 -132.115052) (xy 315.062398 -132.123577) (xy 315.05858 -132.142993)
			(xy 315.062392 -132.162411) (xy 315.067442 -132.170932) (xy 315.273182 -132.484368) (xy 315.274198 -132.4864)
			(xy 315.275468 -132.488432) (xy 315.281056 -132.497068) (xy 315.281056 -132.505704) (xy 315.28131 -132.508244)
			(xy 315.281564 -132.512308) (xy 315.281564 -132.575808) (xy 315.916564 -132.575808) (xy 315.916564 -131.712208)
			(xy 315.917054 -131.68224) (xy 315.924877 -131.622818) (xy 315.94039 -131.564925) (xy 315.963326 -131.509552)
			(xy 315.993293 -131.457646) (xy 316.02978 -131.410096) (xy 316.07216 -131.367716) (xy 316.11971 -131.331229)
			(xy 316.171616 -131.301262) (xy 316.226989 -131.278326) (xy 316.284882 -131.262813) (xy 316.344304 -131.25499)
			(xy 316.40424 -131.25499) (xy 316.463662 -131.262813) (xy 316.521555 -131.278326) (xy 316.568893 -131.297934)
			(xy 382.967992 -131.297934) (xy 382.967992 -130.434334) (xy 382.968482 -130.404366) (xy 382.976305 -130.344944)
			(xy 382.991818 -130.287051) (xy 383.014754 -130.231678) (xy 383.044721 -130.179772) (xy 383.081208 -130.132222)
			(xy 383.123588 -130.089842) (xy 383.171138 -130.053355) (xy 383.223044 -130.023388) (xy 383.278417 -130.000452)
			(xy 383.33631 -129.984939) (xy 383.395732 -129.977116) (xy 383.455668 -129.977116) (xy 383.51509 -129.984939)
			(xy 383.572983 -130.000452) (xy 383.628356 -130.023388) (xy 383.680262 -130.053355) (xy 383.727812 -130.089842)
			(xy 383.770192 -130.132222) (xy 383.806679 -130.179772) (xy 383.836646 -130.231678) (xy 383.859582 -130.287051)
			(xy 383.875095 -130.344944) (xy 383.882918 -130.404366) (xy 383.883408 -130.434334) (xy 383.883408 -131.297934)
			(xy 383.882918 -131.327902) (xy 383.875095 -131.387324) (xy 383.859582 -131.445217) (xy 383.852097 -131.463288)
			(xy 384.518408 -131.463288) (xy 384.518408 -131.235704) (xy 384.518662 -131.23164) (xy 384.518916 -131.2291)
			(xy 384.518916 -131.220464) (xy 384.524504 -131.211828) (xy 384.525774 -131.209796) (xy 384.52679 -131.207764)
			(xy 384.724148 -130.906774) (xy 384.728001 -130.900437) (xy 384.73227 -130.886244) (xy 384.73253 -130.878834)
			(xy 384.73253 -130.85318) (xy 384.732314 -130.845847) (xy 384.728191 -130.831775) (xy 384.724402 -130.825494)
			(xy 384.526536 -130.522472) (xy 384.52425 -130.518662) (xy 384.523996 -130.518154) (xy 384.52298 -130.516376)
			(xy 384.518916 -130.509772) (xy 384.518916 -130.501644) (xy 384.518662 -130.499104) (xy 384.518408 -130.49504)
			(xy 384.518408 -130.266948) (xy 384.518852 -130.256726) (xy 384.526664 -130.237835) (xy 384.541115 -130.223377)
			(xy 384.560003 -130.215556) (xy 384.570224 -130.215132) (xy 385.306824 -130.215132) (xy 385.317053 -130.215494)
			(xy 385.33595 -130.223334) (xy 385.350407 -130.23781) (xy 385.358221 -130.256718) (xy 385.35864 -130.266948)
			(xy 385.35864 -130.494532) (xy 385.358386 -130.498596) (xy 385.358132 -130.501136) (xy 385.358132 -130.509772)
			(xy 385.35229 -130.51917) (xy 385.351528 -130.52044) (xy 385.350258 -130.522472) (xy 385.144518 -130.837178)
			(xy 385.139446 -130.84569) (xy 385.13563 -130.865115) (xy 385.139457 -130.884538) (xy 385.144518 -130.893058)
			(xy 385.350258 -131.206494) (xy 385.351274 -131.208526) (xy 385.352544 -131.210558) (xy 385.358132 -131.219194)
			(xy 385.358132 -131.22783) (xy 385.358386 -131.23037) (xy 385.35864 -131.234434) (xy 385.35864 -131.368292)
			(xy 393.732004 -131.368292) (xy 393.732004 -130.361944) (xy 393.732458 -130.351792) (xy 393.74024 -130.33304)
			(xy 393.754627 -130.318715) (xy 393.773413 -130.311015) (xy 393.783566 -130.310636) (xy 394.964666 -130.310636)
			(xy 394.97479 -130.311155) (xy 394.99351 -130.31887) (xy 395.007867 -130.333147) (xy 395.015688 -130.351823)
			(xy 395.016228 -130.361944) (xy 395.016228 -131.368292) (xy 398.268952 -131.368292) (xy 398.268952 -130.361944)
			(xy 398.269451 -130.35183) (xy 398.277176 -130.333137) (xy 398.291466 -130.318823) (xy 398.310147 -130.311068)
			(xy 398.32026 -130.310636) (xy 399.50136 -130.310636) (xy 399.511484 -130.31105) (xy 399.530194 -130.318791)
			(xy 399.544511 -130.333109) (xy 399.552251 -130.35182) (xy 399.552668 -130.361944) (xy 399.552668 -131.29641)
			(xy 401.939252 -131.29641) (xy 401.939252 -130.43281) (xy 401.939742 -130.402842) (xy 401.947565 -130.34342)
			(xy 401.963078 -130.285527) (xy 401.986014 -130.230154) (xy 402.015981 -130.178248) (xy 402.052468 -130.130698)
			(xy 402.094848 -130.088318) (xy 402.142398 -130.051831) (xy 402.194304 -130.021864) (xy 402.249677 -129.998928)
			(xy 402.30757 -129.983415) (xy 402.366992 -129.975592) (xy 402.426928 -129.975592) (xy 402.48635 -129.983415)
			(xy 402.544243 -129.998928) (xy 402.599616 -130.021864) (xy 402.651522 -130.051831) (xy 402.699072 -130.088318)
			(xy 402.741452 -130.130698) (xy 402.777939 -130.178248) (xy 402.807906 -130.230154) (xy 402.830842 -130.285527)
			(xy 402.846355 -130.34342) (xy 402.854178 -130.402842) (xy 402.854668 -130.43281) (xy 402.854668 -130.777234)
			(xy 414.899348 -130.777234) (xy 414.899348 -129.913634) (xy 414.899838 -129.88365) (xy 414.907666 -129.824194)
			(xy 414.923187 -129.766269) (xy 414.946136 -129.710865) (xy 414.97612 -129.658931) (xy 415.012626 -129.611355)
			(xy 415.055031 -129.56895) (xy 415.102607 -129.532444) (xy 415.154541 -129.50246) (xy 415.209945 -129.479511)
			(xy 415.26787 -129.46399) (xy 415.327326 -129.456162) (xy 415.387294 -129.456162) (xy 415.44675 -129.46399)
			(xy 415.504675 -129.479511) (xy 415.560079 -129.50246) (xy 415.612013 -129.532444) (xy 415.659589 -129.56895)
			(xy 415.701994 -129.611355) (xy 415.7385 -129.658931) (xy 415.768484 -129.710865) (xy 415.791433 -129.766269)
			(xy 415.806954 -129.824194) (xy 415.814782 -129.88365) (xy 415.815272 -129.913634) (xy 415.815272 -130.777234)
			(xy 415.814782 -130.807218) (xy 415.809399 -130.8481) (xy 416.347148 -130.8481) (xy 416.347148 -129.841752)
			(xy 416.347645 -129.831647) (xy 416.355388 -129.812977) (xy 416.369681 -129.798686) (xy 416.388351 -129.790944)
			(xy 416.398456 -129.790444) (xy 417.57981 -129.790444) (xy 417.589938 -129.790919) (xy 417.60866 -129.79865)
			(xy 417.623016 -129.81294) (xy 417.630834 -129.831627) (xy 417.631372 -129.841752) (xy 417.631372 -130.8481)
			(xy 420.884096 -130.8481) (xy 420.884096 -129.841752) (xy 420.884546 -129.831641) (xy 420.892299 -129.812962)
			(xy 420.906606 -129.798669) (xy 420.925292 -129.790936) (xy 420.935404 -129.790444) (xy 422.116504 -129.790444)
			(xy 422.126606 -129.790981) (xy 422.145274 -129.798709) (xy 422.159566 -129.812989) (xy 422.167311 -129.83165)
			(xy 422.167812 -129.841752) (xy 422.167812 -130.8481) (xy 422.167315 -130.858207) (xy 422.15958 -130.876883)
			(xy 422.145286 -130.891177) (xy 422.126611 -130.898914) (xy 422.116504 -130.899408) (xy 420.935404 -130.899408)
			(xy 420.925283 -130.898981) (xy 420.906581 -130.891236) (xy 420.892267 -130.876923) (xy 420.88452 -130.858221)
			(xy 420.884096 -130.8481) (xy 417.631372 -130.8481) (xy 417.630983 -130.858226) (xy 417.62323 -130.876935)
			(xy 417.608905 -130.89125) (xy 417.59019 -130.89899) (xy 417.580064 -130.899408) (xy 416.39871 -130.899408)
			(xy 416.38859 -130.898867) (xy 416.369878 -130.891151) (xy 416.355523 -130.876882) (xy 416.347695 -130.858217)
			(xy 416.347148 -130.8481) (xy 415.809399 -130.8481) (xy 415.806954 -130.866674) (xy 415.791433 -130.924599)
			(xy 415.787348 -130.93446) (xy 427.899576 -130.93446) (xy 427.899576 -130.691636) (xy 428.018448 -130.51028)
			(xy 428.080932 -130.414776) (xy 428.105062 -130.377946) (xy 428.108926 -130.371616) (xy 428.113188 -130.357418)
			(xy 428.113444 -130.350006) (xy 428.113444 -130.324098) (xy 428.113254 -130.317948) (xy 428.110298 -130.306007)
			(xy 428.107602 -130.300476) (xy 427.994064 -130.126486) (xy 427.973998 -130.095498) (xy 427.96841 -130.086862)
			(xy 427.907958 -129.994152) (xy 427.90745 -129.99339) (xy 427.906942 -129.992628) (xy 427.906688 -129.99212)
			(xy 427.90618 -129.991358) (xy 427.899576 -129.980944) (xy 427.899576 -129.73812) (xy 427.900207 -129.726569)
			(xy 427.91018 -129.705724) (xy 427.928121 -129.691162) (xy 427.9392 -129.687828) (xy 427.951138 -129.686304)
			(xy 428.687738 -129.686304) (xy 428.698492 -129.68685) (xy 428.718182 -129.695498) (xy 428.725838 -129.703068)
			(xy 428.732037 -129.710467) (xy 428.738952 -129.728474) (xy 428.7393 -129.73812) (xy 428.7393 -129.980944)
			(xy 428.5234 -130.311398) (xy 428.519359 -130.319611) (xy 428.516822 -130.337727) (xy 428.520775 -130.355587)
			(xy 428.525432 -130.363468) (xy 428.55769 -130.413252) (xy 428.7393 -130.690366) (xy 428.7393 -130.769106)
			(xy 429.3743 -130.769106) (xy 429.3743 -129.905506) (xy 429.37479 -129.875522) (xy 429.382618 -129.816066)
			(xy 429.398139 -129.758141) (xy 429.421088 -129.702737) (xy 429.451072 -129.650803) (xy 429.487578 -129.603227)
			(xy 429.529983 -129.560822) (xy 429.577559 -129.524316) (xy 429.629493 -129.494332) (xy 429.684897 -129.471383)
			(xy 429.742822 -129.455862) (xy 429.802278 -129.448034) (xy 429.862246 -129.448034) (xy 429.921702 -129.455862)
			(xy 429.979627 -129.471383) (xy 430.035031 -129.494332) (xy 430.086965 -129.524316) (xy 430.134541 -129.560822)
			(xy 430.176946 -129.603227) (xy 430.213452 -129.650803) (xy 430.243436 -129.702737) (xy 430.266385 -129.758141)
			(xy 430.281906 -129.816066) (xy 430.289734 -129.875522) (xy 430.290224 -129.905506) (xy 430.290224 -130.769106)
			(xy 430.289734 -130.79909) (xy 430.281906 -130.858546) (xy 430.266385 -130.916471) (xy 430.243436 -130.971875)
			(xy 430.213452 -131.023809) (xy 430.176946 -131.071385) (xy 430.134541 -131.11379) (xy 430.086965 -131.150296)
			(xy 430.035031 -131.18028) (xy 429.979627 -131.203229) (xy 429.921702 -131.21875) (xy 429.862246 -131.226578)
			(xy 429.802278 -131.226578) (xy 429.742822 -131.21875) (xy 429.684897 -131.203229) (xy 429.629493 -131.18028)
			(xy 429.577559 -131.150296) (xy 429.529983 -131.11379) (xy 429.487578 -131.071385) (xy 429.451072 -131.023809)
			(xy 429.421088 -130.971875) (xy 429.398139 -130.916471) (xy 429.382618 -130.858546) (xy 429.37479 -130.79909)
			(xy 429.3743 -130.769106) (xy 428.7393 -130.769106) (xy 428.7393 -130.93446) (xy 428.738671 -130.946012)
			(xy 428.728701 -130.96686) (xy 428.710757 -130.98142) (xy 428.699676 -130.984752) (xy 428.687738 -130.986276)
			(xy 427.951138 -130.986276) (xy 427.940381 -130.985749) (xy 427.920692 -130.977088) (xy 427.913038 -130.969512)
			(xy 427.906828 -130.962122) (xy 427.899921 -130.944108) (xy 427.899576 -130.93446) (xy 415.787348 -130.93446)
			(xy 415.768484 -130.980003) (xy 415.7385 -131.031937) (xy 415.701994 -131.079513) (xy 415.659589 -131.121918)
			(xy 415.612013 -131.158424) (xy 415.560079 -131.188408) (xy 415.504675 -131.211357) (xy 415.44675 -131.226878)
			(xy 415.387294 -131.234706) (xy 415.327326 -131.234706) (xy 415.26787 -131.226878) (xy 415.209945 -131.211357)
			(xy 415.154541 -131.188408) (xy 415.102607 -131.158424) (xy 415.055031 -131.121918) (xy 415.012626 -131.079513)
			(xy 414.97612 -131.031937) (xy 414.946136 -130.980003) (xy 414.923187 -130.924599) (xy 414.907666 -130.866674)
			(xy 414.899838 -130.807218) (xy 414.899348 -130.777234) (xy 402.854668 -130.777234) (xy 402.854668 -131.29641)
			(xy 402.854178 -131.326378) (xy 402.846355 -131.3858) (xy 402.830842 -131.443693) (xy 402.807906 -131.499066)
			(xy 402.777939 -131.550972) (xy 402.741452 -131.598522) (xy 402.699072 -131.640902) (xy 402.651522 -131.677389)
			(xy 402.599616 -131.707356) (xy 402.544243 -131.730292) (xy 402.48635 -131.745805) (xy 402.426928 -131.753628)
			(xy 402.366992 -131.753628) (xy 402.30757 -131.745805) (xy 402.249677 -131.730292) (xy 402.194304 -131.707356)
			(xy 402.142398 -131.677389) (xy 402.094848 -131.640902) (xy 402.052468 -131.598522) (xy 402.015981 -131.550972)
			(xy 401.986014 -131.499066) (xy 401.963078 -131.443693) (xy 401.947565 -131.3858) (xy 401.939742 -131.326378)
			(xy 401.939252 -131.29641) (xy 399.552668 -131.29641) (xy 399.552668 -131.368292) (xy 399.552277 -131.378418)
			(xy 399.544525 -131.397128) (xy 399.530201 -131.411443) (xy 399.511486 -131.419183) (xy 399.50136 -131.4196)
			(xy 398.32026 -131.4196) (xy 398.310149 -131.419148) (xy 398.29147 -131.411397) (xy 398.277176 -131.39709)
			(xy 398.269443 -131.378404) (xy 398.268952 -131.368292) (xy 395.016228 -131.368292) (xy 395.015772 -131.378442)
			(xy 395.007985 -131.397189) (xy 394.993599 -131.411512) (xy 394.974818 -131.419217) (xy 394.964666 -131.4196)
			(xy 393.783566 -131.4196) (xy 393.773442 -131.419103) (xy 393.754728 -131.411371) (xy 393.740374 -131.397089)
			(xy 393.732549 -131.378413) (xy 393.732004 -131.368292) (xy 385.35864 -131.368292) (xy 385.35864 -131.463288)
			(xy 385.358109 -131.473492) (xy 385.350305 -131.492349) (xy 385.335879 -131.506784) (xy 385.317028 -131.514602)
			(xy 385.306824 -131.515104) (xy 384.570224 -131.515104) (xy 384.560002 -131.514668) (xy 384.541113 -131.50685)
			(xy 384.526656 -131.492397) (xy 384.518834 -131.47351) (xy 384.518408 -131.463288) (xy 383.852097 -131.463288)
			(xy 383.836646 -131.50059) (xy 383.806679 -131.552496) (xy 383.770192 -131.600046) (xy 383.727812 -131.642426)
			(xy 383.680262 -131.678913) (xy 383.628356 -131.70888) (xy 383.572983 -131.731816) (xy 383.51509 -131.747329)
			(xy 383.455668 -131.755152) (xy 383.395732 -131.755152) (xy 383.33631 -131.747329) (xy 383.278417 -131.731816)
			(xy 383.223044 -131.70888) (xy 383.171138 -131.678913) (xy 383.123588 -131.642426) (xy 383.081208 -131.600046)
			(xy 383.044721 -131.552496) (xy 383.014754 -131.50059) (xy 382.991818 -131.445217) (xy 382.976305 -131.387324)
			(xy 382.968482 -131.327902) (xy 382.967992 -131.297934) (xy 316.568893 -131.297934) (xy 316.576928 -131.301262)
			(xy 316.628834 -131.331229) (xy 316.676384 -131.367716) (xy 316.718764 -131.410096) (xy 316.755251 -131.457646)
			(xy 316.785218 -131.509552) (xy 316.808154 -131.564925) (xy 316.823667 -131.622818) (xy 316.83149 -131.68224)
			(xy 316.83198 -131.712208) (xy 316.83198 -132.575808) (xy 316.83149 -132.605776) (xy 316.823667 -132.665198)
			(xy 316.808154 -132.723091) (xy 316.785218 -132.778464) (xy 316.755251 -132.83037) (xy 316.718764 -132.87792)
			(xy 316.676384 -132.9203) (xy 316.628834 -132.956787) (xy 316.576928 -132.986754) (xy 316.521555 -133.00969)
			(xy 316.463662 -133.025203) (xy 316.40424 -133.033026) (xy 316.344304 -133.033026) (xy 316.284882 -133.025203)
			(xy 316.226989 -133.00969) (xy 316.171616 -132.986754) (xy 316.11971 -132.956787) (xy 316.07216 -132.9203)
			(xy 316.02978 -132.87792) (xy 315.993293 -132.83037) (xy 315.963326 -132.778464) (xy 315.94039 -132.723091)
			(xy 315.924877 -132.665198) (xy 315.917054 -132.605776) (xy 315.916564 -132.575808) (xy 315.281564 -132.575808)
			(xy 315.281564 -132.741162) (xy 315.281105 -132.751331) (xy 315.273333 -132.770124) (xy 315.258958 -132.78451)
			(xy 315.240171 -132.792297) (xy 315.230002 -132.792724) (xy 314.493148 -132.792724) (xy 314.482976 -132.792186)
			(xy 314.464165 -132.784437) (xy 314.449737 -132.770095) (xy 314.441876 -132.751331) (xy 314.441332 -132.741162)
			(xy 297.83004 -132.741162) (xy 297.813958 -132.779988) (xy 297.783991 -132.831894) (xy 297.747504 -132.879444)
			(xy 297.705124 -132.921824) (xy 297.657574 -132.958311) (xy 297.605668 -132.988278) (xy 297.550295 -133.011214)
			(xy 297.492402 -133.026727) (xy 297.43298 -133.03455) (xy 297.373044 -133.03455) (xy 297.313622 -133.026727)
			(xy 297.255729 -133.011214) (xy 297.200356 -132.988278) (xy 297.14845 -132.958311) (xy 297.1009 -132.921824)
			(xy 297.05852 -132.879444) (xy 297.022033 -132.831894) (xy 296.992066 -132.779988) (xy 296.96913 -132.724615)
			(xy 296.953617 -132.666722) (xy 296.945794 -132.6073) (xy 296.945304 -132.577332) (xy 284.900624 -132.577332)
			(xy 284.900624 -133.096508) (xy 284.900134 -133.126492) (xy 284.892306 -133.185948) (xy 284.876785 -133.243873)
			(xy 284.853836 -133.299277) (xy 284.823852 -133.351211) (xy 284.787346 -133.398787) (xy 284.744941 -133.441192)
			(xy 284.697365 -133.477698) (xy 284.645431 -133.507682) (xy 284.590027 -133.530631) (xy 284.532102 -133.546152)
			(xy 284.472646 -133.55398) (xy 284.412678 -133.55398) (xy 284.353222 -133.546152) (xy 284.295297 -133.530631)
			(xy 284.239893 -133.507682) (xy 284.187959 -133.477698) (xy 284.140383 -133.441192) (xy 284.097978 -133.398787)
			(xy 284.061472 -133.351211) (xy 284.031488 -133.299277) (xy 284.008539 -133.243873) (xy 283.993018 -133.185948)
			(xy 283.98519 -133.126492) (xy 283.9847 -133.096508) (xy 283.452824 -133.096508) (xy 283.452824 -133.16839)
			(xy 283.452427 -133.178566) (xy 283.444638 -133.197367) (xy 283.430244 -133.211754) (xy 283.411438 -133.219533)
			(xy 283.401262 -133.219952) (xy 282.220162 -133.219952) (xy 282.210001 -133.219497) (xy 282.191229 -133.211709)
			(xy 282.176864 -133.197331) (xy 282.169093 -133.178552) (xy 282.1686 -133.16839) (xy 278.915876 -133.16839)
			(xy 278.915366 -133.178514) (xy 278.907644 -133.197232) (xy 278.893365 -133.211588) (xy 278.874689 -133.21941)
			(xy 278.864568 -133.219952) (xy 277.683468 -133.219952) (xy 277.673318 -133.219506) (xy 277.654575 -133.211709)
			(xy 277.640255 -133.197321) (xy 277.632547 -133.178542) (xy 277.63216 -133.16839) (xy 271.900396 -133.16839)
			(xy 271.900396 -133.269736) (xy 271.899817 -133.281263) (xy 271.889927 -133.302087) (xy 271.87207 -133.316668)
			(xy 271.861026 -133.320028) (xy 271.860772 -133.320028) (xy 271.848834 -133.321552) (xy 271.112234 -133.321552)
			(xy 271.10586 -133.321341) (xy 271.093523 -133.318118) (xy 271.08785 -133.315202) (xy 271.079857 -133.310434)
			(xy 271.067614 -133.296438) (xy 271.061068 -133.279033) (xy 271.060672 -133.269736) (xy 270.394382 -133.269736)
			(xy 270.378884 -133.307151) (xy 270.3489 -133.359085) (xy 270.312394 -133.406661) (xy 270.269989 -133.449066)
			(xy 270.222413 -133.485572) (xy 270.170479 -133.515556) (xy 270.115075 -133.538505) (xy 270.05715 -133.554026)
			(xy 269.997694 -133.561854) (xy 269.937726 -133.561854) (xy 269.87827 -133.554026) (xy 269.820345 -133.538505)
			(xy 269.764941 -133.515556) (xy 269.713007 -133.485572) (xy 269.665431 -133.449066) (xy 269.623026 -133.406661)
			(xy 269.58652 -133.359085) (xy 269.556536 -133.307151) (xy 269.533587 -133.251747) (xy 269.518066 -133.193822)
			(xy 269.510238 -133.134366) (xy 269.509748 -133.104382) (xy 197.851649 -133.104382) (xy 197.886882 -133.124723)
			(xy 197.934432 -133.16121) (xy 197.976812 -133.20359) (xy 198.013299 -133.25114) (xy 198.043266 -133.303046)
			(xy 198.066202 -133.358419) (xy 198.081715 -133.416312) (xy 198.089538 -133.475734) (xy 198.090028 -133.505702)
			(xy 198.090028 -134.369302) (xy 198.089538 -134.39927) (xy 198.081715 -134.458692) (xy 198.066202 -134.516585)
			(xy 198.043266 -134.571958) (xy 198.013299 -134.623864) (xy 197.976812 -134.671414) (xy 197.934432 -134.713794)
			(xy 197.886882 -134.750281) (xy 197.834976 -134.780248) (xy 197.779603 -134.803184) (xy 197.72171 -134.818697)
			(xy 197.662288 -134.82652) (xy 197.602352 -134.82652) (xy 197.54293 -134.818697) (xy 197.485037 -134.803184)
			(xy 197.429664 -134.780248) (xy 197.377758 -134.750281) (xy 197.330208 -134.713794) (xy 197.287828 -134.671414)
			(xy 197.251341 -134.623864) (xy 197.221374 -134.571958) (xy 197.198438 -134.516585) (xy 197.182925 -134.458692)
			(xy 197.175102 -134.39927) (xy 197.174612 -134.369302) (xy 196.539104 -134.369302) (xy 196.539104 -134.534656)
			(xy 196.538469 -134.546208) (xy 196.528501 -134.567054) (xy 196.51056 -134.581616) (xy 196.49948 -134.584948)
			(xy 196.487542 -134.586472) (xy 195.750942 -134.586472) (xy 195.740185 -134.585944) (xy 195.720496 -134.577284)
			(xy 195.712842 -134.569708) (xy 195.70663 -134.562319) (xy 195.699724 -134.544304) (xy 195.69938 -134.534656)
			(xy 183.587026 -134.534656) (xy 183.568314 -134.579832) (xy 183.538347 -134.631738) (xy 183.50186 -134.679288)
			(xy 183.45948 -134.721668) (xy 183.41193 -134.758155) (xy 183.360024 -134.788122) (xy 183.304651 -134.811058)
			(xy 183.246758 -134.826571) (xy 183.187336 -134.834394) (xy 183.1274 -134.834394) (xy 183.067978 -134.826571)
			(xy 183.010085 -134.811058) (xy 182.954712 -134.788122) (xy 182.902806 -134.758155) (xy 182.855256 -134.721668)
			(xy 182.812876 -134.679288) (xy 182.776389 -134.631738) (xy 182.746422 -134.579832) (xy 182.723486 -134.524459)
			(xy 182.707973 -134.466566) (xy 182.70015 -134.407144) (xy 182.69966 -134.377176) (xy 170.65498 -134.377176)
			(xy 170.65498 -134.896352) (xy 170.65449 -134.926336) (xy 170.646662 -134.985792) (xy 170.631141 -135.043717)
			(xy 170.608192 -135.099121) (xy 170.578208 -135.151055) (xy 170.541702 -135.198631) (xy 170.499297 -135.241036)
			(xy 170.451721 -135.277542) (xy 170.399787 -135.307526) (xy 170.344383 -135.330475) (xy 170.286458 -135.345996)
			(xy 170.227002 -135.353824) (xy 170.167034 -135.353824) (xy 170.107578 -135.345996) (xy 170.049653 -135.330475)
			(xy 169.994249 -135.307526) (xy 169.942315 -135.277542) (xy 169.894739 -135.241036) (xy 169.852334 -135.198631)
			(xy 169.815828 -135.151055) (xy 169.785844 -135.099121) (xy 169.762895 -135.043717) (xy 169.747374 -134.985792)
			(xy 169.739546 -134.926336) (xy 169.739056 -134.896352) (xy 167.352472 -134.896352) (xy 167.352472 -134.968488)
			(xy 167.352074 -134.978613) (xy 167.344324 -134.997322) (xy 167.330002 -135.011638) (xy 167.311289 -135.019378)
			(xy 167.301164 -135.019796) (xy 166.120064 -135.019796) (xy 166.109952 -135.019344) (xy 166.091273 -135.011594)
			(xy 166.076979 -134.997287) (xy 166.069246 -134.9786) (xy 166.068756 -134.968488) (xy 162.816032 -134.968488)
			(xy 162.815569 -134.978637) (xy 162.807784 -134.997383) (xy 162.7934 -135.011706) (xy 162.774621 -135.019412)
			(xy 162.76447 -135.019796) (xy 161.58337 -135.019796) (xy 161.573246 -135.019299) (xy 161.554531 -135.011568)
			(xy 161.540177 -134.997286) (xy 161.532352 -134.97861) (xy 161.531808 -134.968488) (xy 153.158444 -134.968488)
			(xy 153.158444 -135.06323) (xy 153.157991 -135.073392) (xy 153.150203 -135.092165) (xy 153.135825 -135.10653)
			(xy 153.117044 -135.1143) (xy 153.106882 -135.114792) (xy 152.370028 -135.114792) (xy 152.35985 -135.114302)
			(xy 152.341033 -135.106541) (xy 152.326604 -135.092183) (xy 152.31875 -135.073405) (xy 152.318212 -135.06323)
			(xy 151.65243 -135.06323) (xy 151.636932 -135.100645) (xy 151.606948 -135.152579) (xy 151.570442 -135.200155)
			(xy 151.528037 -135.24256) (xy 151.480461 -135.279066) (xy 151.428527 -135.30905) (xy 151.373123 -135.331999)
			(xy 151.315198 -135.34752) (xy 151.255742 -135.355348) (xy 151.195774 -135.355348) (xy 151.136318 -135.34752)
			(xy 151.078393 -135.331999) (xy 151.022989 -135.30905) (xy 150.971055 -135.279066) (xy 150.923479 -135.24256)
			(xy 150.881074 -135.200155) (xy 150.844568 -135.152579) (xy 150.814584 -135.100645) (xy 150.791635 -135.045241)
			(xy 150.776114 -134.987316) (xy 150.768286 -134.92786) (xy 150.767796 -134.897876) (xy 84.369615 -134.897876)
			(xy 84.377099 -134.900976) (xy 84.429033 -134.93096) (xy 84.476609 -134.967466) (xy 84.519014 -135.009871)
			(xy 84.55552 -135.057447) (xy 84.585504 -135.109381) (xy 84.608453 -135.164785) (xy 84.623974 -135.22271)
			(xy 84.631802 -135.282166) (xy 84.632292 -135.31215) (xy 84.632292 -136.17575) (xy 84.631802 -136.205734)
			(xy 84.623974 -136.26519) (xy 84.608453 -136.323115) (xy 84.585504 -136.378519) (xy 84.55552 -136.430453)
			(xy 84.519014 -136.478029) (xy 84.476609 -136.520434) (xy 84.429033 -136.55694) (xy 84.377099 -136.586924)
			(xy 84.321695 -136.609873) (xy 84.26377 -136.625394) (xy 84.204314 -136.633222) (xy 84.144346 -136.633222)
			(xy 84.08489 -136.625394) (xy 84.026965 -136.609873) (xy 83.971561 -136.586924) (xy 83.919627 -136.55694)
			(xy 83.872051 -136.520434) (xy 83.829646 -136.478029) (xy 83.79314 -136.430453) (xy 83.763156 -136.378519)
			(xy 83.740207 -136.323115) (xy 83.724686 -136.26519) (xy 83.716858 -136.205734) (xy 83.716368 -136.17575)
			(xy 83.081368 -136.17575) (xy 83.081368 -136.341104) (xy 83.080712 -136.35262) (xy 83.07085 -136.373435)
			(xy 83.053027 -136.388024) (xy 83.041998 -136.391396) (xy 83.041744 -136.391396) (xy 83.029806 -136.39292)
			(xy 82.293206 -136.39292) (xy 82.286833 -136.392688) (xy 82.274496 -136.38948) (xy 82.268822 -136.38657)
			(xy 82.260809 -136.381832) (xy 82.248571 -136.367822) (xy 82.242034 -136.350405) (xy 82.241644 -136.341104)
			(xy 65.630373 -136.341104) (xy 65.614244 -136.380043) (xy 65.58426 -136.431977) (xy 65.547754 -136.479553)
			(xy 65.505349 -136.521958) (xy 65.457773 -136.558464) (xy 65.405839 -136.588448) (xy 65.350435 -136.611397)
			(xy 65.29251 -136.626918) (xy 65.233054 -136.634746) (xy 65.173086 -136.634746) (xy 65.11363 -136.626918)
			(xy 65.055705 -136.611397) (xy 65.000301 -136.588448) (xy 64.948367 -136.558464) (xy 64.900791 -136.521958)
			(xy 64.858386 -136.479553) (xy 64.82188 -136.431977) (xy 64.791896 -136.380043) (xy 64.768947 -136.324639)
			(xy 64.753426 -136.266714) (xy 64.745598 -136.207258) (xy 64.745108 -136.177274) (xy 52.700428 -136.177274)
			(xy 52.700428 -136.69645) (xy 52.700299 -136.704324) (xy 153.409904 -136.704324) (xy 153.409904 -135.840724)
			(xy 153.410394 -135.81074) (xy 153.418222 -135.751284) (xy 153.433743 -135.693359) (xy 153.456692 -135.637955)
			(xy 153.486676 -135.586021) (xy 153.523182 -135.538445) (xy 153.565587 -135.49604) (xy 153.613163 -135.459534)
			(xy 153.665097 -135.42955) (xy 153.720501 -135.406601) (xy 153.778426 -135.39108) (xy 153.837882 -135.383252)
			(xy 153.89785 -135.383252) (xy 153.957306 -135.39108) (xy 154.015231 -135.406601) (xy 154.070635 -135.42955)
			(xy 154.122569 -135.459534) (xy 154.170145 -135.49604) (xy 154.21255 -135.538445) (xy 154.249056 -135.586021)
			(xy 154.27904 -135.637955) (xy 154.301989 -135.693359) (xy 154.31751 -135.751284) (xy 154.325338 -135.81074)
			(xy 154.325828 -135.840724) (xy 154.325828 -136.704324) (xy 154.325338 -136.734308) (xy 154.31751 -136.793764)
			(xy 154.301989 -136.851689) (xy 154.294538 -136.869678) (xy 154.96032 -136.869678) (xy 154.96032 -136.642094)
			(xy 154.960574 -136.63803) (xy 154.960828 -136.63549) (xy 154.960828 -136.626854) (xy 154.966416 -136.618218)
			(xy 154.967686 -136.616186) (xy 154.968702 -136.614154) (xy 155.16606 -136.313164) (xy 155.169917 -136.30683)
			(xy 155.174184 -136.292635) (xy 155.174442 -136.285224) (xy 155.174442 -136.25957) (xy 155.174228 -136.252237)
			(xy 155.170104 -136.238165) (xy 155.166314 -136.231884) (xy 154.968448 -135.928862) (xy 154.966162 -135.925052)
			(xy 154.965908 -135.924544) (xy 154.964892 -135.922766) (xy 154.960828 -135.916162) (xy 154.960828 -135.908034)
			(xy 154.960574 -135.905494) (xy 154.96032 -135.90143) (xy 154.96032 -135.673338) (xy 154.960795 -135.663171)
			(xy 154.968564 -135.644381) (xy 154.982934 -135.629995) (xy 155.001716 -135.622206) (xy 155.011882 -135.621776)
			(xy 155.748736 -135.621776) (xy 155.758914 -135.622245) (xy 155.777726 -135.630021) (xy 155.792152 -135.644384)
			(xy 155.80001 -135.663162) (xy 155.800552 -135.673338) (xy 155.800552 -135.900922) (xy 155.800298 -135.904986)
			(xy 155.800044 -135.907526) (xy 155.800044 -135.916162) (xy 155.794202 -135.92556) (xy 155.79344 -135.92683)
			(xy 155.79217 -135.928862) (xy 155.58643 -136.243568) (xy 155.581366 -136.252084) (xy 155.577546 -136.271507)
			(xy 155.581371 -136.290929) (xy 155.58643 -136.299448) (xy 155.79217 -136.612884) (xy 155.793186 -136.614916)
			(xy 155.794456 -136.616948) (xy 155.800044 -136.625584) (xy 155.800044 -136.63422) (xy 155.800298 -136.63676)
			(xy 155.800552 -136.640824) (xy 155.800552 -136.768332) (xy 161.531808 -136.768332) (xy 161.531808 -135.761984)
			(xy 161.532208 -135.751828) (xy 161.540011 -135.733073) (xy 161.554414 -135.71875) (xy 161.573212 -135.711053)
			(xy 161.58337 -135.710676) (xy 162.76447 -135.710676) (xy 162.774599 -135.711152) (xy 162.793327 -135.718877)
			(xy 162.807685 -135.733167) (xy 162.815499 -135.751857) (xy 162.816032 -135.761984) (xy 162.816032 -136.768332)
			(xy 166.068756 -136.768332) (xy 166.068756 -135.761984) (xy 166.069271 -135.75188) (xy 166.077006 -135.73321)
			(xy 166.091293 -135.718917) (xy 166.10996 -135.711175) (xy 166.120064 -135.710676) (xy 167.301164 -135.710676)
			(xy 167.311281 -135.711145) (xy 167.329979 -135.718877) (xy 167.344294 -135.733177) (xy 167.352045 -135.751867)
			(xy 167.352472 -135.761984) (xy 167.352472 -136.69645) (xy 167.884856 -136.69645) (xy 167.884856 -135.83285)
			(xy 167.885346 -135.802866) (xy 167.893174 -135.74341) (xy 167.908695 -135.685485) (xy 167.931644 -135.630081)
			(xy 167.961628 -135.578147) (xy 167.998134 -135.530571) (xy 168.040539 -135.488166) (xy 168.088115 -135.45166)
			(xy 168.140049 -135.421676) (xy 168.195453 -135.398727) (xy 168.253378 -135.383206) (xy 168.312834 -135.375378)
			(xy 168.372802 -135.375378) (xy 168.432258 -135.383206) (xy 168.490183 -135.398727) (xy 168.545587 -135.421676)
			(xy 168.597521 -135.45166) (xy 168.645097 -135.488166) (xy 168.687502 -135.530571) (xy 168.724008 -135.578147)
			(xy 168.753992 -135.630081) (xy 168.776941 -135.685485) (xy 168.792462 -135.74341) (xy 168.80029 -135.802866)
			(xy 168.80078 -135.83285) (xy 168.80078 -136.177274) (xy 180.84546 -136.177274) (xy 180.84546 -135.313674)
			(xy 180.84595 -135.283706) (xy 180.853773 -135.224284) (xy 180.869286 -135.166391) (xy 180.892222 -135.111018)
			(xy 180.922189 -135.059112) (xy 180.958676 -135.011562) (xy 181.001056 -134.969182) (xy 181.048606 -134.932695)
			(xy 181.100512 -134.902728) (xy 181.155885 -134.879792) (xy 181.213778 -134.864279) (xy 181.2732 -134.856456)
			(xy 181.333136 -134.856456) (xy 181.392558 -134.864279) (xy 181.450451 -134.879792) (xy 181.505824 -134.902728)
			(xy 181.55773 -134.932695) (xy 181.60528 -134.969182) (xy 181.64766 -135.011562) (xy 181.684147 -135.059112)
			(xy 181.714114 -135.111018) (xy 181.73705 -135.166391) (xy 181.752563 -135.224284) (xy 181.760386 -135.283706)
			(xy 181.760876 -135.313674) (xy 181.760876 -136.177274) (xy 181.760386 -136.207242) (xy 181.755002 -136.24814)
			(xy 184.146952 -136.24814) (xy 184.146952 -135.241792) (xy 184.147478 -135.231689) (xy 184.155209 -135.21302)
			(xy 184.169493 -135.198727) (xy 184.188157 -135.190984) (xy 184.19826 -135.190484) (xy 185.379614 -135.190484)
			(xy 185.389747 -135.190917) (xy 185.408477 -135.198657) (xy 185.422834 -135.21296) (xy 185.430645 -135.231661)
			(xy 185.431176 -135.241792) (xy 185.431176 -136.24814) (xy 188.6839 -136.24814) (xy 188.6839 -135.241792)
			(xy 188.684379 -135.231683) (xy 188.692119 -135.213004) (xy 188.706418 -135.19871) (xy 188.725099 -135.190976)
			(xy 188.735208 -135.190484) (xy 189.916308 -135.190484) (xy 189.926415 -135.190978) (xy 189.94509 -135.198716)
			(xy 189.959384 -135.21301) (xy 189.967122 -135.231685) (xy 189.967616 -135.241792) (xy 189.967616 -136.24814)
			(xy 189.967148 -136.258249) (xy 189.9594 -136.276925) (xy 189.945098 -136.291218) (xy 189.926418 -136.298954)
			(xy 189.916308 -136.299448) (xy 188.735208 -136.299448) (xy 188.725106 -136.29891) (xy 188.706437 -136.291183)
			(xy 188.692143 -136.276903) (xy 188.6844 -136.258242) (xy 188.6839 -136.24814) (xy 185.431176 -136.24814)
			(xy 185.430747 -136.258254) (xy 185.422992 -136.276938) (xy 185.408677 -136.291232) (xy 185.389983 -136.298961)
			(xy 185.379868 -136.299448) (xy 184.198514 -136.299448) (xy 184.188387 -136.298962) (xy 184.169664 -136.291236)
			(xy 184.155306 -136.27695) (xy 184.147489 -136.258265) (xy 184.146952 -136.24814) (xy 181.755002 -136.24814)
			(xy 181.752563 -136.266664) (xy 181.73705 -136.324557) (xy 181.730196 -136.341104) (xy 198.341488 -136.341104)
			(xy 198.341488 -136.09828) (xy 198.486268 -135.877554) (xy 198.535544 -135.802116) (xy 198.555356 -135.77189)
			(xy 198.560312 -135.763431) (xy 198.564049 -135.744203) (xy 198.560314 -135.724975) (xy 198.555356 -135.716518)
			(xy 198.410322 -135.493506) (xy 198.354696 -135.408162) (xy 198.350378 -135.402066) (xy 198.347076 -135.396478)
			(xy 198.346568 -135.395462) (xy 198.341488 -135.387588) (xy 198.341488 -135.144764) (xy 198.342079 -135.133239)
			(xy 198.351965 -135.112416) (xy 198.369817 -135.097834) (xy 198.380858 -135.094472) (xy 198.381112 -135.094472)
			(xy 198.39305 -135.092948) (xy 199.12965 -135.092948) (xy 199.136024 -135.093164) (xy 199.148361 -135.096383)
			(xy 199.154034 -135.099298) (xy 199.162044 -135.104038) (xy 199.174278 -135.11805) (xy 199.180818 -135.135464)
			(xy 199.181212 -135.144764) (xy 199.181212 -135.387588) (xy 198.965312 -135.718042) (xy 198.961314 -135.726273)
			(xy 198.958761 -135.744377) (xy 198.962696 -135.762231) (xy 198.967344 -135.770112) (xy 198.999602 -135.819896)
			(xy 199.015096 -135.843518) (xy 199.181212 -136.09701) (xy 199.181212 -136.17575) (xy 199.81672 -136.17575)
			(xy 199.81672 -135.31215) (xy 199.81721 -135.282182) (xy 199.825033 -135.22276) (xy 199.840546 -135.164867)
			(xy 199.863482 -135.109494) (xy 199.893449 -135.057588) (xy 199.929936 -135.010038) (xy 199.972316 -134.967658)
			(xy 200.019866 -134.931171) (xy 200.071772 -134.901204) (xy 200.127145 -134.878268) (xy 200.185038 -134.862755)
			(xy 200.24446 -134.854932) (xy 200.304396 -134.854932) (xy 200.363818 -134.862755) (xy 200.421711 -134.878268)
			(xy 200.469049 -134.897876) (xy 266.86764 -134.897876) (xy 266.86764 -134.034276) (xy 266.86813 -134.004292)
			(xy 266.875958 -133.944836) (xy 266.891479 -133.886911) (xy 266.914428 -133.831507) (xy 266.944412 -133.779573)
			(xy 266.980918 -133.731997) (xy 267.023323 -133.689592) (xy 267.070899 -133.653086) (xy 267.122833 -133.623102)
			(xy 267.178237 -133.600153) (xy 267.236162 -133.584632) (xy 267.295618 -133.576804) (xy 267.355586 -133.576804)
			(xy 267.415042 -133.584632) (xy 267.472967 -133.600153) (xy 267.528371 -133.623102) (xy 267.580305 -133.653086)
			(xy 267.627881 -133.689592) (xy 267.670286 -133.731997) (xy 267.706792 -133.779573) (xy 267.736776 -133.831507)
			(xy 267.759725 -133.886911) (xy 267.775246 -133.944836) (xy 267.783074 -134.004292) (xy 267.783564 -134.034276)
			(xy 267.783564 -134.897876) (xy 267.783074 -134.92786) (xy 267.775246 -134.987316) (xy 267.759725 -135.045241)
			(xy 267.752274 -135.06323) (xy 268.418564 -135.06323) (xy 268.418564 -134.820406) (xy 268.537436 -134.63905)
			(xy 268.59992 -134.543546) (xy 268.62405 -134.506716) (xy 268.627925 -134.500391) (xy 268.632181 -134.486189)
			(xy 268.632432 -134.478776) (xy 268.632432 -134.452868) (xy 268.632254 -134.446717) (xy 268.62929 -134.434776)
			(xy 268.62659 -134.429246) (xy 268.513052 -134.255256) (xy 268.492986 -134.224268) (xy 268.487398 -134.215632)
			(xy 268.426946 -134.122922) (xy 268.426438 -134.12216) (xy 268.42593 -134.121398) (xy 268.425676 -134.12089)
			(xy 268.425168 -134.120128) (xy 268.418564 -134.109714) (xy 268.418564 -133.86689) (xy 268.418956 -133.856715)
			(xy 268.42675 -133.837915) (xy 268.441145 -133.823529) (xy 268.45995 -133.815749) (xy 268.470126 -133.815328)
			(xy 269.206726 -133.815328) (xy 269.216884 -133.815812) (xy 269.235652 -133.823593) (xy 269.250016 -133.837961)
			(xy 269.257791 -133.856732) (xy 269.258288 -133.86689) (xy 269.258288 -134.109714) (xy 269.042388 -134.440168)
			(xy 269.038372 -134.448391) (xy 269.035827 -134.4665) (xy 269.039769 -134.484357) (xy 269.04442 -134.492238)
			(xy 269.076678 -134.542022) (xy 269.258288 -134.819136) (xy 269.258288 -134.968488) (xy 277.63216 -134.968488)
			(xy 277.63216 -133.96214) (xy 277.632648 -133.952025) (xy 277.640375 -133.93333) (xy 277.65467 -133.919016)
			(xy 277.673354 -133.911262) (xy 277.683468 -133.910832) (xy 278.864568 -133.910832) (xy 278.874692 -133.911243)
			(xy 278.893402 -133.918986) (xy 278.907718 -133.933305) (xy 278.915459 -133.952016) (xy 278.915876 -133.96214)
			(xy 278.915876 -134.968488) (xy 282.1686 -134.968488) (xy 282.1686 -133.96214) (xy 282.169049 -133.95202)
			(xy 282.176784 -133.933317) (xy 282.191091 -133.919002) (xy 282.209788 -133.911255) (xy 282.219908 -133.910832)
			(xy 283.401262 -133.910832) (xy 283.411385 -133.911358) (xy 283.430104 -133.919071) (xy 283.444461 -133.933346)
			(xy 283.452283 -133.95202) (xy 283.452824 -133.96214) (xy 283.452824 -134.896352) (xy 285.8389 -134.896352)
			(xy 285.8389 -134.032752) (xy 285.83939 -134.002768) (xy 285.847218 -133.943312) (xy 285.862739 -133.885387)
			(xy 285.885688 -133.829983) (xy 285.915672 -133.778049) (xy 285.952178 -133.730473) (xy 285.994583 -133.688068)
			(xy 286.042159 -133.651562) (xy 286.094093 -133.621578) (xy 286.149497 -133.598629) (xy 286.207422 -133.583108)
			(xy 286.266878 -133.57528) (xy 286.326846 -133.57528) (xy 286.386302 -133.583108) (xy 286.444227 -133.598629)
			(xy 286.499631 -133.621578) (xy 286.551565 -133.651562) (xy 286.599141 -133.688068) (xy 286.641546 -133.730473)
			(xy 286.678052 -133.778049) (xy 286.708036 -133.829983) (xy 286.730985 -133.885387) (xy 286.746506 -133.943312)
			(xy 286.754334 -134.002768) (xy 286.754824 -134.032752) (xy 286.754824 -134.377176) (xy 298.799504 -134.377176)
			(xy 298.799504 -133.513576) (xy 298.799994 -133.483608) (xy 298.807817 -133.424186) (xy 298.82333 -133.366293)
			(xy 298.846266 -133.31092) (xy 298.876233 -133.259014) (xy 298.91272 -133.211464) (xy 298.9551 -133.169084)
			(xy 299.00265 -133.132597) (xy 299.054556 -133.10263) (xy 299.109929 -133.079694) (xy 299.167822 -133.064181)
			(xy 299.227244 -133.056358) (xy 299.28718 -133.056358) (xy 299.346602 -133.064181) (xy 299.404495 -133.079694)
			(xy 299.459868 -133.10263) (xy 299.511774 -133.132597) (xy 299.559324 -133.169084) (xy 299.601704 -133.211464)
			(xy 299.638191 -133.259014) (xy 299.668158 -133.31092) (xy 299.691094 -133.366293) (xy 299.706607 -133.424186)
			(xy 299.71443 -133.483608) (xy 299.71492 -133.513576) (xy 299.71492 -134.377176) (xy 299.71443 -134.407144)
			(xy 299.709012 -134.448296) (xy 300.247304 -134.448296) (xy 300.247304 -133.441948) (xy 300.247755 -133.431828)
			(xy 300.255489 -133.413125) (xy 300.269795 -133.398809) (xy 300.288492 -133.391063) (xy 300.298612 -133.39064)
			(xy 301.479712 -133.39064) (xy 301.48984 -133.391007) (xy 301.508552 -133.398766) (xy 301.522867 -133.413099)
			(xy 301.530605 -133.431819) (xy 301.53102 -133.441948) (xy 301.53102 -134.448296) (xy 304.783744 -134.448296)
			(xy 304.783744 -133.441948) (xy 304.78426 -133.431804) (xy 304.792029 -133.413063) (xy 304.806396 -133.39874)
			(xy 304.825161 -133.391029) (xy 304.835306 -133.39064) (xy 306.016406 -133.39064) (xy 306.026533 -133.391122)
			(xy 306.045254 -133.398852) (xy 306.05961 -133.413139) (xy 306.067429 -133.431823) (xy 306.067968 -133.441948)
			(xy 306.067968 -134.448296) (xy 306.067574 -134.458454) (xy 306.059774 -134.477212) (xy 306.045368 -134.491537)
			(xy 306.026566 -134.499231) (xy 306.016406 -134.499604) (xy 304.835306 -134.499604) (xy 304.825185 -134.49907)
			(xy 304.806472 -134.491352) (xy 304.792117 -134.477081) (xy 304.78429 -134.458414) (xy 304.783744 -134.448296)
			(xy 301.53102 -134.448296) (xy 301.530512 -134.458402) (xy 301.522779 -134.477076) (xy 301.50849 -134.49137)
			(xy 301.489818 -134.499109) (xy 301.479712 -134.499604) (xy 300.298612 -134.499604) (xy 300.288491 -134.499174)
			(xy 300.269788 -134.491431) (xy 300.255474 -134.477119) (xy 300.247727 -134.458417) (xy 300.247304 -134.448296)
			(xy 299.709012 -134.448296) (xy 299.706607 -134.466566) (xy 299.691094 -134.524459) (xy 299.68687 -134.534656)
			(xy 311.799224 -134.534656) (xy 311.799224 -134.307072) (xy 311.799478 -134.303008) (xy 311.799732 -134.300468)
			(xy 311.799732 -134.291832) (xy 311.80532 -134.283196) (xy 311.80659 -134.281164) (xy 311.807606 -134.279132)
			(xy 312.004964 -133.978142) (xy 312.00883 -133.971813) (xy 312.013091 -133.957614) (xy 312.013346 -133.950202)
			(xy 312.013346 -133.924548) (xy 312.01314 -133.917214) (xy 312.00901 -133.903143) (xy 312.005218 -133.896862)
			(xy 311.807352 -133.59384) (xy 311.805066 -133.59003) (xy 311.804812 -133.589522) (xy 311.803796 -133.587744)
			(xy 311.799732 -133.58114) (xy 311.799732 -133.573012) (xy 311.799478 -133.570472) (xy 311.799224 -133.566408)
			(xy 311.799224 -133.338316) (xy 311.799626 -133.32809) (xy 311.807452 -133.309196) (xy 311.821916 -133.294738)
			(xy 311.840814 -133.286921) (xy 311.85104 -133.2865) (xy 312.58764 -133.2865) (xy 312.597852 -133.286949)
			(xy 312.616718 -133.294778) (xy 312.631153 -133.309229) (xy 312.638962 -133.328103) (xy 312.639456 -133.338316)
			(xy 312.639456 -133.5659) (xy 312.639202 -133.569964) (xy 312.638948 -133.572504) (xy 312.638948 -133.58114)
			(xy 312.633106 -133.590538) (xy 312.632344 -133.591808) (xy 312.631074 -133.59384) (xy 312.425334 -133.908546)
			(xy 312.420295 -133.917074) (xy 312.416477 -133.936488) (xy 312.420286 -133.955905) (xy 312.425334 -133.964426)
			(xy 312.631074 -134.277862) (xy 312.63209 -134.279894) (xy 312.63336 -134.281926) (xy 312.638948 -134.290562)
			(xy 312.638948 -134.299198) (xy 312.639202 -134.301738) (xy 312.639456 -134.305802) (xy 312.639456 -134.369302)
			(xy 313.274456 -134.369302) (xy 313.274456 -133.505702) (xy 313.274946 -133.475734) (xy 313.282769 -133.416312)
			(xy 313.298282 -133.358419) (xy 313.321218 -133.303046) (xy 313.351185 -133.25114) (xy 313.387672 -133.20359)
			(xy 313.430052 -133.16121) (xy 313.477602 -133.124723) (xy 313.529508 -133.094756) (xy 313.584881 -133.07182)
			(xy 313.642774 -133.056307) (xy 313.702196 -133.048484) (xy 313.762132 -133.048484) (xy 313.821554 -133.056307)
			(xy 313.879447 -133.07182) (xy 313.93482 -133.094756) (xy 313.951493 -133.104382) (xy 385.6101 -133.104382)
			(xy 385.6101 -132.240782) (xy 385.61059 -132.210814) (xy 385.618413 -132.151392) (xy 385.633926 -132.093499)
			(xy 385.656862 -132.038126) (xy 385.686829 -131.98622) (xy 385.723316 -131.93867) (xy 385.765696 -131.89629)
			(xy 385.813246 -131.859803) (xy 385.865152 -131.829836) (xy 385.920525 -131.8069) (xy 385.978418 -131.791387)
			(xy 386.03784 -131.783564) (xy 386.097776 -131.783564) (xy 386.157198 -131.791387) (xy 386.215091 -131.8069)
			(xy 386.270464 -131.829836) (xy 386.32237 -131.859803) (xy 386.36992 -131.89629) (xy 386.4123 -131.93867)
			(xy 386.448787 -131.98622) (xy 386.478754 -132.038126) (xy 386.50169 -132.093499) (xy 386.517203 -132.151392)
			(xy 386.525026 -132.210814) (xy 386.525516 -132.240782) (xy 386.525516 -133.104382) (xy 386.525026 -133.13435)
			(xy 386.517203 -133.193772) (xy 386.50169 -133.251665) (xy 386.494205 -133.269736) (xy 387.160516 -133.269736)
			(xy 387.160516 -133.042152) (xy 387.16077 -133.038088) (xy 387.161024 -133.035548) (xy 387.161024 -133.026912)
			(xy 387.166612 -133.018276) (xy 387.167882 -133.016244) (xy 387.168898 -133.014212) (xy 387.366256 -132.713222)
			(xy 387.370129 -132.706896) (xy 387.374386 -132.692695) (xy 387.374638 -132.685282) (xy 387.374638 -132.659628)
			(xy 387.374441 -132.652293) (xy 387.370305 -132.638222) (xy 387.36651 -132.631942) (xy 387.168644 -132.32892)
			(xy 387.166358 -132.32511) (xy 387.166104 -132.324602) (xy 387.165088 -132.322824) (xy 387.161024 -132.31622)
			(xy 387.161024 -132.308092) (xy 387.16077 -132.305552) (xy 387.160516 -132.301488) (xy 387.160516 -132.073396)
			(xy 387.160909 -132.06317) (xy 387.16874 -132.044276) (xy 387.183207 -132.02982) (xy 387.202106 -132.022002)
			(xy 387.212332 -132.02158) (xy 387.948932 -132.02158) (xy 387.959141 -132.022055) (xy 387.978003 -132.029878)
			(xy 387.992438 -132.044321) (xy 388.00025 -132.063186) (xy 388.000748 -132.073396) (xy 388.000748 -132.30098)
			(xy 388.000494 -132.305044) (xy 388.00024 -132.307584) (xy 388.00024 -132.31622) (xy 387.994398 -132.325618)
			(xy 387.993636 -132.326888) (xy 387.992366 -132.32892) (xy 387.786626 -132.643626) (xy 387.781597 -132.65216)
			(xy 387.777765 -132.671571) (xy 387.781575 -132.690987) (xy 387.786626 -132.699506) (xy 387.992366 -133.012942)
			(xy 387.993382 -133.014974) (xy 387.994652 -133.017006) (xy 388.00024 -133.025642) (xy 388.00024 -133.034278)
			(xy 388.000494 -133.036818) (xy 388.000748 -133.040882) (xy 388.000748 -133.16839) (xy 393.732004 -133.16839)
			(xy 393.732004 -132.162042) (xy 393.732497 -132.151877) (xy 393.740262 -132.13309) (xy 393.754626 -132.118705)
			(xy 393.773402 -132.110912) (xy 393.783566 -132.11048) (xy 394.964666 -132.11048) (xy 394.974841 -132.110893)
			(xy 394.993643 -132.118674) (xy 395.00803 -132.133064) (xy 395.015809 -132.151867) (xy 395.016228 -132.162042)
			(xy 395.016228 -133.16839) (xy 395.016218 -133.168644) (xy 398.268952 -133.168644) (xy 398.268952 -132.162042)
			(xy 398.269461 -132.151917) (xy 398.277178 -132.133194) (xy 398.291457 -132.118836) (xy 398.310137 -132.111017)
			(xy 398.32026 -132.11048) (xy 399.50136 -132.11048) (xy 399.511477 -132.110948) (xy 399.530176 -132.11868)
			(xy 399.544491 -132.13298) (xy 399.552241 -132.151671) (xy 399.552668 -132.161788) (xy 399.552668 -133.096508)
			(xy 400.085052 -133.096508) (xy 400.085052 -132.232908) (xy 400.085542 -132.20294) (xy 400.093365 -132.143518)
			(xy 400.108878 -132.085625) (xy 400.131814 -132.030252) (xy 400.161781 -131.978346) (xy 400.198268 -131.930796)
			(xy 400.240648 -131.888416) (xy 400.288198 -131.851929) (xy 400.340104 -131.821962) (xy 400.395477 -131.799026)
			(xy 400.45337 -131.783513) (xy 400.512792 -131.77569) (xy 400.572728 -131.77569) (xy 400.63215 -131.783513)
			(xy 400.690043 -131.799026) (xy 400.745416 -131.821962) (xy 400.797322 -131.851929) (xy 400.844872 -131.888416)
			(xy 400.887252 -131.930796) (xy 400.923739 -131.978346) (xy 400.953706 -132.030252) (xy 400.976642 -132.085625)
			(xy 400.992155 -132.143518) (xy 400.999978 -132.20294) (xy 401.000468 -132.232908) (xy 401.000468 -132.577332)
			(xy 413.045148 -132.577332) (xy 413.045148 -131.713732) (xy 413.045638 -131.683748) (xy 413.053466 -131.624292)
			(xy 413.068987 -131.566367) (xy 413.091936 -131.510963) (xy 413.12192 -131.459029) (xy 413.158426 -131.411453)
			(xy 413.200831 -131.369048) (xy 413.248407 -131.332542) (xy 413.300341 -131.302558) (xy 413.355745 -131.279609)
			(xy 413.41367 -131.264088) (xy 413.473126 -131.25626) (xy 413.533094 -131.25626) (xy 413.59255 -131.264088)
			(xy 413.650475 -131.279609) (xy 413.705879 -131.302558) (xy 413.757813 -131.332542) (xy 413.805389 -131.369048)
			(xy 413.847794 -131.411453) (xy 413.8843 -131.459029) (xy 413.914284 -131.510963) (xy 413.937233 -131.566367)
			(xy 413.952754 -131.624292) (xy 413.960582 -131.683748) (xy 413.961072 -131.713732) (xy 413.961072 -132.577332)
			(xy 413.960582 -132.607316) (xy 413.955199 -132.648198) (xy 416.347148 -132.648198) (xy 416.347148 -131.64185)
			(xy 416.347605 -131.63168) (xy 416.355375 -131.612885) (xy 416.369751 -131.598498) (xy 416.388541 -131.590713)
			(xy 416.39871 -131.590288) (xy 417.57981 -131.590288) (xy 417.589988 -131.590657) (xy 417.608793 -131.598455)
			(xy 417.623179 -131.612858) (xy 417.630955 -131.631671) (xy 417.631372 -131.64185) (xy 417.631372 -132.648198)
			(xy 420.884096 -132.648198) (xy 420.884096 -131.64185) (xy 420.884666 -131.631732) (xy 420.89237 -131.61302)
			(xy 420.90663 -131.598664) (xy 420.925289 -131.590835) (xy 420.935404 -131.590288) (xy 422.116504 -131.590288)
			(xy 422.126657 -131.590718) (xy 422.145407 -131.598513) (xy 422.15973 -131.612907) (xy 422.167431 -131.631695)
			(xy 422.167812 -131.64185) (xy 422.167812 -132.648198) (xy 422.167273 -132.658318) (xy 422.159556 -132.677029)
			(xy 422.145286 -132.691384) (xy 422.126621 -132.699212) (xy 422.116504 -132.69976) (xy 420.935404 -132.69976)
			(xy 420.925245 -132.699374) (xy 420.906485 -132.691573) (xy 420.89216 -132.677164) (xy 420.884468 -132.658359)
			(xy 420.884096 -132.648198) (xy 417.631372 -132.648198) (xy 417.630865 -132.658354) (xy 417.623093 -132.677122)
			(xy 417.608732 -132.691487) (xy 417.589966 -132.699263) (xy 417.57981 -132.69976) (xy 416.39871 -132.69976)
			(xy 416.388539 -132.699328) (xy 416.369744 -132.691546) (xy 416.355359 -132.677163) (xy 416.347574 -132.658369)
			(xy 416.347148 -132.648198) (xy 413.955199 -132.648198) (xy 413.952754 -132.666772) (xy 413.937233 -132.724697)
			(xy 413.930413 -132.741162) (xy 430.541684 -132.741162) (xy 430.541684 -132.498338) (xy 430.660556 -132.316982)
			(xy 430.72304 -132.221478) (xy 430.74717 -132.184648) (xy 430.751034 -132.178318) (xy 430.755296 -132.16412)
			(xy 430.755552 -132.156708) (xy 430.755552 -132.1308) (xy 430.755361 -132.12465) (xy 430.752406 -132.112709)
			(xy 430.74971 -132.107178) (xy 430.636172 -131.933188) (xy 430.616106 -131.9022) (xy 430.610518 -131.893564)
			(xy 430.550066 -131.800854) (xy 430.549558 -131.800092) (xy 430.54905 -131.79933) (xy 430.548796 -131.798822)
			(xy 430.548288 -131.79806) (xy 430.541684 -131.787646) (xy 430.541684 -131.544822) (xy 430.542083 -131.534646)
			(xy 430.549869 -131.515843) (xy 430.564263 -131.501456) (xy 430.58307 -131.493678) (xy 430.593246 -131.49326)
			(xy 431.329846 -131.49326) (xy 431.340009 -131.493696) (xy 431.358784 -131.50149) (xy 431.373148 -131.515873)
			(xy 431.380917 -131.534658) (xy 431.381408 -131.544822) (xy 431.381408 -131.787646) (xy 431.165508 -132.1181)
			(xy 431.161464 -132.126312) (xy 431.158927 -132.144428) (xy 431.162882 -132.162289) (xy 431.16754 -132.17017)
			(xy 431.199798 -132.219954) (xy 431.381408 -132.497068) (xy 431.381408 -132.575808) (xy 432.016408 -132.575808)
			(xy 432.016408 -131.712208) (xy 432.016898 -131.682224) (xy 432.024726 -131.622768) (xy 432.040247 -131.564843)
			(xy 432.063196 -131.509439) (xy 432.09318 -131.457505) (xy 432.129686 -131.409929) (xy 432.172091 -131.367524)
			(xy 432.219667 -131.331018) (xy 432.271601 -131.301034) (xy 432.327005 -131.278085) (xy 432.38493 -131.262564)
			(xy 432.444386 -131.254736) (xy 432.504354 -131.254736) (xy 432.56381 -131.262564) (xy 432.621735 -131.278085)
			(xy 432.677139 -131.301034) (xy 432.729073 -131.331018) (xy 432.776649 -131.367524) (xy 432.819054 -131.409929)
			(xy 432.85556 -131.457505) (xy 432.885544 -131.509439) (xy 432.908493 -131.564843) (xy 432.924014 -131.622768)
			(xy 432.931842 -131.682224) (xy 432.932332 -131.712208) (xy 432.932332 -132.575808) (xy 432.931842 -132.605792)
			(xy 432.924014 -132.665248) (xy 432.908493 -132.723173) (xy 432.885544 -132.778577) (xy 432.85556 -132.830511)
			(xy 432.819054 -132.878087) (xy 432.776649 -132.920492) (xy 432.729073 -132.956998) (xy 432.677139 -132.986982)
			(xy 432.621735 -133.009931) (xy 432.56381 -133.025452) (xy 432.504354 -133.03328) (xy 432.444386 -133.03328)
			(xy 432.38493 -133.025452) (xy 432.327005 -133.009931) (xy 432.271601 -132.986982) (xy 432.219667 -132.956998)
			(xy 432.172091 -132.920492) (xy 432.129686 -132.878087) (xy 432.09318 -132.830511) (xy 432.063196 -132.778577)
			(xy 432.040247 -132.723173) (xy 432.024726 -132.665248) (xy 432.016898 -132.605792) (xy 432.016408 -132.575808)
			(xy 431.381408 -132.575808) (xy 431.381408 -132.741162) (xy 431.380836 -132.751312) (xy 431.373083 -132.770071)
			(xy 431.358742 -132.784436) (xy 431.339995 -132.79222) (xy 431.329846 -132.792724) (xy 430.593246 -132.792724)
			(xy 430.583073 -132.792298) (xy 430.564272 -132.784521) (xy 430.549884 -132.770135) (xy 430.542104 -132.751335)
			(xy 430.541684 -132.741162) (xy 413.930413 -132.741162) (xy 413.914284 -132.780101) (xy 413.8843 -132.832035)
			(xy 413.847794 -132.879611) (xy 413.805389 -132.922016) (xy 413.757813 -132.958522) (xy 413.705879 -132.988506)
			(xy 413.650475 -133.011455) (xy 413.59255 -133.026976) (xy 413.533094 -133.034804) (xy 413.473126 -133.034804)
			(xy 413.41367 -133.026976) (xy 413.355745 -133.011455) (xy 413.300341 -132.988506) (xy 413.248407 -132.958522)
			(xy 413.200831 -132.922016) (xy 413.158426 -132.879611) (xy 413.12192 -132.832035) (xy 413.091936 -132.780101)
			(xy 413.068987 -132.724697) (xy 413.053466 -132.666772) (xy 413.045638 -132.607316) (xy 413.045148 -132.577332)
			(xy 401.000468 -132.577332) (xy 401.000468 -133.096508) (xy 400.999978 -133.126476) (xy 400.992155 -133.185898)
			(xy 400.976642 -133.243791) (xy 400.953706 -133.299164) (xy 400.923739 -133.35107) (xy 400.887252 -133.39862)
			(xy 400.844872 -133.441) (xy 400.797322 -133.477487) (xy 400.745416 -133.507454) (xy 400.690043 -133.53039)
			(xy 400.63215 -133.545903) (xy 400.572728 -133.553726) (xy 400.512792 -133.553726) (xy 400.45337 -133.545903)
			(xy 400.395477 -133.53039) (xy 400.340104 -133.507454) (xy 400.288198 -133.477487) (xy 400.240648 -133.441)
			(xy 400.198268 -133.39862) (xy 400.161781 -133.35107) (xy 400.131814 -133.299164) (xy 400.108878 -133.243791)
			(xy 400.093365 -133.185898) (xy 400.085542 -133.126476) (xy 400.085052 -133.096508) (xy 399.552668 -133.096508)
			(xy 399.552668 -133.16839) (xy 399.552165 -133.178515) (xy 399.544442 -133.197235) (xy 399.530161 -133.211591)
			(xy 399.511482 -133.219412) (xy 399.50136 -133.219952) (xy 398.32026 -133.219952) (xy 398.310155 -133.219449)
			(xy 398.291486 -133.211708) (xy 398.277194 -133.197417) (xy 398.269452 -133.178749) (xy 398.268952 -133.168644)
			(xy 395.016218 -133.168644) (xy 395.015827 -133.178565) (xy 395.008039 -133.197366) (xy 394.993646 -133.211753)
			(xy 394.974841 -133.219532) (xy 394.964666 -133.219952) (xy 393.783566 -133.219952) (xy 393.773405 -133.219494)
			(xy 393.754633 -133.211707) (xy 393.740269 -133.19733) (xy 393.732497 -133.178552) (xy 393.732004 -133.16839)
			(xy 388.000748 -133.16839) (xy 388.000748 -133.269736) (xy 388.000249 -133.279942) (xy 387.99243 -133.298798)
			(xy 387.977995 -133.313232) (xy 387.959138 -133.321049) (xy 387.948932 -133.321552) (xy 387.212332 -133.321552)
			(xy 387.202131 -133.320993) (xy 387.183277 -133.313198) (xy 387.168841 -133.298781) (xy 387.16102 -133.279937)
			(xy 387.160516 -133.269736) (xy 386.494205 -133.269736) (xy 386.478754 -133.307038) (xy 386.448787 -133.358944)
			(xy 386.4123 -133.406494) (xy 386.36992 -133.448874) (xy 386.32237 -133.485361) (xy 386.270464 -133.515328)
			(xy 386.215091 -133.538264) (xy 386.157198 -133.553777) (xy 386.097776 -133.5616) (xy 386.03784 -133.5616)
			(xy 385.978418 -133.553777) (xy 385.920525 -133.538264) (xy 385.865152 -133.515328) (xy 385.813246 -133.485361)
			(xy 385.765696 -133.448874) (xy 385.723316 -133.406494) (xy 385.686829 -133.358944) (xy 385.656862 -133.307038)
			(xy 385.633926 -133.251665) (xy 385.618413 -133.193772) (xy 385.61059 -133.13435) (xy 385.6101 -133.104382)
			(xy 313.951493 -133.104382) (xy 313.986726 -133.124723) (xy 314.034276 -133.16121) (xy 314.076656 -133.20359)
			(xy 314.113143 -133.25114) (xy 314.14311 -133.303046) (xy 314.166046 -133.358419) (xy 314.181559 -133.416312)
			(xy 314.189382 -133.475734) (xy 314.189872 -133.505702) (xy 314.189872 -134.369302) (xy 314.189382 -134.39927)
			(xy 314.181559 -134.458692) (xy 314.166046 -134.516585) (xy 314.14311 -134.571958) (xy 314.113143 -134.623864)
			(xy 314.076656 -134.671414) (xy 314.034276 -134.713794) (xy 313.986726 -134.750281) (xy 313.93482 -134.780248)
			(xy 313.879447 -134.803184) (xy 313.821554 -134.818697) (xy 313.762132 -134.82652) (xy 313.702196 -134.82652)
			(xy 313.642774 -134.818697) (xy 313.584881 -134.803184) (xy 313.529508 -134.780248) (xy 313.477602 -134.750281)
			(xy 313.430052 -134.713794) (xy 313.387672 -134.671414) (xy 313.351185 -134.623864) (xy 313.321218 -134.571958)
			(xy 313.298282 -134.516585) (xy 313.282769 -134.458692) (xy 313.274946 -134.39927) (xy 313.274456 -134.369302)
			(xy 312.639456 -134.369302) (xy 312.639456 -134.534656) (xy 312.638953 -134.54487) (xy 312.631152 -134.563749)
			(xy 312.616719 -134.578205) (xy 312.597853 -134.586037) (xy 312.58764 -134.586472) (xy 311.85104 -134.586472)
			(xy 311.840815 -134.586054) (xy 311.821921 -134.578236) (xy 311.807462 -134.563776) (xy 311.799645 -134.544881)
			(xy 311.799224 -134.534656) (xy 299.68687 -134.534656) (xy 299.668158 -134.579832) (xy 299.638191 -134.631738)
			(xy 299.601704 -134.679288) (xy 299.559324 -134.721668) (xy 299.511774 -134.758155) (xy 299.459868 -134.788122)
			(xy 299.404495 -134.811058) (xy 299.346602 -134.826571) (xy 299.28718 -134.834394) (xy 299.227244 -134.834394)
			(xy 299.167822 -134.826571) (xy 299.109929 -134.811058) (xy 299.054556 -134.788122) (xy 299.00265 -134.758155)
			(xy 298.9551 -134.721668) (xy 298.91272 -134.679288) (xy 298.876233 -134.631738) (xy 298.846266 -134.579832)
			(xy 298.82333 -134.524459) (xy 298.807817 -134.466566) (xy 298.799994 -134.407144) (xy 298.799504 -134.377176)
			(xy 286.754824 -134.377176) (xy 286.754824 -134.896352) (xy 286.754334 -134.926336) (xy 286.746506 -134.985792)
			(xy 286.730985 -135.043717) (xy 286.708036 -135.099121) (xy 286.678052 -135.151055) (xy 286.641546 -135.198631)
			(xy 286.599141 -135.241036) (xy 286.551565 -135.277542) (xy 286.499631 -135.307526) (xy 286.444227 -135.330475)
			(xy 286.386302 -135.345996) (xy 286.326846 -135.353824) (xy 286.266878 -135.353824) (xy 286.207422 -135.345996)
			(xy 286.149497 -135.330475) (xy 286.094093 -135.307526) (xy 286.042159 -135.277542) (xy 285.994583 -135.241036)
			(xy 285.952178 -135.198631) (xy 285.915672 -135.151055) (xy 285.885688 -135.099121) (xy 285.862739 -135.043717)
			(xy 285.847218 -134.985792) (xy 285.83939 -134.926336) (xy 285.8389 -134.896352) (xy 283.452824 -134.896352)
			(xy 283.452824 -134.968488) (xy 283.452306 -134.978593) (xy 283.444576 -134.997266) (xy 283.43029 -135.011561)
			(xy 283.411621 -135.0193) (xy 283.401516 -135.019796) (xy 282.220162 -135.019796) (xy 282.210037 -135.019306)
			(xy 282.191322 -135.011572) (xy 282.176968 -134.997288) (xy 282.169144 -134.97861) (xy 282.1686 -134.968488)
			(xy 278.915876 -134.968488) (xy 278.915474 -134.978613) (xy 278.907725 -134.997321) (xy 278.893404 -135.011636)
			(xy 278.874693 -135.019378) (xy 278.864568 -135.019796) (xy 277.683468 -135.019796) (xy 277.673357 -135.019341)
			(xy 277.654677 -135.011592) (xy 277.640383 -134.997286) (xy 277.63265 -134.9786) (xy 277.63216 -134.968488)
			(xy 269.258288 -134.968488) (xy 269.258288 -135.06323) (xy 269.257792 -135.073386) (xy 269.250012 -135.092151)
			(xy 269.235648 -135.106515) (xy 269.216883 -135.114293) (xy 269.206726 -135.114792) (xy 268.470126 -135.114792)
			(xy 268.459974 -135.114246) (xy 268.441211 -135.106486) (xy 268.426845 -135.092136) (xy 268.419065 -135.073382)
			(xy 268.418564 -135.06323) (xy 267.752274 -135.06323) (xy 267.736776 -135.100645) (xy 267.706792 -135.152579)
			(xy 267.670286 -135.200155) (xy 267.627881 -135.24256) (xy 267.580305 -135.279066) (xy 267.528371 -135.30905)
			(xy 267.472967 -135.331999) (xy 267.415042 -135.34752) (xy 267.355586 -135.355348) (xy 267.295618 -135.355348)
			(xy 267.236162 -135.34752) (xy 267.178237 -135.331999) (xy 267.122833 -135.30905) (xy 267.070899 -135.279066)
			(xy 267.023323 -135.24256) (xy 266.980918 -135.200155) (xy 266.944412 -135.152579) (xy 266.914428 -135.100645)
			(xy 266.891479 -135.045241) (xy 266.875958 -134.987316) (xy 266.86813 -134.92786) (xy 266.86764 -134.897876)
			(xy 200.469049 -134.897876) (xy 200.477084 -134.901204) (xy 200.52899 -134.931171) (xy 200.57654 -134.967658)
			(xy 200.61892 -135.010038) (xy 200.655407 -135.057588) (xy 200.685374 -135.109494) (xy 200.70831 -135.164867)
			(xy 200.723823 -135.22276) (xy 200.731646 -135.282182) (xy 200.732136 -135.31215) (xy 200.732136 -136.17575)
			(xy 200.731646 -136.205718) (xy 200.723823 -136.26514) (xy 200.70831 -136.323033) (xy 200.685374 -136.378406)
			(xy 200.655407 -136.430312) (xy 200.61892 -136.477862) (xy 200.57654 -136.520242) (xy 200.52899 -136.556729)
			(xy 200.477084 -136.586696) (xy 200.421711 -136.609632) (xy 200.363818 -136.625145) (xy 200.304396 -136.632968)
			(xy 200.24446 -136.632968) (xy 200.185038 -136.625145) (xy 200.127145 -136.609632) (xy 200.071772 -136.586696)
			(xy 200.019866 -136.556729) (xy 199.972316 -136.520242) (xy 199.929936 -136.477862) (xy 199.893449 -136.430312)
			(xy 199.863482 -136.378406) (xy 199.840546 -136.323033) (xy 199.825033 -136.26514) (xy 199.81721 -136.205718)
			(xy 199.81672 -136.17575) (xy 199.181212 -136.17575) (xy 199.181212 -136.341104) (xy 199.180597 -136.352626)
			(xy 199.170722 -136.373448) (xy 199.15288 -136.388032) (xy 199.141842 -136.391396) (xy 199.141588 -136.391396)
			(xy 199.12965 -136.39292) (xy 198.39305 -136.39292) (xy 198.386676 -136.392707) (xy 198.374339 -136.389486)
			(xy 198.368666 -136.38657) (xy 198.360641 -136.38185) (xy 198.348409 -136.36783) (xy 198.341877 -136.350407)
			(xy 198.341488 -136.341104) (xy 181.730196 -136.341104) (xy 181.714114 -136.37993) (xy 181.684147 -136.431836)
			(xy 181.64766 -136.479386) (xy 181.60528 -136.521766) (xy 181.55773 -136.558253) (xy 181.505824 -136.58822)
			(xy 181.450451 -136.611156) (xy 181.392558 -136.626669) (xy 181.333136 -136.634492) (xy 181.2732 -136.634492)
			(xy 181.213778 -136.626669) (xy 181.155885 -136.611156) (xy 181.100512 -136.58822) (xy 181.048606 -136.558253)
			(xy 181.001056 -136.521766) (xy 180.958676 -136.479386) (xy 180.922189 -136.431836) (xy 180.892222 -136.37993)
			(xy 180.869286 -136.324557) (xy 180.853773 -136.266664) (xy 180.84595 -136.207242) (xy 180.84546 -136.177274)
			(xy 168.80078 -136.177274) (xy 168.80078 -136.69645) (xy 168.800651 -136.704324) (xy 269.509748 -136.704324)
			(xy 269.509748 -135.840724) (xy 269.510238 -135.81074) (xy 269.518066 -135.751284) (xy 269.533587 -135.693359)
			(xy 269.556536 -135.637955) (xy 269.58652 -135.586021) (xy 269.623026 -135.538445) (xy 269.665431 -135.49604)
			(xy 269.713007 -135.459534) (xy 269.764941 -135.42955) (xy 269.820345 -135.406601) (xy 269.87827 -135.39108)
			(xy 269.937726 -135.383252) (xy 269.997694 -135.383252) (xy 270.05715 -135.39108) (xy 270.115075 -135.406601)
			(xy 270.170479 -135.42955) (xy 270.222413 -135.459534) (xy 270.269989 -135.49604) (xy 270.312394 -135.538445)
			(xy 270.3489 -135.586021) (xy 270.378884 -135.637955) (xy 270.401833 -135.693359) (xy 270.417354 -135.751284)
			(xy 270.425182 -135.81074) (xy 270.425672 -135.840724) (xy 270.425672 -136.704324) (xy 270.425182 -136.734308)
			(xy 270.417354 -136.793764) (xy 270.401833 -136.851689) (xy 270.394382 -136.869678) (xy 271.060672 -136.869678)
			(xy 271.060672 -136.626854) (xy 271.179544 -136.445498) (xy 271.242028 -136.349994) (xy 271.266158 -136.313164)
			(xy 271.270015 -136.30683) (xy 271.274282 -136.292635) (xy 271.27454 -136.285224) (xy 271.27454 -136.259316)
			(xy 271.274344 -136.253166) (xy 271.271393 -136.241225) (xy 271.268698 -136.235694) (xy 271.15516 -136.061704)
			(xy 271.135094 -136.030716) (xy 271.129506 -136.02208) (xy 271.069054 -135.92937) (xy 271.068546 -135.928608)
			(xy 271.068038 -135.927846) (xy 271.067784 -135.927338) (xy 271.067276 -135.926576) (xy 271.060672 -135.916162)
			(xy 271.060672 -135.673338) (xy 271.061096 -135.663165) (xy 271.068875 -135.644364) (xy 271.083261 -135.629977)
			(xy 271.102061 -135.622197) (xy 271.112234 -135.621776) (xy 271.848834 -135.621776) (xy 271.859013 -135.622137)
			(xy 271.877815 -135.62994) (xy 271.8922 -135.644345) (xy 271.899977 -135.663159) (xy 271.900396 -135.673338)
			(xy 271.900396 -135.916162) (xy 271.684496 -136.246616) (xy 271.680441 -136.254823) (xy 271.677909 -136.272943)
			(xy 271.681868 -136.290805) (xy 271.686528 -136.298686) (xy 271.718786 -136.34847) (xy 271.900396 -136.625584)
			(xy 271.900396 -136.768332) (xy 277.63216 -136.768332) (xy 277.63216 -135.761984) (xy 277.632671 -135.751879)
			(xy 277.640407 -135.733208) (xy 277.654695 -135.718916) (xy 277.673363 -135.711174) (xy 277.683468 -135.710676)
			(xy 278.864568 -135.710676) (xy 278.874686 -135.711141) (xy 278.893384 -135.718875) (xy 278.907699 -135.733176)
			(xy 278.915449 -135.751867) (xy 278.915876 -135.761984) (xy 278.915876 -136.768332) (xy 282.1686 -136.768332)
			(xy 282.1686 -135.761984) (xy 282.169072 -135.751874) (xy 282.176815 -135.733196) (xy 282.191116 -135.718902)
			(xy 282.209798 -135.711168) (xy 282.219908 -135.710676) (xy 283.401262 -135.710676) (xy 283.411391 -135.711159)
			(xy 283.430118 -135.718881) (xy 283.444477 -135.733169) (xy 283.452291 -135.751858) (xy 283.452824 -135.761984)
			(xy 283.452824 -136.69645) (xy 283.9847 -136.69645) (xy 283.9847 -135.83285) (xy 283.98519 -135.802866)
			(xy 283.993018 -135.74341) (xy 284.008539 -135.685485) (xy 284.031488 -135.630081) (xy 284.061472 -135.578147)
			(xy 284.097978 -135.530571) (xy 284.140383 -135.488166) (xy 284.187959 -135.45166) (xy 284.239893 -135.421676)
			(xy 284.295297 -135.398727) (xy 284.353222 -135.383206) (xy 284.412678 -135.375378) (xy 284.472646 -135.375378)
			(xy 284.532102 -135.383206) (xy 284.590027 -135.398727) (xy 284.645431 -135.421676) (xy 284.697365 -135.45166)
			(xy 284.744941 -135.488166) (xy 284.787346 -135.530571) (xy 284.823852 -135.578147) (xy 284.853836 -135.630081)
			(xy 284.876785 -135.685485) (xy 284.892306 -135.74341) (xy 284.900134 -135.802866) (xy 284.900624 -135.83285)
			(xy 284.900624 -136.177274) (xy 296.945304 -136.177274) (xy 296.945304 -135.313674) (xy 296.945794 -135.283706)
			(xy 296.953617 -135.224284) (xy 296.96913 -135.166391) (xy 296.992066 -135.111018) (xy 297.022033 -135.059112)
			(xy 297.05852 -135.011562) (xy 297.1009 -134.969182) (xy 297.14845 -134.932695) (xy 297.200356 -134.902728)
			(xy 297.255729 -134.879792) (xy 297.313622 -134.864279) (xy 297.373044 -134.856456) (xy 297.43298 -134.856456)
			(xy 297.492402 -134.864279) (xy 297.550295 -134.879792) (xy 297.605668 -134.902728) (xy 297.657574 -134.932695)
			(xy 297.705124 -134.969182) (xy 297.747504 -135.011562) (xy 297.783991 -135.059112) (xy 297.813958 -135.111018)
			(xy 297.836894 -135.166391) (xy 297.852407 -135.224284) (xy 297.86023 -135.283706) (xy 297.86072 -135.313674)
			(xy 297.86072 -136.177274) (xy 297.86023 -136.207242) (xy 297.854846 -136.24814) (xy 300.247304 -136.24814)
			(xy 300.247304 -135.241792) (xy 300.24771 -135.231669) (xy 300.255461 -135.212964) (xy 300.269781 -135.19865)
			(xy 300.288488 -135.190906) (xy 300.298612 -135.190484) (xy 301.479712 -135.190484) (xy 301.489819 -135.190975)
			(xy 301.508495 -135.198714) (xy 301.522789 -135.213009) (xy 301.530526 -135.231684) (xy 301.53102 -135.241792)
			(xy 301.53102 -136.24814) (xy 304.783744 -136.24814) (xy 304.783744 -135.241792) (xy 304.784214 -135.231644)
			(xy 304.792002 -135.212903) (xy 304.806383 -135.198582) (xy 304.825157 -135.190872) (xy 304.835306 -135.190484)
			(xy 306.016406 -135.190484) (xy 306.026538 -135.190923) (xy 306.045268 -135.198661) (xy 306.059626 -135.212962)
			(xy 306.067437 -135.231662) (xy 306.067968 -135.241792) (xy 306.067968 -136.24814) (xy 306.06761 -136.258301)
			(xy 306.059796 -136.27706) (xy 306.045379 -136.291383) (xy 306.026569 -136.299076) (xy 306.016406 -136.299448)
			(xy 304.835306 -136.299448) (xy 304.825178 -136.298968) (xy 304.806455 -136.29124) (xy 304.792098 -136.276952)
			(xy 304.784281 -136.258265) (xy 304.783744 -136.24814) (xy 301.53102 -136.24814) (xy 301.530548 -136.258249)
			(xy 301.522801 -136.276924) (xy 301.508501 -136.291217) (xy 301.489821 -136.298954) (xy 301.479712 -136.299448)
			(xy 300.298612 -136.299448) (xy 300.28851 -136.298906) (xy 300.269841 -136.291182) (xy 300.255548 -136.276902)
			(xy 300.247804 -136.258242) (xy 300.247304 -136.24814) (xy 297.854846 -136.24814) (xy 297.852407 -136.266664)
			(xy 297.836894 -136.324557) (xy 297.83004 -136.341104) (xy 314.441332 -136.341104) (xy 314.441332 -136.09828)
			(xy 314.44692 -136.089898) (xy 314.447174 -136.08939) (xy 314.449206 -136.086342) (xy 314.44946 -136.085834)
			(xy 314.6552 -135.77189) (xy 314.660186 -135.76345) (xy 314.664007 -135.744243) (xy 314.660367 -135.725)
			(xy 314.655454 -135.716518) (xy 314.569602 -135.584438) (xy 314.560204 -135.56996) (xy 314.447936 -135.398002)
			(xy 314.447428 -135.396986) (xy 314.445396 -135.393938) (xy 314.445142 -135.39343) (xy 314.441332 -135.387588)
			(xy 314.441332 -135.144764) (xy 314.441684 -135.134534) (xy 314.449528 -135.115637) (xy 314.464007 -135.101181)
			(xy 314.482917 -135.093367) (xy 314.493148 -135.092948) (xy 315.229748 -135.092948) (xy 315.239954 -135.093442)
			(xy 315.25881 -135.101264) (xy 315.273243 -135.1157) (xy 315.281061 -135.134557) (xy 315.281564 -135.144764)
			(xy 315.281564 -135.387588) (xy 315.277754 -135.39343) (xy 315.2775 -135.393938) (xy 315.273436 -135.400034)
			(xy 315.273182 -135.400288) (xy 315.13526 -135.611362) (xy 315.082174 -135.692642) (xy 315.069728 -135.711692)
			(xy 315.067696 -135.714486) (xy 315.066426 -135.716518) (xy 315.062206 -135.723925) (xy 315.058498 -135.740554)
			(xy 315.060466 -135.757477) (xy 315.063886 -135.765286) (xy 315.251084 -136.050782) (xy 315.253624 -136.054592)
			(xy 315.273436 -136.084564) (xy 315.27369 -136.085072) (xy 315.27496 -136.087104) (xy 315.276738 -136.089644)
			(xy 315.281564 -136.09701) (xy 315.281564 -136.17575) (xy 315.916564 -136.17575) (xy 315.916564 -135.31215)
			(xy 315.917054 -135.282182) (xy 315.924877 -135.22276) (xy 315.94039 -135.164867) (xy 315.963326 -135.109494)
			(xy 315.993293 -135.057588) (xy 316.02978 -135.010038) (xy 316.07216 -134.967658) (xy 316.11971 -134.931171)
			(xy 316.171616 -134.901204) (xy 316.226989 -134.878268) (xy 316.284882 -134.862755) (xy 316.344304 -134.854932)
			(xy 316.40424 -134.854932) (xy 316.463662 -134.862755) (xy 316.521555 -134.878268) (xy 316.568893 -134.897876)
			(xy 382.967992 -134.897876) (xy 382.967992 -134.034276) (xy 382.968482 -134.004308) (xy 382.976305 -133.944886)
			(xy 382.991818 -133.886993) (xy 383.014754 -133.83162) (xy 383.044721 -133.779714) (xy 383.081208 -133.732164)
			(xy 383.123588 -133.689784) (xy 383.171138 -133.653297) (xy 383.223044 -133.62333) (xy 383.278417 -133.600394)
			(xy 383.33631 -133.584881) (xy 383.395732 -133.577058) (xy 383.455668 -133.577058) (xy 383.51509 -133.584881)
			(xy 383.572983 -133.600394) (xy 383.628356 -133.62333) (xy 383.680262 -133.653297) (xy 383.727812 -133.689784)
			(xy 383.770192 -133.732164) (xy 383.806679 -133.779714) (xy 383.836646 -133.83162) (xy 383.859582 -133.886993)
			(xy 383.875095 -133.944886) (xy 383.882918 -134.004308) (xy 383.883408 -134.034276) (xy 383.883408 -134.897876)
			(xy 383.882918 -134.927844) (xy 383.875095 -134.987266) (xy 383.859582 -135.045159) (xy 383.852097 -135.06323)
			(xy 384.518408 -135.06323) (xy 384.518408 -134.835646) (xy 384.518662 -134.831582) (xy 384.518916 -134.829042)
			(xy 384.518916 -134.820406) (xy 384.524504 -134.81177) (xy 384.525774 -134.809738) (xy 384.52679 -134.807706)
			(xy 384.724148 -134.506716) (xy 384.728022 -134.500391) (xy 384.732279 -134.486189) (xy 384.73253 -134.478776)
			(xy 384.73253 -134.453122) (xy 384.732337 -134.445787) (xy 384.728199 -134.431716) (xy 384.724402 -134.425436)
			(xy 384.526536 -134.122414) (xy 384.52425 -134.118604) (xy 384.523996 -134.118096) (xy 384.52298 -134.116318)
			(xy 384.518916 -134.109714) (xy 384.518916 -134.101586) (xy 384.518662 -134.099046) (xy 384.518408 -134.094982)
			(xy 384.518408 -133.86689) (xy 384.518925 -133.856735) (xy 384.526697 -133.837972) (xy 384.541055 -133.823608)
			(xy 384.559816 -133.815829) (xy 384.56997 -133.815328) (xy 385.306824 -133.815328) (xy 385.317007 -133.815756)
			(xy 385.33583 -133.823538) (xy 385.350257 -133.837914) (xy 385.358107 -133.856708) (xy 385.35864 -133.86689)
			(xy 385.35864 -134.094474) (xy 385.358386 -134.098538) (xy 385.358132 -134.101078) (xy 385.358132 -134.109714)
			(xy 385.35229 -134.119112) (xy 385.351528 -134.120382) (xy 385.350258 -134.122414) (xy 385.144518 -134.43712)
			(xy 385.139494 -134.445657) (xy 385.135662 -134.465066) (xy 385.139469 -134.484481) (xy 385.144518 -134.493)
			(xy 385.350258 -134.806436) (xy 385.351274 -134.808468) (xy 385.352544 -134.8105) (xy 385.358132 -134.819136)
			(xy 385.358132 -134.827772) (xy 385.358386 -134.830312) (xy 385.35864 -134.834376) (xy 385.35864 -134.968488)
			(xy 393.732004 -134.968488) (xy 393.732004 -133.96214) (xy 393.732455 -133.951988) (xy 393.740238 -133.933236)
			(xy 393.754626 -133.918911) (xy 393.773412 -133.91121) (xy 393.783566 -133.910832) (xy 394.964666 -133.910832)
			(xy 394.97479 -133.911354) (xy 394.993508 -133.91907) (xy 395.007865 -133.933345) (xy 395.015687 -133.952019)
			(xy 395.016228 -133.96214) (xy 395.016228 -134.968488) (xy 398.268952 -134.968488) (xy 398.268952 -133.96214)
			(xy 398.269517 -133.95204) (xy 398.277232 -133.933372) (xy 398.291505 -133.919077) (xy 398.310161 -133.911333)
			(xy 398.32026 -133.910832) (xy 399.50136 -133.910832) (xy 399.511484 -133.91125) (xy 399.530193 -133.918991)
			(xy 399.544509 -133.933307) (xy 399.55225 -133.952016) (xy 399.552668 -133.96214) (xy 399.552668 -134.896352)
			(xy 401.939252 -134.896352) (xy 401.939252 -134.032752) (xy 401.939742 -134.002784) (xy 401.947565 -133.943362)
			(xy 401.963078 -133.885469) (xy 401.986014 -133.830096) (xy 402.015981 -133.77819) (xy 402.052468 -133.73064)
			(xy 402.094848 -133.68826) (xy 402.142398 -133.651773) (xy 402.194304 -133.621806) (xy 402.249677 -133.59887)
			(xy 402.30757 -133.583357) (xy 402.366992 -133.575534) (xy 402.426928 -133.575534) (xy 402.48635 -133.583357)
			(xy 402.544243 -133.59887) (xy 402.599616 -133.621806) (xy 402.651522 -133.651773) (xy 402.699072 -133.68826)
			(xy 402.741452 -133.73064) (xy 402.777939 -133.77819) (xy 402.807906 -133.830096) (xy 402.830842 -133.885469)
			(xy 402.846355 -133.943362) (xy 402.854178 -134.002784) (xy 402.854668 -134.032752) (xy 402.854668 -134.377176)
			(xy 414.899348 -134.377176) (xy 414.899348 -133.513576) (xy 414.899838 -133.483592) (xy 414.907666 -133.424136)
			(xy 414.923187 -133.366211) (xy 414.946136 -133.310807) (xy 414.97612 -133.258873) (xy 415.012626 -133.211297)
			(xy 415.055031 -133.168892) (xy 415.102607 -133.132386) (xy 415.154541 -133.102402) (xy 415.209945 -133.079453)
			(xy 415.26787 -133.063932) (xy 415.327326 -133.056104) (xy 415.387294 -133.056104) (xy 415.44675 -133.063932)
			(xy 415.504675 -133.079453) (xy 415.560079 -133.102402) (xy 415.612013 -133.132386) (xy 415.659589 -133.168892)
			(xy 415.701994 -133.211297) (xy 415.7385 -133.258873) (xy 415.768484 -133.310807) (xy 415.791433 -133.366211)
			(xy 415.806954 -133.424136) (xy 415.814782 -133.483592) (xy 415.815272 -133.513576) (xy 415.815272 -134.377176)
			(xy 415.814782 -134.40716) (xy 415.809366 -134.448296) (xy 416.347148 -134.448296) (xy 416.347148 -133.441948)
			(xy 416.347654 -133.431835) (xy 416.355377 -133.413142) (xy 416.369665 -133.398828) (xy 416.388344 -133.391072)
			(xy 416.398456 -133.39064) (xy 417.57981 -133.39064) (xy 417.589937 -133.391119) (xy 417.608659 -133.39885)
			(xy 417.623015 -133.413138) (xy 417.630833 -133.431823) (xy 417.631372 -133.441948) (xy 417.631372 -134.448296)
			(xy 420.884096 -134.448296) (xy 420.884096 -133.441948) (xy 420.884555 -133.431829) (xy 420.892287 -133.413127)
			(xy 420.90659 -133.398812) (xy 420.925286 -133.391064) (xy 420.935404 -133.39064) (xy 422.116504 -133.39064)
			(xy 422.126632 -133.391014) (xy 422.145343 -133.398771) (xy 422.159659 -133.413101) (xy 422.167396 -133.43182)
			(xy 422.167812 -133.441948) (xy 422.167812 -134.448296) (xy 422.167312 -134.458403) (xy 422.159578 -134.477079)
			(xy 422.145286 -134.491373) (xy 422.126611 -134.49911) (xy 422.116504 -134.499604) (xy 420.935404 -134.499604)
			(xy 420.925282 -134.499181) (xy 420.90658 -134.491435) (xy 420.892265 -134.47712) (xy 420.884519 -134.458418)
			(xy 420.884096 -134.448296) (xy 417.631372 -134.448296) (xy 417.63098 -134.458422) (xy 417.623228 -134.477131)
			(xy 417.608904 -134.491446) (xy 417.59019 -134.499186) (xy 417.580064 -134.499604) (xy 416.39871 -134.499604)
			(xy 416.388589 -134.499067) (xy 416.369877 -134.49135) (xy 416.355522 -134.47708) (xy 416.347694 -134.458414)
			(xy 416.347148 -134.448296) (xy 415.809366 -134.448296) (xy 415.806954 -134.466616) (xy 415.791433 -134.524541)
			(xy 415.787243 -134.534656) (xy 427.899576 -134.534656) (xy 427.899576 -134.291832) (xy 428.018448 -134.110476)
			(xy 428.080932 -134.014972) (xy 428.105062 -133.978142) (xy 428.108928 -133.971813) (xy 428.113189 -133.957614)
			(xy 428.113444 -133.950202) (xy 428.113444 -133.924294) (xy 428.113255 -133.918144) (xy 428.110299 -133.906203)
			(xy 428.107602 -133.900672) (xy 427.994064 -133.726682) (xy 427.973998 -133.695694) (xy 427.96841 -133.687058)
			(xy 427.907958 -133.594348) (xy 427.90745 -133.593586) (xy 427.906942 -133.592824) (xy 427.906688 -133.592316)
			(xy 427.90618 -133.591554) (xy 427.899576 -133.58114) (xy 427.899576 -133.338316) (xy 427.900204 -133.326764)
			(xy 427.910178 -133.30592) (xy 427.92812 -133.291358) (xy 427.9392 -133.288024) (xy 427.951138 -133.2865)
			(xy 428.687738 -133.2865) (xy 428.698492 -133.287047) (xy 428.718181 -133.295695) (xy 428.725838 -133.303264)
			(xy 428.732035 -133.310664) (xy 428.738951 -133.32867) (xy 428.7393 -133.338316) (xy 428.7393 -133.58114)
			(xy 428.5234 -133.911594) (xy 428.519362 -133.919808) (xy 428.516824 -133.937923) (xy 428.520776 -133.955783)
			(xy 428.525432 -133.963664) (xy 428.55769 -134.013448) (xy 428.7393 -134.290562) (xy 428.7393 -134.369302)
			(xy 429.3743 -134.369302) (xy 429.3743 -133.505702) (xy 429.37479 -133.475718) (xy 429.382618 -133.416262)
			(xy 429.398139 -133.358337) (xy 429.421088 -133.302933) (xy 429.451072 -133.250999) (xy 429.487578 -133.203423)
			(xy 429.529983 -133.161018) (xy 429.577559 -133.124512) (xy 429.629493 -133.094528) (xy 429.684897 -133.071579)
			(xy 429.742822 -133.056058) (xy 429.802278 -133.04823) (xy 429.862246 -133.04823) (xy 429.921702 -133.056058)
			(xy 429.979627 -133.071579) (xy 430.035031 -133.094528) (xy 430.086965 -133.124512) (xy 430.134541 -133.161018)
			(xy 430.176946 -133.203423) (xy 430.213452 -133.250999) (xy 430.243436 -133.302933) (xy 430.266385 -133.358337)
			(xy 430.281906 -133.416262) (xy 430.289734 -133.475718) (xy 430.290224 -133.505702) (xy 430.290224 -134.369302)
			(xy 430.289734 -134.399286) (xy 430.281906 -134.458742) (xy 430.266385 -134.516667) (xy 430.243436 -134.572071)
			(xy 430.213452 -134.624005) (xy 430.176946 -134.671581) (xy 430.134541 -134.713986) (xy 430.086965 -134.750492)
			(xy 430.035031 -134.780476) (xy 429.979627 -134.803425) (xy 429.921702 -134.818946) (xy 429.862246 -134.826774)
			(xy 429.802278 -134.826774) (xy 429.742822 -134.818946) (xy 429.684897 -134.803425) (xy 429.629493 -134.780476)
			(xy 429.577559 -134.750492) (xy 429.529983 -134.713986) (xy 429.487578 -134.671581) (xy 429.451072 -134.624005)
			(xy 429.421088 -134.572071) (xy 429.398139 -134.516667) (xy 429.382618 -134.458742) (xy 429.37479 -134.399286)
			(xy 429.3743 -134.369302) (xy 428.7393 -134.369302) (xy 428.7393 -134.534656) (xy 428.738668 -134.546208)
			(xy 428.728699 -134.567055) (xy 428.710756 -134.581616) (xy 428.699676 -134.584948) (xy 428.687738 -134.586472)
			(xy 427.951138 -134.586472) (xy 427.940381 -134.585947) (xy 427.920692 -134.577285) (xy 427.913038 -134.569708)
			(xy 427.906826 -134.562319) (xy 427.89992 -134.544304) (xy 427.899576 -134.534656) (xy 415.787243 -134.534656)
			(xy 415.768484 -134.579945) (xy 415.7385 -134.631879) (xy 415.701994 -134.679455) (xy 415.659589 -134.72186)
			(xy 415.612013 -134.758366) (xy 415.560079 -134.78835) (xy 415.504675 -134.811299) (xy 415.44675 -134.82682)
			(xy 415.387294 -134.834648) (xy 415.327326 -134.834648) (xy 415.26787 -134.82682) (xy 415.209945 -134.811299)
			(xy 415.154541 -134.78835) (xy 415.102607 -134.758366) (xy 415.055031 -134.72186) (xy 415.012626 -134.679455)
			(xy 414.97612 -134.631879) (xy 414.946136 -134.579945) (xy 414.923187 -134.524541) (xy 414.907666 -134.466616)
			(xy 414.899838 -134.40716) (xy 414.899348 -134.377176) (xy 402.854668 -134.377176) (xy 402.854668 -134.896352)
			(xy 402.854178 -134.92632) (xy 402.846355 -134.985742) (xy 402.830842 -135.043635) (xy 402.807906 -135.099008)
			(xy 402.777939 -135.150914) (xy 402.741452 -135.198464) (xy 402.699072 -135.240844) (xy 402.651522 -135.277331)
			(xy 402.599616 -135.307298) (xy 402.544243 -135.330234) (xy 402.48635 -135.345747) (xy 402.426928 -135.35357)
			(xy 402.366992 -135.35357) (xy 402.30757 -135.345747) (xy 402.249677 -135.330234) (xy 402.194304 -135.307298)
			(xy 402.142398 -135.277331) (xy 402.094848 -135.240844) (xy 402.052468 -135.198464) (xy 402.015981 -135.150914)
			(xy 401.986014 -135.099008) (xy 401.963078 -135.043635) (xy 401.947565 -134.985742) (xy 401.939742 -134.92632)
			(xy 401.939252 -134.896352) (xy 399.552668 -134.896352) (xy 399.552668 -134.968488) (xy 399.552273 -134.978614)
			(xy 399.544523 -134.997323) (xy 399.5302 -135.011639) (xy 399.511486 -135.019379) (xy 399.50136 -135.019796)
			(xy 398.32026 -135.019796) (xy 398.310148 -135.019347) (xy 398.291468 -135.011596) (xy 398.277175 -134.997288)
			(xy 398.269442 -134.9786) (xy 398.268952 -134.968488) (xy 395.016228 -134.968488) (xy 395.015769 -134.978638)
			(xy 395.007983 -134.997385) (xy 394.993598 -135.011707) (xy 394.974818 -135.019413) (xy 394.964666 -135.019796)
			(xy 393.783566 -135.019796) (xy 393.773442 -135.019302) (xy 393.754726 -135.01157) (xy 393.740373 -134.997287)
			(xy 393.732548 -134.97861) (xy 393.732004 -134.968488) (xy 385.35864 -134.968488) (xy 385.35864 -135.06323)
			(xy 385.358191 -135.073392) (xy 385.350402 -135.092167) (xy 385.336023 -135.106532) (xy 385.317241 -135.114301)
			(xy 385.307078 -135.114792) (xy 384.570224 -135.114792) (xy 384.560046 -135.114305) (xy 384.541229 -135.106543)
			(xy 384.5268 -135.092184) (xy 384.518946 -135.073405) (xy 384.518408 -135.06323) (xy 383.852097 -135.06323)
			(xy 383.836646 -135.100532) (xy 383.806679 -135.152438) (xy 383.770192 -135.199988) (xy 383.727812 -135.242368)
			(xy 383.680262 -135.278855) (xy 383.628356 -135.308822) (xy 383.572983 -135.331758) (xy 383.51509 -135.347271)
			(xy 383.455668 -135.355094) (xy 383.395732 -135.355094) (xy 383.33631 -135.347271) (xy 383.278417 -135.331758)
			(xy 383.223044 -135.308822) (xy 383.171138 -135.278855) (xy 383.123588 -135.242368) (xy 383.081208 -135.199988)
			(xy 383.044721 -135.152438) (xy 383.014754 -135.100532) (xy 382.991818 -135.045159) (xy 382.976305 -134.987266)
			(xy 382.968482 -134.927844) (xy 382.967992 -134.897876) (xy 316.568893 -134.897876) (xy 316.576928 -134.901204)
			(xy 316.628834 -134.931171) (xy 316.676384 -134.967658) (xy 316.718764 -135.010038) (xy 316.755251 -135.057588)
			(xy 316.785218 -135.109494) (xy 316.808154 -135.164867) (xy 316.823667 -135.22276) (xy 316.83149 -135.282182)
			(xy 316.83198 -135.31215) (xy 316.83198 -136.17575) (xy 316.83149 -136.205718) (xy 316.823667 -136.26514)
			(xy 316.808154 -136.323033) (xy 316.785218 -136.378406) (xy 316.755251 -136.430312) (xy 316.718764 -136.477862)
			(xy 316.676384 -136.520242) (xy 316.628834 -136.556729) (xy 316.576928 -136.586696) (xy 316.521555 -136.609632)
			(xy 316.463662 -136.625145) (xy 316.40424 -136.632968) (xy 316.344304 -136.632968) (xy 316.284882 -136.625145)
			(xy 316.226989 -136.609632) (xy 316.171616 -136.586696) (xy 316.11971 -136.556729) (xy 316.07216 -136.520242)
			(xy 316.02978 -136.477862) (xy 315.993293 -136.430312) (xy 315.963326 -136.378406) (xy 315.94039 -136.323033)
			(xy 315.924877 -136.26514) (xy 315.917054 -136.205718) (xy 315.916564 -136.17575) (xy 315.281564 -136.17575)
			(xy 315.281564 -136.341104) (xy 315.281023 -136.351306) (xy 315.273217 -136.370159) (xy 315.258796 -136.384593)
			(xy 315.23995 -136.392414) (xy 315.229748 -136.39292) (xy 314.493148 -136.39292) (xy 314.48293 -136.392449)
			(xy 314.464044 -136.384642) (xy 314.449587 -136.370199) (xy 314.441761 -136.351322) (xy 314.441332 -136.341104)
			(xy 297.83004 -136.341104) (xy 297.813958 -136.37993) (xy 297.783991 -136.431836) (xy 297.747504 -136.479386)
			(xy 297.705124 -136.521766) (xy 297.657574 -136.558253) (xy 297.605668 -136.58822) (xy 297.550295 -136.611156)
			(xy 297.492402 -136.626669) (xy 297.43298 -136.634492) (xy 297.373044 -136.634492) (xy 297.313622 -136.626669)
			(xy 297.255729 -136.611156) (xy 297.200356 -136.58822) (xy 297.14845 -136.558253) (xy 297.1009 -136.521766)
			(xy 297.05852 -136.479386) (xy 297.022033 -136.431836) (xy 296.992066 -136.37993) (xy 296.96913 -136.324557)
			(xy 296.953617 -136.266664) (xy 296.945794 -136.207242) (xy 296.945304 -136.177274) (xy 284.900624 -136.177274)
			(xy 284.900624 -136.69645) (xy 284.900495 -136.704324) (xy 385.6101 -136.704324) (xy 385.6101 -135.840724)
			(xy 385.61059 -135.810756) (xy 385.618413 -135.751334) (xy 385.633926 -135.693441) (xy 385.656862 -135.638068)
			(xy 385.686829 -135.586162) (xy 385.723316 -135.538612) (xy 385.765696 -135.496232) (xy 385.813246 -135.459745)
			(xy 385.865152 -135.429778) (xy 385.920525 -135.406842) (xy 385.978418 -135.391329) (xy 386.03784 -135.383506)
			(xy 386.097776 -135.383506) (xy 386.157198 -135.391329) (xy 386.215091 -135.406842) (xy 386.270464 -135.429778)
			(xy 386.32237 -135.459745) (xy 386.36992 -135.496232) (xy 386.4123 -135.538612) (xy 386.448787 -135.586162)
			(xy 386.478754 -135.638068) (xy 386.50169 -135.693441) (xy 386.517203 -135.751334) (xy 386.525026 -135.810756)
			(xy 386.525516 -135.840724) (xy 386.525516 -136.704324) (xy 386.525026 -136.734292) (xy 386.517203 -136.793714)
			(xy 386.50169 -136.851607) (xy 386.494205 -136.869678) (xy 387.160516 -136.869678) (xy 387.160516 -136.642094)
			(xy 387.16077 -136.63803) (xy 387.161024 -136.63549) (xy 387.161024 -136.626854) (xy 387.166612 -136.618218)
			(xy 387.167882 -136.616186) (xy 387.168898 -136.614154) (xy 387.366256 -136.313164) (xy 387.370113 -136.30683)
			(xy 387.37438 -136.292635) (xy 387.374638 -136.285224) (xy 387.374638 -136.25957) (xy 387.374424 -136.252237)
			(xy 387.3703 -136.238165) (xy 387.36651 -136.231884) (xy 387.168644 -135.928862) (xy 387.166358 -135.925052)
			(xy 387.166104 -135.924544) (xy 387.165088 -135.922766) (xy 387.161024 -135.916162) (xy 387.161024 -135.908034)
			(xy 387.16077 -135.905494) (xy 387.160516 -135.90143) (xy 387.160516 -135.673338) (xy 387.160994 -135.663172)
			(xy 387.168763 -135.644382) (xy 387.183132 -135.629997) (xy 387.201912 -135.622206) (xy 387.212078 -135.621776)
			(xy 387.948932 -135.621776) (xy 387.95911 -135.622248) (xy 387.977922 -135.630023) (xy 387.992348 -135.644385)
			(xy 388.000206 -135.663163) (xy 388.000748 -135.673338) (xy 388.000748 -135.900922) (xy 388.000494 -135.904986)
			(xy 388.00024 -135.907526) (xy 388.00024 -135.916162) (xy 387.994398 -135.92556) (xy 387.993636 -135.92683)
			(xy 387.992366 -135.928862) (xy 387.786626 -136.243568) (xy 387.781562 -136.252084) (xy 387.777742 -136.271507)
			(xy 387.781567 -136.290928) (xy 387.786626 -136.299448) (xy 387.992366 -136.612884) (xy 387.993382 -136.614916)
			(xy 387.994652 -136.616948) (xy 388.00024 -136.625584) (xy 388.00024 -136.63422) (xy 388.000494 -136.63676)
			(xy 388.000748 -136.640824) (xy 388.000748 -136.768332) (xy 393.732004 -136.768332) (xy 393.732004 -135.761984)
			(xy 393.732408 -135.751828) (xy 393.74021 -135.733075) (xy 393.754612 -135.718752) (xy 393.773408 -135.711053)
			(xy 393.783566 -135.710676) (xy 394.964666 -135.710676) (xy 394.974795 -135.711156) (xy 394.993522 -135.718879)
			(xy 395.007881 -135.733168) (xy 395.015695 -135.751858) (xy 395.016228 -135.761984) (xy 395.016228 -136.768332)
			(xy 398.268952 -136.768332) (xy 398.268952 -135.761984) (xy 398.269471 -135.75188) (xy 398.277205 -135.733211)
			(xy 398.291491 -135.718918) (xy 398.310156 -135.711176) (xy 398.32026 -135.710676) (xy 399.50136 -135.710676)
			(xy 399.511477 -135.711148) (xy 399.530175 -135.718879) (xy 399.54449 -135.733178) (xy 399.552241 -135.751868)
			(xy 399.552668 -135.761984) (xy 399.552668 -136.69645) (xy 400.085052 -136.69645) (xy 400.085052 -135.83285)
			(xy 400.085542 -135.802882) (xy 400.093365 -135.74346) (xy 400.108878 -135.685567) (xy 400.131814 -135.630194)
			(xy 400.161781 -135.578288) (xy 400.198268 -135.530738) (xy 400.240648 -135.488358) (xy 400.288198 -135.451871)
			(xy 400.340104 -135.421904) (xy 400.395477 -135.398968) (xy 400.45337 -135.383455) (xy 400.512792 -135.375632)
			(xy 400.572728 -135.375632) (xy 400.63215 -135.383455) (xy 400.690043 -135.398968) (xy 400.745416 -135.421904)
			(xy 400.797322 -135.451871) (xy 400.844872 -135.488358) (xy 400.887252 -135.530738) (xy 400.923739 -135.578288)
			(xy 400.953706 -135.630194) (xy 400.976642 -135.685567) (xy 400.992155 -135.74346) (xy 400.999978 -135.802882)
			(xy 401.000468 -135.83285) (xy 401.000468 -136.177274) (xy 413.045148 -136.177274) (xy 413.045148 -135.313674)
			(xy 413.045638 -135.28369) (xy 413.053466 -135.224234) (xy 413.068987 -135.166309) (xy 413.091936 -135.110905)
			(xy 413.12192 -135.058971) (xy 413.158426 -135.011395) (xy 413.200831 -134.96899) (xy 413.248407 -134.932484)
			(xy 413.300341 -134.9025) (xy 413.355745 -134.879551) (xy 413.41367 -134.86403) (xy 413.473126 -134.856202)
			(xy 413.533094 -134.856202) (xy 413.59255 -134.86403) (xy 413.650475 -134.879551) (xy 413.705879 -134.9025)
			(xy 413.757813 -134.932484) (xy 413.805389 -134.96899) (xy 413.847794 -135.011395) (xy 413.8843 -135.058971)
			(xy 413.914284 -135.110905) (xy 413.937233 -135.166309) (xy 413.952754 -135.224234) (xy 413.960582 -135.28369)
			(xy 413.961072 -135.313674) (xy 413.961072 -136.177274) (xy 413.960582 -136.207258) (xy 413.955199 -136.24814)
			(xy 416.347148 -136.24814) (xy 416.347148 -135.241792) (xy 416.347677 -135.231689) (xy 416.355408 -135.213021)
			(xy 416.369691 -135.198728) (xy 416.388354 -135.190985) (xy 416.398456 -135.190484) (xy 417.57981 -135.190484)
			(xy 417.589943 -135.19092) (xy 417.608672 -135.198659) (xy 417.62303 -135.212961) (xy 417.630841 -135.231661)
			(xy 417.631372 -135.241792) (xy 417.631372 -136.24814) (xy 420.884096 -136.24814) (xy 420.884096 -135.241792)
			(xy 420.884579 -135.231683) (xy 420.892318 -135.213006) (xy 420.906616 -135.198711) (xy 420.925295 -135.190976)
			(xy 420.935404 -135.190484) (xy 422.116504 -135.190484) (xy 422.126611 -135.190982) (xy 422.145286 -135.198718)
			(xy 422.15958 -135.21301) (xy 422.167318 -135.231685) (xy 422.167812 -135.241792) (xy 422.167812 -136.24814)
			(xy 422.167348 -136.25825) (xy 422.159599 -136.276927) (xy 422.145296 -136.29122) (xy 422.126614 -136.298955)
			(xy 422.116504 -136.299448) (xy 420.935404 -136.299448) (xy 420.925301 -136.298913) (xy 420.906633 -136.291185)
			(xy 420.892339 -136.276904) (xy 420.884596 -136.258242) (xy 420.884096 -136.24814) (xy 417.631372 -136.24814)
			(xy 417.630947 -136.258255) (xy 417.623191 -136.276939) (xy 417.608875 -136.291234) (xy 417.590179 -136.298962)
			(xy 417.580064 -136.299448) (xy 416.39871 -136.299448) (xy 416.388582 -136.298965) (xy 416.369859 -136.291238)
			(xy 416.355502 -136.276951) (xy 416.347685 -136.258265) (xy 416.347148 -136.24814) (xy 413.955199 -136.24814)
			(xy 413.952754 -136.266714) (xy 413.937233 -136.324639) (xy 413.930413 -136.341104) (xy 430.541684 -136.341104)
			(xy 430.541684 -136.09828) (xy 430.660556 -135.916924) (xy 430.72304 -135.82142) (xy 430.74717 -135.78459)
			(xy 430.751056 -135.778271) (xy 430.755304 -135.764065) (xy 430.755552 -135.75665) (xy 430.755552 -135.730742)
			(xy 430.755346 -135.724593) (xy 430.752401 -135.712652) (xy 430.74971 -135.70712) (xy 430.636172 -135.53313)
			(xy 430.616106 -135.502142) (xy 430.610518 -135.493506) (xy 430.550066 -135.400796) (xy 430.549558 -135.400034)
			(xy 430.54905 -135.399272) (xy 430.548796 -135.398764) (xy 430.548288 -135.398002) (xy 430.541684 -135.387588)
			(xy 430.541684 -135.144764) (xy 430.542343 -135.133215) (xy 430.5523 -135.112371) (xy 430.570232 -135.097807)
			(xy 430.581308 -135.094472) (xy 430.593246 -135.092948) (xy 431.329846 -135.092948) (xy 431.340603 -135.093476)
			(xy 431.360292 -135.102136) (xy 431.367946 -135.109712) (xy 431.374122 -135.117127) (xy 431.38105 -135.135122)
			(xy 431.381408 -135.144764) (xy 431.381408 -135.387588) (xy 431.165508 -135.718042) (xy 431.161511 -135.726273)
			(xy 431.158957 -135.744377) (xy 431.162892 -135.762231) (xy 431.16754 -135.770112) (xy 431.199798 -135.819896)
			(xy 431.381408 -136.09701) (xy 431.381408 -136.17575) (xy 432.016408 -136.17575) (xy 432.016408 -135.31215)
			(xy 432.016898 -135.282166) (xy 432.024726 -135.22271) (xy 432.040247 -135.164785) (xy 432.063196 -135.109381)
			(xy 432.09318 -135.057447) (xy 432.129686 -135.009871) (xy 432.172091 -134.967466) (xy 432.219667 -134.93096)
			(xy 432.271601 -134.900976) (xy 432.327005 -134.878027) (xy 432.38493 -134.862506) (xy 432.444386 -134.854678)
			(xy 432.504354 -134.854678) (xy 432.56381 -134.862506) (xy 432.621735 -134.878027) (xy 432.677139 -134.900976)
			(xy 432.729073 -134.93096) (xy 432.776649 -134.967466) (xy 432.819054 -135.009871) (xy 432.85556 -135.057447)
			(xy 432.885544 -135.109381) (xy 432.908493 -135.164785) (xy 432.924014 -135.22271) (xy 432.931842 -135.282166)
			(xy 432.932332 -135.31215) (xy 432.932332 -136.17575) (xy 432.931842 -136.205734) (xy 432.924014 -136.26519)
			(xy 432.908493 -136.323115) (xy 432.885544 -136.378519) (xy 432.85556 -136.430453) (xy 432.819054 -136.478029)
			(xy 432.776649 -136.520434) (xy 432.729073 -136.55694) (xy 432.677139 -136.586924) (xy 432.621735 -136.609873)
			(xy 432.56381 -136.625394) (xy 432.504354 -136.633222) (xy 432.444386 -136.633222) (xy 432.38493 -136.625394)
			(xy 432.327005 -136.609873) (xy 432.271601 -136.586924) (xy 432.219667 -136.55694) (xy 432.172091 -136.520434)
			(xy 432.129686 -136.478029) (xy 432.09318 -136.430453) (xy 432.063196 -136.378519) (xy 432.040247 -136.323115)
			(xy 432.024726 -136.26519) (xy 432.016898 -136.205734) (xy 432.016408 -136.17575) (xy 431.381408 -136.17575)
			(xy 431.381408 -136.341104) (xy 431.38073 -136.352651) (xy 431.370783 -136.373496) (xy 431.352858 -136.388061)
			(xy 431.341784 -136.391396) (xy 431.329846 -136.39292) (xy 430.593246 -136.39292) (xy 430.582492 -136.392376)
			(xy 430.562803 -136.383725) (xy 430.555146 -136.376156) (xy 430.548955 -136.368751) (xy 430.542036 -136.350749)
			(xy 430.541684 -136.341104) (xy 413.930413 -136.341104) (xy 413.914284 -136.380043) (xy 413.8843 -136.431977)
			(xy 413.847794 -136.479553) (xy 413.805389 -136.521958) (xy 413.757813 -136.558464) (xy 413.705879 -136.588448)
			(xy 413.650475 -136.611397) (xy 413.59255 -136.626918) (xy 413.533094 -136.634746) (xy 413.473126 -136.634746)
			(xy 413.41367 -136.626918) (xy 413.355745 -136.611397) (xy 413.300341 -136.588448) (xy 413.248407 -136.558464)
			(xy 413.200831 -136.521958) (xy 413.158426 -136.479553) (xy 413.12192 -136.431977) (xy 413.091936 -136.380043)
			(xy 413.068987 -136.324639) (xy 413.053466 -136.266714) (xy 413.045638 -136.207258) (xy 413.045148 -136.177274)
			(xy 401.000468 -136.177274) (xy 401.000468 -136.69645) (xy 400.999978 -136.726418) (xy 400.992155 -136.78584)
			(xy 400.976642 -136.843733) (xy 400.953706 -136.899106) (xy 400.923739 -136.951012) (xy 400.887252 -136.998562)
			(xy 400.844872 -137.040942) (xy 400.797322 -137.077429) (xy 400.745416 -137.107396) (xy 400.690043 -137.130332)
			(xy 400.63215 -137.145845) (xy 400.572728 -137.153668) (xy 400.512792 -137.153668) (xy 400.45337 -137.145845)
			(xy 400.395477 -137.130332) (xy 400.340104 -137.107396) (xy 400.288198 -137.077429) (xy 400.240648 -137.040942)
			(xy 400.198268 -136.998562) (xy 400.161781 -136.951012) (xy 400.131814 -136.899106) (xy 400.108878 -136.843733)
			(xy 400.093365 -136.78584) (xy 400.085542 -136.726418) (xy 400.085052 -136.69645) (xy 399.552668 -136.69645)
			(xy 399.552668 -136.768332) (xy 399.552309 -136.778461) (xy 399.544545 -136.797171) (xy 399.53021 -136.811485)
			(xy 399.511489 -136.819224) (xy 399.50136 -136.81964) (xy 398.32026 -136.81964) (xy 398.310154 -136.819149)
			(xy 398.291482 -136.811405) (xy 398.27719 -136.797111) (xy 398.26945 -136.778438) (xy 398.268952 -136.768332)
			(xy 395.016228 -136.768332) (xy 395.015805 -136.778485) (xy 395.008004 -136.797232) (xy 394.993609 -136.811554)
			(xy 394.974821 -136.819257) (xy 394.964666 -136.81964) (xy 393.783566 -136.81964) (xy 393.773435 -136.819201)
			(xy 393.754709 -136.811458) (xy 393.740353 -136.797157) (xy 393.732539 -136.778461) (xy 393.732004 -136.768332)
			(xy 388.000748 -136.768332) (xy 388.000748 -136.869678) (xy 388.000318 -136.87985) (xy 387.992537 -136.898647)
			(xy 387.978153 -136.913033) (xy 387.959358 -136.920816) (xy 387.949186 -136.92124) (xy 387.212332 -136.92124)
			(xy 387.20216 -136.9207) (xy 387.183352 -136.912949) (xy 387.168925 -136.898608) (xy 387.161062 -136.879846)
			(xy 387.160516 -136.869678) (xy 386.494205 -136.869678) (xy 386.478754 -136.90698) (xy 386.448787 -136.958886)
			(xy 386.4123 -137.006436) (xy 386.36992 -137.048816) (xy 386.32237 -137.085303) (xy 386.270464 -137.11527)
			(xy 386.215091 -137.138206) (xy 386.157198 -137.153719) (xy 386.097776 -137.161542) (xy 386.03784 -137.161542)
			(xy 385.978418 -137.153719) (xy 385.920525 -137.138206) (xy 385.865152 -137.11527) (xy 385.813246 -137.085303)
			(xy 385.765696 -137.048816) (xy 385.723316 -137.006436) (xy 385.686829 -136.958886) (xy 385.656862 -136.90698)
			(xy 385.633926 -136.851607) (xy 385.618413 -136.793714) (xy 385.61059 -136.734292) (xy 385.6101 -136.704324)
			(xy 284.900495 -136.704324) (xy 284.900134 -136.726434) (xy 284.892306 -136.78589) (xy 284.876785 -136.843815)
			(xy 284.853836 -136.899219) (xy 284.823852 -136.951153) (xy 284.787346 -136.998729) (xy 284.744941 -137.041134)
			(xy 284.697365 -137.07764) (xy 284.645431 -137.107624) (xy 284.590027 -137.130573) (xy 284.532102 -137.146094)
			(xy 284.472646 -137.153922) (xy 284.412678 -137.153922) (xy 284.353222 -137.146094) (xy 284.295297 -137.130573)
			(xy 284.239893 -137.107624) (xy 284.187959 -137.07764) (xy 284.140383 -137.041134) (xy 284.097978 -136.998729)
			(xy 284.061472 -136.951153) (xy 284.031488 -136.899219) (xy 284.008539 -136.843815) (xy 283.993018 -136.78589)
			(xy 283.98519 -136.726434) (xy 283.9847 -136.69645) (xy 283.452824 -136.69645) (xy 283.452824 -136.768332)
			(xy 283.452342 -136.77844) (xy 283.444598 -136.797114) (xy 283.430301 -136.811407) (xy 283.411624 -136.819145)
			(xy 283.401516 -136.81964) (xy 282.220162 -136.81964) (xy 282.21003 -136.819204) (xy 282.191305 -136.81146)
			(xy 282.176949 -136.797158) (xy 282.169135 -136.778462) (xy 282.1686 -136.768332) (xy 278.915876 -136.768332)
			(xy 278.915441 -136.778446) (xy 278.907688 -136.797129) (xy 278.893376 -136.811424) (xy 278.874682 -136.819153)
			(xy 278.864568 -136.81964) (xy 277.683468 -136.81964) (xy 277.673362 -136.819142) (xy 277.654691 -136.811401)
			(xy 277.640399 -136.797109) (xy 277.632658 -136.778438) (xy 277.63216 -136.768332) (xy 271.900396 -136.768332)
			(xy 271.900396 -136.869678) (xy 271.89985 -136.87983) (xy 271.892089 -136.898592) (xy 271.877739 -136.912957)
			(xy 271.858986 -136.920739) (xy 271.848834 -136.92124) (xy 271.112234 -136.92124) (xy 271.102062 -136.920808)
			(xy 271.083264 -136.91303) (xy 271.068877 -136.898646) (xy 271.061095 -136.87985) (xy 271.060672 -136.869678)
			(xy 270.394382 -136.869678) (xy 270.378884 -136.907093) (xy 270.3489 -136.959027) (xy 270.312394 -137.006603)
			(xy 270.269989 -137.049008) (xy 270.222413 -137.085514) (xy 270.170479 -137.115498) (xy 270.115075 -137.138447)
			(xy 270.05715 -137.153968) (xy 269.997694 -137.161796) (xy 269.937726 -137.161796) (xy 269.87827 -137.153968)
			(xy 269.820345 -137.138447) (xy 269.764941 -137.115498) (xy 269.713007 -137.085514) (xy 269.665431 -137.049008)
			(xy 269.623026 -137.006603) (xy 269.58652 -136.959027) (xy 269.556536 -136.907093) (xy 269.533587 -136.851689)
			(xy 269.518066 -136.793764) (xy 269.510238 -136.734308) (xy 269.509748 -136.704324) (xy 168.800651 -136.704324)
			(xy 168.80029 -136.726434) (xy 168.792462 -136.78589) (xy 168.776941 -136.843815) (xy 168.753992 -136.899219)
			(xy 168.724008 -136.951153) (xy 168.687502 -136.998729) (xy 168.645097 -137.041134) (xy 168.597521 -137.07764)
			(xy 168.545587 -137.107624) (xy 168.490183 -137.130573) (xy 168.432258 -137.146094) (xy 168.372802 -137.153922)
			(xy 168.312834 -137.153922) (xy 168.253378 -137.146094) (xy 168.195453 -137.130573) (xy 168.140049 -137.107624)
			(xy 168.088115 -137.07764) (xy 168.040539 -137.041134) (xy 167.998134 -136.998729) (xy 167.961628 -136.951153)
			(xy 167.931644 -136.899219) (xy 167.908695 -136.843815) (xy 167.893174 -136.78589) (xy 167.885346 -136.726434)
			(xy 167.884856 -136.69645) (xy 167.352472 -136.69645) (xy 167.352472 -136.768332) (xy 167.35211 -136.77846)
			(xy 167.344346 -136.79717) (xy 167.330013 -136.811484) (xy 167.311293 -136.819223) (xy 167.301164 -136.81964)
			(xy 166.120064 -136.81964) (xy 166.109958 -136.819145) (xy 166.091287 -136.811403) (xy 166.076994 -136.79711)
			(xy 166.069254 -136.778438) (xy 166.068756 -136.768332) (xy 162.816032 -136.768332) (xy 162.815605 -136.778484)
			(xy 162.807805 -136.797231) (xy 162.793411 -136.811552) (xy 162.774624 -136.819257) (xy 162.76447 -136.81964)
			(xy 161.58337 -136.81964) (xy 161.573239 -136.819198) (xy 161.554513 -136.811456) (xy 161.540157 -136.797156)
			(xy 161.532343 -136.778461) (xy 161.531808 -136.768332) (xy 155.800552 -136.768332) (xy 155.800552 -136.869678)
			(xy 155.800118 -136.879849) (xy 155.792338 -136.898645) (xy 155.777956 -136.913031) (xy 155.759161 -136.920815)
			(xy 155.74899 -136.92124) (xy 155.012136 -136.92124) (xy 155.001965 -136.920696) (xy 154.983157 -136.912947)
			(xy 154.96873 -136.898607) (xy 154.960866 -136.879846) (xy 154.96032 -136.869678) (xy 154.294538 -136.869678)
			(xy 154.27904 -136.907093) (xy 154.249056 -136.959027) (xy 154.21255 -137.006603) (xy 154.170145 -137.049008)
			(xy 154.122569 -137.085514) (xy 154.070635 -137.115498) (xy 154.015231 -137.138447) (xy 153.957306 -137.153968)
			(xy 153.89785 -137.161796) (xy 153.837882 -137.161796) (xy 153.778426 -137.153968) (xy 153.720501 -137.138447)
			(xy 153.665097 -137.115498) (xy 153.613163 -137.085514) (xy 153.565587 -137.049008) (xy 153.523182 -137.006603)
			(xy 153.486676 -136.959027) (xy 153.456692 -136.907093) (xy 153.433743 -136.851689) (xy 153.418222 -136.793764)
			(xy 153.410394 -136.734308) (xy 153.409904 -136.704324) (xy 52.700299 -136.704324) (xy 52.699938 -136.726418)
			(xy 52.692115 -136.78584) (xy 52.676602 -136.843733) (xy 52.653666 -136.899106) (xy 52.623699 -136.951012)
			(xy 52.587212 -136.998562) (xy 52.544832 -137.040942) (xy 52.497282 -137.077429) (xy 52.445376 -137.107396)
			(xy 52.390003 -137.130332) (xy 52.33211 -137.145845) (xy 52.272688 -137.153668) (xy 52.212752 -137.153668)
			(xy 52.15333 -137.145845) (xy 52.095437 -137.130332) (xy 52.040064 -137.107396) (xy 51.988158 -137.077429)
			(xy 51.940608 -137.040942) (xy 51.898228 -136.998562) (xy 51.861741 -136.951012) (xy 51.831774 -136.899106)
			(xy 51.808838 -136.843733) (xy 51.793325 -136.78584) (xy 51.785502 -136.726418) (xy 51.785012 -136.69645)
			(xy 51.252628 -136.69645) (xy 51.252628 -136.768332) (xy 51.252142 -136.778439) (xy 51.244399 -136.797113)
			(xy 51.230103 -136.811406) (xy 51.211427 -136.819144) (xy 51.20132 -136.81964) (xy 50.02022 -136.81964)
			(xy 50.010117 -136.8191) (xy 49.991447 -136.811376) (xy 49.977153 -136.797096) (xy 49.969411 -136.778434)
			(xy 49.968912 -136.768332) (xy 46.716188 -136.768332) (xy 46.715804 -136.77849) (xy 46.707996 -136.797245)
			(xy 46.693588 -136.811568) (xy 46.674786 -136.819264) (xy 46.664626 -136.81964) (xy 45.483526 -136.81964)
			(xy 45.473398 -136.819152) (xy 45.454674 -136.811429) (xy 45.440316 -136.797143) (xy 45.432499 -136.778457)
			(xy 45.431964 -136.768332) (xy 39.700708 -136.768332) (xy 39.700708 -136.869678) (xy 39.70015 -136.879829)
			(xy 39.692391 -136.898589) (xy 39.678046 -136.912953) (xy 39.659296 -136.920737) (xy 39.649146 -136.92124)
			(xy 38.912292 -136.92124) (xy 38.902118 -136.920732) (xy 38.883309 -136.912968) (xy 38.868883 -136.898617)
			(xy 38.861022 -136.879849) (xy 38.860476 -136.869678) (xy 38.194165 -136.869678) (xy 38.178714 -136.90698)
			(xy 38.148747 -136.958886) (xy 38.11226 -137.006436) (xy 38.06988 -137.048816) (xy 38.02233 -137.085303)
			(xy 37.970424 -137.11527) (xy 37.915051 -137.138206) (xy 37.857158 -137.153719) (xy 37.797736 -137.161542)
			(xy 37.7378 -137.161542) (xy 37.678378 -137.153719) (xy 37.620485 -137.138206) (xy 37.565112 -137.11527)
			(xy 37.513206 -137.085303) (xy 37.465656 -137.048816) (xy 37.423276 -137.006436) (xy 37.386789 -136.958886)
			(xy 37.356822 -136.90698) (xy 37.333886 -136.851607) (xy 37.318373 -136.793714) (xy 37.31055 -136.734292)
			(xy 37.31006 -136.704324) (xy 4.30911 -136.704324) (xy 4.30911 -138.496548) (xy 43.97248 -138.496548)
			(xy 43.97248 -137.632948) (xy 43.97297 -137.602964) (xy 43.980798 -137.543508) (xy 43.996319 -137.485583)
			(xy 44.019268 -137.430179) (xy 44.049252 -137.378245) (xy 44.085758 -137.330669) (xy 44.128163 -137.288264)
			(xy 44.175739 -137.251758) (xy 44.227673 -137.221774) (xy 44.283077 -137.198825) (xy 44.341002 -137.183304)
			(xy 44.400458 -137.175476) (xy 44.460426 -137.175476) (xy 44.519882 -137.183304) (xy 44.577807 -137.198825)
			(xy 44.633211 -137.221774) (xy 44.685145 -137.251758) (xy 44.732721 -137.288264) (xy 44.775126 -137.330669)
			(xy 44.811632 -137.378245) (xy 44.841616 -137.430179) (xy 44.864565 -137.485583) (xy 44.880086 -137.543508)
			(xy 44.887914 -137.602964) (xy 44.888404 -137.632948) (xy 44.888404 -138.496548) (xy 44.887914 -138.526532)
			(xy 44.882465 -138.567922) (xy 45.431964 -138.567922) (xy 45.431964 -137.561574) (xy 45.432413 -137.551411)
			(xy 45.4402 -137.532637) (xy 45.45458 -137.518271) (xy 45.473363 -137.510502) (xy 45.483526 -137.510012)
			(xy 46.664626 -137.510012) (xy 46.674782 -137.510511) (xy 46.693547 -137.518289) (xy 46.707911 -137.532653)
			(xy 46.715689 -137.551418) (xy 46.716188 -137.561574) (xy 46.716188 -138.496548) (xy 160.072324 -138.496548)
			(xy 160.072324 -137.632948) (xy 160.072814 -137.602964) (xy 160.080642 -137.543508) (xy 160.096163 -137.485583)
			(xy 160.119112 -137.430179) (xy 160.149096 -137.378245) (xy 160.185602 -137.330669) (xy 160.228007 -137.288264)
			(xy 160.275583 -137.251758) (xy 160.327517 -137.221774) (xy 160.382921 -137.198825) (xy 160.440846 -137.183304)
			(xy 160.500302 -137.175476) (xy 160.56027 -137.175476) (xy 160.619726 -137.183304) (xy 160.677651 -137.198825)
			(xy 160.733055 -137.221774) (xy 160.784989 -137.251758) (xy 160.832565 -137.288264) (xy 160.87497 -137.330669)
			(xy 160.911476 -137.378245) (xy 160.94146 -137.430179) (xy 160.964409 -137.485583) (xy 160.97993 -137.543508)
			(xy 160.987758 -137.602964) (xy 160.988248 -137.632948) (xy 160.988248 -138.496548) (xy 160.987758 -138.526532)
			(xy 160.982309 -138.567922) (xy 161.531808 -138.567922) (xy 161.531808 -137.561574) (xy 161.532311 -137.551418)
			(xy 161.540089 -137.532654) (xy 161.554451 -137.518291) (xy 161.573214 -137.510512) (xy 161.58337 -137.510012)
			(xy 162.76447 -137.510012) (xy 162.774636 -137.510488) (xy 162.793425 -137.518258) (xy 162.80781 -137.532628)
			(xy 162.815601 -137.551408) (xy 162.816032 -137.561574) (xy 162.816032 -138.496548) (xy 276.172676 -138.496548)
			(xy 276.172676 -137.632948) (xy 276.173166 -137.60298) (xy 276.180989 -137.543558) (xy 276.196502 -137.485665)
			(xy 276.219438 -137.430292) (xy 276.249405 -137.378386) (xy 276.285892 -137.330836) (xy 276.328272 -137.288456)
			(xy 276.375822 -137.251969) (xy 276.427728 -137.222002) (xy 276.483101 -137.199066) (xy 276.540994 -137.183553)
			(xy 276.600416 -137.17573) (xy 276.660352 -137.17573) (xy 276.719774 -137.183553) (xy 276.777667 -137.199066)
			(xy 276.83304 -137.222002) (xy 276.884946 -137.251969) (xy 276.932496 -137.288456) (xy 276.974876 -137.330836)
			(xy 277.011363 -137.378386) (xy 277.04133 -137.430292) (xy 277.064266 -137.485665) (xy 277.079779 -137.543558)
			(xy 277.087602 -137.60298) (xy 277.088092 -137.632948) (xy 277.088092 -138.496548) (xy 277.087602 -138.526516)
			(xy 277.082151 -138.567922) (xy 277.63216 -138.567922) (xy 277.63216 -137.561574) (xy 277.632606 -137.551443)
			(xy 277.640346 -137.532718) (xy 277.654645 -137.518361) (xy 277.673339 -137.510547) (xy 277.683468 -137.510012)
			(xy 278.864568 -137.510012) (xy 278.874722 -137.510448) (xy 278.893476 -137.518235) (xy 278.907801 -137.532628)
			(xy 278.915499 -137.551419) (xy 278.915876 -137.561574) (xy 278.915876 -138.497056) (xy 392.27252 -138.497056)
			(xy 392.27252 -137.633456) (xy 392.27301 -137.603472) (xy 392.280838 -137.544016) (xy 392.296359 -137.486091)
			(xy 392.319308 -137.430687) (xy 392.349292 -137.378753) (xy 392.385798 -137.331177) (xy 392.428203 -137.288772)
			(xy 392.475779 -137.252266) (xy 392.527713 -137.222282) (xy 392.583117 -137.199333) (xy 392.641042 -137.183812)
			(xy 392.700498 -137.175984) (xy 392.760466 -137.175984) (xy 392.819922 -137.183812) (xy 392.877847 -137.199333)
			(xy 392.933251 -137.222282) (xy 392.985185 -137.252266) (xy 393.032761 -137.288772) (xy 393.075166 -137.331177)
			(xy 393.111672 -137.378753) (xy 393.141656 -137.430687) (xy 393.164605 -137.486091) (xy 393.180126 -137.544016)
			(xy 393.187954 -137.603472) (xy 393.188444 -137.633456) (xy 393.188444 -138.497056) (xy 393.187954 -138.52704)
			(xy 393.182571 -138.567922) (xy 393.732004 -138.567922) (xy 393.732004 -137.561574) (xy 393.732511 -137.551419)
			(xy 393.740288 -137.532655) (xy 393.754649 -137.518292) (xy 393.773411 -137.510513) (xy 393.783566 -137.510012)
			(xy 394.964666 -137.510012) (xy 394.974832 -137.510491) (xy 394.993621 -137.51826) (xy 395.008006 -137.532628)
			(xy 395.015797 -137.551408) (xy 395.016228 -137.561574) (xy 395.016228 -138.567922) (xy 395.015853 -138.578099)
			(xy 395.008055 -138.596901) (xy 394.993654 -138.611286) (xy 394.974844 -138.619064) (xy 394.964666 -138.619484)
			(xy 393.783566 -138.619484) (xy 393.773409 -138.618995) (xy 393.754643 -138.611214) (xy 393.74028 -138.596847)
			(xy 393.732503 -138.578079) (xy 393.732004 -138.567922) (xy 393.182571 -138.567922) (xy 393.180126 -138.586496)
			(xy 393.164605 -138.644421) (xy 393.141656 -138.699825) (xy 393.111672 -138.751759) (xy 393.075166 -138.799335)
			(xy 393.032761 -138.84174) (xy 392.985185 -138.878246) (xy 392.933251 -138.90823) (xy 392.877847 -138.931179)
			(xy 392.819922 -138.9467) (xy 392.760466 -138.954528) (xy 392.700498 -138.954528) (xy 392.641042 -138.9467)
			(xy 392.583117 -138.931179) (xy 392.527713 -138.90823) (xy 392.475779 -138.878246) (xy 392.428203 -138.84174)
			(xy 392.385798 -138.799335) (xy 392.349292 -138.751759) (xy 392.319308 -138.699825) (xy 392.296359 -138.644421)
			(xy 392.280838 -138.586496) (xy 392.27301 -138.52704) (xy 392.27252 -138.497056) (xy 278.915876 -138.497056)
			(xy 278.915876 -138.567922) (xy 278.915392 -138.578048) (xy 278.90766 -138.596767) (xy 278.893373 -138.611122)
			(xy 278.874692 -138.618943) (xy 278.864568 -138.619484) (xy 277.683468 -138.619484) (xy 277.67331 -138.619104)
			(xy 277.654554 -138.611295) (xy 277.640231 -138.596886) (xy 277.632535 -138.578083) (xy 277.63216 -138.567922)
			(xy 277.082151 -138.567922) (xy 277.079779 -138.585938) (xy 277.064266 -138.643831) (xy 277.04133 -138.699204)
			(xy 277.011363 -138.75111) (xy 276.974876 -138.79866) (xy 276.932496 -138.84104) (xy 276.884946 -138.877527)
			(xy 276.83304 -138.907494) (xy 276.777667 -138.93043) (xy 276.719774 -138.945943) (xy 276.660352 -138.953766)
			(xy 276.600416 -138.953766) (xy 276.540994 -138.945943) (xy 276.483101 -138.93043) (xy 276.427728 -138.907494)
			(xy 276.375822 -138.877527) (xy 276.328272 -138.84104) (xy 276.285892 -138.79866) (xy 276.249405 -138.75111)
			(xy 276.219438 -138.699204) (xy 276.196502 -138.643831) (xy 276.180989 -138.585938) (xy 276.173166 -138.526516)
			(xy 276.172676 -138.496548) (xy 162.816032 -138.496548) (xy 162.816032 -138.567922) (xy 162.815653 -138.578099)
			(xy 162.807855 -138.5969) (xy 162.793456 -138.611285) (xy 162.774647 -138.619063) (xy 162.76447 -138.619484)
			(xy 161.58337 -138.619484) (xy 161.573213 -138.618992) (xy 161.554447 -138.611212) (xy 161.540084 -138.596846)
			(xy 161.532307 -138.578079) (xy 161.531808 -138.567922) (xy 160.982309 -138.567922) (xy 160.97993 -138.585988)
			(xy 160.964409 -138.643913) (xy 160.94146 -138.699317) (xy 160.911476 -138.751251) (xy 160.87497 -138.798827)
			(xy 160.832565 -138.841232) (xy 160.784989 -138.877738) (xy 160.733055 -138.907722) (xy 160.677651 -138.930671)
			(xy 160.619726 -138.946192) (xy 160.56027 -138.95402) (xy 160.500302 -138.95402) (xy 160.440846 -138.946192)
			(xy 160.382921 -138.930671) (xy 160.327517 -138.907722) (xy 160.275583 -138.877738) (xy 160.228007 -138.841232)
			(xy 160.185602 -138.798827) (xy 160.149096 -138.751251) (xy 160.119112 -138.699317) (xy 160.096163 -138.643913)
			(xy 160.080642 -138.585988) (xy 160.072814 -138.526532) (xy 160.072324 -138.496548) (xy 46.716188 -138.496548)
			(xy 46.716188 -138.567922) (xy 46.715685 -138.578078) (xy 46.707909 -138.596843) (xy 46.693546 -138.611206)
			(xy 46.674782 -138.618985) (xy 46.664626 -138.619484) (xy 45.483526 -138.619484) (xy 45.473359 -138.619015)
			(xy 45.454569 -138.611243) (xy 45.440184 -138.596871) (xy 45.432394 -138.578089) (xy 45.431964 -138.567922)
			(xy 44.882465 -138.567922) (xy 44.880086 -138.585988) (xy 44.864565 -138.643913) (xy 44.841616 -138.699317)
			(xy 44.811632 -138.751251) (xy 44.775126 -138.798827) (xy 44.732721 -138.841232) (xy 44.685145 -138.877738)
			(xy 44.633211 -138.907722) (xy 44.577807 -138.930671) (xy 44.519882 -138.946192) (xy 44.460426 -138.95402)
			(xy 44.400458 -138.95402) (xy 44.341002 -138.946192) (xy 44.283077 -138.930671) (xy 44.227673 -138.907722)
			(xy 44.175739 -138.877738) (xy 44.128163 -138.841232) (xy 44.085758 -138.798827) (xy 44.049252 -138.751251)
			(xy 44.019268 -138.699317) (xy 43.996319 -138.643913) (xy 43.980798 -138.585988) (xy 43.97297 -138.526532)
			(xy 43.97248 -138.496548) (xy 4.30911 -138.496548) (xy 4.30911 -143.48714) (xy 66.599308 -143.48714)
			(xy 66.599308 -142.62354) (xy 66.599798 -142.593556) (xy 66.607626 -142.5341) (xy 66.623147 -142.476175)
			(xy 66.646096 -142.420771) (xy 66.67608 -142.368837) (xy 66.712586 -142.321261) (xy 66.754991 -142.278856)
			(xy 66.802567 -142.24235) (xy 66.854501 -142.212366) (xy 66.909905 -142.189417) (xy 66.96783 -142.173896)
			(xy 67.027286 -142.166068) (xy 67.087254 -142.166068) (xy 67.14671 -142.173896) (xy 67.204635 -142.189417)
			(xy 67.260039 -142.212366) (xy 67.311973 -142.24235) (xy 67.359549 -142.278856) (xy 67.401954 -142.321261)
			(xy 67.43846 -142.368837) (xy 67.468444 -142.420771) (xy 67.491393 -142.476175) (xy 67.506914 -142.5341)
			(xy 67.514742 -142.593556) (xy 67.515232 -142.62354) (xy 67.515232 -143.48714) (xy 67.514742 -143.517124)
			(xy 67.509326 -143.55826) (xy 68.047108 -143.55826) (xy 68.047108 -142.551912) (xy 68.047526 -142.541789)
			(xy 68.055272 -142.523084) (xy 68.069588 -142.508769) (xy 68.088293 -142.501025) (xy 68.098416 -142.500604)
			(xy 69.27977 -142.500604) (xy 69.28989 -142.50115) (xy 69.308604 -142.508861) (xy 69.32296 -142.523129)
			(xy 69.330787 -142.541795) (xy 69.331332 -142.551912) (xy 69.331332 -143.55826) (xy 72.584056 -143.55826)
			(xy 72.584056 -142.551912) (xy 72.584594 -142.541809) (xy 72.592319 -142.52314) (xy 72.6066 -142.508846)
			(xy 72.625262 -142.501103) (xy 72.635364 -142.500604) (xy 73.816464 -142.500604) (xy 73.826585 -142.501046)
			(xy 73.845288 -142.508783) (xy 73.859604 -142.523092) (xy 73.86735 -142.541792) (xy 73.867772 -142.551912)
			(xy 73.867772 -143.55826) (xy 73.86735 -143.568383) (xy 73.85961 -143.587091) (xy 73.845295 -143.601408)
			(xy 73.826587 -143.60915) (xy 73.816464 -143.609568) (xy 72.635364 -143.609568) (xy 72.625235 -143.609213)
			(xy 72.606525 -143.601447) (xy 72.592211 -143.587111) (xy 72.584472 -143.568389) (xy 72.584056 -143.55826)
			(xy 69.331332 -143.55826) (xy 69.330852 -143.568376) (xy 69.323123 -143.587072) (xy 69.308826 -143.601387)
			(xy 69.290139 -143.609139) (xy 69.280024 -143.609568) (xy 68.09867 -143.609568) (xy 68.088542 -143.609098)
			(xy 68.069822 -143.601362) (xy 68.055467 -143.587071) (xy 68.047647 -143.568385) (xy 68.047108 -143.55826)
			(xy 67.509326 -143.55826) (xy 67.506914 -143.57658) (xy 67.491393 -143.634505) (xy 67.487203 -143.64462)
			(xy 79.599536 -143.64462) (xy 79.599536 -143.401796) (xy 79.744316 -143.18107) (xy 79.793592 -143.105632)
			(xy 79.813404 -143.075406) (xy 79.818343 -143.066939) (xy 79.822081 -143.047717) (xy 79.818356 -143.028492)
			(xy 79.813404 -143.020034) (xy 79.66837 -142.797022) (xy 79.612744 -142.711678) (xy 79.608426 -142.705582)
			(xy 79.605124 -142.699994) (xy 79.604616 -142.698978) (xy 79.599536 -142.691104) (xy 79.599536 -142.44828)
			(xy 79.600177 -142.436762) (xy 79.610046 -142.415946) (xy 79.627875 -142.401358) (xy 79.638906 -142.397988)
			(xy 79.63916 -142.397988) (xy 79.651098 -142.396464) (xy 80.387698 -142.396464) (xy 80.394071 -142.396697)
			(xy 80.406408 -142.399904) (xy 80.412082 -142.402814) (xy 80.420089 -142.407561) (xy 80.432328 -142.421567)
			(xy 80.438867 -142.43898) (xy 80.43926 -142.44828) (xy 80.43926 -142.691104) (xy 80.22336 -143.021558)
			(xy 80.219354 -143.029785) (xy 80.216808 -143.047891) (xy 80.220745 -143.065746) (xy 80.225392 -143.073628)
			(xy 80.25765 -143.123412) (xy 80.273144 -143.147034) (xy 80.43926 -143.400526) (xy 80.43926 -143.479266)
			(xy 81.07426 -143.479266) (xy 81.07426 -142.615666) (xy 81.07475 -142.585682) (xy 81.082578 -142.526226)
			(xy 81.098099 -142.468301) (xy 81.121048 -142.412897) (xy 81.151032 -142.360963) (xy 81.187538 -142.313387)
			(xy 81.229943 -142.270982) (xy 81.277519 -142.234476) (xy 81.329453 -142.204492) (xy 81.384857 -142.181543)
			(xy 81.442782 -142.166022) (xy 81.502238 -142.158194) (xy 81.562206 -142.158194) (xy 81.621662 -142.166022)
			(xy 81.679587 -142.181543) (xy 81.734991 -142.204492) (xy 81.786925 -142.234476) (xy 81.834501 -142.270982)
			(xy 81.876906 -142.313387) (xy 81.913412 -142.360963) (xy 81.943396 -142.412897) (xy 81.966345 -142.468301)
			(xy 81.981866 -142.526226) (xy 81.989694 -142.585682) (xy 81.990184 -142.615666) (xy 81.990184 -143.479266)
			(xy 81.990055 -143.48714) (xy 182.69966 -143.48714) (xy 182.69966 -142.62354) (xy 182.70015 -142.593572)
			(xy 182.707973 -142.53415) (xy 182.723486 -142.476257) (xy 182.746422 -142.420884) (xy 182.776389 -142.368978)
			(xy 182.812876 -142.321428) (xy 182.855256 -142.279048) (xy 182.902806 -142.242561) (xy 182.954712 -142.212594)
			(xy 183.010085 -142.189658) (xy 183.067978 -142.174145) (xy 183.1274 -142.166322) (xy 183.187336 -142.166322)
			(xy 183.246758 -142.174145) (xy 183.304651 -142.189658) (xy 183.360024 -142.212594) (xy 183.41193 -142.242561)
			(xy 183.45948 -142.279048) (xy 183.50186 -142.321428) (xy 183.538347 -142.368978) (xy 183.568314 -142.420884)
			(xy 183.59125 -142.476257) (xy 183.606763 -142.53415) (xy 183.614586 -142.593572) (xy 183.615076 -142.62354)
			(xy 183.615076 -143.48714) (xy 183.614586 -143.517108) (xy 183.609168 -143.55826) (xy 184.146952 -143.55826)
			(xy 184.146952 -142.551912) (xy 184.147494 -142.54181) (xy 184.155218 -142.523141) (xy 184.169498 -142.508848)
			(xy 184.188158 -142.501104) (xy 184.19826 -142.500604) (xy 185.379614 -142.500604) (xy 185.389737 -142.501114)
			(xy 185.408452 -142.50884) (xy 185.422806 -142.523118) (xy 185.430631 -142.541792) (xy 185.431176 -142.551912)
			(xy 185.431176 -143.55826) (xy 188.6839 -143.55826) (xy 188.6839 -142.551912) (xy 188.684326 -142.54179)
			(xy 188.69207 -142.523087) (xy 188.706384 -142.508772) (xy 188.725086 -142.501027) (xy 188.735208 -142.500604)
			(xy 189.916308 -142.500604) (xy 189.926431 -142.50101) (xy 189.945136 -142.508761) (xy 189.95945 -142.523081)
			(xy 189.967194 -142.541788) (xy 189.967616 -142.551912) (xy 189.967616 -143.55826) (xy 189.967151 -143.568378)
			(xy 189.95942 -143.587078) (xy 189.945118 -143.601393) (xy 189.926425 -143.609142) (xy 189.916308 -143.609568)
			(xy 188.735208 -143.609568) (xy 188.725082 -143.609177) (xy 188.706372 -143.601425) (xy 188.692057 -143.587101)
			(xy 188.684317 -143.568386) (xy 188.6839 -143.55826) (xy 185.431176 -143.55826) (xy 185.430751 -143.568383)
			(xy 185.423011 -143.58709) (xy 185.408697 -143.601407) (xy 185.389991 -143.609149) (xy 185.379868 -143.609568)
			(xy 184.198514 -143.609568) (xy 184.188389 -143.609062) (xy 184.16967 -143.601341) (xy 184.155313 -143.58706)
			(xy 184.147492 -143.568382) (xy 184.146952 -143.55826) (xy 183.609168 -143.55826) (xy 183.606763 -143.57653)
			(xy 183.59125 -143.634423) (xy 183.587026 -143.64462) (xy 195.69938 -143.64462) (xy 195.69938 -143.401796)
			(xy 195.84416 -143.18107) (xy 195.893436 -143.105632) (xy 195.913248 -143.075406) (xy 195.918191 -143.06694)
			(xy 195.921934 -143.047717) (xy 195.918204 -143.028491) (xy 195.913248 -143.020034) (xy 195.768214 -142.797022)
			(xy 195.712588 -142.711678) (xy 195.70827 -142.705582) (xy 195.704968 -142.699994) (xy 195.70446 -142.698978)
			(xy 195.69938 -142.691104) (xy 195.69938 -142.44828) (xy 195.699989 -142.436757) (xy 195.709867 -142.415936)
			(xy 195.727712 -142.401352) (xy 195.73875 -142.397988) (xy 195.739004 -142.397988) (xy 195.750942 -142.396464)
			(xy 196.487542 -142.396464) (xy 196.493916 -142.396681) (xy 196.506253 -142.399899) (xy 196.511926 -142.402814)
			(xy 196.519942 -142.407546) (xy 196.532176 -142.421561) (xy 196.538712 -142.438978) (xy 196.539104 -142.44828)
			(xy 196.539104 -142.691104) (xy 196.323204 -143.021558) (xy 196.319194 -143.029784) (xy 196.316646 -143.047891)
			(xy 196.320586 -143.065747) (xy 196.325236 -143.073628) (xy 196.357494 -143.123412) (xy 196.372988 -143.147034)
			(xy 196.539104 -143.400526) (xy 196.539104 -143.479266) (xy 197.174612 -143.479266) (xy 197.174612 -142.615666)
			(xy 197.175102 -142.585698) (xy 197.182925 -142.526276) (xy 197.198438 -142.468383) (xy 197.221374 -142.41301)
			(xy 197.251341 -142.361104) (xy 197.287828 -142.313554) (xy 197.330208 -142.271174) (xy 197.377758 -142.234687)
			(xy 197.429664 -142.20472) (xy 197.485037 -142.181784) (xy 197.54293 -142.166271) (xy 197.602352 -142.158448)
			(xy 197.662288 -142.158448) (xy 197.72171 -142.166271) (xy 197.779603 -142.181784) (xy 197.834976 -142.20472)
			(xy 197.886882 -142.234687) (xy 197.934432 -142.271174) (xy 197.976812 -142.313554) (xy 198.013299 -142.361104)
			(xy 198.043266 -142.41301) (xy 198.066202 -142.468383) (xy 198.081715 -142.526276) (xy 198.089538 -142.585698)
			(xy 198.090028 -142.615666) (xy 198.090028 -143.479266) (xy 198.089899 -143.48714) (xy 298.799504 -143.48714)
			(xy 298.799504 -142.62354) (xy 298.799994 -142.593572) (xy 298.807817 -142.53415) (xy 298.82333 -142.476257)
			(xy 298.846266 -142.420884) (xy 298.876233 -142.368978) (xy 298.91272 -142.321428) (xy 298.9551 -142.279048)
			(xy 299.00265 -142.242561) (xy 299.054556 -142.212594) (xy 299.109929 -142.189658) (xy 299.167822 -142.174145)
			(xy 299.227244 -142.166322) (xy 299.28718 -142.166322) (xy 299.346602 -142.174145) (xy 299.404495 -142.189658)
			(xy 299.459868 -142.212594) (xy 299.511774 -142.242561) (xy 299.559324 -142.279048) (xy 299.601704 -142.321428)
			(xy 299.638191 -142.368978) (xy 299.668158 -142.420884) (xy 299.691094 -142.476257) (xy 299.706607 -142.53415)
			(xy 299.71443 -142.593572) (xy 299.71492 -142.62354) (xy 299.71492 -143.48714) (xy 299.71443 -143.517108)
			(xy 299.709012 -143.55826) (xy 300.247304 -143.55826) (xy 300.247304 -142.551912) (xy 300.247726 -142.54179)
			(xy 300.255471 -142.523086) (xy 300.269786 -142.508771) (xy 300.28849 -142.501026) (xy 300.298612 -142.500604)
			(xy 301.479712 -142.500604) (xy 301.489822 -142.501076) (xy 301.508501 -142.508818) (xy 301.522796 -142.523119)
			(xy 301.530529 -142.541802) (xy 301.53102 -142.551912) (xy 301.53102 -143.55826) (xy 304.783744 -143.55826)
			(xy 304.783744 -142.551912) (xy 304.78423 -142.541766) (xy 304.792011 -142.523024) (xy 304.806387 -142.508702)
			(xy 304.825158 -142.500992) (xy 304.835306 -142.500604) (xy 306.016406 -142.500604) (xy 306.026529 -142.501121)
			(xy 306.045243 -142.508844) (xy 306.059598 -142.52312) (xy 306.067423 -142.541792) (xy 306.067968 -142.551912)
			(xy 306.067968 -143.55826) (xy 306.067545 -143.568415) (xy 306.059757 -143.587173) (xy 306.045359 -143.601499)
			(xy 306.026563 -143.609194) (xy 306.016406 -143.609568) (xy 304.835306 -143.609568) (xy 304.825181 -143.609069)
			(xy 304.806461 -143.601344) (xy 304.792105 -143.587062) (xy 304.784284 -143.568383) (xy 304.783744 -143.55826)
			(xy 301.53102 -143.55826) (xy 301.530552 -143.568377) (xy 301.52282 -143.587076) (xy 301.50852 -143.601391)
			(xy 301.489829 -143.609141) (xy 301.479712 -143.609568) (xy 300.298612 -143.609568) (xy 300.288486 -143.609173)
			(xy 300.269777 -143.601423) (xy 300.255461 -143.5871) (xy 300.247721 -143.568386) (xy 300.247304 -143.55826)
			(xy 299.709012 -143.55826) (xy 299.706607 -143.57653) (xy 299.691094 -143.634423) (xy 299.68687 -143.64462)
			(xy 311.799224 -143.64462) (xy 311.799224 -143.417036) (xy 311.799478 -143.412972) (xy 311.799732 -143.410432)
			(xy 311.799732 -143.401796) (xy 311.80532 -143.39316) (xy 311.80659 -143.391128) (xy 311.807606 -143.389096)
			(xy 312.004964 -143.088106) (xy 312.008843 -143.081784) (xy 312.013096 -143.06758) (xy 312.013346 -143.060166)
			(xy 312.013346 -143.034512) (xy 312.013155 -143.027177) (xy 312.009015 -143.013106) (xy 312.005218 -143.006826)
			(xy 311.807352 -142.703804) (xy 311.805066 -142.699994) (xy 311.804812 -142.699486) (xy 311.803796 -142.697708)
			(xy 311.799732 -142.691104) (xy 311.799732 -142.682976) (xy 311.799478 -142.680436) (xy 311.799224 -142.676372)
			(xy 311.799224 -142.44828) (xy 311.799597 -142.438052) (xy 311.807434 -142.419157) (xy 311.821907 -142.4047)
			(xy 311.840812 -142.396885) (xy 311.85104 -142.396464) (xy 312.58764 -142.396464) (xy 312.597848 -142.396949)
			(xy 312.616707 -142.404771) (xy 312.63114 -142.41921) (xy 312.638955 -142.438072) (xy 312.639456 -142.44828)
			(xy 312.639456 -142.675864) (xy 312.639202 -142.679928) (xy 312.638948 -142.682468) (xy 312.638948 -142.691104)
			(xy 312.633106 -142.700502) (xy 312.632344 -142.701772) (xy 312.631074 -142.703804) (xy 312.425334 -143.01851)
			(xy 312.420242 -143.02701) (xy 312.416441 -143.046442) (xy 312.420274 -143.065868) (xy 312.425334 -143.07439)
			(xy 312.631074 -143.387826) (xy 312.63209 -143.389858) (xy 312.63336 -143.39189) (xy 312.638948 -143.400526)
			(xy 312.638948 -143.409162) (xy 312.639202 -143.411702) (xy 312.639456 -143.415766) (xy 312.639456 -143.479266)
			(xy 313.274456 -143.479266) (xy 313.274456 -142.615666) (xy 313.274946 -142.585698) (xy 313.282769 -142.526276)
			(xy 313.298282 -142.468383) (xy 313.321218 -142.41301) (xy 313.351185 -142.361104) (xy 313.387672 -142.313554)
			(xy 313.430052 -142.271174) (xy 313.477602 -142.234687) (xy 313.529508 -142.20472) (xy 313.584881 -142.181784)
			(xy 313.642774 -142.166271) (xy 313.702196 -142.158448) (xy 313.762132 -142.158448) (xy 313.821554 -142.166271)
			(xy 313.879447 -142.181784) (xy 313.93482 -142.20472) (xy 313.986726 -142.234687) (xy 314.034276 -142.271174)
			(xy 314.076656 -142.313554) (xy 314.113143 -142.361104) (xy 314.14311 -142.41301) (xy 314.166046 -142.468383)
			(xy 314.181559 -142.526276) (xy 314.189382 -142.585698) (xy 314.189872 -142.615666) (xy 314.189872 -143.479266)
			(xy 314.189743 -143.48714) (xy 414.899348 -143.48714) (xy 414.899348 -142.62354) (xy 414.899838 -142.593556)
			(xy 414.907666 -142.5341) (xy 414.923187 -142.476175) (xy 414.946136 -142.420771) (xy 414.97612 -142.368837)
			(xy 415.012626 -142.321261) (xy 415.055031 -142.278856) (xy 415.102607 -142.24235) (xy 415.154541 -142.212366)
			(xy 415.209945 -142.189417) (xy 415.26787 -142.173896) (xy 415.327326 -142.166068) (xy 415.387294 -142.166068)
			(xy 415.44675 -142.173896) (xy 415.504675 -142.189417) (xy 415.560079 -142.212366) (xy 415.612013 -142.24235)
			(xy 415.659589 -142.278856) (xy 415.701994 -142.321261) (xy 415.7385 -142.368837) (xy 415.768484 -142.420771)
			(xy 415.791433 -142.476175) (xy 415.806954 -142.5341) (xy 415.814782 -142.593556) (xy 415.815272 -142.62354)
			(xy 415.815272 -143.48714) (xy 415.814782 -143.517124) (xy 415.809366 -143.55826) (xy 416.347148 -143.55826)
			(xy 416.347148 -142.551912) (xy 416.347694 -142.54181) (xy 416.355418 -142.523142) (xy 416.369695 -142.508849)
			(xy 416.388355 -142.501105) (xy 416.398456 -142.500604) (xy 417.57981 -142.500604) (xy 417.589933 -142.501117)
			(xy 417.608647 -142.508842) (xy 417.623002 -142.523119) (xy 417.630827 -142.541792) (xy 417.631372 -142.551912)
			(xy 417.631372 -143.55826) (xy 420.884096 -143.55826) (xy 420.884096 -142.551912) (xy 420.884526 -142.541791)
			(xy 420.892269 -142.523088) (xy 420.906581 -142.508774) (xy 420.925283 -142.501027) (xy 420.935404 -142.500604)
			(xy 422.116504 -142.500604) (xy 422.126627 -142.501013) (xy 422.145332 -142.508763) (xy 422.159646 -142.523082)
			(xy 422.16739 -142.541789) (xy 422.167812 -142.551912) (xy 422.167812 -143.55826) (xy 422.167351 -143.568378)
			(xy 422.159619 -143.587079) (xy 422.145316 -143.601394) (xy 422.126622 -143.609143) (xy 422.116504 -143.609568)
			(xy 420.935404 -143.609568) (xy 420.925278 -143.60918) (xy 420.906568 -143.601427) (xy 420.892253 -143.587102)
			(xy 420.884513 -143.568386) (xy 420.884096 -143.55826) (xy 417.631372 -143.55826) (xy 417.63095 -143.568383)
			(xy 417.62321 -143.587091) (xy 417.608895 -143.601408) (xy 417.590187 -143.60915) (xy 417.580064 -143.609568)
			(xy 416.39871 -143.609568) (xy 416.388585 -143.609065) (xy 416.369865 -143.601342) (xy 416.355509 -143.587061)
			(xy 416.347688 -143.568382) (xy 416.347148 -143.55826) (xy 415.809366 -143.55826) (xy 415.806954 -143.57658)
			(xy 415.791433 -143.634505) (xy 415.787243 -143.64462) (xy 427.899576 -143.64462) (xy 427.899576 -143.401796)
			(xy 428.044356 -143.18107) (xy 428.093632 -143.105632) (xy 428.113444 -143.075406) (xy 428.118388 -143.066941)
			(xy 428.12213 -143.047717) (xy 428.1184 -143.028491) (xy 428.113444 -143.020034) (xy 427.96841 -142.797022)
			(xy 427.912784 -142.711678) (xy 427.908466 -142.705582) (xy 427.905164 -142.699994) (xy 427.904656 -142.698978)
			(xy 427.899576 -142.691104) (xy 427.899576 -142.44828) (xy 427.900188 -142.436758) (xy 427.910065 -142.415937)
			(xy 427.927908 -142.401352) (xy 427.938946 -142.397988) (xy 427.9392 -142.397988) (xy 427.951138 -142.396464)
			(xy 428.687738 -142.396464) (xy 428.694112 -142.396683) (xy 428.706449 -142.3999) (xy 428.712122 -142.402814)
			(xy 428.720137 -142.407548) (xy 428.732371 -142.421562) (xy 428.738908 -142.438979) (xy 428.7393 -142.44828)
			(xy 428.7393 -142.691104) (xy 428.5234 -143.021558) (xy 428.519391 -143.029784) (xy 428.516843 -143.047891)
			(xy 428.520782 -143.065747) (xy 428.525432 -143.073628) (xy 428.55769 -143.123412) (xy 428.573184 -143.147034)
			(xy 428.7393 -143.400526) (xy 428.7393 -143.479266) (xy 429.3743 -143.479266) (xy 429.3743 -142.615666)
			(xy 429.37479 -142.585682) (xy 429.382618 -142.526226) (xy 429.398139 -142.468301) (xy 429.421088 -142.412897)
			(xy 429.451072 -142.360963) (xy 429.487578 -142.313387) (xy 429.529983 -142.270982) (xy 429.577559 -142.234476)
			(xy 429.629493 -142.204492) (xy 429.684897 -142.181543) (xy 429.742822 -142.166022) (xy 429.802278 -142.158194)
			(xy 429.862246 -142.158194) (xy 429.921702 -142.166022) (xy 429.979627 -142.181543) (xy 430.035031 -142.204492)
			(xy 430.086965 -142.234476) (xy 430.134541 -142.270982) (xy 430.176946 -142.313387) (xy 430.213452 -142.360963)
			(xy 430.243436 -142.412897) (xy 430.266385 -142.468301) (xy 430.281906 -142.526226) (xy 430.289734 -142.585682)
			(xy 430.290224 -142.615666) (xy 430.290224 -143.479266) (xy 430.289734 -143.50925) (xy 430.281906 -143.568706)
			(xy 430.266385 -143.626631) (xy 430.243436 -143.682035) (xy 430.213452 -143.733969) (xy 430.176946 -143.781545)
			(xy 430.134541 -143.82395) (xy 430.086965 -143.860456) (xy 430.035031 -143.89044) (xy 429.979627 -143.913389)
			(xy 429.921702 -143.92891) (xy 429.862246 -143.936738) (xy 429.802278 -143.936738) (xy 429.742822 -143.92891)
			(xy 429.684897 -143.913389) (xy 429.629493 -143.89044) (xy 429.577559 -143.860456) (xy 429.529983 -143.82395)
			(xy 429.487578 -143.781545) (xy 429.451072 -143.733969) (xy 429.421088 -143.682035) (xy 429.398139 -143.626631)
			(xy 429.382618 -143.568706) (xy 429.37479 -143.50925) (xy 429.3743 -143.479266) (xy 428.7393 -143.479266)
			(xy 428.7393 -143.64462) (xy 428.738706 -143.656145) (xy 428.728823 -143.676969) (xy 428.710971 -143.691551)
			(xy 428.69993 -143.694912) (xy 428.699676 -143.694912) (xy 428.687738 -143.696436) (xy 427.951138 -143.696436)
			(xy 427.944764 -143.696226) (xy 427.932427 -143.693003) (xy 427.926754 -143.690086) (xy 427.918755 -143.685327)
			(xy 427.906512 -143.671328) (xy 427.89997 -143.653919) (xy 427.899576 -143.64462) (xy 415.787243 -143.64462)
			(xy 415.768484 -143.689909) (xy 415.7385 -143.741843) (xy 415.701994 -143.789419) (xy 415.659589 -143.831824)
			(xy 415.612013 -143.86833) (xy 415.560079 -143.898314) (xy 415.504675 -143.921263) (xy 415.44675 -143.936784)
			(xy 415.387294 -143.944612) (xy 415.327326 -143.944612) (xy 415.26787 -143.936784) (xy 415.209945 -143.921263)
			(xy 415.154541 -143.898314) (xy 415.102607 -143.86833) (xy 415.055031 -143.831824) (xy 415.012626 -143.789419)
			(xy 414.97612 -143.741843) (xy 414.946136 -143.689909) (xy 414.923187 -143.634505) (xy 414.907666 -143.57658)
			(xy 414.899838 -143.517124) (xy 414.899348 -143.48714) (xy 314.189743 -143.48714) (xy 314.189382 -143.509234)
			(xy 314.181559 -143.568656) (xy 314.166046 -143.626549) (xy 314.14311 -143.681922) (xy 314.113143 -143.733828)
			(xy 314.076656 -143.781378) (xy 314.034276 -143.823758) (xy 313.986726 -143.860245) (xy 313.93482 -143.890212)
			(xy 313.879447 -143.913148) (xy 313.821554 -143.928661) (xy 313.762132 -143.936484) (xy 313.702196 -143.936484)
			(xy 313.642774 -143.928661) (xy 313.584881 -143.913148) (xy 313.529508 -143.890212) (xy 313.477602 -143.860245)
			(xy 313.430052 -143.823758) (xy 313.387672 -143.781378) (xy 313.351185 -143.733828) (xy 313.321218 -143.681922)
			(xy 313.298282 -143.626549) (xy 313.282769 -143.568656) (xy 313.274946 -143.509234) (xy 313.274456 -143.479266)
			(xy 312.639456 -143.479266) (xy 312.639456 -143.64462) (xy 312.638936 -143.654824) (xy 312.631124 -143.673679)
			(xy 312.616695 -143.688113) (xy 312.597844 -143.695932) (xy 312.58764 -143.696436) (xy 311.85104 -143.696436)
			(xy 311.840823 -143.695956) (xy 311.821941 -143.688149) (xy 311.807484 -143.67371) (xy 311.799656 -143.654836)
			(xy 311.799224 -143.64462) (xy 299.68687 -143.64462) (xy 299.668158 -143.689796) (xy 299.638191 -143.741702)
			(xy 299.601704 -143.789252) (xy 299.559324 -143.831632) (xy 299.511774 -143.868119) (xy 299.459868 -143.898086)
			(xy 299.404495 -143.921022) (xy 299.346602 -143.936535) (xy 299.28718 -143.944358) (xy 299.227244 -143.944358)
			(xy 299.167822 -143.936535) (xy 299.109929 -143.921022) (xy 299.054556 -143.898086) (xy 299.00265 -143.868119)
			(xy 298.9551 -143.831632) (xy 298.91272 -143.789252) (xy 298.876233 -143.741702) (xy 298.846266 -143.689796)
			(xy 298.82333 -143.634423) (xy 298.807817 -143.57653) (xy 298.799994 -143.517108) (xy 298.799504 -143.48714)
			(xy 198.089899 -143.48714) (xy 198.089538 -143.509234) (xy 198.081715 -143.568656) (xy 198.066202 -143.626549)
			(xy 198.043266 -143.681922) (xy 198.013299 -143.733828) (xy 197.976812 -143.781378) (xy 197.934432 -143.823758)
			(xy 197.886882 -143.860245) (xy 197.834976 -143.890212) (xy 197.779603 -143.913148) (xy 197.72171 -143.928661)
			(xy 197.662288 -143.936484) (xy 197.602352 -143.936484) (xy 197.54293 -143.928661) (xy 197.485037 -143.913148)
			(xy 197.429664 -143.890212) (xy 197.377758 -143.860245) (xy 197.330208 -143.823758) (xy 197.287828 -143.781378)
			(xy 197.251341 -143.733828) (xy 197.221374 -143.681922) (xy 197.198438 -143.626549) (xy 197.182925 -143.568656)
			(xy 197.175102 -143.509234) (xy 197.174612 -143.479266) (xy 196.539104 -143.479266) (xy 196.539104 -143.64462)
			(xy 196.538507 -143.656144) (xy 196.528625 -143.676968) (xy 196.510775 -143.691551) (xy 196.499734 -143.694912)
			(xy 196.49948 -143.694912) (xy 196.487542 -143.696436) (xy 195.750942 -143.696436) (xy 195.744568 -143.696224)
			(xy 195.732231 -143.693002) (xy 195.726558 -143.690086) (xy 195.71856 -143.685326) (xy 195.706316 -143.671327)
			(xy 195.699774 -143.653919) (xy 195.69938 -143.64462) (xy 183.587026 -143.64462) (xy 183.568314 -143.689796)
			(xy 183.538347 -143.741702) (xy 183.50186 -143.789252) (xy 183.45948 -143.831632) (xy 183.41193 -143.868119)
			(xy 183.360024 -143.898086) (xy 183.304651 -143.921022) (xy 183.246758 -143.936535) (xy 183.187336 -143.944358)
			(xy 183.1274 -143.944358) (xy 183.067978 -143.936535) (xy 183.010085 -143.921022) (xy 182.954712 -143.898086)
			(xy 182.902806 -143.868119) (xy 182.855256 -143.831632) (xy 182.812876 -143.789252) (xy 182.776389 -143.741702)
			(xy 182.746422 -143.689796) (xy 182.723486 -143.634423) (xy 182.707973 -143.57653) (xy 182.70015 -143.517108)
			(xy 182.69966 -143.48714) (xy 81.990055 -143.48714) (xy 81.989694 -143.50925) (xy 81.981866 -143.568706)
			(xy 81.966345 -143.626631) (xy 81.943396 -143.682035) (xy 81.913412 -143.733969) (xy 81.876906 -143.781545)
			(xy 81.834501 -143.82395) (xy 81.786925 -143.860456) (xy 81.734991 -143.89044) (xy 81.679587 -143.913389)
			(xy 81.621662 -143.92891) (xy 81.562206 -143.936738) (xy 81.502238 -143.936738) (xy 81.442782 -143.92891)
			(xy 81.384857 -143.913389) (xy 81.329453 -143.89044) (xy 81.277519 -143.860456) (xy 81.229943 -143.82395)
			(xy 81.187538 -143.781545) (xy 81.151032 -143.733969) (xy 81.121048 -143.682035) (xy 81.098099 -143.626631)
			(xy 81.082578 -143.568706) (xy 81.07475 -143.50925) (xy 81.07426 -143.479266) (xy 80.43926 -143.479266)
			(xy 80.43926 -143.64462) (xy 80.438622 -143.656138) (xy 80.428752 -143.676955) (xy 80.410922 -143.691542)
			(xy 80.39989 -143.694912) (xy 80.399636 -143.694912) (xy 80.387698 -143.696436) (xy 79.651098 -143.696436)
			(xy 79.644725 -143.696205) (xy 79.632388 -143.692996) (xy 79.626714 -143.690086) (xy 79.618706 -143.68534)
			(xy 79.606468 -143.671333) (xy 79.599929 -143.65392) (xy 79.599536 -143.64462) (xy 67.487203 -143.64462)
			(xy 67.468444 -143.689909) (xy 67.43846 -143.741843) (xy 67.401954 -143.789419) (xy 67.359549 -143.831824)
			(xy 67.311973 -143.86833) (xy 67.260039 -143.898314) (xy 67.204635 -143.921263) (xy 67.14671 -143.936784)
			(xy 67.087254 -143.944612) (xy 67.027286 -143.944612) (xy 66.96783 -143.936784) (xy 66.909905 -143.921263)
			(xy 66.854501 -143.898314) (xy 66.802567 -143.86833) (xy 66.754991 -143.831824) (xy 66.712586 -143.789419)
			(xy 66.67608 -143.741843) (xy 66.646096 -143.689909) (xy 66.623147 -143.634505) (xy 66.607626 -143.57658)
			(xy 66.599798 -143.517124) (xy 66.599308 -143.48714) (xy 4.30911 -143.48714) (xy 4.30911 -145.287238)
			(xy 64.745108 -145.287238) (xy 64.745108 -144.423638) (xy 64.745598 -144.393654) (xy 64.753426 -144.334198)
			(xy 64.768947 -144.276273) (xy 64.791896 -144.220869) (xy 64.82188 -144.168935) (xy 64.858386 -144.121359)
			(xy 64.900791 -144.078954) (xy 64.948367 -144.042448) (xy 65.000301 -144.012464) (xy 65.055705 -143.989515)
			(xy 65.11363 -143.973994) (xy 65.173086 -143.966166) (xy 65.233054 -143.966166) (xy 65.29251 -143.973994)
			(xy 65.350435 -143.989515) (xy 65.405839 -144.012464) (xy 65.457773 -144.042448) (xy 65.505349 -144.078954)
			(xy 65.547754 -144.121359) (xy 65.58426 -144.168935) (xy 65.614244 -144.220869) (xy 65.637193 -144.276273)
			(xy 65.652714 -144.334198) (xy 65.660542 -144.393654) (xy 65.661032 -144.423638) (xy 65.661032 -145.287238)
			(xy 65.660542 -145.317222) (xy 65.655159 -145.358104) (xy 68.047108 -145.358104) (xy 68.047108 -144.351756)
			(xy 68.047549 -144.341643) (xy 68.055303 -144.322963) (xy 68.069613 -144.308669) (xy 68.088303 -144.300938)
			(xy 68.098416 -144.300448) (xy 69.27977 -144.300448) (xy 69.289896 -144.300951) (xy 69.308618 -144.308671)
			(xy 69.322976 -144.322952) (xy 69.330794 -144.341633) (xy 69.331332 -144.351756) (xy 69.331332 -145.358104)
			(xy 72.584056 -145.358104) (xy 72.584056 -144.351756) (xy 72.584548 -144.34165) (xy 72.592292 -144.322979)
			(xy 72.606586 -144.308687) (xy 72.625258 -144.300946) (xy 72.635364 -144.300448) (xy 73.816464 -144.300448)
			(xy 73.826564 -144.301014) (xy 73.845231 -144.30873) (xy 73.859526 -144.323001) (xy 73.867271 -144.341657)
			(xy 73.867772 -144.351756) (xy 73.867772 -145.358104) (xy 73.867386 -145.36823) (xy 73.859632 -145.386939)
			(xy 73.845306 -145.401254) (xy 73.826591 -145.408994) (xy 73.816464 -145.409412) (xy 72.635364 -145.409412)
			(xy 72.625254 -145.408945) (xy 72.606578 -145.401197) (xy 72.592285 -145.386895) (xy 72.584549 -145.368214)
			(xy 72.584056 -145.358104) (xy 69.331332 -145.358104) (xy 69.330819 -145.368209) (xy 69.323086 -145.386881)
			(xy 69.308798 -145.401175) (xy 69.290129 -145.408915) (xy 69.280024 -145.409412) (xy 68.09867 -145.409412)
			(xy 68.088548 -145.4089) (xy 68.069836 -145.401172) (xy 68.055482 -145.386894) (xy 68.047655 -145.368223)
			(xy 68.047108 -145.358104) (xy 65.655159 -145.358104) (xy 65.652714 -145.376678) (xy 65.637193 -145.434603)
			(xy 65.630373 -145.451068) (xy 82.241644 -145.451068) (xy 82.241644 -145.208244) (xy 82.360516 -145.026888)
			(xy 82.423 -144.931384) (xy 82.44713 -144.894554) (xy 82.450989 -144.888221) (xy 82.455255 -144.874025)
			(xy 82.455512 -144.866614) (xy 82.455512 -144.840706) (xy 82.455323 -144.834556) (xy 82.452367 -144.822615)
			(xy 82.44967 -144.817084) (xy 82.336132 -144.643094) (xy 82.316066 -144.612106) (xy 82.310478 -144.60347)
			(xy 82.250026 -144.51076) (xy 82.249518 -144.509998) (xy 82.24901 -144.509236) (xy 82.248756 -144.508728)
			(xy 82.248248 -144.507966) (xy 82.241644 -144.497552) (xy 82.241644 -144.254728) (xy 82.242232 -144.24317)
			(xy 82.252216 -144.222317) (xy 82.270179 -144.20776) (xy 82.281268 -144.204436) (xy 82.293206 -144.202912)
			(xy 83.029806 -144.202912) (xy 83.040565 -144.203418) (xy 83.060254 -144.212094) (xy 83.067906 -144.219676)
			(xy 83.074117 -144.227066) (xy 83.081022 -144.24508) (xy 83.081368 -144.254728) (xy 83.081368 -144.497552)
			(xy 82.865468 -144.828006) (xy 82.861424 -144.836217) (xy 82.858891 -144.854334) (xy 82.862844 -144.872194)
			(xy 82.8675 -144.880076) (xy 82.899758 -144.92986) (xy 83.081368 -145.206974) (xy 83.081368 -145.285714)
			(xy 83.716368 -145.285714) (xy 83.716368 -144.422114) (xy 83.716858 -144.39213) (xy 83.724686 -144.332674)
			(xy 83.740207 -144.274749) (xy 83.763156 -144.219345) (xy 83.79314 -144.167411) (xy 83.829646 -144.119835)
			(xy 83.872051 -144.07743) (xy 83.919627 -144.040924) (xy 83.971561 -144.01094) (xy 84.026965 -143.987991)
			(xy 84.08489 -143.97247) (xy 84.144346 -143.964642) (xy 84.204314 -143.964642) (xy 84.26377 -143.97247)
			(xy 84.321695 -143.987991) (xy 84.377099 -144.01094) (xy 84.429033 -144.040924) (xy 84.476609 -144.07743)
			(xy 84.519014 -144.119835) (xy 84.55552 -144.167411) (xy 84.585504 -144.219345) (xy 84.608453 -144.274749)
			(xy 84.623974 -144.332674) (xy 84.631802 -144.39213) (xy 84.632292 -144.422114) (xy 84.632292 -145.285714)
			(xy 84.632267 -145.287238) (xy 180.84546 -145.287238) (xy 180.84546 -144.423638) (xy 180.84595 -144.39367)
			(xy 180.853773 -144.334248) (xy 180.869286 -144.276355) (xy 180.892222 -144.220982) (xy 180.922189 -144.169076)
			(xy 180.958676 -144.121526) (xy 181.001056 -144.079146) (xy 181.048606 -144.042659) (xy 181.100512 -144.012692)
			(xy 181.155885 -143.989756) (xy 181.213778 -143.974243) (xy 181.2732 -143.96642) (xy 181.333136 -143.96642)
			(xy 181.392558 -143.974243) (xy 181.450451 -143.989756) (xy 181.505824 -144.012692) (xy 181.55773 -144.042659)
			(xy 181.60528 -144.079146) (xy 181.64766 -144.121526) (xy 181.684147 -144.169076) (xy 181.714114 -144.220982)
			(xy 181.73705 -144.276355) (xy 181.752563 -144.334248) (xy 181.760386 -144.39367) (xy 181.760876 -144.423638)
			(xy 181.760876 -145.287238) (xy 181.760386 -145.317206) (xy 181.755002 -145.358104) (xy 184.146952 -145.358104)
			(xy 184.146952 -144.351756) (xy 184.147448 -144.34165) (xy 184.155191 -144.32298) (xy 184.169484 -144.308689)
			(xy 184.188154 -144.300947) (xy 184.19826 -144.300448) (xy 185.379614 -144.300448) (xy 185.389743 -144.300916)
			(xy 185.408465 -144.308649) (xy 185.422821 -144.322942) (xy 185.430639 -144.34163) (xy 185.431176 -144.351756)
			(xy 185.431176 -145.358104) (xy 188.6839 -145.358104) (xy 188.6839 -144.351756) (xy 188.684349 -144.341644)
			(xy 188.692101 -144.322965) (xy 188.706409 -144.308672) (xy 188.725096 -144.300939) (xy 188.735208 -144.300448)
			(xy 189.916308 -144.300448) (xy 189.926411 -144.300977) (xy 189.945079 -144.308708) (xy 189.959372 -144.322991)
			(xy 189.967115 -144.341654) (xy 189.967616 -144.351756) (xy 189.967616 -145.358104) (xy 189.967118 -145.368211)
			(xy 189.959382 -145.386886) (xy 189.94509 -145.40118) (xy 189.926415 -145.408918) (xy 189.916308 -145.409412)
			(xy 188.735208 -145.409412) (xy 188.725088 -145.408978) (xy 188.706386 -145.401234) (xy 188.692072 -145.386924)
			(xy 188.684325 -145.368224) (xy 188.6839 -145.358104) (xy 185.431176 -145.358104) (xy 185.430787 -145.36823)
			(xy 185.423033 -145.386938) (xy 185.408708 -145.401253) (xy 185.389994 -145.408994) (xy 185.379868 -145.409412)
			(xy 184.198514 -145.409412) (xy 184.188395 -145.408864) (xy 184.169684 -145.40115) (xy 184.155329 -145.386883)
			(xy 184.1475 -145.36822) (xy 184.146952 -145.358104) (xy 181.755002 -145.358104) (xy 181.752563 -145.376628)
			(xy 181.73705 -145.434521) (xy 181.730196 -145.451068) (xy 198.341488 -145.451068) (xy 198.341488 -145.208244)
			(xy 198.486268 -144.987518) (xy 198.535544 -144.91208) (xy 198.555356 -144.881854) (xy 198.560342 -144.87341)
			(xy 198.564069 -144.854173) (xy 198.560322 -144.83494) (xy 198.555356 -144.826482) (xy 198.410322 -144.60347)
			(xy 198.354696 -144.518126) (xy 198.350378 -144.51203) (xy 198.347076 -144.506442) (xy 198.346568 -144.505426)
			(xy 198.341488 -144.497552) (xy 198.341488 -144.254728) (xy 198.342127 -144.243208) (xy 198.35199 -144.222387)
			(xy 198.369824 -144.207801) (xy 198.380858 -144.204436) (xy 198.381112 -144.204436) (xy 198.39305 -144.202912)
			(xy 199.12965 -144.202912) (xy 199.136024 -144.203132) (xy 199.148361 -144.206349) (xy 199.154034 -144.209262)
			(xy 199.162029 -144.214025) (xy 199.174265 -144.228027) (xy 199.180812 -144.245431) (xy 199.181212 -144.254728)
			(xy 199.181212 -144.497552) (xy 198.965312 -144.828006) (xy 198.961263 -144.836216) (xy 198.958728 -144.854334)
			(xy 198.962685 -144.872195) (xy 198.967344 -144.880076) (xy 198.999602 -144.92986) (xy 199.015096 -144.953482)
			(xy 199.181212 -145.206974) (xy 199.181212 -145.285714) (xy 199.81672 -145.285714) (xy 199.81672 -144.422114)
			(xy 199.81721 -144.392146) (xy 199.825033 -144.332724) (xy 199.840546 -144.274831) (xy 199.863482 -144.219458)
			(xy 199.893449 -144.167552) (xy 199.929936 -144.120002) (xy 199.972316 -144.077622) (xy 200.019866 -144.041135)
			(xy 200.071772 -144.011168) (xy 200.127145 -143.988232) (xy 200.185038 -143.972719) (xy 200.24446 -143.964896)
			(xy 200.304396 -143.964896) (xy 200.363818 -143.972719) (xy 200.421711 -143.988232) (xy 200.477084 -144.011168)
			(xy 200.52899 -144.041135) (xy 200.57654 -144.077622) (xy 200.61892 -144.120002) (xy 200.655407 -144.167552)
			(xy 200.685374 -144.219458) (xy 200.70831 -144.274831) (xy 200.723823 -144.332724) (xy 200.731646 -144.392146)
			(xy 200.732136 -144.422114) (xy 200.732136 -145.285714) (xy 200.732111 -145.287238) (xy 296.945304 -145.287238)
			(xy 296.945304 -144.423638) (xy 296.945794 -144.39367) (xy 296.953617 -144.334248) (xy 296.96913 -144.276355)
			(xy 296.992066 -144.220982) (xy 297.022033 -144.169076) (xy 297.05852 -144.121526) (xy 297.1009 -144.079146)
			(xy 297.14845 -144.042659) (xy 297.200356 -144.012692) (xy 297.255729 -143.989756) (xy 297.313622 -143.974243)
			(xy 297.373044 -143.96642) (xy 297.43298 -143.96642) (xy 297.492402 -143.974243) (xy 297.550295 -143.989756)
			(xy 297.605668 -144.012692) (xy 297.657574 -144.042659) (xy 297.705124 -144.079146) (xy 297.747504 -144.121526)
			(xy 297.783991 -144.169076) (xy 297.813958 -144.220982) (xy 297.836894 -144.276355) (xy 297.852407 -144.334248)
			(xy 297.86023 -144.39367) (xy 297.86072 -144.423638) (xy 297.86072 -145.287238) (xy 297.86023 -145.317206)
			(xy 297.854846 -145.358104) (xy 300.247304 -145.358104) (xy 300.247304 -144.351756) (xy 300.247749 -144.341644)
			(xy 300.255502 -144.322964) (xy 300.269811 -144.308671) (xy 300.288499 -144.300938) (xy 300.298612 -144.300448)
			(xy 301.479712 -144.300448) (xy 301.489815 -144.300974) (xy 301.508483 -144.308706) (xy 301.522776 -144.32299)
			(xy 301.530519 -144.341653) (xy 301.53102 -144.351756) (xy 301.53102 -145.358104) (xy 304.783744 -145.358104)
			(xy 304.783744 -144.351756) (xy 304.784185 -144.341606) (xy 304.791984 -144.322864) (xy 304.806374 -144.308544)
			(xy 304.825154 -144.300836) (xy 304.835306 -144.300448) (xy 306.016406 -144.300448) (xy 306.026534 -144.300922)
			(xy 306.045257 -144.308653) (xy 306.059613 -144.322943) (xy 306.067431 -144.34163) (xy 306.067968 -144.351756)
			(xy 306.067968 -145.358104) (xy 306.067581 -145.368262) (xy 306.059778 -145.387021) (xy 306.04537 -145.401345)
			(xy 306.026567 -145.409039) (xy 306.016406 -145.409412) (xy 304.835306 -145.409412) (xy 304.825186 -145.40887)
			(xy 304.806475 -145.401154) (xy 304.79212 -145.386885) (xy 304.784292 -145.368221) (xy 304.783744 -145.358104)
			(xy 301.53102 -145.358104) (xy 301.530519 -145.36821) (xy 301.522783 -145.386885) (xy 301.508492 -145.401179)
			(xy 301.489818 -145.408917) (xy 301.479712 -145.409412) (xy 300.298612 -145.409412) (xy 300.288492 -145.408975)
			(xy 300.269791 -145.401233) (xy 300.255476 -145.386923) (xy 300.247729 -145.368224) (xy 300.247304 -145.358104)
			(xy 297.854846 -145.358104) (xy 297.852407 -145.376628) (xy 297.836894 -145.434521) (xy 297.83004 -145.451068)
			(xy 314.441332 -145.451068) (xy 314.441332 -145.208244) (xy 314.44692 -145.199862) (xy 314.447174 -145.199354)
			(xy 314.449206 -145.196306) (xy 314.44946 -145.195798) (xy 314.6552 -144.881854) (xy 314.660216 -144.87343)
			(xy 314.664027 -144.854212) (xy 314.660375 -144.834964) (xy 314.655454 -144.826482) (xy 314.569602 -144.694402)
			(xy 314.560204 -144.679924) (xy 314.447936 -144.507966) (xy 314.447428 -144.50695) (xy 314.445396 -144.503902)
			(xy 314.445142 -144.503394) (xy 314.441332 -144.497552) (xy 314.441332 -144.254728) (xy 314.441736 -144.244502)
			(xy 314.449559 -144.225606) (xy 314.464023 -144.211148) (xy 314.482922 -144.203332) (xy 314.493148 -144.202912)
			(xy 315.229748 -144.202912) (xy 315.239962 -144.203343) (xy 315.25883 -144.211177) (xy 315.273266 -144.225634)
			(xy 315.281072 -144.244513) (xy 315.281564 -144.254728) (xy 315.281564 -144.497552) (xy 315.277754 -144.503394)
			(xy 315.2775 -144.503902) (xy 315.273436 -144.509998) (xy 315.273182 -144.510252) (xy 315.13526 -144.721326)
			(xy 315.082174 -144.802606) (xy 315.069728 -144.821656) (xy 315.067696 -144.82445) (xy 315.066426 -144.826482)
			(xy 315.062233 -144.833902) (xy 315.058515 -144.850523) (xy 315.060472 -144.867442) (xy 315.063886 -144.87525)
			(xy 315.251084 -145.160746) (xy 315.253624 -145.164556) (xy 315.273436 -145.194528) (xy 315.27369 -145.195036)
			(xy 315.27496 -145.197068) (xy 315.276738 -145.199608) (xy 315.281564 -145.206974) (xy 315.281564 -145.285714)
			(xy 315.916564 -145.285714) (xy 315.916564 -144.422114) (xy 315.917054 -144.392146) (xy 315.924877 -144.332724)
			(xy 315.94039 -144.274831) (xy 315.963326 -144.219458) (xy 315.993293 -144.167552) (xy 316.02978 -144.120002)
			(xy 316.07216 -144.077622) (xy 316.11971 -144.041135) (xy 316.171616 -144.011168) (xy 316.226989 -143.988232)
			(xy 316.284882 -143.972719) (xy 316.344304 -143.964896) (xy 316.40424 -143.964896) (xy 316.463662 -143.972719)
			(xy 316.521555 -143.988232) (xy 316.576928 -144.011168) (xy 316.628834 -144.041135) (xy 316.676384 -144.077622)
			(xy 316.718764 -144.120002) (xy 316.755251 -144.167552) (xy 316.785218 -144.219458) (xy 316.808154 -144.274831)
			(xy 316.823667 -144.332724) (xy 316.83149 -144.392146) (xy 316.83198 -144.422114) (xy 316.83198 -145.285714)
			(xy 316.831955 -145.287238) (xy 413.045148 -145.287238) (xy 413.045148 -144.423638) (xy 413.045638 -144.393654)
			(xy 413.053466 -144.334198) (xy 413.068987 -144.276273) (xy 413.091936 -144.220869) (xy 413.12192 -144.168935)
			(xy 413.158426 -144.121359) (xy 413.200831 -144.078954) (xy 413.248407 -144.042448) (xy 413.300341 -144.012464)
			(xy 413.355745 -143.989515) (xy 413.41367 -143.973994) (xy 413.473126 -143.966166) (xy 413.533094 -143.966166)
			(xy 413.59255 -143.973994) (xy 413.650475 -143.989515) (xy 413.705879 -144.012464) (xy 413.757813 -144.042448)
			(xy 413.805389 -144.078954) (xy 413.847794 -144.121359) (xy 413.8843 -144.168935) (xy 413.914284 -144.220869)
			(xy 413.937233 -144.276273) (xy 413.952754 -144.334198) (xy 413.960582 -144.393654) (xy 413.961072 -144.423638)
			(xy 413.961072 -145.287238) (xy 413.960582 -145.317222) (xy 413.955199 -145.358104) (xy 416.347148 -145.358104)
			(xy 416.347148 -144.351756) (xy 416.347648 -144.341651) (xy 416.35539 -144.322982) (xy 416.369682 -144.30869)
			(xy 416.388351 -144.300948) (xy 416.398456 -144.300448) (xy 417.57981 -144.300448) (xy 417.589938 -144.300919)
			(xy 417.608661 -144.308651) (xy 417.623017 -144.322942) (xy 417.630835 -144.34163) (xy 417.631372 -144.351756)
			(xy 417.631372 -145.358104) (xy 420.884096 -145.358104) (xy 420.884096 -144.351756) (xy 420.884549 -144.341645)
			(xy 420.8923 -144.322967) (xy 420.906607 -144.308673) (xy 420.925293 -144.30094) (xy 420.935404 -144.300448)
			(xy 422.116504 -144.300448) (xy 422.126607 -144.300981) (xy 422.145275 -144.30871) (xy 422.159568 -144.322992)
			(xy 422.167311 -144.341654) (xy 422.167812 -144.351756) (xy 422.167812 -145.358104) (xy 422.167318 -145.368211)
			(xy 422.159582 -145.386887) (xy 422.145287 -145.401182) (xy 422.126611 -145.408918) (xy 422.116504 -145.409412)
			(xy 420.935404 -145.409412) (xy 420.925297 -145.408912) (xy 420.906621 -145.401178) (xy 420.892327 -145.386886)
			(xy 420.88459 -145.368211) (xy 420.884096 -145.358104) (xy 417.631372 -145.358104) (xy 417.630986 -145.36823)
			(xy 417.623232 -145.386939) (xy 417.608906 -145.401254) (xy 417.590191 -145.408994) (xy 417.580064 -145.409412)
			(xy 416.39871 -145.409412) (xy 416.38859 -145.408867) (xy 416.369879 -145.401152) (xy 416.355524 -145.386884)
			(xy 416.347696 -145.368221) (xy 416.347148 -145.358104) (xy 413.955199 -145.358104) (xy 413.952754 -145.376678)
			(xy 413.937233 -145.434603) (xy 413.930413 -145.451068) (xy 430.541684 -145.451068) (xy 430.541684 -145.208244)
			(xy 430.686464 -144.987518) (xy 430.73574 -144.91208) (xy 430.755552 -144.881854) (xy 430.760538 -144.87341)
			(xy 430.764266 -144.854173) (xy 430.760518 -144.834939) (xy 430.755552 -144.826482) (xy 430.610518 -144.60347)
			(xy 430.554892 -144.518126) (xy 430.550574 -144.51203) (xy 430.547272 -144.506442) (xy 430.546764 -144.505426)
			(xy 430.541684 -144.497552) (xy 430.541684 -144.254728) (xy 430.542326 -144.243209) (xy 430.552188 -144.222388)
			(xy 430.57002 -144.207801) (xy 430.581054 -144.204436) (xy 430.581308 -144.204436) (xy 430.593246 -144.202912)
			(xy 431.329846 -144.202912) (xy 431.33622 -144.203133) (xy 431.348556 -144.206349) (xy 431.35423 -144.209262)
			(xy 431.362224 -144.214027) (xy 431.37446 -144.228028) (xy 431.381008 -144.245431) (xy 431.381408 -144.254728)
			(xy 431.381408 -144.497552) (xy 431.165508 -144.828006) (xy 431.161459 -144.836216) (xy 431.158924 -144.854334)
			(xy 431.162881 -144.872195) (xy 431.16754 -144.880076) (xy 431.199798 -144.92986) (xy 431.215292 -144.953482)
			(xy 431.381408 -145.206974) (xy 431.381408 -145.285714) (xy 432.016408 -145.285714) (xy 432.016408 -144.422114)
			(xy 432.016898 -144.39213) (xy 432.024726 -144.332674) (xy 432.040247 -144.274749) (xy 432.063196 -144.219345)
			(xy 432.09318 -144.167411) (xy 432.129686 -144.119835) (xy 432.172091 -144.07743) (xy 432.219667 -144.040924)
			(xy 432.271601 -144.01094) (xy 432.327005 -143.987991) (xy 432.38493 -143.97247) (xy 432.444386 -143.964642)
			(xy 432.504354 -143.964642) (xy 432.56381 -143.97247) (xy 432.621735 -143.987991) (xy 432.677139 -144.01094)
			(xy 432.729073 -144.040924) (xy 432.776649 -144.07743) (xy 432.819054 -144.119835) (xy 432.85556 -144.167411)
			(xy 432.885544 -144.219345) (xy 432.908493 -144.274749) (xy 432.924014 -144.332674) (xy 432.931842 -144.39213)
			(xy 432.932332 -144.422114) (xy 432.932332 -145.285714) (xy 432.931842 -145.315698) (xy 432.924014 -145.375154)
			(xy 432.908493 -145.433079) (xy 432.885544 -145.488483) (xy 432.85556 -145.540417) (xy 432.819054 -145.587993)
			(xy 432.776649 -145.630398) (xy 432.729073 -145.666904) (xy 432.677139 -145.696888) (xy 432.621735 -145.719837)
			(xy 432.56381 -145.735358) (xy 432.504354 -145.743186) (xy 432.444386 -145.743186) (xy 432.38493 -145.735358)
			(xy 432.327005 -145.719837) (xy 432.271601 -145.696888) (xy 432.219667 -145.666904) (xy 432.172091 -145.630398)
			(xy 432.129686 -145.587993) (xy 432.09318 -145.540417) (xy 432.063196 -145.488483) (xy 432.040247 -145.433079)
			(xy 432.024726 -145.375154) (xy 432.016898 -145.315698) (xy 432.016408 -145.285714) (xy 431.381408 -145.285714)
			(xy 431.381408 -145.451068) (xy 431.380768 -145.462588) (xy 431.370907 -145.48341) (xy 431.353073 -145.497996)
			(xy 431.342038 -145.50136) (xy 431.341784 -145.50136) (xy 431.329846 -145.502884) (xy 430.593246 -145.502884)
			(xy 430.586872 -145.502666) (xy 430.574535 -145.499448) (xy 430.568862 -145.496534) (xy 430.560865 -145.491774)
			(xy 430.548629 -145.477771) (xy 430.542084 -145.460365) (xy 430.541684 -145.451068) (xy 413.930413 -145.451068)
			(xy 413.914284 -145.490007) (xy 413.8843 -145.541941) (xy 413.847794 -145.589517) (xy 413.805389 -145.631922)
			(xy 413.757813 -145.668428) (xy 413.705879 -145.698412) (xy 413.650475 -145.721361) (xy 413.59255 -145.736882)
			(xy 413.533094 -145.74471) (xy 413.473126 -145.74471) (xy 413.41367 -145.736882) (xy 413.355745 -145.721361)
			(xy 413.300341 -145.698412) (xy 413.248407 -145.668428) (xy 413.200831 -145.631922) (xy 413.158426 -145.589517)
			(xy 413.12192 -145.541941) (xy 413.091936 -145.490007) (xy 413.068987 -145.434603) (xy 413.053466 -145.376678)
			(xy 413.045638 -145.317222) (xy 413.045148 -145.287238) (xy 316.831955 -145.287238) (xy 316.83149 -145.315682)
			(xy 316.823667 -145.375104) (xy 316.808154 -145.432997) (xy 316.785218 -145.48837) (xy 316.755251 -145.540276)
			(xy 316.718764 -145.587826) (xy 316.676384 -145.630206) (xy 316.628834 -145.666693) (xy 316.576928 -145.69666)
			(xy 316.521555 -145.719596) (xy 316.463662 -145.735109) (xy 316.40424 -145.742932) (xy 316.344304 -145.742932)
			(xy 316.284882 -145.735109) (xy 316.226989 -145.719596) (xy 316.171616 -145.69666) (xy 316.11971 -145.666693)
			(xy 316.07216 -145.630206) (xy 316.02978 -145.587826) (xy 315.993293 -145.540276) (xy 315.963326 -145.48837)
			(xy 315.94039 -145.432997) (xy 315.924877 -145.375104) (xy 315.917054 -145.315682) (xy 315.916564 -145.285714)
			(xy 315.281564 -145.285714) (xy 315.281564 -145.451068) (xy 315.280993 -145.461268) (xy 315.2732 -145.48012)
			(xy 315.258787 -145.494555) (xy 315.239947 -145.502378) (xy 315.229748 -145.502884) (xy 314.493148 -145.502884)
			(xy 314.482925 -145.502448) (xy 314.464033 -145.494635) (xy 314.449574 -145.48018) (xy 314.441755 -145.46129)
			(xy 314.441332 -145.451068) (xy 297.83004 -145.451068) (xy 297.813958 -145.489894) (xy 297.783991 -145.5418)
			(xy 297.747504 -145.58935) (xy 297.705124 -145.63173) (xy 297.657574 -145.668217) (xy 297.605668 -145.698184)
			(xy 297.550295 -145.72112) (xy 297.492402 -145.736633) (xy 297.43298 -145.744456) (xy 297.373044 -145.744456)
			(xy 297.313622 -145.736633) (xy 297.255729 -145.72112) (xy 297.200356 -145.698184) (xy 297.14845 -145.668217)
			(xy 297.1009 -145.63173) (xy 297.05852 -145.58935) (xy 297.022033 -145.5418) (xy 296.992066 -145.489894)
			(xy 296.96913 -145.434521) (xy 296.953617 -145.376628) (xy 296.945794 -145.317206) (xy 296.945304 -145.287238)
			(xy 200.732111 -145.287238) (xy 200.731646 -145.315682) (xy 200.723823 -145.375104) (xy 200.70831 -145.432997)
			(xy 200.685374 -145.48837) (xy 200.655407 -145.540276) (xy 200.61892 -145.587826) (xy 200.57654 -145.630206)
			(xy 200.52899 -145.666693) (xy 200.477084 -145.69666) (xy 200.421711 -145.719596) (xy 200.363818 -145.735109)
			(xy 200.304396 -145.742932) (xy 200.24446 -145.742932) (xy 200.185038 -145.735109) (xy 200.127145 -145.719596)
			(xy 200.071772 -145.69666) (xy 200.019866 -145.666693) (xy 199.972316 -145.630206) (xy 199.929936 -145.587826)
			(xy 199.893449 -145.540276) (xy 199.863482 -145.48837) (xy 199.840546 -145.432997) (xy 199.825033 -145.375104)
			(xy 199.81721 -145.315682) (xy 199.81672 -145.285714) (xy 199.181212 -145.285714) (xy 199.181212 -145.451068)
			(xy 199.180569 -145.462588) (xy 199.170709 -145.483409) (xy 199.152876 -145.497995) (xy 199.141842 -145.50136)
			(xy 199.141588 -145.50136) (xy 199.12965 -145.502884) (xy 198.39305 -145.502884) (xy 198.386676 -145.502664)
			(xy 198.37434 -145.499447) (xy 198.368666 -145.496534) (xy 198.36067 -145.491773) (xy 198.348434 -145.47777)
			(xy 198.341888 -145.460365) (xy 198.341488 -145.451068) (xy 181.730196 -145.451068) (xy 181.714114 -145.489894)
			(xy 181.684147 -145.5418) (xy 181.64766 -145.58935) (xy 181.60528 -145.63173) (xy 181.55773 -145.668217)
			(xy 181.505824 -145.698184) (xy 181.450451 -145.72112) (xy 181.392558 -145.736633) (xy 181.333136 -145.744456)
			(xy 181.2732 -145.744456) (xy 181.213778 -145.736633) (xy 181.155885 -145.72112) (xy 181.100512 -145.698184)
			(xy 181.048606 -145.668217) (xy 181.001056 -145.63173) (xy 180.958676 -145.58935) (xy 180.922189 -145.5418)
			(xy 180.892222 -145.489894) (xy 180.869286 -145.434521) (xy 180.853773 -145.376628) (xy 180.84595 -145.317206)
			(xy 180.84546 -145.287238) (xy 84.632267 -145.287238) (xy 84.631802 -145.315698) (xy 84.623974 -145.375154)
			(xy 84.608453 -145.433079) (xy 84.585504 -145.488483) (xy 84.55552 -145.540417) (xy 84.519014 -145.587993)
			(xy 84.476609 -145.630398) (xy 84.429033 -145.666904) (xy 84.377099 -145.696888) (xy 84.321695 -145.719837)
			(xy 84.26377 -145.735358) (xy 84.204314 -145.743186) (xy 84.144346 -145.743186) (xy 84.08489 -145.735358)
			(xy 84.026965 -145.719837) (xy 83.971561 -145.696888) (xy 83.919627 -145.666904) (xy 83.872051 -145.630398)
			(xy 83.829646 -145.587993) (xy 83.79314 -145.540417) (xy 83.763156 -145.488483) (xy 83.740207 -145.433079)
			(xy 83.724686 -145.375154) (xy 83.716858 -145.315698) (xy 83.716368 -145.285714) (xy 83.081368 -145.285714)
			(xy 83.081368 -145.451068) (xy 83.080768 -145.462625) (xy 83.070788 -145.483476) (xy 83.052831 -145.498034)
			(xy 83.041744 -145.50136) (xy 83.029806 -145.502884) (xy 82.293206 -145.502884) (xy 82.282448 -145.502372)
			(xy 82.262759 -145.4937) (xy 82.255106 -145.48612) (xy 82.248895 -145.47873) (xy 82.241989 -145.460716)
			(xy 82.241644 -145.451068) (xy 65.630373 -145.451068) (xy 65.614244 -145.490007) (xy 65.58426 -145.541941)
			(xy 65.547754 -145.589517) (xy 65.505349 -145.631922) (xy 65.457773 -145.668428) (xy 65.405839 -145.698412)
			(xy 65.350435 -145.721361) (xy 65.29251 -145.736882) (xy 65.233054 -145.74471) (xy 65.173086 -145.74471)
			(xy 65.11363 -145.736882) (xy 65.055705 -145.721361) (xy 65.000301 -145.698412) (xy 64.948367 -145.668428)
			(xy 64.900791 -145.631922) (xy 64.858386 -145.589517) (xy 64.82188 -145.541941) (xy 64.791896 -145.490007)
			(xy 64.768947 -145.434603) (xy 64.753426 -145.376678) (xy 64.745598 -145.317222) (xy 64.745108 -145.287238)
			(xy 4.30911 -145.287238) (xy 4.30911 -147.087336) (xy 66.599308 -147.087336) (xy 66.599308 -146.223736)
			(xy 66.599798 -146.193752) (xy 66.607626 -146.134296) (xy 66.623147 -146.076371) (xy 66.646096 -146.020967)
			(xy 66.67608 -145.969033) (xy 66.712586 -145.921457) (xy 66.754991 -145.879052) (xy 66.802567 -145.842546)
			(xy 66.854501 -145.812562) (xy 66.909905 -145.789613) (xy 66.96783 -145.774092) (xy 67.027286 -145.766264)
			(xy 67.087254 -145.766264) (xy 67.14671 -145.774092) (xy 67.204635 -145.789613) (xy 67.260039 -145.812562)
			(xy 67.311973 -145.842546) (xy 67.359549 -145.879052) (xy 67.401954 -145.921457) (xy 67.43846 -145.969033)
			(xy 67.468444 -146.020967) (xy 67.491393 -146.076371) (xy 67.506914 -146.134296) (xy 67.514742 -146.193752)
			(xy 67.515232 -146.223736) (xy 67.515232 -147.087336) (xy 67.514742 -147.11732) (xy 67.509359 -147.158202)
			(xy 68.047108 -147.158202) (xy 68.047108 -146.151854) (xy 68.047595 -146.141697) (xy 68.055379 -146.122933)
			(xy 68.069746 -146.10857) (xy 68.088513 -146.100792) (xy 68.09867 -146.100292) (xy 69.27977 -146.100292)
			(xy 69.28992 -146.100857) (xy 69.30868 -146.108613) (xy 69.323045 -146.122956) (xy 69.330828 -146.141705)
			(xy 69.331332 -146.151854) (xy 69.331332 -147.158202) (xy 72.584056 -147.158202) (xy 72.584056 -146.151854)
			(xy 72.584489 -146.141722) (xy 72.592235 -146.122997) (xy 72.606538 -146.108642) (xy 72.625234 -146.100827)
			(xy 72.635364 -146.100292) (xy 73.816464 -146.100292) (xy 73.826615 -146.100751) (xy 73.845365 -146.108533)
			(xy 73.859689 -146.122919) (xy 73.867391 -146.141702) (xy 73.867772 -146.151854) (xy 73.867772 -147.158202)
			(xy 73.867275 -147.168327) (xy 73.859549 -147.187046) (xy 73.845266 -147.201402) (xy 73.826587 -147.209223)
			(xy 73.816464 -147.209764) (xy 72.635364 -147.209764) (xy 72.625203 -147.209407) (xy 72.606443 -147.201593)
			(xy 72.59212 -147.187176) (xy 72.584428 -147.168366) (xy 72.584056 -147.158202) (xy 69.331332 -147.158202)
			(xy 69.330937 -147.168377) (xy 69.323146 -147.187178) (xy 69.308751 -147.201564) (xy 69.289946 -147.209343)
			(xy 69.27977 -147.209764) (xy 68.09867 -147.209764) (xy 68.088511 -147.209291) (xy 68.069741 -147.201507)
			(xy 68.055377 -147.187135) (xy 68.047603 -147.168362) (xy 68.047108 -147.158202) (xy 67.509359 -147.158202)
			(xy 67.506914 -147.176776) (xy 67.491393 -147.234701) (xy 67.487308 -147.244562) (xy 79.599536 -147.244562)
			(xy 79.599536 -147.001738) (xy 79.744316 -146.781012) (xy 79.793592 -146.705574) (xy 79.813404 -146.675348)
			(xy 79.818391 -146.666905) (xy 79.822113 -146.647668) (xy 79.818367 -146.628435) (xy 79.813404 -146.619976)
			(xy 79.66837 -146.396964) (xy 79.612744 -146.31162) (xy 79.608426 -146.305524) (xy 79.605124 -146.299936)
			(xy 79.604616 -146.29892) (xy 79.599536 -146.291046) (xy 79.599536 -146.048222) (xy 79.599982 -146.038052)
			(xy 79.607759 -146.019258) (xy 79.622138 -146.004873) (xy 79.640928 -145.997087) (xy 79.651098 -145.99666)
			(xy 80.387698 -145.99666) (xy 80.397872 -145.997066) (xy 80.416671 -146.004854) (xy 80.431057 -146.019246)
			(xy 80.438838 -146.038048) (xy 80.43926 -146.048222) (xy 80.43926 -146.291046) (xy 80.22336 -146.6215)
			(xy 80.219321 -146.629713) (xy 80.216787 -146.647828) (xy 80.220738 -146.665688) (xy 80.225392 -146.67357)
			(xy 80.25765 -146.723354) (xy 80.273144 -146.746976) (xy 80.43926 -147.000468) (xy 80.43926 -147.079208)
			(xy 81.07426 -147.079208) (xy 81.07426 -146.215608) (xy 81.07475 -146.185624) (xy 81.082578 -146.126168)
			(xy 81.098099 -146.068243) (xy 81.121048 -146.012839) (xy 81.151032 -145.960905) (xy 81.187538 -145.913329)
			(xy 81.229943 -145.870924) (xy 81.277519 -145.834418) (xy 81.329453 -145.804434) (xy 81.384857 -145.781485)
			(xy 81.442782 -145.765964) (xy 81.502238 -145.758136) (xy 81.562206 -145.758136) (xy 81.621662 -145.765964)
			(xy 81.679587 -145.781485) (xy 81.734991 -145.804434) (xy 81.786925 -145.834418) (xy 81.834501 -145.870924)
			(xy 81.876906 -145.913329) (xy 81.913412 -145.960905) (xy 81.943396 -146.012839) (xy 81.966345 -146.068243)
			(xy 81.981866 -146.126168) (xy 81.989694 -146.185624) (xy 81.990184 -146.215608) (xy 81.990184 -147.079208)
			(xy 81.990051 -147.087336) (xy 182.69966 -147.087336) (xy 182.69966 -146.223736) (xy 182.70015 -146.193768)
			(xy 182.707973 -146.134346) (xy 182.723486 -146.076453) (xy 182.746422 -146.02108) (xy 182.776389 -145.969174)
			(xy 182.812876 -145.921624) (xy 182.855256 -145.879244) (xy 182.902806 -145.842757) (xy 182.954712 -145.81279)
			(xy 183.010085 -145.789854) (xy 183.067978 -145.774341) (xy 183.1274 -145.766518) (xy 183.187336 -145.766518)
			(xy 183.246758 -145.774341) (xy 183.304651 -145.789854) (xy 183.360024 -145.81279) (xy 183.41193 -145.842757)
			(xy 183.45948 -145.879244) (xy 183.50186 -145.921624) (xy 183.538347 -145.969174) (xy 183.568314 -146.02108)
			(xy 183.59125 -146.076453) (xy 183.606763 -146.134346) (xy 183.614586 -146.193768) (xy 183.615076 -146.223736)
			(xy 183.615076 -147.087336) (xy 183.614586 -147.117304) (xy 183.609202 -147.158202) (xy 184.146952 -147.158202)
			(xy 184.146952 -146.151854) (xy 184.147396 -146.141692) (xy 184.155188 -146.122919) (xy 184.169569 -146.108555)
			(xy 184.188351 -146.100784) (xy 184.198514 -146.100292) (xy 185.379614 -146.100292) (xy 185.389767 -146.100821)
			(xy 185.408528 -146.108591) (xy 185.422891 -146.122946) (xy 185.430673 -146.141701) (xy 185.431176 -146.151854)
			(xy 185.431176 -147.158202) (xy 188.6839 -147.158202) (xy 188.6839 -146.151854) (xy 188.684388 -146.141729)
			(xy 188.692123 -146.123015) (xy 188.706408 -146.108661) (xy 188.725086 -146.100837) (xy 188.735208 -146.100292)
			(xy 189.916308 -146.100292) (xy 189.926462 -146.100715) (xy 189.945213 -146.108512) (xy 189.959535 -146.122908)
			(xy 189.967236 -146.141698) (xy 189.967616 -146.151854) (xy 189.967616 -147.158202) (xy 189.967174 -147.168334)
			(xy 189.959437 -147.187064) (xy 189.945137 -147.201421) (xy 189.926438 -147.209233) (xy 189.916308 -147.209764)
			(xy 188.735208 -147.209764) (xy 188.72505 -147.209371) (xy 188.706291 -147.201571) (xy 188.691966 -147.187165)
			(xy 188.684272 -147.168362) (xy 188.6839 -147.158202) (xy 185.431176 -147.158202) (xy 185.430669 -147.168358)
			(xy 185.422896 -147.187125) (xy 185.408535 -147.201489) (xy 185.38977 -147.209266) (xy 185.379614 -147.209764)
			(xy 184.198514 -147.209764) (xy 184.188344 -147.209325) (xy 184.169549 -147.201545) (xy 184.155164 -147.187164)
			(xy 184.147378 -147.168372) (xy 184.146952 -147.158202) (xy 183.609202 -147.158202) (xy 183.606763 -147.176726)
			(xy 183.59125 -147.234619) (xy 183.587132 -147.244562) (xy 195.69938 -147.244562) (xy 195.69938 -147.001738)
			(xy 195.818252 -146.820382) (xy 195.880736 -146.724878) (xy 195.904866 -146.688048) (xy 195.90873 -146.681718)
			(xy 195.912992 -146.66752) (xy 195.913248 -146.660108) (xy 195.913248 -146.6342) (xy 195.913057 -146.62805)
			(xy 195.910102 -146.616109) (xy 195.907406 -146.610578) (xy 195.793868 -146.436588) (xy 195.773802 -146.4056)
			(xy 195.768214 -146.396964) (xy 195.707762 -146.304254) (xy 195.707254 -146.303492) (xy 195.706746 -146.30273)
			(xy 195.706492 -146.302222) (xy 195.705984 -146.30146) (xy 195.69938 -146.291046) (xy 195.69938 -146.048222)
			(xy 195.699783 -146.038047) (xy 195.707569 -146.019244) (xy 195.721961 -146.004857) (xy 195.740766 -145.997079)
			(xy 195.750942 -145.99666) (xy 196.487542 -145.99666) (xy 196.497705 -145.9971) (xy 196.516479 -146.004892)
			(xy 196.530844 -146.019274) (xy 196.538613 -146.038058) (xy 196.539104 -146.048222) (xy 196.539104 -146.291046)
			(xy 196.323204 -146.6215) (xy 196.319161 -146.629712) (xy 196.316624 -146.647828) (xy 196.320578 -146.665689)
			(xy 196.325236 -146.67357) (xy 196.357494 -146.723354) (xy 196.539104 -147.000468) (xy 196.539104 -147.079208)
			(xy 197.174612 -147.079208) (xy 197.174612 -146.215608) (xy 197.175102 -146.18564) (xy 197.182925 -146.126218)
			(xy 197.198438 -146.068325) (xy 197.221374 -146.012952) (xy 197.251341 -145.961046) (xy 197.287828 -145.913496)
			(xy 197.330208 -145.871116) (xy 197.377758 -145.834629) (xy 197.429664 -145.804662) (xy 197.485037 -145.781726)
			(xy 197.54293 -145.766213) (xy 197.602352 -145.75839) (xy 197.662288 -145.75839) (xy 197.72171 -145.766213)
			(xy 197.779603 -145.781726) (xy 197.834976 -145.804662) (xy 197.886882 -145.834629) (xy 197.934432 -145.871116)
			(xy 197.976812 -145.913496) (xy 198.013299 -145.961046) (xy 198.043266 -146.012952) (xy 198.066202 -146.068325)
			(xy 198.081715 -146.126218) (xy 198.089538 -146.18564) (xy 198.090028 -146.215608) (xy 198.090028 -147.079208)
			(xy 198.089895 -147.087336) (xy 298.799504 -147.087336) (xy 298.799504 -146.223736) (xy 298.799994 -146.193768)
			(xy 298.807817 -146.134346) (xy 298.82333 -146.076453) (xy 298.846266 -146.02108) (xy 298.876233 -145.969174)
			(xy 298.91272 -145.921624) (xy 298.9551 -145.879244) (xy 299.00265 -145.842757) (xy 299.054556 -145.81279)
			(xy 299.109929 -145.789854) (xy 299.167822 -145.774341) (xy 299.227244 -145.766518) (xy 299.28718 -145.766518)
			(xy 299.346602 -145.774341) (xy 299.404495 -145.789854) (xy 299.459868 -145.81279) (xy 299.511774 -145.842757)
			(xy 299.559324 -145.879244) (xy 299.601704 -145.921624) (xy 299.638191 -145.969174) (xy 299.668158 -146.02108)
			(xy 299.691094 -146.076453) (xy 299.706607 -146.134346) (xy 299.71443 -146.193768) (xy 299.71492 -146.223736)
			(xy 299.71492 -147.087336) (xy 299.71443 -147.117304) (xy 299.709012 -147.158456) (xy 300.247304 -147.158456)
			(xy 300.247304 -146.151854) (xy 300.247788 -146.141729) (xy 300.255524 -146.123013) (xy 300.26981 -146.10866)
			(xy 300.288489 -146.100836) (xy 300.298612 -146.100292) (xy 301.479712 -146.100292) (xy 301.48982 -146.100775)
			(xy 301.508497 -146.108515) (xy 301.522791 -146.122813) (xy 301.530527 -146.141491) (xy 301.53102 -146.1516)
			(xy 301.53102 -147.158202) (xy 304.783744 -147.158202) (xy 304.783744 -146.151854) (xy 304.784196 -146.141693)
			(xy 304.791987 -146.122921) (xy 304.806365 -146.108557) (xy 304.825144 -146.100786) (xy 304.835306 -146.100292)
			(xy 306.016406 -146.100292) (xy 306.026558 -146.100827) (xy 306.045319 -146.108595) (xy 306.059682 -146.122948)
			(xy 306.067465 -146.141702) (xy 306.067968 -146.151854) (xy 306.067968 -147.158202) (xy 306.067468 -147.168359)
			(xy 306.059694 -147.187127) (xy 306.045331 -147.201492) (xy 306.026563 -147.209268) (xy 306.016406 -147.209764)
			(xy 304.835306 -147.209764) (xy 304.825135 -147.209331) (xy 304.806341 -147.201549) (xy 304.791956 -147.187166)
			(xy 304.78417 -147.168373) (xy 304.783744 -147.158202) (xy 301.53102 -147.158202) (xy 301.530574 -147.168334)
			(xy 301.522838 -147.187062) (xy 301.508539 -147.20142) (xy 301.489842 -147.209232) (xy 301.479712 -147.209764)
			(xy 300.298612 -147.209764) (xy 300.288486 -147.209373) (xy 300.269776 -147.201622) (xy 300.25546 -147.187298)
			(xy 300.24772 -147.168582) (xy 300.247304 -147.158456) (xy 299.709012 -147.158456) (xy 299.706607 -147.176726)
			(xy 299.691094 -147.234619) (xy 299.686976 -147.244562) (xy 311.799224 -147.244562) (xy 311.799224 -147.016978)
			(xy 311.799478 -147.012914) (xy 311.799732 -147.010374) (xy 311.799732 -147.001738) (xy 311.80532 -146.993102)
			(xy 311.80659 -146.99107) (xy 311.807606 -146.989038) (xy 312.004964 -146.688048) (xy 312.008828 -146.681717)
			(xy 312.01309 -146.66752) (xy 312.013346 -146.660108) (xy 312.013346 -146.634454) (xy 312.013138 -146.62712)
			(xy 312.00901 -146.613049) (xy 312.005218 -146.606768) (xy 311.807352 -146.303746) (xy 311.805066 -146.299936)
			(xy 311.804812 -146.299428) (xy 311.803796 -146.29765) (xy 311.799732 -146.291046) (xy 311.799732 -146.282918)
			(xy 311.799478 -146.280378) (xy 311.799224 -146.276314) (xy 311.799224 -146.048222) (xy 311.799682 -146.038054)
			(xy 311.807457 -146.019262) (xy 311.821832 -146.004877) (xy 311.840618 -145.997089) (xy 311.850786 -145.99666)
			(xy 312.58764 -145.99666) (xy 312.597816 -145.997141) (xy 312.616626 -146.004916) (xy 312.63105 -146.019275)
			(xy 312.638911 -146.038048) (xy 312.639456 -146.048222) (xy 312.639456 -146.275806) (xy 312.639202 -146.27987)
			(xy 312.638948 -146.28241) (xy 312.638948 -146.291046) (xy 312.633106 -146.300444) (xy 312.632344 -146.301714)
			(xy 312.631074 -146.303746) (xy 312.425334 -146.618452) (xy 312.42029 -146.626977) (xy 312.416473 -146.646393)
			(xy 312.420285 -146.665811) (xy 312.425334 -146.674332) (xy 312.631074 -146.987768) (xy 312.63209 -146.9898)
			(xy 312.63336 -146.991832) (xy 312.638948 -147.000468) (xy 312.638948 -147.009104) (xy 312.639202 -147.011644)
			(xy 312.639456 -147.015708) (xy 312.639456 -147.079208) (xy 313.274456 -147.079208) (xy 313.274456 -146.215608)
			(xy 313.274946 -146.18564) (xy 313.282769 -146.126218) (xy 313.298282 -146.068325) (xy 313.321218 -146.012952)
			(xy 313.351185 -145.961046) (xy 313.387672 -145.913496) (xy 313.430052 -145.871116) (xy 313.477602 -145.834629)
			(xy 313.529508 -145.804662) (xy 313.584881 -145.781726) (xy 313.642774 -145.766213) (xy 313.702196 -145.75839)
			(xy 313.762132 -145.75839) (xy 313.821554 -145.766213) (xy 313.879447 -145.781726) (xy 313.93482 -145.804662)
			(xy 313.986726 -145.834629) (xy 314.034276 -145.871116) (xy 314.076656 -145.913496) (xy 314.113143 -145.961046)
			(xy 314.14311 -146.012952) (xy 314.166046 -146.068325) (xy 314.181559 -146.126218) (xy 314.189382 -146.18564)
			(xy 314.189872 -146.215608) (xy 314.189872 -147.079208) (xy 314.189739 -147.087336) (xy 414.899348 -147.087336)
			(xy 414.899348 -146.223736) (xy 414.899838 -146.193752) (xy 414.907666 -146.134296) (xy 414.923187 -146.076371)
			(xy 414.946136 -146.020967) (xy 414.97612 -145.969033) (xy 415.012626 -145.921457) (xy 415.055031 -145.879052)
			(xy 415.102607 -145.842546) (xy 415.154541 -145.812562) (xy 415.209945 -145.789613) (xy 415.26787 -145.774092)
			(xy 415.327326 -145.766264) (xy 415.387294 -145.766264) (xy 415.44675 -145.774092) (xy 415.504675 -145.789613)
			(xy 415.560079 -145.812562) (xy 415.612013 -145.842546) (xy 415.659589 -145.879052) (xy 415.701994 -145.921457)
			(xy 415.7385 -145.969033) (xy 415.768484 -146.020967) (xy 415.791433 -146.076371) (xy 415.806954 -146.134296)
			(xy 415.814782 -146.193752) (xy 415.815272 -146.223736) (xy 415.815272 -147.087336) (xy 415.814782 -147.11732)
			(xy 415.809399 -147.158202) (xy 416.347148 -147.158202) (xy 416.347148 -146.151854) (xy 416.347596 -146.141692)
			(xy 416.355387 -146.12292) (xy 416.369767 -146.108556) (xy 416.388548 -146.100785) (xy 416.39871 -146.100292)
			(xy 417.57981 -146.100292) (xy 417.589963 -146.100824) (xy 417.608723 -146.108593) (xy 417.623086 -146.122947)
			(xy 417.630869 -146.141702) (xy 417.631372 -146.151854) (xy 417.631372 -147.158202) (xy 420.884096 -147.158202)
			(xy 420.884096 -146.151854) (xy 420.884588 -146.14173) (xy 420.892322 -146.123016) (xy 420.906606 -146.108663)
			(xy 420.925282 -146.100838) (xy 420.935404 -146.100292) (xy 422.116504 -146.100292) (xy 422.126657 -146.100718)
			(xy 422.145408 -146.108514) (xy 422.159731 -146.122909) (xy 422.167432 -146.141699) (xy 422.167812 -146.151854)
			(xy 422.167812 -147.158202) (xy 422.167277 -147.168322) (xy 422.159558 -147.187034) (xy 422.145287 -147.201388)
			(xy 422.126621 -147.209216) (xy 422.116504 -147.209764) (xy 420.935404 -147.209764) (xy 420.925246 -147.209374)
			(xy 420.906486 -147.201573) (xy 420.892162 -147.187166) (xy 420.884468 -147.168363) (xy 420.884096 -147.158202)
			(xy 417.631372 -147.158202) (xy 417.630868 -147.168359) (xy 417.623095 -147.187126) (xy 417.608733 -147.201491)
			(xy 417.589967 -147.209267) (xy 417.57981 -147.209764) (xy 416.39871 -147.209764) (xy 416.388539 -147.209328)
			(xy 416.369745 -147.201547) (xy 416.35536 -147.187165) (xy 416.347574 -147.168373) (xy 416.347148 -147.158202)
			(xy 415.809399 -147.158202) (xy 415.806954 -147.176776) (xy 415.791433 -147.234701) (xy 415.787348 -147.244562)
			(xy 427.899576 -147.244562) (xy 427.899576 -147.001738) (xy 428.044356 -146.781012) (xy 428.093632 -146.705574)
			(xy 428.113444 -146.675348) (xy 428.118435 -146.666907) (xy 428.122162 -146.647668) (xy 428.118411 -146.628434)
			(xy 428.113444 -146.619976) (xy 427.96841 -146.396964) (xy 427.912784 -146.31162) (xy 427.908466 -146.305524)
			(xy 427.905164 -146.299936) (xy 427.904656 -146.29892) (xy 427.899576 -146.291046) (xy 427.899576 -146.048222)
			(xy 427.899983 -146.038047) (xy 427.907768 -146.019246) (xy 427.922159 -146.004859) (xy 427.940963 -145.99708)
			(xy 427.951138 -145.99666) (xy 428.687738 -145.99666) (xy 428.697901 -145.997103) (xy 428.716675 -146.004894)
			(xy 428.73104 -146.019275) (xy 428.738809 -146.038058) (xy 428.7393 -146.048222) (xy 428.7393 -146.291046)
			(xy 428.5234 -146.6215) (xy 428.519357 -146.629712) (xy 428.516821 -146.647828) (xy 428.520775 -146.665689)
			(xy 428.525432 -146.67357) (xy 428.55769 -146.723354) (xy 428.573184 -146.746976) (xy 428.7393 -147.000468)
			(xy 428.7393 -147.079208) (xy 429.3743 -147.079208) (xy 429.3743 -146.215608) (xy 429.37479 -146.185624)
			(xy 429.382618 -146.126168) (xy 429.398139 -146.068243) (xy 429.421088 -146.012839) (xy 429.451072 -145.960905)
			(xy 429.487578 -145.913329) (xy 429.529983 -145.870924) (xy 429.577559 -145.834418) (xy 429.629493 -145.804434)
			(xy 429.684897 -145.781485) (xy 429.742822 -145.765964) (xy 429.802278 -145.758136) (xy 429.862246 -145.758136)
			(xy 429.921702 -145.765964) (xy 429.979627 -145.781485) (xy 430.035031 -145.804434) (xy 430.086965 -145.834418)
			(xy 430.134541 -145.870924) (xy 430.176946 -145.913329) (xy 430.213452 -145.960905) (xy 430.243436 -146.012839)
			(xy 430.266385 -146.068243) (xy 430.281906 -146.126168) (xy 430.289734 -146.185624) (xy 430.290224 -146.215608)
			(xy 430.290224 -147.079208) (xy 430.289734 -147.109192) (xy 430.281906 -147.168648) (xy 430.266385 -147.226573)
			(xy 430.243436 -147.281977) (xy 430.213452 -147.333911) (xy 430.176946 -147.381487) (xy 430.134541 -147.423892)
			(xy 430.086965 -147.460398) (xy 430.035031 -147.490382) (xy 429.979627 -147.513331) (xy 429.921702 -147.528852)
			(xy 429.862246 -147.53668) (xy 429.802278 -147.53668) (xy 429.742822 -147.528852) (xy 429.684897 -147.513331)
			(xy 429.629493 -147.490382) (xy 429.577559 -147.460398) (xy 429.529983 -147.423892) (xy 429.487578 -147.381487)
			(xy 429.451072 -147.333911) (xy 429.421088 -147.281977) (xy 429.398139 -147.226573) (xy 429.382618 -147.168648)
			(xy 429.37479 -147.109192) (xy 429.3743 -147.079208) (xy 428.7393 -147.079208) (xy 428.7393 -147.244562)
			(xy 428.738736 -147.254713) (xy 428.730981 -147.273474) (xy 428.716637 -147.287839) (xy 428.697888 -147.295621)
			(xy 428.687738 -147.296124) (xy 427.951138 -147.296124) (xy 427.940964 -147.295704) (xy 427.922163 -147.287924)
			(xy 427.907776 -147.273537) (xy 427.899996 -147.254736) (xy 427.899576 -147.244562) (xy 415.787348 -147.244562)
			(xy 415.768484 -147.290105) (xy 415.7385 -147.342039) (xy 415.701994 -147.389615) (xy 415.659589 -147.43202)
			(xy 415.612013 -147.468526) (xy 415.560079 -147.49851) (xy 415.504675 -147.521459) (xy 415.44675 -147.53698)
			(xy 415.387294 -147.544808) (xy 415.327326 -147.544808) (xy 415.26787 -147.53698) (xy 415.209945 -147.521459)
			(xy 415.154541 -147.49851) (xy 415.102607 -147.468526) (xy 415.055031 -147.43202) (xy 415.012626 -147.389615)
			(xy 414.97612 -147.342039) (xy 414.946136 -147.290105) (xy 414.923187 -147.234701) (xy 414.907666 -147.176776)
			(xy 414.899838 -147.11732) (xy 414.899348 -147.087336) (xy 314.189739 -147.087336) (xy 314.189382 -147.109176)
			(xy 314.181559 -147.168598) (xy 314.166046 -147.226491) (xy 314.14311 -147.281864) (xy 314.113143 -147.33377)
			(xy 314.076656 -147.38132) (xy 314.034276 -147.4237) (xy 313.986726 -147.460187) (xy 313.93482 -147.490154)
			(xy 313.879447 -147.51309) (xy 313.821554 -147.528603) (xy 313.762132 -147.536426) (xy 313.702196 -147.536426)
			(xy 313.642774 -147.528603) (xy 313.584881 -147.51309) (xy 313.529508 -147.490154) (xy 313.477602 -147.460187)
			(xy 313.430052 -147.4237) (xy 313.387672 -147.38132) (xy 313.351185 -147.33377) (xy 313.321218 -147.281864)
			(xy 313.298282 -147.226491) (xy 313.282769 -147.168598) (xy 313.274946 -147.109176) (xy 313.274456 -147.079208)
			(xy 312.639456 -147.079208) (xy 312.639456 -147.244562) (xy 312.639005 -147.254732) (xy 312.631231 -147.273527)
			(xy 312.616854 -147.287913) (xy 312.598064 -147.295699) (xy 312.587894 -147.296124) (xy 311.85104 -147.296124)
			(xy 311.840867 -147.295592) (xy 311.822056 -147.287841) (xy 311.807628 -147.273497) (xy 311.799768 -147.254732)
			(xy 311.799224 -147.244562) (xy 299.686976 -147.244562) (xy 299.668158 -147.289992) (xy 299.638191 -147.341898)
			(xy 299.601704 -147.389448) (xy 299.559324 -147.431828) (xy 299.511774 -147.468315) (xy 299.459868 -147.498282)
			(xy 299.404495 -147.521218) (xy 299.346602 -147.536731) (xy 299.28718 -147.544554) (xy 299.227244 -147.544554)
			(xy 299.167822 -147.536731) (xy 299.109929 -147.521218) (xy 299.054556 -147.498282) (xy 299.00265 -147.468315)
			(xy 298.9551 -147.431828) (xy 298.91272 -147.389448) (xy 298.876233 -147.341898) (xy 298.846266 -147.289992)
			(xy 298.82333 -147.234619) (xy 298.807817 -147.176726) (xy 298.799994 -147.117304) (xy 298.799504 -147.087336)
			(xy 198.089895 -147.087336) (xy 198.089538 -147.109176) (xy 198.081715 -147.168598) (xy 198.066202 -147.226491)
			(xy 198.043266 -147.281864) (xy 198.013299 -147.33377) (xy 197.976812 -147.38132) (xy 197.934432 -147.4237)
			(xy 197.886882 -147.460187) (xy 197.834976 -147.490154) (xy 197.779603 -147.51309) (xy 197.72171 -147.528603)
			(xy 197.662288 -147.536426) (xy 197.602352 -147.536426) (xy 197.54293 -147.528603) (xy 197.485037 -147.51309)
			(xy 197.429664 -147.490154) (xy 197.377758 -147.460187) (xy 197.330208 -147.4237) (xy 197.287828 -147.38132)
			(xy 197.251341 -147.33377) (xy 197.221374 -147.281864) (xy 197.198438 -147.226491) (xy 197.182925 -147.168598)
			(xy 197.175102 -147.109176) (xy 197.174612 -147.079208) (xy 196.539104 -147.079208) (xy 196.539104 -147.244562)
			(xy 196.538536 -147.254712) (xy 196.530782 -147.273472) (xy 196.516439 -147.287837) (xy 196.497691 -147.295621)
			(xy 196.487542 -147.296124) (xy 195.750942 -147.296124) (xy 195.740768 -147.295701) (xy 195.721967 -147.287923)
			(xy 195.70758 -147.273536) (xy 195.6998 -147.254736) (xy 195.69938 -147.244562) (xy 183.587132 -147.244562)
			(xy 183.568314 -147.289992) (xy 183.538347 -147.341898) (xy 183.50186 -147.389448) (xy 183.45948 -147.431828)
			(xy 183.41193 -147.468315) (xy 183.360024 -147.498282) (xy 183.304651 -147.521218) (xy 183.246758 -147.536731)
			(xy 183.187336 -147.544554) (xy 183.1274 -147.544554) (xy 183.067978 -147.536731) (xy 183.010085 -147.521218)
			(xy 182.954712 -147.498282) (xy 182.902806 -147.468315) (xy 182.855256 -147.431828) (xy 182.812876 -147.389448)
			(xy 182.776389 -147.341898) (xy 182.746422 -147.289992) (xy 182.723486 -147.234619) (xy 182.707973 -147.176726)
			(xy 182.70015 -147.117304) (xy 182.69966 -147.087336) (xy 81.990051 -147.087336) (xy 81.989694 -147.109192)
			(xy 81.981866 -147.168648) (xy 81.966345 -147.226573) (xy 81.943396 -147.281977) (xy 81.913412 -147.333911)
			(xy 81.876906 -147.381487) (xy 81.834501 -147.423892) (xy 81.786925 -147.460398) (xy 81.734991 -147.490382)
			(xy 81.679587 -147.513331) (xy 81.621662 -147.528852) (xy 81.562206 -147.53668) (xy 81.502238 -147.53668)
			(xy 81.442782 -147.528852) (xy 81.384857 -147.513331) (xy 81.329453 -147.490382) (xy 81.277519 -147.460398)
			(xy 81.229943 -147.423892) (xy 81.187538 -147.381487) (xy 81.151032 -147.333911) (xy 81.121048 -147.281977)
			(xy 81.098099 -147.226573) (xy 81.082578 -147.168648) (xy 81.07475 -147.109192) (xy 81.07426 -147.079208)
			(xy 80.43926 -147.079208) (xy 80.43926 -147.244562) (xy 80.438805 -147.254731) (xy 80.431032 -147.273526)
			(xy 80.416656 -147.287912) (xy 80.397867 -147.295698) (xy 80.387698 -147.296124) (xy 79.651098 -147.296124)
			(xy 79.640922 -147.295737) (xy 79.62212 -147.287944) (xy 79.607733 -147.273547) (xy 79.599955 -147.254739)
			(xy 79.599536 -147.244562) (xy 67.487308 -147.244562) (xy 67.468444 -147.290105) (xy 67.43846 -147.342039)
			(xy 67.401954 -147.389615) (xy 67.359549 -147.43202) (xy 67.311973 -147.468526) (xy 67.260039 -147.49851)
			(xy 67.204635 -147.521459) (xy 67.14671 -147.53698) (xy 67.087254 -147.544808) (xy 67.027286 -147.544808)
			(xy 66.96783 -147.53698) (xy 66.909905 -147.521459) (xy 66.854501 -147.49851) (xy 66.802567 -147.468526)
			(xy 66.754991 -147.43202) (xy 66.712586 -147.389615) (xy 66.67608 -147.342039) (xy 66.646096 -147.290105)
			(xy 66.623147 -147.234701) (xy 66.607626 -147.176776) (xy 66.599798 -147.11732) (xy 66.599308 -147.087336)
			(xy 4.30911 -147.087336) (xy 4.30911 -148.887434) (xy 64.745108 -148.887434) (xy 64.745108 -148.023834)
			(xy 64.745598 -147.99385) (xy 64.753426 -147.934394) (xy 64.768947 -147.876469) (xy 64.791896 -147.821065)
			(xy 64.82188 -147.769131) (xy 64.858386 -147.721555) (xy 64.900791 -147.67915) (xy 64.948367 -147.642644)
			(xy 65.000301 -147.61266) (xy 65.055705 -147.589711) (xy 65.11363 -147.57419) (xy 65.173086 -147.566362)
			(xy 65.233054 -147.566362) (xy 65.29251 -147.57419) (xy 65.350435 -147.589711) (xy 65.405839 -147.61266)
			(xy 65.457773 -147.642644) (xy 65.505349 -147.67915) (xy 65.547754 -147.721555) (xy 65.58426 -147.769131)
			(xy 65.614244 -147.821065) (xy 65.637193 -147.876469) (xy 65.652714 -147.934394) (xy 65.660542 -147.99385)
			(xy 65.661032 -148.023834) (xy 65.661032 -148.887434) (xy 65.660542 -148.917418) (xy 65.655159 -148.9583)
			(xy 68.047108 -148.9583) (xy 68.047108 -147.951952) (xy 68.047546 -147.941839) (xy 68.055301 -147.923158)
			(xy 68.069612 -147.908865) (xy 68.088303 -147.901134) (xy 68.098416 -147.900644) (xy 69.27977 -147.900644)
			(xy 69.289895 -147.901151) (xy 69.308617 -147.90887) (xy 69.322974 -147.92315) (xy 69.330794 -147.941829)
			(xy 69.331332 -147.951952) (xy 69.331332 -148.9583) (xy 72.584056 -148.9583) (xy 72.584056 -147.951952)
			(xy 72.584545 -147.941846) (xy 72.59229 -147.923175) (xy 72.606585 -147.908883) (xy 72.625258 -147.901142)
			(xy 72.635364 -147.900644) (xy 73.816464 -147.900644) (xy 73.826564 -147.901213) (xy 73.84523 -147.908929)
			(xy 73.859524 -147.923199) (xy 73.86727 -147.941853) (xy 73.867772 -147.951952) (xy 73.867772 -148.9583)
			(xy 73.867383 -148.968426) (xy 73.85963 -148.987135) (xy 73.845305 -149.00145) (xy 73.82659 -149.00919)
			(xy 73.816464 -149.009608) (xy 72.635364 -149.009608) (xy 72.625254 -149.009145) (xy 72.606576 -149.001397)
			(xy 72.592283 -148.987093) (xy 72.584548 -148.96841) (xy 72.584056 -148.9583) (xy 69.331332 -148.9583)
			(xy 69.330816 -148.968405) (xy 69.323084 -148.987077) (xy 69.308797 -149.00137) (xy 69.290129 -149.009111)
			(xy 69.280024 -149.009608) (xy 68.09867 -149.009608) (xy 68.088547 -149.0091) (xy 68.069834 -149.001371)
			(xy 68.055481 -148.987092) (xy 68.047654 -148.96842) (xy 68.047108 -148.9583) (xy 65.655159 -148.9583)
			(xy 65.652714 -148.976874) (xy 65.637193 -149.034799) (xy 65.630373 -149.051264) (xy 82.241644 -149.051264)
			(xy 82.241644 -148.80844) (xy 82.360516 -148.627084) (xy 82.423 -148.53158) (xy 82.44713 -148.49475)
			(xy 82.45099 -148.488417) (xy 82.455256 -148.474221) (xy 82.455512 -148.46681) (xy 82.455512 -148.440902)
			(xy 82.455324 -148.434752) (xy 82.452367 -148.422811) (xy 82.44967 -148.41728) (xy 82.336132 -148.24329)
			(xy 82.316066 -148.212302) (xy 82.310478 -148.203666) (xy 82.250026 -148.110956) (xy 82.249518 -148.110194)
			(xy 82.24901 -148.109432) (xy 82.248756 -148.108924) (xy 82.248248 -148.108162) (xy 82.241644 -148.097748)
			(xy 82.241644 -147.854924) (xy 82.242229 -147.843366) (xy 82.252215 -147.822512) (xy 82.270179 -147.807956)
			(xy 82.281268 -147.804632) (xy 82.293206 -147.803108) (xy 83.029806 -147.803108) (xy 83.040565 -147.803616)
			(xy 83.060254 -147.812291) (xy 83.067906 -147.819872) (xy 83.074115 -147.827263) (xy 83.081022 -147.845276)
			(xy 83.081368 -147.854924) (xy 83.081368 -148.097748) (xy 82.865468 -148.428202) (xy 82.861427 -148.436414)
			(xy 82.858893 -148.45453) (xy 82.862845 -148.47239) (xy 82.8675 -148.480272) (xy 82.899758 -148.530056)
			(xy 83.081368 -148.80717) (xy 83.081368 -148.88591) (xy 83.716368 -148.88591) (xy 83.716368 -148.02231)
			(xy 83.716858 -147.992326) (xy 83.724686 -147.93287) (xy 83.740207 -147.874945) (xy 83.763156 -147.819541)
			(xy 83.79314 -147.767607) (xy 83.829646 -147.720031) (xy 83.872051 -147.677626) (xy 83.919627 -147.64112)
			(xy 83.971561 -147.611136) (xy 84.026965 -147.588187) (xy 84.08489 -147.572666) (xy 84.144346 -147.564838)
			(xy 84.204314 -147.564838) (xy 84.26377 -147.572666) (xy 84.321695 -147.588187) (xy 84.377099 -147.611136)
			(xy 84.429033 -147.64112) (xy 84.476609 -147.677626) (xy 84.519014 -147.720031) (xy 84.55552 -147.767607)
			(xy 84.585504 -147.819541) (xy 84.608453 -147.874945) (xy 84.623974 -147.93287) (xy 84.631802 -147.992326)
			(xy 84.632292 -148.02231) (xy 84.632292 -148.88591) (xy 84.632267 -148.887434) (xy 180.84546 -148.887434)
			(xy 180.84546 -148.023834) (xy 180.84595 -147.993866) (xy 180.853773 -147.934444) (xy 180.869286 -147.876551)
			(xy 180.892222 -147.821178) (xy 180.922189 -147.769272) (xy 180.958676 -147.721722) (xy 181.001056 -147.679342)
			(xy 181.048606 -147.642855) (xy 181.100512 -147.612888) (xy 181.155885 -147.589952) (xy 181.213778 -147.574439)
			(xy 181.2732 -147.566616) (xy 181.333136 -147.566616) (xy 181.392558 -147.574439) (xy 181.450451 -147.589952)
			(xy 181.505824 -147.612888) (xy 181.55773 -147.642855) (xy 181.60528 -147.679342) (xy 181.64766 -147.721722)
			(xy 181.684147 -147.769272) (xy 181.714114 -147.821178) (xy 181.73705 -147.876551) (xy 181.752563 -147.934444)
			(xy 181.760386 -147.993866) (xy 181.760876 -148.023834) (xy 181.760876 -148.887434) (xy 181.760386 -148.917402)
			(xy 181.755002 -148.9583) (xy 184.146952 -148.9583) (xy 184.146952 -147.951952) (xy 184.147445 -147.941846)
			(xy 184.155189 -147.923176) (xy 184.169483 -147.908885) (xy 184.188154 -147.901143) (xy 184.19826 -147.900644)
			(xy 185.379614 -147.900644) (xy 185.389742 -147.901115) (xy 185.408464 -147.908849) (xy 185.42282 -147.923139)
			(xy 185.430638 -147.941826) (xy 185.431176 -147.951952) (xy 185.431176 -148.9583) (xy 188.6839 -148.9583)
			(xy 188.6839 -147.951952) (xy 188.684346 -147.94184) (xy 188.692099 -147.923161) (xy 188.706408 -147.908868)
			(xy 188.725096 -147.901135) (xy 188.735208 -147.900644) (xy 189.916308 -147.900644) (xy 189.92641 -147.901177)
			(xy 189.945078 -147.908907) (xy 189.95937 -147.923189) (xy 189.967115 -147.94185) (xy 189.967616 -147.951952)
			(xy 189.967616 -148.9583) (xy 189.967115 -148.968407) (xy 189.959381 -148.987082) (xy 189.945089 -149.001376)
			(xy 189.926415 -149.009114) (xy 189.916308 -149.009608) (xy 188.735208 -149.009608) (xy 188.725087 -149.009178)
			(xy 188.706385 -149.001434) (xy 188.692071 -148.987122) (xy 188.684324 -148.968421) (xy 188.6839 -148.9583)
			(xy 185.431176 -148.9583) (xy 185.430783 -148.968425) (xy 185.423031 -148.987134) (xy 185.408707 -149.001449)
			(xy 185.389994 -149.00919) (xy 185.379868 -149.009608) (xy 184.198514 -149.009608) (xy 184.188394 -149.009063)
			(xy 184.169682 -149.001349) (xy 184.155327 -148.987081) (xy 184.147499 -148.968417) (xy 184.146952 -148.9583)
			(xy 181.755002 -148.9583) (xy 181.752563 -148.976824) (xy 181.73705 -149.034717) (xy 181.730196 -149.051264)
			(xy 198.341488 -149.051264) (xy 198.341488 -148.80844) (xy 198.46036 -148.627084) (xy 198.522844 -148.53158)
			(xy 198.546974 -148.49475) (xy 198.550838 -148.48842) (xy 198.5551 -148.474222) (xy 198.555356 -148.46681)
			(xy 198.555356 -148.440902) (xy 198.555163 -148.434752) (xy 198.552209 -148.422811) (xy 198.549514 -148.41728)
			(xy 198.435976 -148.24329) (xy 198.41591 -148.212302) (xy 198.410322 -148.203666) (xy 198.34987 -148.110956)
			(xy 198.349362 -148.110194) (xy 198.348854 -148.109432) (xy 198.3486 -148.108924) (xy 198.348092 -148.108162)
			(xy 198.341488 -148.097748) (xy 198.341488 -147.854924) (xy 198.342114 -147.843372) (xy 198.352087 -147.822526)
			(xy 198.370031 -147.807964) (xy 198.381112 -147.804632) (xy 198.39305 -147.803108) (xy 199.12965 -147.803108)
			(xy 199.140405 -147.803646) (xy 199.160095 -147.8123) (xy 199.16775 -147.819872) (xy 199.173952 -147.827268)
			(xy 199.180865 -147.845277) (xy 199.181212 -147.854924) (xy 199.181212 -148.097748) (xy 198.965312 -148.428202)
			(xy 198.961266 -148.436413) (xy 198.95873 -148.45453) (xy 198.962685 -148.472391) (xy 198.967344 -148.480272)
			(xy 198.999602 -148.530056) (xy 199.181212 -148.80717) (xy 199.181212 -148.88591) (xy 199.81672 -148.88591)
			(xy 199.81672 -148.02231) (xy 199.81721 -147.992342) (xy 199.825033 -147.93292) (xy 199.840546 -147.875027)
			(xy 199.863482 -147.819654) (xy 199.893449 -147.767748) (xy 199.929936 -147.720198) (xy 199.972316 -147.677818)
			(xy 200.019866 -147.641331) (xy 200.071772 -147.611364) (xy 200.127145 -147.588428) (xy 200.185038 -147.572915)
			(xy 200.24446 -147.565092) (xy 200.304396 -147.565092) (xy 200.363818 -147.572915) (xy 200.421711 -147.588428)
			(xy 200.477084 -147.611364) (xy 200.52899 -147.641331) (xy 200.57654 -147.677818) (xy 200.61892 -147.720198)
			(xy 200.655407 -147.767748) (xy 200.685374 -147.819654) (xy 200.70831 -147.875027) (xy 200.723823 -147.93292)
			(xy 200.731646 -147.992342) (xy 200.732136 -148.02231) (xy 200.732136 -148.88591) (xy 200.731646 -148.915878)
			(xy 200.723823 -148.9753) (xy 200.70831 -149.033193) (xy 200.685374 -149.088566) (xy 200.655407 -149.140472)
			(xy 200.61892 -149.188022) (xy 200.57654 -149.230402) (xy 200.52899 -149.266889) (xy 200.477084 -149.296856)
			(xy 200.421711 -149.319792) (xy 200.363818 -149.335305) (xy 200.304396 -149.343128) (xy 200.24446 -149.343128)
			(xy 200.185038 -149.335305) (xy 200.127145 -149.319792) (xy 200.071772 -149.296856) (xy 200.019866 -149.266889)
			(xy 199.972316 -149.230402) (xy 199.929936 -149.188022) (xy 199.893449 -149.140472) (xy 199.863482 -149.088566)
			(xy 199.840546 -149.033193) (xy 199.825033 -148.9753) (xy 199.81721 -148.915878) (xy 199.81672 -148.88591)
			(xy 199.181212 -148.88591) (xy 199.181212 -149.051264) (xy 199.180577 -149.062815) (xy 199.170608 -149.083661)
			(xy 199.152667 -149.098223) (xy 199.141588 -149.101556) (xy 199.12965 -149.10308) (xy 198.39305 -149.10308)
			(xy 198.382294 -149.102546) (xy 198.362605 -149.09389) (xy 198.35495 -149.086316) (xy 198.348743 -149.078923)
			(xy 198.341833 -149.060911) (xy 198.341488 -149.051264) (xy 181.730196 -149.051264) (xy 181.714114 -149.09009)
			(xy 181.684147 -149.141996) (xy 181.64766 -149.189546) (xy 181.60528 -149.231926) (xy 181.55773 -149.268413)
			(xy 181.505824 -149.29838) (xy 181.450451 -149.321316) (xy 181.392558 -149.336829) (xy 181.333136 -149.344652)
			(xy 181.2732 -149.344652) (xy 181.213778 -149.336829) (xy 181.155885 -149.321316) (xy 181.100512 -149.29838)
			(xy 181.048606 -149.268413) (xy 181.001056 -149.231926) (xy 180.958676 -149.189546) (xy 180.922189 -149.141996)
			(xy 180.892222 -149.09009) (xy 180.869286 -149.034717) (xy 180.853773 -148.976824) (xy 180.84595 -148.917402)
			(xy 180.84546 -148.887434) (xy 84.632267 -148.887434) (xy 84.631802 -148.915894) (xy 84.623974 -148.97535)
			(xy 84.608453 -149.033275) (xy 84.585504 -149.088679) (xy 84.55552 -149.140613) (xy 84.519014 -149.188189)
			(xy 84.476609 -149.230594) (xy 84.429033 -149.2671) (xy 84.377099 -149.297084) (xy 84.321695 -149.320033)
			(xy 84.26377 -149.335554) (xy 84.204314 -149.343382) (xy 84.144346 -149.343382) (xy 84.08489 -149.335554)
			(xy 84.026965 -149.320033) (xy 83.971561 -149.297084) (xy 83.919627 -149.2671) (xy 83.872051 -149.230594)
			(xy 83.829646 -149.188189) (xy 83.79314 -149.140613) (xy 83.763156 -149.088679) (xy 83.740207 -149.033275)
			(xy 83.724686 -148.97535) (xy 83.716858 -148.915894) (xy 83.716368 -148.88591) (xy 83.081368 -148.88591)
			(xy 83.081368 -149.051264) (xy 83.080765 -149.06282) (xy 83.070786 -149.083672) (xy 83.05283 -149.098229)
			(xy 83.041744 -149.101556) (xy 83.029806 -149.10308) (xy 82.293206 -149.10308) (xy 82.282448 -149.102569)
			(xy 82.262758 -149.093896) (xy 82.255106 -149.086316) (xy 82.248893 -149.078928) (xy 82.241988 -149.060912)
			(xy 82.241644 -149.051264) (xy 65.630373 -149.051264) (xy 65.614244 -149.090203) (xy 65.58426 -149.142137)
			(xy 65.547754 -149.189713) (xy 65.505349 -149.232118) (xy 65.457773 -149.268624) (xy 65.405839 -149.298608)
			(xy 65.350435 -149.321557) (xy 65.29251 -149.337078) (xy 65.233054 -149.344906) (xy 65.173086 -149.344906)
			(xy 65.11363 -149.337078) (xy 65.055705 -149.321557) (xy 65.000301 -149.298608) (xy 64.948367 -149.268624)
			(xy 64.900791 -149.232118) (xy 64.858386 -149.189713) (xy 64.82188 -149.142137) (xy 64.791896 -149.090203)
			(xy 64.768947 -149.034799) (xy 64.753426 -148.976874) (xy 64.745598 -148.917418) (xy 64.745108 -148.887434)
			(xy 4.30911 -148.887434) (xy 4.30911 -150.687278) (xy 66.599308 -150.687278) (xy 66.599308 -149.823678)
			(xy 66.599798 -149.793694) (xy 66.607626 -149.734238) (xy 66.623147 -149.676313) (xy 66.646096 -149.620909)
			(xy 66.67608 -149.568975) (xy 66.712586 -149.521399) (xy 66.754991 -149.478994) (xy 66.802567 -149.442488)
			(xy 66.854501 -149.412504) (xy 66.909905 -149.389555) (xy 66.96783 -149.374034) (xy 67.027286 -149.366206)
			(xy 67.087254 -149.366206) (xy 67.14671 -149.374034) (xy 67.204635 -149.389555) (xy 67.260039 -149.412504)
			(xy 67.311973 -149.442488) (xy 67.359549 -149.478994) (xy 67.401954 -149.521399) (xy 67.43846 -149.568975)
			(xy 67.468444 -149.620909) (xy 67.491393 -149.676313) (xy 67.506914 -149.734238) (xy 67.514742 -149.793694)
			(xy 67.515232 -149.823678) (xy 67.515232 -150.687278) (xy 67.514742 -150.717262) (xy 67.509359 -150.758144)
			(xy 68.047108 -150.758144) (xy 68.047108 -149.751796) (xy 68.047513 -149.741672) (xy 68.055264 -149.722967)
			(xy 68.069584 -149.708653) (xy 68.088292 -149.700909) (xy 68.098416 -149.700488) (xy 69.27977 -149.700488)
			(xy 69.289888 -149.701049) (xy 69.308599 -149.708758) (xy 69.322955 -149.723021) (xy 69.330784 -149.741681)
			(xy 69.331332 -149.751796) (xy 69.331332 -150.758144) (xy 72.584056 -150.758144) (xy 72.584056 -149.751796)
			(xy 72.584581 -149.741692) (xy 72.592312 -149.723023) (xy 72.606596 -149.70873) (xy 72.625261 -149.700987)
			(xy 72.635364 -149.700488) (xy 73.816464 -149.700488) (xy 73.826583 -149.700945) (xy 73.845283 -149.708679)
			(xy 73.859598 -149.722983) (xy 73.867347 -149.741678) (xy 73.867772 -149.751796) (xy 73.867772 -150.758144)
			(xy 73.86735 -150.768259) (xy 73.859593 -150.786944) (xy 73.845276 -150.801238) (xy 73.82658 -150.808966)
			(xy 73.816464 -150.809452) (xy 72.635364 -150.809452) (xy 72.625259 -150.808946) (xy 72.60659 -150.801206)
			(xy 72.592299 -150.786916) (xy 72.584556 -150.768249) (xy 72.584056 -150.758144) (xy 69.331332 -150.758144)
			(xy 69.330852 -150.768252) (xy 69.323105 -150.786925) (xy 69.308808 -150.801217) (xy 69.290132 -150.808956)
			(xy 69.280024 -150.809452) (xy 68.09867 -150.809452) (xy 68.08854 -150.808998) (xy 68.069817 -150.801259)
			(xy 68.055461 -150.786963) (xy 68.047645 -150.768271) (xy 68.047108 -150.758144) (xy 67.509359 -150.758144)
			(xy 67.506914 -150.776718) (xy 67.491393 -150.834643) (xy 67.487308 -150.844504) (xy 79.599536 -150.844504)
			(xy 79.599536 -150.60168) (xy 79.718408 -150.420324) (xy 79.780892 -150.32482) (xy 79.805022 -150.28799)
			(xy 79.808904 -150.281669) (xy 79.813156 -150.267464) (xy 79.813404 -150.26005) (xy 79.813404 -150.234142)
			(xy 79.813203 -150.227993) (xy 79.810255 -150.216052) (xy 79.807562 -150.21052) (xy 79.694024 -150.03653)
			(xy 79.673958 -150.005542) (xy 79.66837 -149.996906) (xy 79.607918 -149.904196) (xy 79.60741 -149.903434)
			(xy 79.606902 -149.902672) (xy 79.606648 -149.902164) (xy 79.60614 -149.901402) (xy 79.599536 -149.890988)
			(xy 79.599536 -149.648164) (xy 79.600157 -149.63661) (xy 79.610126 -149.615758) (xy 79.628076 -149.601199)
			(xy 79.63916 -149.597872) (xy 79.651098 -149.596348) (xy 80.387698 -149.596348) (xy 80.398458 -149.596848)
			(xy 80.418147 -149.605527) (xy 80.425798 -149.613112) (xy 80.43198 -149.620522) (xy 80.438903 -149.638521)
			(xy 80.43926 -149.648164) (xy 80.43926 -149.890988) (xy 80.22336 -150.221442) (xy 80.219367 -150.229675)
			(xy 80.216817 -150.247777) (xy 80.220748 -150.26563) (xy 80.225392 -150.273512) (xy 80.25765 -150.323296)
			(xy 80.43926 -150.60041) (xy 80.43926 -150.67915) (xy 81.07426 -150.67915) (xy 81.07426 -149.81555)
			(xy 81.07475 -149.785566) (xy 81.082578 -149.72611) (xy 81.098099 -149.668185) (xy 81.121048 -149.612781)
			(xy 81.151032 -149.560847) (xy 81.187538 -149.513271) (xy 81.229943 -149.470866) (xy 81.277519 -149.43436)
			(xy 81.329453 -149.404376) (xy 81.384857 -149.381427) (xy 81.442782 -149.365906) (xy 81.502238 -149.358078)
			(xy 81.562206 -149.358078) (xy 81.621662 -149.365906) (xy 81.679587 -149.381427) (xy 81.734991 -149.404376)
			(xy 81.786925 -149.43436) (xy 81.834501 -149.470866) (xy 81.876906 -149.513271) (xy 81.913412 -149.560847)
			(xy 81.943396 -149.612781) (xy 81.966345 -149.668185) (xy 81.981866 -149.72611) (xy 81.989694 -149.785566)
			(xy 81.990184 -149.81555) (xy 81.990184 -150.67915) (xy 81.990051 -150.687278) (xy 182.69966 -150.687278)
			(xy 182.69966 -149.823678) (xy 182.70015 -149.79371) (xy 182.707973 -149.734288) (xy 182.723486 -149.676395)
			(xy 182.746422 -149.621022) (xy 182.776389 -149.569116) (xy 182.812876 -149.521566) (xy 182.855256 -149.479186)
			(xy 182.902806 -149.442699) (xy 182.954712 -149.412732) (xy 183.010085 -149.389796) (xy 183.067978 -149.374283)
			(xy 183.1274 -149.36646) (xy 183.187336 -149.36646) (xy 183.246758 -149.374283) (xy 183.304651 -149.389796)
			(xy 183.360024 -149.412732) (xy 183.41193 -149.442699) (xy 183.45948 -149.479186) (xy 183.50186 -149.521566)
			(xy 183.538347 -149.569116) (xy 183.568314 -149.621022) (xy 183.59125 -149.676395) (xy 183.606763 -149.734288)
			(xy 183.614586 -149.79371) (xy 183.615076 -149.823678) (xy 183.615076 -150.687278) (xy 183.614586 -150.717246)
			(xy 183.609202 -150.758144) (xy 184.146952 -150.758144) (xy 184.146952 -149.751796) (xy 184.147481 -149.741693)
			(xy 184.155211 -149.723024) (xy 184.169494 -149.708731) (xy 184.188157 -149.700988) (xy 184.19826 -149.700488)
			(xy 185.379614 -149.700488) (xy 185.389735 -149.701014) (xy 185.408447 -149.708737) (xy 185.422801 -149.72301)
			(xy 185.430628 -149.741678) (xy 185.431176 -149.751796) (xy 185.431176 -150.758144) (xy 188.6839 -150.758144)
			(xy 188.6839 -149.751796) (xy 188.684313 -149.741673) (xy 188.692062 -149.72297) (xy 188.70638 -149.708656)
			(xy 188.725085 -149.70091) (xy 188.735208 -149.700488) (xy 189.916308 -149.700488) (xy 189.926416 -149.700978)
			(xy 189.945092 -149.708716) (xy 189.959386 -149.723012) (xy 189.967122 -149.741688) (xy 189.967616 -149.751796)
			(xy 189.967616 -150.758144) (xy 189.967151 -150.768254) (xy 189.959402 -150.78693) (xy 189.945099 -150.801222)
			(xy 189.926418 -150.808958) (xy 189.916308 -150.809452) (xy 188.735208 -150.809452) (xy 188.725106 -150.80891)
			(xy 188.706438 -150.801184) (xy 188.692145 -150.786906) (xy 188.684401 -150.768245) (xy 188.6839 -150.758144)
			(xy 185.431176 -150.758144) (xy 185.43075 -150.768259) (xy 185.422994 -150.786942) (xy 185.408678 -150.801236)
			(xy 185.389983 -150.808965) (xy 185.379868 -150.809452) (xy 184.198514 -150.809452) (xy 184.188387 -150.808962)
			(xy 184.169665 -150.801237) (xy 184.155308 -150.786952) (xy 184.147489 -150.768268) (xy 184.146952 -150.758144)
			(xy 183.609202 -150.758144) (xy 183.606763 -150.776668) (xy 183.59125 -150.834561) (xy 183.587132 -150.844504)
			(xy 195.69938 -150.844504) (xy 195.69938 -150.60168) (xy 195.818252 -150.420324) (xy 195.880736 -150.32482)
			(xy 195.904866 -150.28799) (xy 195.908752 -150.281671) (xy 195.913 -150.267465) (xy 195.913248 -150.26005)
			(xy 195.913248 -150.234142) (xy 195.913043 -150.227993) (xy 195.910097 -150.216052) (xy 195.907406 -150.21052)
			(xy 195.793868 -150.03653) (xy 195.773802 -150.005542) (xy 195.768214 -149.996906) (xy 195.707762 -149.904196)
			(xy 195.707254 -149.903434) (xy 195.706746 -149.902672) (xy 195.706492 -149.902164) (xy 195.705984 -149.901402)
			(xy 195.69938 -149.890988) (xy 195.69938 -149.648164) (xy 195.700042 -149.636616) (xy 195.709998 -149.615772)
			(xy 195.727929 -149.601207) (xy 195.739004 -149.597872) (xy 195.750942 -149.596348) (xy 196.487542 -149.596348)
			(xy 196.498298 -149.596879) (xy 196.517988 -149.605536) (xy 196.525642 -149.613112) (xy 196.531817 -149.620528)
			(xy 196.538746 -149.638522) (xy 196.539104 -149.648164) (xy 196.539104 -149.890988) (xy 196.323204 -150.221442)
			(xy 196.319207 -150.229673) (xy 196.316654 -150.247777) (xy 196.320589 -150.265631) (xy 196.325236 -150.273512)
			(xy 196.357494 -150.323296) (xy 196.539104 -150.60041) (xy 196.539104 -150.67915) (xy 197.174612 -150.67915)
			(xy 197.174612 -149.81555) (xy 197.175102 -149.785582) (xy 197.182925 -149.72616) (xy 197.198438 -149.668267)
			(xy 197.221374 -149.612894) (xy 197.251341 -149.560988) (xy 197.287828 -149.513438) (xy 197.330208 -149.471058)
			(xy 197.377758 -149.434571) (xy 197.429664 -149.404604) (xy 197.485037 -149.381668) (xy 197.54293 -149.366155)
			(xy 197.602352 -149.358332) (xy 197.662288 -149.358332) (xy 197.72171 -149.366155) (xy 197.779603 -149.381668)
			(xy 197.834976 -149.404604) (xy 197.886882 -149.434571) (xy 197.934432 -149.471058) (xy 197.976812 -149.513438)
			(xy 198.013299 -149.560988) (xy 198.043266 -149.612894) (xy 198.066202 -149.668267) (xy 198.072386 -149.691344)
			(xy 236.708188 -149.691344) (xy 236.708188 -148.827744) (xy 236.708678 -148.79776) (xy 236.716506 -148.738304)
			(xy 236.732027 -148.680379) (xy 236.754976 -148.624975) (xy 236.78496 -148.573041) (xy 236.821466 -148.525465)
			(xy 236.863871 -148.48306) (xy 236.911447 -148.446554) (xy 236.963381 -148.41657) (xy 237.018785 -148.393621)
			(xy 237.07671 -148.3781) (xy 237.136166 -148.370272) (xy 237.196134 -148.370272) (xy 237.25559 -148.3781)
			(xy 237.313515 -148.393621) (xy 237.368919 -148.41657) (xy 237.420853 -148.446554) (xy 237.468429 -148.48306)
			(xy 237.510834 -148.525465) (xy 237.54734 -148.573041) (xy 237.577324 -148.624975) (xy 237.600273 -148.680379)
			(xy 237.615794 -148.738304) (xy 237.623622 -148.79776) (xy 237.624112 -148.827744) (xy 237.624112 -148.887434)
			(xy 296.945304 -148.887434) (xy 296.945304 -148.023834) (xy 296.945794 -147.993866) (xy 296.953617 -147.934444)
			(xy 296.96913 -147.876551) (xy 296.992066 -147.821178) (xy 297.022033 -147.769272) (xy 297.05852 -147.721722)
			(xy 297.1009 -147.679342) (xy 297.14845 -147.642855) (xy 297.200356 -147.612888) (xy 297.255729 -147.589952)
			(xy 297.313622 -147.574439) (xy 297.373044 -147.566616) (xy 297.43298 -147.566616) (xy 297.492402 -147.574439)
			(xy 297.550295 -147.589952) (xy 297.605668 -147.612888) (xy 297.657574 -147.642855) (xy 297.705124 -147.679342)
			(xy 297.747504 -147.721722) (xy 297.783991 -147.769272) (xy 297.813958 -147.821178) (xy 297.836894 -147.876551)
			(xy 297.852407 -147.934444) (xy 297.86023 -147.993866) (xy 297.86072 -148.023834) (xy 297.86072 -148.887434)
			(xy 297.86023 -148.917402) (xy 297.854846 -148.9583) (xy 300.247304 -148.9583) (xy 300.247304 -147.951952)
			(xy 300.247746 -147.94184) (xy 300.2555 -147.92316) (xy 300.26981 -147.908867) (xy 300.288499 -147.901134)
			(xy 300.298612 -147.900644) (xy 301.479712 -147.900644) (xy 301.489815 -147.901174) (xy 301.508482 -147.908905)
			(xy 301.522775 -147.923188) (xy 301.530519 -147.94185) (xy 301.53102 -147.951952) (xy 301.53102 -148.9583)
			(xy 304.783744 -148.9583) (xy 304.783744 -147.951952) (xy 304.784181 -147.941802) (xy 304.791982 -147.923059)
			(xy 304.806373 -147.90874) (xy 304.825154 -147.901031) (xy 304.835306 -147.900644) (xy 306.016406 -147.900644)
			(xy 306.026534 -147.901122) (xy 306.045256 -147.908852) (xy 306.059612 -147.923141) (xy 306.06743 -147.941827)
			(xy 306.067968 -147.951952) (xy 306.067968 -148.9583) (xy 306.067578 -148.968458) (xy 306.059776 -148.987217)
			(xy 306.045369 -149.001541) (xy 306.026566 -149.009235) (xy 306.016406 -149.009608) (xy 304.835306 -149.009608)
			(xy 304.825186 -149.00907) (xy 304.806474 -149.001353) (xy 304.792119 -148.987083) (xy 304.784291 -148.968417)
			(xy 304.783744 -148.9583) (xy 301.53102 -148.9583) (xy 301.530515 -148.968406) (xy 301.522781 -148.987081)
			(xy 301.508491 -149.001375) (xy 301.489818 -149.009113) (xy 301.479712 -149.009608) (xy 300.298612 -149.009608)
			(xy 300.288491 -149.009174) (xy 300.269789 -149.001432) (xy 300.255475 -148.987121) (xy 300.247728 -148.968421)
			(xy 300.247304 -148.9583) (xy 297.854846 -148.9583) (xy 297.852407 -148.976824) (xy 297.836894 -149.034717)
			(xy 297.83004 -149.051264) (xy 314.441332 -149.051264) (xy 314.441332 -148.82368) (xy 314.441586 -148.819616)
			(xy 314.44184 -148.817076) (xy 314.44184 -148.80844) (xy 314.447428 -148.799804) (xy 314.448698 -148.797772)
			(xy 314.449714 -148.79574) (xy 314.647072 -148.49475) (xy 314.650936 -148.488419) (xy 314.655198 -148.474222)
			(xy 314.655454 -148.46681) (xy 314.655454 -148.441156) (xy 314.655244 -148.433822) (xy 314.651117 -148.419751)
			(xy 314.647326 -148.41347) (xy 314.44946 -148.110448) (xy 314.447174 -148.106638) (xy 314.44692 -148.10613)
			(xy 314.445904 -148.104352) (xy 314.44184 -148.097748) (xy 314.44184 -148.08962) (xy 314.441586 -148.08708)
			(xy 314.441332 -148.083016) (xy 314.441332 -147.854924) (xy 314.441733 -147.844698) (xy 314.449557 -147.825802)
			(xy 314.464022 -147.811344) (xy 314.482922 -147.803528) (xy 314.493148 -147.803108) (xy 315.229748 -147.803108)
			(xy 315.239962 -147.803543) (xy 315.258829 -147.811376) (xy 315.273264 -147.825831) (xy 315.281071 -147.844709)
			(xy 315.281564 -147.854924) (xy 315.281564 -148.082508) (xy 315.28131 -148.086572) (xy 315.281056 -148.089112)
			(xy 315.281056 -148.097748) (xy 315.275214 -148.107146) (xy 315.274452 -148.108416) (xy 315.273182 -148.110448)
			(xy 315.067442 -148.425154) (xy 315.062396 -148.433678) (xy 315.058579 -148.453095) (xy 315.062392 -148.472513)
			(xy 315.067442 -148.481034) (xy 315.273182 -148.79447) (xy 315.274198 -148.796502) (xy 315.275468 -148.798534)
			(xy 315.281056 -148.80717) (xy 315.281056 -148.815806) (xy 315.28131 -148.818346) (xy 315.281564 -148.82241)
			(xy 315.281564 -148.88591) (xy 315.916564 -148.88591) (xy 315.916564 -148.02231) (xy 315.917054 -147.992342)
			(xy 315.924877 -147.93292) (xy 315.94039 -147.875027) (xy 315.963326 -147.819654) (xy 315.993293 -147.767748)
			(xy 316.02978 -147.720198) (xy 316.07216 -147.677818) (xy 316.11971 -147.641331) (xy 316.171616 -147.611364)
			(xy 316.226989 -147.588428) (xy 316.284882 -147.572915) (xy 316.344304 -147.565092) (xy 316.40424 -147.565092)
			(xy 316.463662 -147.572915) (xy 316.521555 -147.588428) (xy 316.576928 -147.611364) (xy 316.628834 -147.641331)
			(xy 316.676384 -147.677818) (xy 316.718764 -147.720198) (xy 316.755251 -147.767748) (xy 316.785218 -147.819654)
			(xy 316.808154 -147.875027) (xy 316.823667 -147.93292) (xy 316.83149 -147.992342) (xy 316.83198 -148.02231)
			(xy 316.83198 -148.88591) (xy 316.831955 -148.887434) (xy 413.045148 -148.887434) (xy 413.045148 -148.023834)
			(xy 413.045638 -147.99385) (xy 413.053466 -147.934394) (xy 413.068987 -147.876469) (xy 413.091936 -147.821065)
			(xy 413.12192 -147.769131) (xy 413.158426 -147.721555) (xy 413.200831 -147.67915) (xy 413.248407 -147.642644)
			(xy 413.300341 -147.61266) (xy 413.355745 -147.589711) (xy 413.41367 -147.57419) (xy 413.473126 -147.566362)
			(xy 413.533094 -147.566362) (xy 413.59255 -147.57419) (xy 413.650475 -147.589711) (xy 413.705879 -147.61266)
			(xy 413.757813 -147.642644) (xy 413.805389 -147.67915) (xy 413.847794 -147.721555) (xy 413.8843 -147.769131)
			(xy 413.914284 -147.821065) (xy 413.937233 -147.876469) (xy 413.952754 -147.934394) (xy 413.960582 -147.99385)
			(xy 413.961072 -148.023834) (xy 413.961072 -148.887434) (xy 413.960582 -148.917418) (xy 413.955199 -148.9583)
			(xy 416.347148 -148.9583) (xy 416.347148 -147.951952) (xy 416.347645 -147.941847) (xy 416.355388 -147.923177)
			(xy 416.369681 -147.908886) (xy 416.388351 -147.901144) (xy 416.398456 -147.900644) (xy 417.57981 -147.900644)
			(xy 417.589938 -147.901119) (xy 417.60866 -147.90885) (xy 417.623016 -147.92314) (xy 417.630834 -147.941827)
			(xy 417.631372 -147.951952) (xy 417.631372 -148.9583) (xy 420.884096 -148.9583) (xy 420.884096 -147.951952)
			(xy 420.884546 -147.941841) (xy 420.892299 -147.923162) (xy 420.906606 -147.908869) (xy 420.925292 -147.901136)
			(xy 420.935404 -147.900644) (xy 422.116504 -147.900644) (xy 422.126606 -147.901181) (xy 422.145274 -147.908909)
			(xy 422.159566 -147.923189) (xy 422.167311 -147.94185) (xy 422.167812 -147.951952) (xy 422.167812 -148.9583)
			(xy 422.167315 -148.968407) (xy 422.15958 -148.987083) (xy 422.145286 -149.001377) (xy 422.126611 -149.009114)
			(xy 422.116504 -149.009608) (xy 420.935404 -149.009608) (xy 420.925283 -149.009181) (xy 420.906581 -149.001436)
			(xy 420.892267 -148.987123) (xy 420.88452 -148.968421) (xy 420.884096 -148.9583) (xy 417.631372 -148.9583)
			(xy 417.630983 -148.968426) (xy 417.62323 -148.987135) (xy 417.608905 -149.00145) (xy 417.59019 -149.00919)
			(xy 417.580064 -149.009608) (xy 416.39871 -149.009608) (xy 416.38859 -149.009067) (xy 416.369878 -149.001351)
			(xy 416.355523 -148.987082) (xy 416.347695 -148.968417) (xy 416.347148 -148.9583) (xy 413.955199 -148.9583)
			(xy 413.952754 -148.976874) (xy 413.937233 -149.034799) (xy 413.930413 -149.051264) (xy 430.541684 -149.051264)
			(xy 430.541684 -148.80844) (xy 430.660556 -148.627084) (xy 430.72304 -148.53158) (xy 430.74717 -148.49475)
			(xy 430.751033 -148.488419) (xy 430.755296 -148.474222) (xy 430.755552 -148.46681) (xy 430.755552 -148.440902)
			(xy 430.75536 -148.434752) (xy 430.752405 -148.422811) (xy 430.74971 -148.41728) (xy 430.636172 -148.24329)
			(xy 430.616106 -148.212302) (xy 430.610518 -148.203666) (xy 430.550066 -148.110956) (xy 430.549558 -148.110194)
			(xy 430.54905 -148.109432) (xy 430.548796 -148.108924) (xy 430.548288 -148.108162) (xy 430.541684 -148.097748)
			(xy 430.541684 -147.854924) (xy 430.542312 -147.843372) (xy 430.552285 -147.822527) (xy 430.570228 -147.807965)
			(xy 430.581308 -147.804632) (xy 430.593246 -147.803108) (xy 431.329846 -147.803108) (xy 431.340601 -147.803648)
			(xy 431.36029 -147.8123) (xy 431.367946 -147.819872) (xy 431.374148 -147.827269) (xy 431.38106 -147.845277)
			(xy 431.381408 -147.854924) (xy 431.381408 -148.097748) (xy 431.165508 -148.428202) (xy 431.161463 -148.436413)
			(xy 431.158926 -148.45453) (xy 431.162882 -148.472391) (xy 431.16754 -148.480272) (xy 431.199798 -148.530056)
			(xy 431.381408 -148.80717) (xy 431.381408 -148.88591) (xy 432.016408 -148.88591) (xy 432.016408 -148.02231)
			(xy 432.016898 -147.992326) (xy 432.024726 -147.93287) (xy 432.040247 -147.874945) (xy 432.063196 -147.819541)
			(xy 432.09318 -147.767607) (xy 432.129686 -147.720031) (xy 432.172091 -147.677626) (xy 432.219667 -147.64112)
			(xy 432.271601 -147.611136) (xy 432.327005 -147.588187) (xy 432.38493 -147.572666) (xy 432.444386 -147.564838)
			(xy 432.504354 -147.564838) (xy 432.56381 -147.572666) (xy 432.621735 -147.588187) (xy 432.677139 -147.611136)
			(xy 432.729073 -147.64112) (xy 432.776649 -147.677626) (xy 432.819054 -147.720031) (xy 432.85556 -147.767607)
			(xy 432.885544 -147.819541) (xy 432.908493 -147.874945) (xy 432.924014 -147.93287) (xy 432.931842 -147.992326)
			(xy 432.932332 -148.02231) (xy 432.932332 -148.88591) (xy 432.931842 -148.915894) (xy 432.924014 -148.97535)
			(xy 432.908493 -149.033275) (xy 432.885544 -149.088679) (xy 432.85556 -149.140613) (xy 432.819054 -149.188189)
			(xy 432.776649 -149.230594) (xy 432.729073 -149.2671) (xy 432.677139 -149.297084) (xy 432.621735 -149.320033)
			(xy 432.56381 -149.335554) (xy 432.504354 -149.343382) (xy 432.444386 -149.343382) (xy 432.38493 -149.335554)
			(xy 432.327005 -149.320033) (xy 432.271601 -149.297084) (xy 432.219667 -149.2671) (xy 432.172091 -149.230594)
			(xy 432.129686 -149.188189) (xy 432.09318 -149.140613) (xy 432.063196 -149.088679) (xy 432.040247 -149.033275)
			(xy 432.024726 -148.97535) (xy 432.016898 -148.915894) (xy 432.016408 -148.88591) (xy 431.381408 -148.88591)
			(xy 431.381408 -149.051264) (xy 431.380776 -149.062816) (xy 431.370806 -149.083662) (xy 431.352864 -149.098223)
			(xy 431.341784 -149.101556) (xy 431.329846 -149.10308) (xy 430.593246 -149.10308) (xy 430.58249 -149.102548)
			(xy 430.562801 -149.09389) (xy 430.555146 -149.086316) (xy 430.548938 -149.078924) (xy 430.542029 -149.060912)
			(xy 430.541684 -149.051264) (xy 413.930413 -149.051264) (xy 413.914284 -149.090203) (xy 413.8843 -149.142137)
			(xy 413.847794 -149.189713) (xy 413.805389 -149.232118) (xy 413.757813 -149.268624) (xy 413.705879 -149.298608)
			(xy 413.650475 -149.321557) (xy 413.59255 -149.337078) (xy 413.533094 -149.344906) (xy 413.473126 -149.344906)
			(xy 413.41367 -149.337078) (xy 413.355745 -149.321557) (xy 413.300341 -149.298608) (xy 413.248407 -149.268624)
			(xy 413.200831 -149.232118) (xy 413.158426 -149.189713) (xy 413.12192 -149.142137) (xy 413.091936 -149.090203)
			(xy 413.068987 -149.034799) (xy 413.053466 -148.976874) (xy 413.045638 -148.917418) (xy 413.045148 -148.887434)
			(xy 316.831955 -148.887434) (xy 316.83149 -148.915878) (xy 316.823667 -148.9753) (xy 316.808154 -149.033193)
			(xy 316.785218 -149.088566) (xy 316.755251 -149.140472) (xy 316.718764 -149.188022) (xy 316.676384 -149.230402)
			(xy 316.628834 -149.266889) (xy 316.576928 -149.296856) (xy 316.521555 -149.319792) (xy 316.463662 -149.335305)
			(xy 316.40424 -149.343128) (xy 316.344304 -149.343128) (xy 316.284882 -149.335305) (xy 316.226989 -149.319792)
			(xy 316.171616 -149.296856) (xy 316.11971 -149.266889) (xy 316.07216 -149.230402) (xy 316.02978 -149.188022)
			(xy 315.993293 -149.140472) (xy 315.963326 -149.088566) (xy 315.94039 -149.033193) (xy 315.924877 -148.9753)
			(xy 315.917054 -148.915878) (xy 315.916564 -148.88591) (xy 315.281564 -148.88591) (xy 315.281564 -149.051264)
			(xy 315.28099 -149.061464) (xy 315.273198 -149.080315) (xy 315.258786 -149.094751) (xy 315.239947 -149.102573)
			(xy 315.229748 -149.10308) (xy 314.493148 -149.10308) (xy 314.482925 -149.102648) (xy 314.464032 -149.094834)
			(xy 314.449573 -149.080378) (xy 314.441754 -149.061487) (xy 314.441332 -149.051264) (xy 297.83004 -149.051264)
			(xy 297.813958 -149.09009) (xy 297.783991 -149.141996) (xy 297.747504 -149.189546) (xy 297.705124 -149.231926)
			(xy 297.657574 -149.268413) (xy 297.605668 -149.29838) (xy 297.550295 -149.321316) (xy 297.492402 -149.336829)
			(xy 297.43298 -149.344652) (xy 297.373044 -149.344652) (xy 297.313622 -149.336829) (xy 297.255729 -149.321316)
			(xy 297.200356 -149.29838) (xy 297.14845 -149.268413) (xy 297.1009 -149.231926) (xy 297.05852 -149.189546)
			(xy 297.022033 -149.141996) (xy 296.992066 -149.09009) (xy 296.96913 -149.034717) (xy 296.953617 -148.976824)
			(xy 296.945794 -148.917402) (xy 296.945304 -148.887434) (xy 237.624112 -148.887434) (xy 237.624112 -149.691344)
			(xy 237.623622 -149.721328) (xy 237.615794 -149.780784) (xy 237.600273 -149.838709) (xy 237.577324 -149.894113)
			(xy 237.54734 -149.946047) (xy 237.510834 -149.993623) (xy 237.468429 -150.036028) (xy 237.420853 -150.072534)
			(xy 237.368919 -150.102518) (xy 237.313515 -150.125467) (xy 237.25559 -150.140988) (xy 237.196134 -150.148816)
			(xy 237.136166 -150.148816) (xy 237.07671 -150.140988) (xy 237.018785 -150.125467) (xy 236.963381 -150.102518)
			(xy 236.911447 -150.072534) (xy 236.863871 -150.036028) (xy 236.821466 -149.993623) (xy 236.78496 -149.946047)
			(xy 236.754976 -149.894113) (xy 236.732027 -149.838709) (xy 236.716506 -149.780784) (xy 236.708678 -149.721328)
			(xy 236.708188 -149.691344) (xy 198.072386 -149.691344) (xy 198.081715 -149.72616) (xy 198.089538 -149.785582)
			(xy 198.090028 -149.81555) (xy 198.090028 -150.67915) (xy 198.089538 -150.709118) (xy 198.081715 -150.76854)
			(xy 198.066202 -150.826433) (xy 198.043266 -150.881806) (xy 198.013299 -150.933712) (xy 197.976812 -150.981262)
			(xy 197.934432 -151.023642) (xy 197.886882 -151.060129) (xy 197.834976 -151.090096) (xy 197.779603 -151.113032)
			(xy 197.72171 -151.128545) (xy 197.662288 -151.136368) (xy 197.602352 -151.136368) (xy 197.54293 -151.128545)
			(xy 197.485037 -151.113032) (xy 197.429664 -151.090096) (xy 197.377758 -151.060129) (xy 197.330208 -151.023642)
			(xy 197.287828 -150.981262) (xy 197.251341 -150.933712) (xy 197.221374 -150.881806) (xy 197.198438 -150.826433)
			(xy 197.182925 -150.76854) (xy 197.175102 -150.709118) (xy 197.174612 -150.67915) (xy 196.539104 -150.67915)
			(xy 196.539104 -150.844504) (xy 196.538429 -150.856051) (xy 196.528481 -150.876897) (xy 196.510554 -150.891461)
			(xy 196.49948 -150.894796) (xy 196.487542 -150.89632) (xy 195.750942 -150.89632) (xy 195.740188 -150.895778)
			(xy 195.720499 -150.887126) (xy 195.712842 -150.879556) (xy 195.706651 -150.872152) (xy 195.699732 -150.854149)
			(xy 195.69938 -150.844504) (xy 183.587132 -150.844504) (xy 183.568314 -150.889934) (xy 183.538347 -150.94184)
			(xy 183.50186 -150.98939) (xy 183.45948 -151.03177) (xy 183.41193 -151.068257) (xy 183.360024 -151.098224)
			(xy 183.304651 -151.12116) (xy 183.246758 -151.136673) (xy 183.187336 -151.144496) (xy 183.1274 -151.144496)
			(xy 183.067978 -151.136673) (xy 183.010085 -151.12116) (xy 182.954712 -151.098224) (xy 182.902806 -151.068257)
			(xy 182.855256 -151.03177) (xy 182.812876 -150.98939) (xy 182.776389 -150.94184) (xy 182.746422 -150.889934)
			(xy 182.723486 -150.834561) (xy 182.707973 -150.776668) (xy 182.70015 -150.717246) (xy 182.69966 -150.687278)
			(xy 81.990051 -150.687278) (xy 81.989694 -150.709134) (xy 81.981866 -150.76859) (xy 81.966345 -150.826515)
			(xy 81.943396 -150.881919) (xy 81.913412 -150.933853) (xy 81.876906 -150.981429) (xy 81.834501 -151.023834)
			(xy 81.786925 -151.06034) (xy 81.734991 -151.090324) (xy 81.679587 -151.113273) (xy 81.621662 -151.128794)
			(xy 81.562206 -151.136622) (xy 81.502238 -151.136622) (xy 81.442782 -151.128794) (xy 81.384857 -151.113273)
			(xy 81.329453 -151.090324) (xy 81.277519 -151.06034) (xy 81.229943 -151.023834) (xy 81.187538 -150.981429)
			(xy 81.151032 -150.933853) (xy 81.121048 -150.881919) (xy 81.098099 -150.826515) (xy 81.082578 -150.76859)
			(xy 81.07475 -150.709134) (xy 81.07426 -150.67915) (xy 80.43926 -150.67915) (xy 80.43926 -150.844504)
			(xy 80.438618 -150.856056) (xy 80.42866 -150.876908) (xy 80.410717 -150.891468) (xy 80.399636 -150.894796)
			(xy 80.387698 -150.89632) (xy 79.651098 -150.89632) (xy 79.640341 -150.895802) (xy 79.620652 -150.887133)
			(xy 79.612998 -150.879556) (xy 79.606801 -150.872156) (xy 79.599887 -150.85415) (xy 79.599536 -150.844504)
			(xy 67.487308 -150.844504) (xy 67.468444 -150.890047) (xy 67.43846 -150.941981) (xy 67.401954 -150.989557)
			(xy 67.359549 -151.031962) (xy 67.311973 -151.068468) (xy 67.260039 -151.098452) (xy 67.204635 -151.121401)
			(xy 67.14671 -151.136922) (xy 67.087254 -151.14475) (xy 67.027286 -151.14475) (xy 66.96783 -151.136922)
			(xy 66.909905 -151.121401) (xy 66.854501 -151.098452) (xy 66.802567 -151.068468) (xy 66.754991 -151.031962)
			(xy 66.712586 -150.989557) (xy 66.67608 -150.941981) (xy 66.646096 -150.890047) (xy 66.623147 -150.834643)
			(xy 66.607626 -150.776718) (xy 66.599798 -150.717262) (xy 66.599308 -150.687278) (xy 4.30911 -150.687278)
			(xy 4.30911 -152.487376) (xy 64.745108 -152.487376) (xy 64.745108 -151.623776) (xy 64.745598 -151.593792)
			(xy 64.753426 -151.534336) (xy 64.768947 -151.476411) (xy 64.791896 -151.421007) (xy 64.82188 -151.369073)
			(xy 64.858386 -151.321497) (xy 64.900791 -151.279092) (xy 64.948367 -151.242586) (xy 65.000301 -151.212602)
			(xy 65.055705 -151.189653) (xy 65.11363 -151.174132) (xy 65.173086 -151.166304) (xy 65.233054 -151.166304)
			(xy 65.29251 -151.174132) (xy 65.350435 -151.189653) (xy 65.405839 -151.212602) (xy 65.457773 -151.242586)
			(xy 65.505349 -151.279092) (xy 65.547754 -151.321497) (xy 65.58426 -151.369073) (xy 65.614244 -151.421007)
			(xy 65.637193 -151.476411) (xy 65.652714 -151.534336) (xy 65.660542 -151.593792) (xy 65.661032 -151.623776)
			(xy 65.661032 -152.487376) (xy 65.660542 -152.51736) (xy 65.655159 -152.558242) (xy 68.047108 -152.558242)
			(xy 68.047108 -151.551894) (xy 68.047628 -151.54174) (xy 68.055399 -151.522976) (xy 68.069756 -151.508612)
			(xy 68.088516 -151.500833) (xy 68.09867 -151.500332) (xy 69.27977 -151.500332) (xy 69.289939 -151.500788)
			(xy 69.308732 -151.508562) (xy 69.323117 -151.522938) (xy 69.330904 -151.541725) (xy 69.331332 -151.551894)
			(xy 69.331332 -152.558242) (xy 72.584056 -152.558242) (xy 72.584056 -151.551894) (xy 72.584522 -151.541765)
			(xy 72.592255 -151.523041) (xy 72.606548 -151.508684) (xy 72.625237 -151.500868) (xy 72.635364 -151.500332)
			(xy 73.816464 -151.500332) (xy 73.82662 -151.500752) (xy 73.845377 -151.508542) (xy 73.859703 -151.52294)
			(xy 73.867398 -151.541736) (xy 73.867772 -151.551894) (xy 73.867772 -152.558242) (xy 73.867308 -152.56837)
			(xy 73.859569 -152.58709) (xy 73.845276 -152.601444) (xy 73.82659 -152.609264) (xy 73.816464 -152.609804)
			(xy 72.635364 -152.609804) (xy 72.625208 -152.609408) (xy 72.606456 -152.601601) (xy 72.592134 -152.587197)
			(xy 72.584435 -152.5684) (xy 72.584056 -152.558242) (xy 69.331332 -152.558242) (xy 69.3309 -152.568406)
			(xy 69.323106 -152.587182) (xy 69.308722 -152.601547) (xy 69.289935 -152.609314) (xy 69.27977 -152.609804)
			(xy 68.09867 -152.609804) (xy 68.088515 -152.609292) (xy 68.069754 -152.601516) (xy 68.055391 -152.587156)
			(xy 68.04761 -152.568396) (xy 68.047108 -152.558242) (xy 65.655159 -152.558242) (xy 65.652714 -152.576816)
			(xy 65.637193 -152.634741) (xy 65.630373 -152.651206) (xy 82.241644 -152.651206) (xy 82.241644 -152.408382)
			(xy 82.360516 -152.227026) (xy 82.423 -152.131522) (xy 82.44713 -152.094692) (xy 82.451012 -152.088371)
			(xy 82.455264 -152.074166) (xy 82.455512 -152.066752) (xy 82.455512 -152.040844) (xy 82.45531 -152.034695)
			(xy 82.452363 -152.022754) (xy 82.44967 -152.017222) (xy 82.336132 -151.843232) (xy 82.316066 -151.812244)
			(xy 82.310478 -151.803608) (xy 82.250026 -151.710898) (xy 82.249518 -151.710136) (xy 82.24901 -151.709374)
			(xy 82.248756 -151.708866) (xy 82.248248 -151.708104) (xy 82.241644 -151.69769) (xy 82.241644 -151.454866)
			(xy 82.242106 -151.444705) (xy 82.249892 -151.425934) (xy 82.264268 -151.41157) (xy 82.283045 -151.403798)
			(xy 82.293206 -151.403304) (xy 83.029806 -151.403304) (xy 83.03996 -151.403828) (xy 83.058723 -151.411598)
			(xy 83.073086 -151.425954) (xy 83.080867 -151.444712) (xy 83.081368 -151.454866) (xy 83.081368 -151.69769)
			(xy 82.865468 -152.028144) (xy 82.861473 -152.036376) (xy 82.858922 -152.054479) (xy 82.862855 -152.072332)
			(xy 82.8675 -152.080214) (xy 82.899758 -152.129998) (xy 83.081368 -152.407112) (xy 83.081368 -152.485852)
			(xy 83.716368 -152.485852) (xy 83.716368 -151.622252) (xy 83.716858 -151.592268) (xy 83.724686 -151.532812)
			(xy 83.740207 -151.474887) (xy 83.763156 -151.419483) (xy 83.79314 -151.367549) (xy 83.829646 -151.319973)
			(xy 83.872051 -151.277568) (xy 83.919627 -151.241062) (xy 83.971561 -151.211078) (xy 84.026965 -151.188129)
			(xy 84.08489 -151.172608) (xy 84.144346 -151.16478) (xy 84.204314 -151.16478) (xy 84.26377 -151.172608)
			(xy 84.321695 -151.188129) (xy 84.377099 -151.211078) (xy 84.429033 -151.241062) (xy 84.476609 -151.277568)
			(xy 84.519014 -151.319973) (xy 84.55552 -151.367549) (xy 84.585504 -151.419483) (xy 84.608453 -151.474887)
			(xy 84.623974 -151.532812) (xy 84.631802 -151.592268) (xy 84.632292 -151.622252) (xy 84.632292 -152.485852)
			(xy 84.632267 -152.487376) (xy 180.84546 -152.487376) (xy 180.84546 -151.623776) (xy 180.84595 -151.593808)
			(xy 180.853773 -151.534386) (xy 180.869286 -151.476493) (xy 180.892222 -151.42112) (xy 180.922189 -151.369214)
			(xy 180.958676 -151.321664) (xy 181.001056 -151.279284) (xy 181.048606 -151.242797) (xy 181.100512 -151.21283)
			(xy 181.155885 -151.189894) (xy 181.213778 -151.174381) (xy 181.2732 -151.166558) (xy 181.333136 -151.166558)
			(xy 181.392558 -151.174381) (xy 181.450451 -151.189894) (xy 181.505824 -151.21283) (xy 181.55773 -151.242797)
			(xy 181.60528 -151.279284) (xy 181.64766 -151.321664) (xy 181.684147 -151.369214) (xy 181.714114 -151.42112)
			(xy 181.73705 -151.476493) (xy 181.752563 -151.534386) (xy 181.760386 -151.593808) (xy 181.760876 -151.623776)
			(xy 181.760876 -152.487376) (xy 181.760386 -152.517344) (xy 181.755002 -152.558242) (xy 184.146952 -152.558242)
			(xy 184.146952 -151.551894) (xy 184.147359 -151.54172) (xy 184.155149 -151.522923) (xy 184.16954 -151.508538)
			(xy 184.18834 -151.500755) (xy 184.198514 -151.500332) (xy 185.379614 -151.500332) (xy 185.389772 -151.500822)
			(xy 185.40854 -151.5086) (xy 185.422905 -151.522967) (xy 185.43068 -151.541736) (xy 185.431176 -151.551894)
			(xy 185.431176 -152.558242) (xy 188.6839 -152.558242) (xy 188.6839 -151.551894) (xy 188.684421 -151.541772)
			(xy 188.692143 -151.523058) (xy 188.706418 -151.508704) (xy 188.725089 -151.500878) (xy 188.735208 -151.500332)
			(xy 189.916308 -151.500332) (xy 189.926467 -151.500716) (xy 189.945225 -151.50852) (xy 189.959549 -151.522929)
			(xy 189.967243 -151.541733) (xy 189.967616 -151.551894) (xy 189.967616 -152.558242) (xy 189.967207 -152.568377)
			(xy 189.959457 -152.587107) (xy 189.945147 -152.601464) (xy 189.926441 -152.609274) (xy 189.916308 -152.609804)
			(xy 188.735208 -152.609804) (xy 188.725055 -152.609372) (xy 188.706303 -152.60158) (xy 188.69198 -152.587186)
			(xy 188.684279 -152.568397) (xy 188.6839 -152.558242) (xy 185.431176 -152.558242) (xy 185.430701 -152.568401)
			(xy 185.422916 -152.587168) (xy 185.408545 -152.601531) (xy 185.389773 -152.609307) (xy 185.379614 -152.609804)
			(xy 184.198514 -152.609804) (xy 184.188362 -152.609256) (xy 184.169601 -152.601494) (xy 184.155237 -152.587146)
			(xy 184.147455 -152.568393) (xy 184.146952 -152.558242) (xy 181.755002 -152.558242) (xy 181.752563 -152.576766)
			(xy 181.73705 -152.634659) (xy 181.730196 -152.651206) (xy 198.341488 -152.651206) (xy 198.341488 -152.408382)
			(xy 198.46036 -152.227026) (xy 198.522844 -152.131522) (xy 198.546974 -152.094692) (xy 198.550859 -152.088373)
			(xy 198.555108 -152.074166) (xy 198.555356 -152.066752) (xy 198.555356 -152.040844) (xy 198.555149 -152.034695)
			(xy 198.552205 -152.022754) (xy 198.549514 -152.017222) (xy 198.435976 -151.843232) (xy 198.41591 -151.812244)
			(xy 198.410322 -151.803608) (xy 198.34987 -151.710898) (xy 198.349362 -151.710136) (xy 198.348854 -151.709374)
			(xy 198.3486 -151.708866) (xy 198.348092 -151.708104) (xy 198.341488 -151.69769) (xy 198.341488 -151.454866)
			(xy 198.341837 -151.444686) (xy 198.349643 -151.425881) (xy 198.364052 -151.411495) (xy 198.382869 -151.403721)
			(xy 198.39305 -151.403304) (xy 199.12965 -151.403304) (xy 199.139814 -151.403804) (xy 199.158601 -151.411566)
			(xy 199.172987 -151.425928) (xy 199.18078 -151.444703) (xy 199.181212 -151.454866) (xy 199.181212 -151.69769)
			(xy 198.965312 -152.028144) (xy 198.961313 -152.036375) (xy 198.95876 -152.054479) (xy 198.962696 -152.072333)
			(xy 198.967344 -152.080214) (xy 198.999602 -152.129998) (xy 199.181212 -152.407112) (xy 199.181212 -152.485852)
			(xy 199.81672 -152.485852) (xy 199.81672 -151.622252) (xy 199.81721 -151.592284) (xy 199.825033 -151.532862)
			(xy 199.840546 -151.474969) (xy 199.863482 -151.419596) (xy 199.893449 -151.36769) (xy 199.929936 -151.32014)
			(xy 199.972316 -151.27776) (xy 200.019866 -151.241273) (xy 200.071772 -151.211306) (xy 200.127145 -151.18837)
			(xy 200.185038 -151.172857) (xy 200.24446 -151.165034) (xy 200.304396 -151.165034) (xy 200.363818 -151.172857)
			(xy 200.421711 -151.18837) (xy 200.477084 -151.211306) (xy 200.52899 -151.241273) (xy 200.57654 -151.27776)
			(xy 200.61892 -151.32014) (xy 200.655407 -151.36769) (xy 200.685374 -151.419596) (xy 200.70831 -151.474969)
			(xy 200.723823 -151.532862) (xy 200.731646 -151.592284) (xy 200.732136 -151.622252) (xy 200.732136 -151.914098)
			(xy 236.712252 -151.914098) (xy 236.712252 -151.050498) (xy 236.712742 -151.020514) (xy 236.72057 -150.961058)
			(xy 236.736091 -150.903133) (xy 236.75904 -150.847729) (xy 236.789024 -150.795795) (xy 236.82553 -150.748219)
			(xy 236.867935 -150.705814) (xy 236.915511 -150.669308) (xy 236.967445 -150.639324) (xy 237.022849 -150.616375)
			(xy 237.080774 -150.600854) (xy 237.14023 -150.593026) (xy 237.200198 -150.593026) (xy 237.259654 -150.600854)
			(xy 237.317579 -150.616375) (xy 237.372983 -150.639324) (xy 237.424917 -150.669308) (xy 237.448336 -150.687278)
			(xy 298.799504 -150.687278) (xy 298.799504 -149.823678) (xy 298.799994 -149.79371) (xy 298.807817 -149.734288)
			(xy 298.82333 -149.676395) (xy 298.846266 -149.621022) (xy 298.876233 -149.569116) (xy 298.91272 -149.521566)
			(xy 298.9551 -149.479186) (xy 299.00265 -149.442699) (xy 299.054556 -149.412732) (xy 299.109929 -149.389796)
			(xy 299.167822 -149.374283) (xy 299.227244 -149.36646) (xy 299.28718 -149.36646) (xy 299.346602 -149.374283)
			(xy 299.404495 -149.389796) (xy 299.459868 -149.412732) (xy 299.511774 -149.442699) (xy 299.559324 -149.479186)
			(xy 299.601704 -149.521566) (xy 299.638191 -149.569116) (xy 299.668158 -149.621022) (xy 299.691094 -149.676395)
			(xy 299.706607 -149.734288) (xy 299.71443 -149.79371) (xy 299.71492 -149.823678) (xy 299.71492 -150.687278)
			(xy 299.71443 -150.717246) (xy 299.709046 -150.758144) (xy 300.247304 -150.758144) (xy 300.247304 -149.751796)
			(xy 300.247713 -149.741673) (xy 300.255463 -149.722968) (xy 300.269782 -149.708654) (xy 300.288489 -149.70091)
			(xy 300.298612 -149.700488) (xy 301.479712 -149.700488) (xy 301.48982 -149.700975) (xy 301.508496 -149.708715)
			(xy 301.52279 -149.723011) (xy 301.530526 -149.741688) (xy 301.53102 -149.751796) (xy 301.53102 -150.758144)
			(xy 304.783744 -150.758144) (xy 304.783744 -149.751796) (xy 304.784217 -149.741649) (xy 304.792004 -149.722907)
			(xy 304.806384 -149.708586) (xy 304.825157 -149.700876) (xy 304.835306 -149.700488) (xy 306.016406 -149.700488)
			(xy 306.026527 -149.70102) (xy 306.045238 -149.70874) (xy 306.059592 -149.723012) (xy 306.06742 -149.741678)
			(xy 306.067968 -149.751796) (xy 306.067968 -150.758144) (xy 306.067614 -150.768305) (xy 306.059798 -150.787064)
			(xy 306.04538 -150.801387) (xy 306.02657 -150.80908) (xy 306.016406 -150.809452) (xy 304.835306 -150.809452)
			(xy 304.825179 -150.808968) (xy 304.806456 -150.801241) (xy 304.792099 -150.786954) (xy 304.784281 -150.768269)
			(xy 304.783744 -150.758144) (xy 301.53102 -150.758144) (xy 301.530551 -150.768253) (xy 301.522803 -150.786928)
			(xy 301.508502 -150.801221) (xy 301.489821 -150.808958) (xy 301.479712 -150.809452) (xy 300.298612 -150.809452)
			(xy 300.28851 -150.808906) (xy 300.269842 -150.801182) (xy 300.255549 -150.786905) (xy 300.247805 -150.768245)
			(xy 300.247304 -150.758144) (xy 299.709046 -150.758144) (xy 299.706607 -150.776668) (xy 299.691094 -150.834561)
			(xy 299.686976 -150.844504) (xy 311.799224 -150.844504) (xy 311.799224 -150.61692) (xy 311.799478 -150.612856)
			(xy 311.799732 -150.610316) (xy 311.799732 -150.60168) (xy 311.80532 -150.593044) (xy 311.80659 -150.591012)
			(xy 311.807606 -150.58898) (xy 312.004964 -150.28799) (xy 312.008849 -150.281671) (xy 312.013098 -150.267464)
			(xy 312.013346 -150.26005) (xy 312.013346 -150.234396) (xy 312.013162 -150.22706) (xy 312.009017 -150.212989)
			(xy 312.005218 -150.20671) (xy 311.807352 -149.903688) (xy 311.805066 -149.899878) (xy 311.804812 -149.89937)
			(xy 311.803796 -149.897592) (xy 311.799732 -149.890988) (xy 311.799732 -149.88286) (xy 311.799478 -149.88032)
			(xy 311.799224 -149.876256) (xy 311.799224 -149.648164) (xy 311.799584 -149.637935) (xy 311.807426 -149.619039)
			(xy 311.821903 -149.604584) (xy 311.84081 -149.596769) (xy 311.85104 -149.596348) (xy 312.58764 -149.596348)
			(xy 312.597846 -149.596848) (xy 312.616702 -149.604667) (xy 312.631135 -149.619102) (xy 312.638953 -149.637958)
			(xy 312.639456 -149.648164) (xy 312.639456 -149.875748) (xy 312.639202 -149.879812) (xy 312.638948 -149.882352)
			(xy 312.638948 -149.890988) (xy 312.633106 -149.900386) (xy 312.632344 -149.901656) (xy 312.631074 -149.903688)
			(xy 312.425334 -150.218394) (xy 312.420255 -150.226901) (xy 312.41645 -150.246329) (xy 312.420277 -150.265752)
			(xy 312.425334 -150.274274) (xy 312.631074 -150.58771) (xy 312.63209 -150.589742) (xy 312.63336 -150.591774)
			(xy 312.638948 -150.60041) (xy 312.638948 -150.609046) (xy 312.639202 -150.611586) (xy 312.639456 -150.61565)
			(xy 312.639456 -150.67915) (xy 313.274456 -150.67915) (xy 313.274456 -149.81555) (xy 313.274946 -149.785582)
			(xy 313.282769 -149.72616) (xy 313.298282 -149.668267) (xy 313.321218 -149.612894) (xy 313.351185 -149.560988)
			(xy 313.387672 -149.513438) (xy 313.430052 -149.471058) (xy 313.477602 -149.434571) (xy 313.529508 -149.404604)
			(xy 313.584881 -149.381668) (xy 313.642774 -149.366155) (xy 313.702196 -149.358332) (xy 313.762132 -149.358332)
			(xy 313.821554 -149.366155) (xy 313.879447 -149.381668) (xy 313.93482 -149.404604) (xy 313.986726 -149.434571)
			(xy 314.034276 -149.471058) (xy 314.076656 -149.513438) (xy 314.113143 -149.560988) (xy 314.14311 -149.612894)
			(xy 314.166046 -149.668267) (xy 314.181559 -149.72616) (xy 314.189382 -149.785582) (xy 314.189872 -149.81555)
			(xy 314.189872 -150.67915) (xy 314.189739 -150.687278) (xy 414.899348 -150.687278) (xy 414.899348 -149.823678)
			(xy 414.899838 -149.793694) (xy 414.907666 -149.734238) (xy 414.923187 -149.676313) (xy 414.946136 -149.620909)
			(xy 414.97612 -149.568975) (xy 415.012626 -149.521399) (xy 415.055031 -149.478994) (xy 415.102607 -149.442488)
			(xy 415.154541 -149.412504) (xy 415.209945 -149.389555) (xy 415.26787 -149.374034) (xy 415.327326 -149.366206)
			(xy 415.387294 -149.366206) (xy 415.44675 -149.374034) (xy 415.504675 -149.389555) (xy 415.560079 -149.412504)
			(xy 415.612013 -149.442488) (xy 415.659589 -149.478994) (xy 415.701994 -149.521399) (xy 415.7385 -149.568975)
			(xy 415.768484 -149.620909) (xy 415.791433 -149.676313) (xy 415.806954 -149.734238) (xy 415.814782 -149.793694)
			(xy 415.815272 -149.823678) (xy 415.815272 -150.687278) (xy 415.814782 -150.717262) (xy 415.809399 -150.758144)
			(xy 416.347148 -150.758144) (xy 416.347148 -149.751796) (xy 416.347681 -149.741693) (xy 416.35541 -149.723025)
			(xy 416.369692 -149.708732) (xy 416.388354 -149.700989) (xy 416.398456 -149.700488) (xy 417.57981 -149.700488)
			(xy 417.589931 -149.701017) (xy 417.608642 -149.708738) (xy 417.622996 -149.723011) (xy 417.630824 -149.741678)
			(xy 417.631372 -149.751796) (xy 417.631372 -150.758144) (xy 420.884096 -150.758144) (xy 420.884096 -149.751796)
			(xy 420.884582 -149.741688) (xy 420.89232 -149.72301) (xy 420.906617 -149.708716) (xy 420.925295 -149.70098)
			(xy 420.935404 -149.700488) (xy 422.116504 -149.700488) (xy 422.126611 -149.700982) (xy 422.145287 -149.708718)
			(xy 422.159582 -149.723013) (xy 422.167318 -149.741689) (xy 422.167812 -149.751796) (xy 422.167812 -150.758144)
			(xy 422.167351 -150.768254) (xy 422.159601 -150.786931) (xy 422.145297 -150.801224) (xy 422.126614 -150.808959)
			(xy 422.116504 -150.809452) (xy 420.935404 -150.809452) (xy 420.925302 -150.808913) (xy 420.906634 -150.801186)
			(xy 420.892341 -150.786907) (xy 420.884597 -150.768246) (xy 420.884096 -150.758144) (xy 417.631372 -150.758144)
			(xy 417.63095 -150.768259) (xy 417.623193 -150.786944) (xy 417.608876 -150.801238) (xy 417.59018 -150.808966)
			(xy 417.580064 -150.809452) (xy 416.39871 -150.809452) (xy 416.388583 -150.808965) (xy 416.36986 -150.801239)
			(xy 416.355504 -150.786953) (xy 416.347685 -150.768269) (xy 416.347148 -150.758144) (xy 415.809399 -150.758144)
			(xy 415.806954 -150.776718) (xy 415.791433 -150.834643) (xy 415.787348 -150.844504) (xy 427.899576 -150.844504)
			(xy 427.899576 -150.60168) (xy 428.018448 -150.420324) (xy 428.080932 -150.32482) (xy 428.105062 -150.28799)
			(xy 428.108947 -150.281671) (xy 428.113196 -150.267464) (xy 428.113444 -150.26005) (xy 428.113444 -150.234142)
			(xy 428.113239 -150.227993) (xy 428.110294 -150.216052) (xy 428.107602 -150.21052) (xy 427.994064 -150.03653)
			(xy 427.973998 -150.005542) (xy 427.96841 -149.996906) (xy 427.907958 -149.904196) (xy 427.90745 -149.903434)
			(xy 427.906942 -149.902672) (xy 427.906688 -149.902164) (xy 427.90618 -149.901402) (xy 427.899576 -149.890988)
			(xy 427.899576 -149.648164) (xy 427.900241 -149.636616) (xy 427.910197 -149.615773) (xy 427.928126 -149.601208)
			(xy 427.9392 -149.597872) (xy 427.951138 -149.596348) (xy 428.687738 -149.596348) (xy 428.698494 -149.596881)
			(xy 428.718184 -149.605537) (xy 428.725838 -149.613112) (xy 428.732013 -149.620528) (xy 428.738942 -149.638522)
			(xy 428.7393 -149.648164) (xy 428.7393 -149.890988) (xy 428.5234 -150.221442) (xy 428.519403 -150.229674)
			(xy 428.516851 -150.247777) (xy 428.520785 -150.265631) (xy 428.525432 -150.273512) (xy 428.55769 -150.323296)
			(xy 428.7393 -150.60041) (xy 428.7393 -150.67915) (xy 429.3743 -150.67915) (xy 429.3743 -149.81555)
			(xy 429.37479 -149.785566) (xy 429.382618 -149.72611) (xy 429.398139 -149.668185) (xy 429.421088 -149.612781)
			(xy 429.451072 -149.560847) (xy 429.487578 -149.513271) (xy 429.529983 -149.470866) (xy 429.577559 -149.43436)
			(xy 429.629493 -149.404376) (xy 429.684897 -149.381427) (xy 429.742822 -149.365906) (xy 429.802278 -149.358078)
			(xy 429.862246 -149.358078) (xy 429.921702 -149.365906) (xy 429.979627 -149.381427) (xy 430.035031 -149.404376)
			(xy 430.086965 -149.43436) (xy 430.134541 -149.470866) (xy 430.176946 -149.513271) (xy 430.213452 -149.560847)
			(xy 430.243436 -149.612781) (xy 430.266385 -149.668185) (xy 430.281906 -149.72611) (xy 430.289734 -149.785566)
			(xy 430.290224 -149.81555) (xy 430.290224 -150.67915) (xy 430.289734 -150.709134) (xy 430.281906 -150.76859)
			(xy 430.266385 -150.826515) (xy 430.243436 -150.881919) (xy 430.213452 -150.933853) (xy 430.176946 -150.981429)
			(xy 430.134541 -151.023834) (xy 430.086965 -151.06034) (xy 430.035031 -151.090324) (xy 429.979627 -151.113273)
			(xy 429.921702 -151.128794) (xy 429.862246 -151.136622) (xy 429.802278 -151.136622) (xy 429.742822 -151.128794)
			(xy 429.684897 -151.113273) (xy 429.629493 -151.090324) (xy 429.577559 -151.06034) (xy 429.529983 -151.023834)
			(xy 429.487578 -150.981429) (xy 429.451072 -150.933853) (xy 429.421088 -150.881919) (xy 429.398139 -150.826515)
			(xy 429.382618 -150.76859) (xy 429.37479 -150.709134) (xy 429.3743 -150.67915) (xy 428.7393 -150.67915)
			(xy 428.7393 -150.844504) (xy 428.738628 -150.856052) (xy 428.728679 -150.876898) (xy 428.710751 -150.891462)
			(xy 428.699676 -150.894796) (xy 428.687738 -150.89632) (xy 427.951138 -150.89632) (xy 427.940383 -150.89578)
			(xy 427.920695 -150.887126) (xy 427.913038 -150.879556) (xy 427.906847 -150.872152) (xy 427.899928 -150.854149)
			(xy 427.899576 -150.844504) (xy 415.787348 -150.844504) (xy 415.768484 -150.890047) (xy 415.7385 -150.941981)
			(xy 415.701994 -150.989557) (xy 415.659589 -151.031962) (xy 415.612013 -151.068468) (xy 415.560079 -151.098452)
			(xy 415.504675 -151.121401) (xy 415.44675 -151.136922) (xy 415.387294 -151.14475) (xy 415.327326 -151.14475)
			(xy 415.26787 -151.136922) (xy 415.209945 -151.121401) (xy 415.154541 -151.098452) (xy 415.102607 -151.068468)
			(xy 415.055031 -151.031962) (xy 415.012626 -150.989557) (xy 414.97612 -150.941981) (xy 414.946136 -150.890047)
			(xy 414.923187 -150.834643) (xy 414.907666 -150.776718) (xy 414.899838 -150.717262) (xy 414.899348 -150.687278)
			(xy 314.189739 -150.687278) (xy 314.189382 -150.709118) (xy 314.181559 -150.76854) (xy 314.166046 -150.826433)
			(xy 314.14311 -150.881806) (xy 314.113143 -150.933712) (xy 314.076656 -150.981262) (xy 314.034276 -151.023642)
			(xy 313.986726 -151.060129) (xy 313.93482 -151.090096) (xy 313.879447 -151.113032) (xy 313.821554 -151.128545)
			(xy 313.762132 -151.136368) (xy 313.702196 -151.136368) (xy 313.642774 -151.128545) (xy 313.584881 -151.113032)
			(xy 313.529508 -151.090096) (xy 313.477602 -151.060129) (xy 313.430052 -151.023642) (xy 313.387672 -150.981262)
			(xy 313.351185 -150.933712) (xy 313.321218 -150.881806) (xy 313.298282 -150.826433) (xy 313.282769 -150.76854)
			(xy 313.274946 -150.709118) (xy 313.274456 -150.67915) (xy 312.639456 -150.67915) (xy 312.639456 -150.844504)
			(xy 312.638922 -150.854707) (xy 312.631116 -150.873561) (xy 312.616691 -150.887996) (xy 312.597843 -150.895815)
			(xy 312.58764 -150.89632) (xy 311.85104 -150.89632) (xy 311.840821 -150.895856) (xy 311.821936 -150.888046)
			(xy 311.807479 -150.873601) (xy 311.799653 -150.854722) (xy 311.799224 -150.844504) (xy 299.686976 -150.844504)
			(xy 299.668158 -150.889934) (xy 299.638191 -150.94184) (xy 299.601704 -150.98939) (xy 299.559324 -151.03177)
			(xy 299.511774 -151.068257) (xy 299.459868 -151.098224) (xy 299.404495 -151.12116) (xy 299.346602 -151.136673)
			(xy 299.28718 -151.144496) (xy 299.227244 -151.144496) (xy 299.167822 -151.136673) (xy 299.109929 -151.12116)
			(xy 299.054556 -151.098224) (xy 299.00265 -151.068257) (xy 298.9551 -151.03177) (xy 298.91272 -150.98939)
			(xy 298.876233 -150.94184) (xy 298.846266 -150.889934) (xy 298.82333 -150.834561) (xy 298.807817 -150.776668)
			(xy 298.799994 -150.717246) (xy 298.799504 -150.687278) (xy 237.448336 -150.687278) (xy 237.472493 -150.705814)
			(xy 237.514898 -150.748219) (xy 237.551404 -150.795795) (xy 237.581388 -150.847729) (xy 237.604337 -150.903133)
			(xy 237.619858 -150.961058) (xy 237.627686 -151.020514) (xy 237.628176 -151.050498) (xy 237.628176 -151.914098)
			(xy 237.627686 -151.944082) (xy 237.619858 -152.003538) (xy 237.604337 -152.061463) (xy 237.581388 -152.116867)
			(xy 237.551404 -152.168801) (xy 237.514898 -152.216377) (xy 237.472493 -152.258782) (xy 237.424917 -152.295288)
			(xy 237.372983 -152.325272) (xy 237.317579 -152.348221) (xy 237.259654 -152.363742) (xy 237.200198 -152.37157)
			(xy 237.14023 -152.37157) (xy 237.080774 -152.363742) (xy 237.022849 -152.348221) (xy 236.967445 -152.325272)
			(xy 236.915511 -152.295288) (xy 236.867935 -152.258782) (xy 236.82553 -152.216377) (xy 236.789024 -152.168801)
			(xy 236.75904 -152.116867) (xy 236.736091 -152.061463) (xy 236.72057 -152.003538) (xy 236.712742 -151.944082)
			(xy 236.712252 -151.914098) (xy 200.732136 -151.914098) (xy 200.732136 -152.485852) (xy 200.732111 -152.487376)
			(xy 296.945304 -152.487376) (xy 296.945304 -151.623776) (xy 296.945794 -151.593808) (xy 296.953617 -151.534386)
			(xy 296.96913 -151.476493) (xy 296.992066 -151.42112) (xy 297.022033 -151.369214) (xy 297.05852 -151.321664)
			(xy 297.1009 -151.279284) (xy 297.14845 -151.242797) (xy 297.200356 -151.21283) (xy 297.255729 -151.189894)
			(xy 297.313622 -151.174381) (xy 297.373044 -151.166558) (xy 297.43298 -151.166558) (xy 297.492402 -151.174381)
			(xy 297.550295 -151.189894) (xy 297.605668 -151.21283) (xy 297.657574 -151.242797) (xy 297.705124 -151.279284)
			(xy 297.747504 -151.321664) (xy 297.783991 -151.369214) (xy 297.813958 -151.42112) (xy 297.836894 -151.476493)
			(xy 297.852407 -151.534386) (xy 297.86023 -151.593808) (xy 297.86072 -151.623776) (xy 297.86072 -152.487376)
			(xy 297.86023 -152.517344) (xy 297.854812 -152.558496) (xy 300.247304 -152.558496) (xy 300.247304 -151.551894)
			(xy 300.247821 -151.541771) (xy 300.255544 -151.523057) (xy 300.26982 -151.508702) (xy 300.288492 -151.500877)
			(xy 300.298612 -151.500332) (xy 301.479712 -151.500332) (xy 301.489839 -151.500707) (xy 301.508549 -151.508465)
			(xy 301.522864 -151.522794) (xy 301.530604 -151.541512) (xy 301.53102 -151.55164) (xy 301.53102 -152.558242)
			(xy 304.783744 -152.558242) (xy 304.783744 -151.551894) (xy 304.784229 -151.541735) (xy 304.792006 -151.522965)
			(xy 304.806375 -151.5086) (xy 304.825147 -151.500826) (xy 304.835306 -151.500332) (xy 306.016406 -151.500332)
			(xy 306.026563 -151.500828) (xy 306.045331 -151.508604) (xy 306.059696 -151.522969) (xy 306.067472 -151.541737)
			(xy 306.067968 -151.551894) (xy 306.067968 -152.558242) (xy 306.067501 -152.568402) (xy 306.059714 -152.587171)
			(xy 306.04534 -152.601534) (xy 306.026566 -152.609308) (xy 306.016406 -152.609804) (xy 304.835306 -152.609804)
			(xy 304.825154 -152.609263) (xy 304.806393 -152.601498) (xy 304.792029 -152.587147) (xy 304.784247 -152.568394)
			(xy 304.783744 -152.558242) (xy 301.53102 -152.558242) (xy 301.530607 -152.568376) (xy 301.522858 -152.587106)
			(xy 301.508549 -152.601462) (xy 301.489845 -152.609273) (xy 301.479712 -152.609804) (xy 300.298612 -152.609804)
			(xy 300.288491 -152.609374) (xy 300.269788 -152.601631) (xy 300.255474 -152.587319) (xy 300.247727 -152.568617)
			(xy 300.247304 -152.558496) (xy 297.854812 -152.558496) (xy 297.852407 -152.576766) (xy 297.836894 -152.634659)
			(xy 297.83004 -152.651206) (xy 314.441332 -152.651206) (xy 314.441332 -152.423622) (xy 314.441586 -152.419558)
			(xy 314.44184 -152.417018) (xy 314.44184 -152.408382) (xy 314.447428 -152.399746) (xy 314.448698 -152.397714)
			(xy 314.449714 -152.395682) (xy 314.647072 -152.094692) (xy 314.650957 -152.088373) (xy 314.655206 -152.074166)
			(xy 314.655454 -152.066752) (xy 314.655454 -152.041098) (xy 314.655268 -152.033762) (xy 314.651125 -152.019691)
			(xy 314.647326 -152.013412) (xy 314.44946 -151.71039) (xy 314.447174 -151.70658) (xy 314.44692 -151.706072)
			(xy 314.445904 -151.704294) (xy 314.44184 -151.69769) (xy 314.44184 -151.689562) (xy 314.441586 -151.687022)
			(xy 314.441332 -151.682958) (xy 314.441332 -151.454866) (xy 314.441805 -151.444707) (xy 314.44959 -151.425938)
			(xy 314.463962 -151.411574) (xy 314.482735 -151.4038) (xy 314.492894 -151.403304) (xy 315.229748 -151.403304)
			(xy 315.23993 -151.403736) (xy 315.258748 -151.411521) (xy 315.273174 -151.425896) (xy 315.281027 -151.444686)
			(xy 315.281564 -151.454866) (xy 315.281564 -151.68245) (xy 315.28131 -151.686514) (xy 315.281056 -151.689054)
			(xy 315.281056 -151.69769) (xy 315.275214 -151.707088) (xy 315.274452 -151.708358) (xy 315.273182 -151.71039)
			(xy 315.067442 -152.025096) (xy 315.062361 -152.033602) (xy 315.058556 -152.05303) (xy 315.062384 -152.072454)
			(xy 315.067442 -152.080976) (xy 315.273182 -152.394412) (xy 315.274198 -152.396444) (xy 315.275468 -152.398476)
			(xy 315.281056 -152.407112) (xy 315.281056 -152.415748) (xy 315.28131 -152.418288) (xy 315.281564 -152.422352)
			(xy 315.281564 -152.485852) (xy 315.916564 -152.485852) (xy 315.916564 -151.622252) (xy 315.917054 -151.592284)
			(xy 315.924877 -151.532862) (xy 315.94039 -151.474969) (xy 315.963326 -151.419596) (xy 315.993293 -151.36769)
			(xy 316.02978 -151.32014) (xy 316.07216 -151.27776) (xy 316.11971 -151.241273) (xy 316.171616 -151.211306)
			(xy 316.226989 -151.18837) (xy 316.284882 -151.172857) (xy 316.344304 -151.165034) (xy 316.40424 -151.165034)
			(xy 316.463662 -151.172857) (xy 316.521555 -151.18837) (xy 316.576928 -151.211306) (xy 316.628834 -151.241273)
			(xy 316.676384 -151.27776) (xy 316.718764 -151.32014) (xy 316.755251 -151.36769) (xy 316.785218 -151.419596)
			(xy 316.808154 -151.474969) (xy 316.823667 -151.532862) (xy 316.83149 -151.592284) (xy 316.83198 -151.622252)
			(xy 316.83198 -152.485852) (xy 316.831955 -152.487376) (xy 413.045148 -152.487376) (xy 413.045148 -151.623776)
			(xy 413.045638 -151.593792) (xy 413.053466 -151.534336) (xy 413.068987 -151.476411) (xy 413.091936 -151.421007)
			(xy 413.12192 -151.369073) (xy 413.158426 -151.321497) (xy 413.200831 -151.279092) (xy 413.248407 -151.242586)
			(xy 413.300341 -151.212602) (xy 413.355745 -151.189653) (xy 413.41367 -151.174132) (xy 413.473126 -151.166304)
			(xy 413.533094 -151.166304) (xy 413.59255 -151.174132) (xy 413.650475 -151.189653) (xy 413.705879 -151.212602)
			(xy 413.757813 -151.242586) (xy 413.805389 -151.279092) (xy 413.847794 -151.321497) (xy 413.8843 -151.369073)
			(xy 413.914284 -151.421007) (xy 413.937233 -151.476411) (xy 413.952754 -151.534336) (xy 413.960582 -151.593792)
			(xy 413.961072 -151.623776) (xy 413.961072 -152.487376) (xy 413.960582 -152.51736) (xy 413.955199 -152.558242)
			(xy 416.347148 -152.558242) (xy 416.347148 -151.551894) (xy 416.347559 -151.541721) (xy 416.355348 -151.522924)
			(xy 416.369737 -151.508539) (xy 416.388537 -151.500756) (xy 416.39871 -151.500332) (xy 417.57981 -151.500332)
			(xy 417.589968 -151.500825) (xy 417.608736 -151.508602) (xy 417.6231 -151.522968) (xy 417.630876 -151.541736)
			(xy 417.631372 -151.551894) (xy 417.631372 -152.558242) (xy 420.884096 -152.558242) (xy 420.884096 -151.551894)
			(xy 420.88462 -151.541772) (xy 420.892342 -151.523059) (xy 420.906616 -151.508705) (xy 420.925285 -151.500878)
			(xy 420.935404 -151.500332) (xy 422.116504 -151.500332) (xy 422.126662 -151.500719) (xy 422.145421 -151.508522)
			(xy 422.159745 -151.52293) (xy 422.167439 -151.541733) (xy 422.167812 -151.551894) (xy 422.167812 -152.558242)
			(xy 422.167309 -152.568365) (xy 422.159577 -152.587077) (xy 422.145297 -152.60143) (xy 422.126624 -152.609257)
			(xy 422.116504 -152.609804) (xy 420.935404 -152.609804) (xy 420.925251 -152.609375) (xy 420.906499 -152.601582)
			(xy 420.892176 -152.587187) (xy 420.884475 -152.568397) (xy 420.884096 -152.558242) (xy 417.631372 -152.558242)
			(xy 417.630901 -152.568401) (xy 417.623115 -152.587169) (xy 417.608743 -152.601533) (xy 417.58997 -152.609308)
			(xy 417.57981 -152.609804) (xy 416.39871 -152.609804) (xy 416.388558 -152.60926) (xy 416.369797 -152.601496)
			(xy 416.355433 -152.587147) (xy 416.347651 -152.568393) (xy 416.347148 -152.558242) (xy 413.955199 -152.558242)
			(xy 413.952754 -152.576816) (xy 413.937233 -152.634741) (xy 413.930413 -152.651206) (xy 430.541684 -152.651206)
			(xy 430.541684 -152.408382) (xy 430.660556 -152.227026) (xy 430.72304 -152.131522) (xy 430.74717 -152.094692)
			(xy 430.751055 -152.088373) (xy 430.755304 -152.074166) (xy 430.755552 -152.066752) (xy 430.755552 -152.040844)
			(xy 430.755345 -152.034695) (xy 430.752401 -152.022754) (xy 430.74971 -152.017222) (xy 430.636172 -151.843232)
			(xy 430.616106 -151.812244) (xy 430.610518 -151.803608) (xy 430.550066 -151.710898) (xy 430.549558 -151.710136)
			(xy 430.54905 -151.709374) (xy 430.548796 -151.708866) (xy 430.548288 -151.708104) (xy 430.541684 -151.69769)
			(xy 430.541684 -151.454866) (xy 430.542037 -151.444686) (xy 430.549842 -151.425882) (xy 430.564249 -151.411497)
			(xy 430.583066 -151.403721) (xy 430.593246 -151.403304) (xy 431.329846 -151.403304) (xy 431.340003 -151.403795)
			(xy 431.358766 -151.411578) (xy 431.373129 -151.425944) (xy 431.380907 -151.444709) (xy 431.381408 -151.454866)
			(xy 431.381408 -151.69769) (xy 431.165508 -152.028144) (xy 431.161509 -152.036375) (xy 431.158956 -152.054479)
			(xy 431.162892 -152.072333) (xy 431.16754 -152.080214) (xy 431.199798 -152.129998) (xy 431.381408 -152.407112)
			(xy 431.381408 -152.485852) (xy 432.016408 -152.485852) (xy 432.016408 -151.622252) (xy 432.016898 -151.592268)
			(xy 432.024726 -151.532812) (xy 432.040247 -151.474887) (xy 432.063196 -151.419483) (xy 432.09318 -151.367549)
			(xy 432.129686 -151.319973) (xy 432.172091 -151.277568) (xy 432.219667 -151.241062) (xy 432.271601 -151.211078)
			(xy 432.327005 -151.188129) (xy 432.38493 -151.172608) (xy 432.444386 -151.16478) (xy 432.504354 -151.16478)
			(xy 432.56381 -151.172608) (xy 432.621735 -151.188129) (xy 432.677139 -151.211078) (xy 432.729073 -151.241062)
			(xy 432.776649 -151.277568) (xy 432.819054 -151.319973) (xy 432.85556 -151.367549) (xy 432.885544 -151.419483)
			(xy 432.908493 -151.474887) (xy 432.924014 -151.532812) (xy 432.931842 -151.592268) (xy 432.932332 -151.622252)
			(xy 432.932332 -152.485852) (xy 432.931842 -152.515836) (xy 432.924014 -152.575292) (xy 432.908493 -152.633217)
			(xy 432.885544 -152.688621) (xy 432.85556 -152.740555) (xy 432.819054 -152.788131) (xy 432.776649 -152.830536)
			(xy 432.729073 -152.867042) (xy 432.677139 -152.897026) (xy 432.621735 -152.919975) (xy 432.56381 -152.935496)
			(xy 432.504354 -152.943324) (xy 432.444386 -152.943324) (xy 432.38493 -152.935496) (xy 432.327005 -152.919975)
			(xy 432.271601 -152.897026) (xy 432.219667 -152.867042) (xy 432.172091 -152.830536) (xy 432.129686 -152.788131)
			(xy 432.09318 -152.740555) (xy 432.063196 -152.688621) (xy 432.040247 -152.633217) (xy 432.024726 -152.575292)
			(xy 432.016898 -152.515836) (xy 432.016408 -152.485852) (xy 431.381408 -152.485852) (xy 431.381408 -152.651206)
			(xy 431.380873 -152.661358) (xy 431.373105 -152.680119) (xy 431.358752 -152.694482) (xy 431.339998 -152.702265)
			(xy 431.329846 -152.702768) (xy 430.593246 -152.702768) (xy 430.583078 -152.702299) (xy 430.564286 -152.69453)
			(xy 430.549899 -152.680158) (xy 430.542112 -152.661373) (xy 430.541684 -152.651206) (xy 413.930413 -152.651206)
			(xy 413.914284 -152.690145) (xy 413.8843 -152.742079) (xy 413.847794 -152.789655) (xy 413.805389 -152.83206)
			(xy 413.757813 -152.868566) (xy 413.705879 -152.89855) (xy 413.650475 -152.921499) (xy 413.59255 -152.93702)
			(xy 413.533094 -152.944848) (xy 413.473126 -152.944848) (xy 413.41367 -152.93702) (xy 413.355745 -152.921499)
			(xy 413.300341 -152.89855) (xy 413.248407 -152.868566) (xy 413.200831 -152.83206) (xy 413.158426 -152.789655)
			(xy 413.12192 -152.742079) (xy 413.091936 -152.690145) (xy 413.068987 -152.634741) (xy 413.053466 -152.576816)
			(xy 413.045638 -152.51736) (xy 413.045148 -152.487376) (xy 316.831955 -152.487376) (xy 316.83149 -152.51582)
			(xy 316.823667 -152.575242) (xy 316.808154 -152.633135) (xy 316.785218 -152.688508) (xy 316.755251 -152.740414)
			(xy 316.718764 -152.787964) (xy 316.676384 -152.830344) (xy 316.628834 -152.866831) (xy 316.576928 -152.896798)
			(xy 316.521555 -152.919734) (xy 316.463662 -152.935247) (xy 316.40424 -152.94307) (xy 316.344304 -152.94307)
			(xy 316.284882 -152.935247) (xy 316.226989 -152.919734) (xy 316.171616 -152.896798) (xy 316.11971 -152.866831)
			(xy 316.07216 -152.830344) (xy 316.02978 -152.787964) (xy 315.993293 -152.740414) (xy 315.963326 -152.688508)
			(xy 315.94039 -152.633135) (xy 315.924877 -152.575242) (xy 315.917054 -152.51582) (xy 315.916564 -152.485852)
			(xy 315.281564 -152.485852) (xy 315.281564 -152.651206) (xy 315.281071 -152.661364) (xy 315.273295 -152.680133)
			(xy 315.258929 -152.694498) (xy 315.24016 -152.702272) (xy 315.230002 -152.702768) (xy 314.493148 -152.702768)
			(xy 314.482969 -152.702284) (xy 314.464147 -152.694525) (xy 314.449717 -152.680166) (xy 314.441866 -152.661383)
			(xy 314.441332 -152.651206) (xy 297.83004 -152.651206) (xy 297.813958 -152.690032) (xy 297.783991 -152.741938)
			(xy 297.747504 -152.789488) (xy 297.705124 -152.831868) (xy 297.657574 -152.868355) (xy 297.605668 -152.898322)
			(xy 297.550295 -152.921258) (xy 297.492402 -152.936771) (xy 297.43298 -152.944594) (xy 297.373044 -152.944594)
			(xy 297.313622 -152.936771) (xy 297.255729 -152.921258) (xy 297.200356 -152.898322) (xy 297.14845 -152.868355)
			(xy 297.1009 -152.831868) (xy 297.05852 -152.789488) (xy 297.022033 -152.741938) (xy 296.992066 -152.690032)
			(xy 296.96913 -152.634659) (xy 296.953617 -152.576766) (xy 296.945794 -152.517344) (xy 296.945304 -152.487376)
			(xy 200.732111 -152.487376) (xy 200.731646 -152.51582) (xy 200.723823 -152.575242) (xy 200.70831 -152.633135)
			(xy 200.685374 -152.688508) (xy 200.655407 -152.740414) (xy 200.61892 -152.787964) (xy 200.57654 -152.830344)
			(xy 200.52899 -152.866831) (xy 200.477084 -152.896798) (xy 200.421711 -152.919734) (xy 200.363818 -152.935247)
			(xy 200.304396 -152.94307) (xy 200.24446 -152.94307) (xy 200.185038 -152.935247) (xy 200.127145 -152.919734)
			(xy 200.071772 -152.896798) (xy 200.019866 -152.866831) (xy 199.972316 -152.830344) (xy 199.929936 -152.787964)
			(xy 199.893449 -152.740414) (xy 199.863482 -152.688508) (xy 199.840546 -152.633135) (xy 199.825033 -152.575242)
			(xy 199.81721 -152.51582) (xy 199.81672 -152.485852) (xy 199.181212 -152.485852) (xy 199.181212 -152.651206)
			(xy 199.18084 -152.661384) (xy 199.173044 -152.680189) (xy 199.158641 -152.694575) (xy 199.139829 -152.702351)
			(xy 199.12965 -152.702768) (xy 198.39305 -152.702768) (xy 198.382882 -152.702295) (xy 198.36409 -152.694528)
			(xy 198.349703 -152.680157) (xy 198.341916 -152.661373) (xy 198.341488 -152.651206) (xy 181.730196 -152.651206)
			(xy 181.714114 -152.690032) (xy 181.684147 -152.741938) (xy 181.64766 -152.789488) (xy 181.60528 -152.831868)
			(xy 181.55773 -152.868355) (xy 181.505824 -152.898322) (xy 181.450451 -152.921258) (xy 181.392558 -152.936771)
			(xy 181.333136 -152.944594) (xy 181.2732 -152.944594) (xy 181.213778 -152.936771) (xy 181.155885 -152.921258)
			(xy 181.100512 -152.898322) (xy 181.048606 -152.868355) (xy 181.001056 -152.831868) (xy 180.958676 -152.789488)
			(xy 180.922189 -152.741938) (xy 180.892222 -152.690032) (xy 180.869286 -152.634659) (xy 180.853773 -152.576766)
			(xy 180.84595 -152.517344) (xy 180.84546 -152.487376) (xy 84.632267 -152.487376) (xy 84.631802 -152.515836)
			(xy 84.623974 -152.575292) (xy 84.608453 -152.633217) (xy 84.585504 -152.688621) (xy 84.55552 -152.740555)
			(xy 84.519014 -152.788131) (xy 84.476609 -152.830536) (xy 84.429033 -152.867042) (xy 84.377099 -152.897026)
			(xy 84.321695 -152.919975) (xy 84.26377 -152.935496) (xy 84.204314 -152.943324) (xy 84.144346 -152.943324)
			(xy 84.08489 -152.935496) (xy 84.026965 -152.919975) (xy 83.971561 -152.897026) (xy 83.919627 -152.867042)
			(xy 83.872051 -152.830536) (xy 83.829646 -152.788131) (xy 83.79314 -152.740555) (xy 83.763156 -152.688621)
			(xy 83.740207 -152.633217) (xy 83.724686 -152.575292) (xy 83.716858 -152.515836) (xy 83.716368 -152.485852)
			(xy 83.081368 -152.485852) (xy 83.081368 -152.651206) (xy 83.080872 -152.661363) (xy 83.073096 -152.680131)
			(xy 83.058731 -152.694496) (xy 83.039963 -152.702272) (xy 83.029806 -152.702768) (xy 82.293206 -152.702768)
			(xy 82.283049 -152.702262) (xy 82.264281 -152.694491) (xy 82.249916 -152.680129) (xy 82.242141 -152.661363)
			(xy 82.241644 -152.651206) (xy 65.630373 -152.651206) (xy 65.614244 -152.690145) (xy 65.58426 -152.742079)
			(xy 65.547754 -152.789655) (xy 65.505349 -152.83206) (xy 65.457773 -152.868566) (xy 65.405839 -152.89855)
			(xy 65.350435 -152.921499) (xy 65.29251 -152.93702) (xy 65.233054 -152.944848) (xy 65.173086 -152.944848)
			(xy 65.11363 -152.93702) (xy 65.055705 -152.921499) (xy 65.000301 -152.89855) (xy 64.948367 -152.868566)
			(xy 64.900791 -152.83206) (xy 64.858386 -152.789655) (xy 64.82188 -152.742079) (xy 64.791896 -152.690145)
			(xy 64.768947 -152.634741) (xy 64.753426 -152.576816) (xy 64.745598 -152.51736) (xy 64.745108 -152.487376)
			(xy 4.30911 -152.487376) (xy 4.30911 -154.28722) (xy 66.599308 -154.28722) (xy 66.599308 -153.42362)
			(xy 66.599798 -153.393636) (xy 66.607626 -153.33418) (xy 66.623147 -153.276255) (xy 66.646096 -153.220851)
			(xy 66.67608 -153.168917) (xy 66.712586 -153.121341) (xy 66.754991 -153.078936) (xy 66.802567 -153.04243)
			(xy 66.854501 -153.012446) (xy 66.909905 -152.989497) (xy 66.96783 -152.973976) (xy 67.027286 -152.966148)
			(xy 67.087254 -152.966148) (xy 67.14671 -152.973976) (xy 67.204635 -152.989497) (xy 67.260039 -153.012446)
			(xy 67.311973 -153.04243) (xy 67.359549 -153.078936) (xy 67.401954 -153.121341) (xy 67.43846 -153.168917)
			(xy 67.468444 -153.220851) (xy 67.491393 -153.276255) (xy 67.506914 -153.33418) (xy 67.514742 -153.393636)
			(xy 67.515232 -153.42362) (xy 67.515232 -154.28722) (xy 67.514742 -154.317204) (xy 67.509326 -154.35834)
			(xy 68.047108 -154.35834) (xy 68.047108 -153.351992) (xy 68.04751 -153.341868) (xy 68.055262 -153.323163)
			(xy 68.069583 -153.308849) (xy 68.088292 -153.301105) (xy 68.098416 -153.300684) (xy 69.27977 -153.300684)
			(xy 69.2899 -153.301152) (xy 69.308629 -153.308878) (xy 69.322988 -153.323171) (xy 69.330801 -153.341864)
			(xy 69.331332 -153.351992) (xy 69.331332 -154.358086) (xy 72.584056 -154.358086) (xy 72.584056 -153.351738)
			(xy 72.584558 -153.341612) (xy 72.592277 -153.322889) (xy 72.606559 -153.30853) (xy 72.625241 -153.300713)
			(xy 72.635364 -153.300176) (xy 73.816464 -153.300176) (xy 73.826613 -153.300651) (xy 73.84536 -153.30843)
			(xy 73.859683 -153.32281) (xy 73.867389 -153.341588) (xy 73.867772 -153.351738) (xy 73.867772 -154.358086)
			(xy 73.867262 -154.36821) (xy 73.859541 -154.386929) (xy 73.845262 -154.401285) (xy 73.826586 -154.409107)
			(xy 73.816464 -154.409648) (xy 72.635364 -154.409648) (xy 72.625214 -154.409209) (xy 72.60647 -154.40141)
			(xy 72.592149 -154.38702) (xy 72.584442 -154.368238) (xy 72.584056 -154.358086) (xy 69.331332 -154.358086)
			(xy 69.331332 -154.35834) (xy 69.330848 -154.368447) (xy 69.323104 -154.38712) (xy 69.308807 -154.401413)
			(xy 69.290131 -154.409152) (xy 69.280024 -154.409648) (xy 68.09867 -154.409648) (xy 68.08854 -154.409198)
			(xy 68.069816 -154.401458) (xy 68.05546 -154.387161) (xy 68.047644 -154.368468) (xy 68.047108 -154.35834)
			(xy 67.509326 -154.35834) (xy 67.506914 -154.37666) (xy 67.491393 -154.434585) (xy 67.487203 -154.4447)
			(xy 79.599536 -154.4447) (xy 79.599536 -154.201876) (xy 79.718408 -154.02052) (xy 79.780892 -153.925016)
			(xy 79.805022 -153.888186) (xy 79.808905 -153.881866) (xy 79.813157 -153.86766) (xy 79.813404 -153.860246)
			(xy 79.813404 -153.834338) (xy 79.813205 -153.828188) (xy 79.810256 -153.816247) (xy 79.807562 -153.810716)
			(xy 79.694024 -153.636726) (xy 79.673958 -153.605738) (xy 79.66837 -153.597102) (xy 79.607918 -153.504392)
			(xy 79.60741 -153.50363) (xy 79.606902 -153.502868) (xy 79.606648 -153.50236) (xy 79.60614 -153.501598)
			(xy 79.599536 -153.491184) (xy 79.599536 -153.24836) (xy 79.600154 -153.236805) (xy 79.610124 -153.215954)
			(xy 79.628076 -153.201395) (xy 79.63916 -153.198068) (xy 79.651098 -153.196544) (xy 80.387698 -153.196544)
			(xy 80.398458 -153.197045) (xy 80.418147 -153.205724) (xy 80.425798 -153.213308) (xy 80.431979 -153.22072)
			(xy 80.438903 -153.238717) (xy 80.43926 -153.24836) (xy 80.43926 -153.491184) (xy 80.22336 -153.821638)
			(xy 80.21937 -153.829872) (xy 80.216819 -153.847973) (xy 80.220748 -153.865826) (xy 80.225392 -153.873708)
			(xy 80.25765 -153.923492) (xy 80.43926 -154.200606) (xy 80.43926 -154.279346) (xy 81.07426 -154.279346)
			(xy 81.07426 -153.415746) (xy 81.07475 -153.385762) (xy 81.082578 -153.326306) (xy 81.098099 -153.268381)
			(xy 81.121048 -153.212977) (xy 81.151032 -153.161043) (xy 81.187538 -153.113467) (xy 81.229943 -153.071062)
			(xy 81.277519 -153.034556) (xy 81.329453 -153.004572) (xy 81.384857 -152.981623) (xy 81.442782 -152.966102)
			(xy 81.502238 -152.958274) (xy 81.562206 -152.958274) (xy 81.621662 -152.966102) (xy 81.679587 -152.981623)
			(xy 81.734991 -153.004572) (xy 81.786925 -153.034556) (xy 81.834501 -153.071062) (xy 81.876906 -153.113467)
			(xy 81.913412 -153.161043) (xy 81.943396 -153.212977) (xy 81.966345 -153.268381) (xy 81.981866 -153.326306)
			(xy 81.989694 -153.385762) (xy 81.990184 -153.415746) (xy 81.990184 -154.279346) (xy 81.990055 -154.28722)
			(xy 182.69966 -154.28722) (xy 182.69966 -153.42362) (xy 182.70015 -153.393652) (xy 182.707973 -153.33423)
			(xy 182.723486 -153.276337) (xy 182.746422 -153.220964) (xy 182.776389 -153.169058) (xy 182.812876 -153.121508)
			(xy 182.855256 -153.079128) (xy 182.902806 -153.042641) (xy 182.954712 -153.012674) (xy 183.010085 -152.989738)
			(xy 183.067978 -152.974225) (xy 183.1274 -152.966402) (xy 183.187336 -152.966402) (xy 183.246758 -152.974225)
			(xy 183.304651 -152.989738) (xy 183.360024 -153.012674) (xy 183.41193 -153.042641) (xy 183.45948 -153.079128)
			(xy 183.50186 -153.121508) (xy 183.538347 -153.169058) (xy 183.568314 -153.220964) (xy 183.59125 -153.276337)
			(xy 183.606763 -153.33423) (xy 183.614586 -153.393652) (xy 183.615076 -153.42362) (xy 183.615076 -154.28722)
			(xy 183.614586 -154.317188) (xy 183.609168 -154.35834) (xy 184.146952 -154.35834) (xy 184.146952 -153.351992)
			(xy 184.147478 -153.341889) (xy 184.155209 -153.32322) (xy 184.169493 -153.308927) (xy 184.188157 -153.301184)
			(xy 184.19826 -153.300684) (xy 185.379614 -153.300684) (xy 185.389747 -153.301117) (xy 185.408477 -153.308857)
			(xy 185.422834 -153.32316) (xy 185.430645 -153.341861) (xy 185.431176 -153.351992) (xy 185.431176 -154.358086)
			(xy 188.6839 -154.358086) (xy 188.6839 -153.351738) (xy 188.684457 -153.341619) (xy 188.692165 -153.322906)
			(xy 188.706429 -153.30855) (xy 188.725092 -153.300722) (xy 188.735208 -153.300176) (xy 189.916308 -153.300176)
			(xy 189.92646 -153.300615) (xy 189.945207 -153.308408) (xy 189.95953 -153.322799) (xy 189.967233 -153.341584)
			(xy 189.967616 -153.351738) (xy 189.967616 -154.358086) (xy 189.967161 -154.368217) (xy 189.959429 -154.386946)
			(xy 189.945133 -154.401305) (xy 189.926437 -154.409117) (xy 189.916308 -154.409648) (xy 188.735208 -154.409648)
			(xy 188.72506 -154.409173) (xy 188.706317 -154.401389) (xy 188.691995 -154.387009) (xy 188.684287 -154.368235)
			(xy 188.6839 -154.358086) (xy 185.431176 -154.358086) (xy 185.431176 -154.35834) (xy 185.430747 -154.368454)
			(xy 185.422992 -154.387138) (xy 185.408677 -154.401432) (xy 185.389983 -154.409161) (xy 185.379868 -154.409648)
			(xy 184.198514 -154.409648) (xy 184.188387 -154.409162) (xy 184.169664 -154.401436) (xy 184.155306 -154.38715)
			(xy 184.147489 -154.368465) (xy 184.146952 -154.35834) (xy 183.609168 -154.35834) (xy 183.606763 -154.37661)
			(xy 183.59125 -154.434503) (xy 183.587026 -154.4447) (xy 195.69938 -154.4447) (xy 195.69938 -154.201876)
			(xy 195.818252 -154.02052) (xy 195.880736 -153.925016) (xy 195.904866 -153.888186) (xy 195.908753 -153.881868)
			(xy 195.913001 -153.867661) (xy 195.913248 -153.860246) (xy 195.913248 -153.834338) (xy 195.913044 -153.828189)
			(xy 195.910098 -153.816248) (xy 195.907406 -153.810716) (xy 195.793868 -153.636726) (xy 195.773802 -153.605738)
			(xy 195.768214 -153.597102) (xy 195.707762 -153.504392) (xy 195.707254 -153.50363) (xy 195.706746 -153.502868)
			(xy 195.706492 -153.50236) (xy 195.705984 -153.501598) (xy 195.69938 -153.491184) (xy 195.69938 -153.24836)
			(xy 195.700039 -153.236811) (xy 195.709997 -153.215967) (xy 195.727928 -153.201403) (xy 195.739004 -153.198068)
			(xy 195.750942 -153.196544) (xy 196.487542 -153.196544) (xy 196.498298 -153.197076) (xy 196.517988 -153.205733)
			(xy 196.525642 -153.213308) (xy 196.531816 -153.220725) (xy 196.538745 -153.238718) (xy 196.539104 -153.24836)
			(xy 196.539104 -153.491184) (xy 196.323204 -153.821638) (xy 196.31921 -153.829871) (xy 196.316656 -153.847973)
			(xy 196.320589 -153.865827) (xy 196.325236 -153.873708) (xy 196.357494 -153.923492) (xy 196.539104 -154.200606)
			(xy 196.539104 -154.279346) (xy 197.174612 -154.279346) (xy 197.174612 -153.415746) (xy 197.175102 -153.385778)
			(xy 197.182925 -153.326356) (xy 197.198438 -153.268463) (xy 197.221374 -153.21309) (xy 197.251341 -153.161184)
			(xy 197.287828 -153.113634) (xy 197.330208 -153.071254) (xy 197.377758 -153.034767) (xy 197.429664 -153.0048)
			(xy 197.485037 -152.981864) (xy 197.54293 -152.966351) (xy 197.602352 -152.958528) (xy 197.662288 -152.958528)
			(xy 197.72171 -152.966351) (xy 197.779603 -152.981864) (xy 197.834976 -153.0048) (xy 197.886882 -153.034767)
			(xy 197.934432 -153.071254) (xy 197.976812 -153.113634) (xy 198.013299 -153.161184) (xy 198.043266 -153.21309)
			(xy 198.066202 -153.268463) (xy 198.081715 -153.326356) (xy 198.089538 -153.385778) (xy 198.090028 -153.415746)
			(xy 198.090028 -154.279346) (xy 198.089899 -154.28722) (xy 298.799504 -154.28722) (xy 298.799504 -153.42362)
			(xy 298.799994 -153.393652) (xy 298.807817 -153.33423) (xy 298.82333 -153.276337) (xy 298.846266 -153.220964)
			(xy 298.876233 -153.169058) (xy 298.91272 -153.121508) (xy 298.9551 -153.079128) (xy 299.00265 -153.042641)
			(xy 299.054556 -153.012674) (xy 299.109929 -152.989738) (xy 299.167822 -152.974225) (xy 299.227244 -152.966402)
			(xy 299.28718 -152.966402) (xy 299.346602 -152.974225) (xy 299.404495 -152.989738) (xy 299.459868 -153.012674)
			(xy 299.511774 -153.042641) (xy 299.559324 -153.079128) (xy 299.601704 -153.121508) (xy 299.638191 -153.169058)
			(xy 299.668158 -153.220964) (xy 299.691094 -153.276337) (xy 299.706607 -153.33423) (xy 299.71443 -153.393652)
			(xy 299.71492 -153.42362) (xy 299.71492 -154.28722) (xy 299.71443 -154.317188) (xy 299.709012 -154.35834)
			(xy 300.247304 -154.35834) (xy 300.247304 -153.351992) (xy 300.24771 -153.341869) (xy 300.255461 -153.323164)
			(xy 300.269781 -153.30885) (xy 300.288488 -153.301106) (xy 300.298612 -153.300684) (xy 301.479712 -153.300684)
			(xy 301.489819 -153.301175) (xy 301.508495 -153.308914) (xy 301.522789 -153.323209) (xy 301.530526 -153.341884)
			(xy 301.53102 -153.351992) (xy 301.53102 -154.358086) (xy 304.783744 -154.358086) (xy 304.783744 -153.351738)
			(xy 304.784195 -153.341568) (xy 304.791969 -153.322773) (xy 304.806346 -153.308387) (xy 304.825136 -153.300601)
			(xy 304.835306 -153.300176) (xy 306.016406 -153.300176) (xy 306.026583 -153.30056) (xy 306.045385 -153.308354)
			(xy 306.059771 -153.322752) (xy 306.067549 -153.341561) (xy 306.067968 -153.351738) (xy 306.067968 -154.358086)
			(xy 306.067525 -154.368256) (xy 306.059746 -154.387049) (xy 306.045366 -154.401434) (xy 306.026576 -154.409221)
			(xy 306.016406 -154.409648) (xy 304.835306 -154.409648) (xy 304.825133 -154.409231) (xy 304.806336 -154.401445)
			(xy 304.79195 -154.387058) (xy 304.784167 -154.368259) (xy 304.783744 -154.358086) (xy 301.53102 -154.358086)
			(xy 301.53102 -154.35834) (xy 301.530548 -154.368449) (xy 301.522801 -154.387124) (xy 301.508501 -154.401417)
			(xy 301.489821 -154.409154) (xy 301.479712 -154.409648) (xy 300.298612 -154.409648) (xy 300.28851 -154.409106)
			(xy 300.269841 -154.401382) (xy 300.255548 -154.387102) (xy 300.247804 -154.368442) (xy 300.247304 -154.35834)
			(xy 299.709012 -154.35834) (xy 299.706607 -154.37661) (xy 299.691094 -154.434503) (xy 299.68687 -154.4447)
			(xy 311.799224 -154.4447) (xy 311.799224 -154.217116) (xy 311.799478 -154.213052) (xy 311.799732 -154.210512)
			(xy 311.799732 -154.201876) (xy 311.80532 -154.19324) (xy 311.80659 -154.191208) (xy 311.807606 -154.189176)
			(xy 312.004964 -153.888186) (xy 312.008851 -153.881868) (xy 312.013099 -153.867661) (xy 312.013346 -153.860246)
			(xy 312.013346 -153.834592) (xy 312.013163 -153.827256) (xy 312.009018 -153.813185) (xy 312.005218 -153.806906)
			(xy 311.807352 -153.503884) (xy 311.805066 -153.500074) (xy 311.804812 -153.499566) (xy 311.803796 -153.497788)
			(xy 311.799732 -153.491184) (xy 311.799732 -153.483056) (xy 311.799478 -153.480516) (xy 311.799224 -153.476452)
			(xy 311.799224 -153.24836) (xy 311.79965 -153.238145) (xy 311.807483 -153.219275) (xy 311.821942 -153.204838)
			(xy 311.840824 -153.197034) (xy 311.85104 -153.196544) (xy 312.58764 -153.196544) (xy 312.597845 -153.197048)
			(xy 312.6167 -153.204867) (xy 312.631133 -153.2193) (xy 312.638952 -153.238155) (xy 312.639456 -153.24836)
			(xy 312.639456 -153.475944) (xy 312.639202 -153.480008) (xy 312.638948 -153.482548) (xy 312.638948 -153.491184)
			(xy 312.633106 -153.500582) (xy 312.632344 -153.501852) (xy 312.631074 -153.503884) (xy 312.425334 -153.81859)
			(xy 312.420259 -153.827099) (xy 312.416452 -153.846525) (xy 312.420278 -153.865948) (xy 312.425334 -153.87447)
			(xy 312.631074 -154.187906) (xy 312.63209 -154.189938) (xy 312.63336 -154.19197) (xy 312.638948 -154.200606)
			(xy 312.638948 -154.209242) (xy 312.639202 -154.211782) (xy 312.639456 -154.215846) (xy 312.639456 -154.279346)
			(xy 313.274456 -154.279346) (xy 313.274456 -153.415746) (xy 313.274946 -153.385778) (xy 313.282769 -153.326356)
			(xy 313.298282 -153.268463) (xy 313.321218 -153.21309) (xy 313.351185 -153.161184) (xy 313.387672 -153.113634)
			(xy 313.430052 -153.071254) (xy 313.477602 -153.034767) (xy 313.529508 -153.0048) (xy 313.584881 -152.981864)
			(xy 313.642774 -152.966351) (xy 313.702196 -152.958528) (xy 313.762132 -152.958528) (xy 313.821554 -152.966351)
			(xy 313.879447 -152.981864) (xy 313.93482 -153.0048) (xy 313.986726 -153.034767) (xy 314.034276 -153.071254)
			(xy 314.076656 -153.113634) (xy 314.113143 -153.161184) (xy 314.14311 -153.21309) (xy 314.166046 -153.268463)
			(xy 314.181559 -153.326356) (xy 314.189382 -153.385778) (xy 314.189872 -153.415746) (xy 314.189872 -154.279346)
			(xy 314.189743 -154.28722) (xy 414.899348 -154.28722) (xy 414.899348 -153.42362) (xy 414.899838 -153.393636)
			(xy 414.907666 -153.33418) (xy 414.923187 -153.276255) (xy 414.946136 -153.220851) (xy 414.97612 -153.168917)
			(xy 415.012626 -153.121341) (xy 415.055031 -153.078936) (xy 415.102607 -153.04243) (xy 415.154541 -153.012446)
			(xy 415.209945 -152.989497) (xy 415.26787 -152.973976) (xy 415.327326 -152.966148) (xy 415.387294 -152.966148)
			(xy 415.44675 -152.973976) (xy 415.504675 -152.989497) (xy 415.560079 -153.012446) (xy 415.612013 -153.04243)
			(xy 415.659589 -153.078936) (xy 415.701994 -153.121341) (xy 415.7385 -153.168917) (xy 415.768484 -153.220851)
			(xy 415.791433 -153.276255) (xy 415.806954 -153.33418) (xy 415.814782 -153.393636) (xy 415.815272 -153.42362)
			(xy 415.815272 -154.28722) (xy 415.814782 -154.317204) (xy 415.809366 -154.35834) (xy 416.347148 -154.35834)
			(xy 416.347148 -153.351992) (xy 416.347677 -153.341889) (xy 416.355408 -153.323221) (xy 416.369691 -153.308928)
			(xy 416.388354 -153.301185) (xy 416.398456 -153.300684) (xy 417.57981 -153.300684) (xy 417.589943 -153.30112)
			(xy 417.608672 -153.308859) (xy 417.62303 -153.323161) (xy 417.630841 -153.341861) (xy 417.631372 -153.351992)
			(xy 417.631372 -154.358086) (xy 420.884096 -154.358086) (xy 420.884096 -153.351738) (xy 420.884657 -153.341619)
			(xy 420.892364 -153.322907) (xy 420.906627 -153.308551) (xy 420.925289 -153.300723) (xy 420.935404 -153.300176)
			(xy 422.116504 -153.300176) (xy 422.126655 -153.300618) (xy 422.145403 -153.30841) (xy 422.159725 -153.3228)
			(xy 422.167429 -153.341585) (xy 422.167812 -153.351738) (xy 422.167812 -154.358086) (xy 422.167264 -154.368205)
			(xy 422.15955 -154.386916) (xy 422.145283 -154.401271) (xy 422.12662 -154.4091) (xy 422.116504 -154.409648)
			(xy 420.935404 -154.409648) (xy 420.925256 -154.409176) (xy 420.906513 -154.401391) (xy 420.892191 -154.38701)
			(xy 420.884483 -154.368236) (xy 420.884096 -154.358086) (xy 417.631372 -154.358086) (xy 417.631372 -154.35834)
			(xy 417.630947 -154.368455) (xy 417.623191 -154.387139) (xy 417.608875 -154.401434) (xy 417.590179 -154.409162)
			(xy 417.580064 -154.409648) (xy 416.39871 -154.409648) (xy 416.388582 -154.409165) (xy 416.369859 -154.401438)
			(xy 416.355502 -154.387151) (xy 416.347685 -154.368465) (xy 416.347148 -154.35834) (xy 415.809366 -154.35834)
			(xy 415.806954 -154.37666) (xy 415.791433 -154.434585) (xy 415.787243 -154.4447) (xy 427.899576 -154.4447)
			(xy 427.899576 -154.201876) (xy 428.018448 -154.02052) (xy 428.080932 -153.925016) (xy 428.105062 -153.888186)
			(xy 428.108949 -153.881868) (xy 428.113197 -153.867661) (xy 428.113444 -153.860246) (xy 428.113444 -153.834338)
			(xy 428.11324 -153.828189) (xy 428.110294 -153.816248) (xy 428.107602 -153.810716) (xy 427.994064 -153.636726)
			(xy 427.973998 -153.605738) (xy 427.96841 -153.597102) (xy 427.907958 -153.504392) (xy 427.90745 -153.50363)
			(xy 427.906942 -153.502868) (xy 427.906688 -153.50236) (xy 427.90618 -153.501598) (xy 427.899576 -153.491184)
			(xy 427.899576 -153.24836) (xy 427.900238 -153.236812) (xy 427.910195 -153.215968) (xy 427.928125 -153.201404)
			(xy 427.9392 -153.198068) (xy 427.951138 -153.196544) (xy 428.687738 -153.196544) (xy 428.698494 -153.197078)
			(xy 428.718184 -153.205734) (xy 428.725838 -153.213308) (xy 428.732011 -153.220725) (xy 428.738941 -153.238718)
			(xy 428.7393 -153.24836) (xy 428.7393 -153.491184) (xy 428.5234 -153.821638) (xy 428.519407 -153.829871)
			(xy 428.516853 -153.847973) (xy 428.520786 -153.865827) (xy 428.525432 -153.873708) (xy 428.55769 -153.923492)
			(xy 428.7393 -154.200606) (xy 428.7393 -154.279346) (xy 429.3743 -154.279346) (xy 429.3743 -153.415746)
			(xy 429.37479 -153.385762) (xy 429.382618 -153.326306) (xy 429.398139 -153.268381) (xy 429.421088 -153.212977)
			(xy 429.451072 -153.161043) (xy 429.487578 -153.113467) (xy 429.529983 -153.071062) (xy 429.577559 -153.034556)
			(xy 429.629493 -153.004572) (xy 429.684897 -152.981623) (xy 429.742822 -152.966102) (xy 429.802278 -152.958274)
			(xy 429.862246 -152.958274) (xy 429.921702 -152.966102) (xy 429.979627 -152.981623) (xy 430.035031 -153.004572)
			(xy 430.086965 -153.034556) (xy 430.134541 -153.071062) (xy 430.176946 -153.113467) (xy 430.213452 -153.161043)
			(xy 430.243436 -153.212977) (xy 430.266385 -153.268381) (xy 430.281906 -153.326306) (xy 430.289734 -153.385762)
			(xy 430.290224 -153.415746) (xy 430.290224 -154.279346) (xy 430.289734 -154.30933) (xy 430.281906 -154.368786)
			(xy 430.266385 -154.426711) (xy 430.243436 -154.482115) (xy 430.213452 -154.534049) (xy 430.176946 -154.581625)
			(xy 430.134541 -154.62403) (xy 430.086965 -154.660536) (xy 430.035031 -154.69052) (xy 429.979627 -154.713469)
			(xy 429.921702 -154.72899) (xy 429.862246 -154.736818) (xy 429.802278 -154.736818) (xy 429.742822 -154.72899)
			(xy 429.684897 -154.713469) (xy 429.629493 -154.69052) (xy 429.577559 -154.660536) (xy 429.529983 -154.62403)
			(xy 429.487578 -154.581625) (xy 429.451072 -154.534049) (xy 429.421088 -154.482115) (xy 429.398139 -154.426711)
			(xy 429.382618 -154.368786) (xy 429.37479 -154.30933) (xy 429.3743 -154.279346) (xy 428.7393 -154.279346)
			(xy 428.7393 -154.4447) (xy 428.738625 -154.456248) (xy 428.728678 -154.477094) (xy 428.71075 -154.491658)
			(xy 428.699676 -154.494992) (xy 428.687738 -154.496516) (xy 427.951138 -154.496516) (xy 427.940383 -154.495977)
			(xy 427.920694 -154.487323) (xy 427.913038 -154.479752) (xy 427.906845 -154.472349) (xy 427.899928 -154.454345)
			(xy 427.899576 -154.4447) (xy 415.787243 -154.4447) (xy 415.768484 -154.489989) (xy 415.7385 -154.541923)
			(xy 415.701994 -154.589499) (xy 415.659589 -154.631904) (xy 415.612013 -154.66841) (xy 415.560079 -154.698394)
			(xy 415.504675 -154.721343) (xy 415.44675 -154.736864) (xy 415.387294 -154.744692) (xy 415.327326 -154.744692)
			(xy 415.26787 -154.736864) (xy 415.209945 -154.721343) (xy 415.154541 -154.698394) (xy 415.102607 -154.66841)
			(xy 415.055031 -154.631904) (xy 415.012626 -154.589499) (xy 414.97612 -154.541923) (xy 414.946136 -154.489989)
			(xy 414.923187 -154.434585) (xy 414.907666 -154.37666) (xy 414.899838 -154.317204) (xy 414.899348 -154.28722)
			(xy 314.189743 -154.28722) (xy 314.189382 -154.309314) (xy 314.181559 -154.368736) (xy 314.166046 -154.426629)
			(xy 314.14311 -154.482002) (xy 314.113143 -154.533908) (xy 314.076656 -154.581458) (xy 314.034276 -154.623838)
			(xy 313.986726 -154.660325) (xy 313.93482 -154.690292) (xy 313.879447 -154.713228) (xy 313.821554 -154.728741)
			(xy 313.762132 -154.736564) (xy 313.702196 -154.736564) (xy 313.642774 -154.728741) (xy 313.584881 -154.713228)
			(xy 313.529508 -154.690292) (xy 313.477602 -154.660325) (xy 313.430052 -154.623838) (xy 313.387672 -154.581458)
			(xy 313.351185 -154.533908) (xy 313.321218 -154.482002) (xy 313.298282 -154.426629) (xy 313.282769 -154.368736)
			(xy 313.274946 -154.309314) (xy 313.274456 -154.279346) (xy 312.639456 -154.279346) (xy 312.639456 -154.4447)
			(xy 312.638919 -154.454903) (xy 312.631114 -154.473757) (xy 312.61669 -154.488191) (xy 312.597842 -154.496011)
			(xy 312.58764 -154.496516) (xy 311.85104 -154.496516) (xy 311.840821 -154.496055) (xy 311.821934 -154.488245)
			(xy 311.807477 -154.473799) (xy 311.799652 -154.454919) (xy 311.799224 -154.4447) (xy 299.68687 -154.4447)
			(xy 299.668158 -154.489876) (xy 299.638191 -154.541782) (xy 299.601704 -154.589332) (xy 299.559324 -154.631712)
			(xy 299.511774 -154.668199) (xy 299.459868 -154.698166) (xy 299.404495 -154.721102) (xy 299.346602 -154.736615)
			(xy 299.28718 -154.744438) (xy 299.227244 -154.744438) (xy 299.167822 -154.736615) (xy 299.109929 -154.721102)
			(xy 299.054556 -154.698166) (xy 299.00265 -154.668199) (xy 298.9551 -154.631712) (xy 298.91272 -154.589332)
			(xy 298.876233 -154.541782) (xy 298.846266 -154.489876) (xy 298.82333 -154.434503) (xy 298.807817 -154.37661)
			(xy 298.799994 -154.317188) (xy 298.799504 -154.28722) (xy 198.089899 -154.28722) (xy 198.089538 -154.309314)
			(xy 198.081715 -154.368736) (xy 198.066202 -154.426629) (xy 198.043266 -154.482002) (xy 198.013299 -154.533908)
			(xy 197.976812 -154.581458) (xy 197.934432 -154.623838) (xy 197.886882 -154.660325) (xy 197.834976 -154.690292)
			(xy 197.779603 -154.713228) (xy 197.72171 -154.728741) (xy 197.662288 -154.736564) (xy 197.602352 -154.736564)
			(xy 197.54293 -154.728741) (xy 197.485037 -154.713228) (xy 197.429664 -154.690292) (xy 197.377758 -154.660325)
			(xy 197.330208 -154.623838) (xy 197.287828 -154.581458) (xy 197.251341 -154.533908) (xy 197.221374 -154.482002)
			(xy 197.198438 -154.426629) (xy 197.182925 -154.368736) (xy 197.175102 -154.309314) (xy 197.174612 -154.279346)
			(xy 196.539104 -154.279346) (xy 196.539104 -154.4447) (xy 196.538426 -154.456247) (xy 196.52848 -154.477093)
			(xy 196.510554 -154.491657) (xy 196.49948 -154.494992) (xy 196.487542 -154.496516) (xy 195.750942 -154.496516)
			(xy 195.740187 -154.495975) (xy 195.720499 -154.487322) (xy 195.712842 -154.479752) (xy 195.706649 -154.472349)
			(xy 195.699732 -154.454345) (xy 195.69938 -154.4447) (xy 183.587026 -154.4447) (xy 183.568314 -154.489876)
			(xy 183.538347 -154.541782) (xy 183.50186 -154.589332) (xy 183.45948 -154.631712) (xy 183.41193 -154.668199)
			(xy 183.360024 -154.698166) (xy 183.304651 -154.721102) (xy 183.246758 -154.736615) (xy 183.187336 -154.744438)
			(xy 183.1274 -154.744438) (xy 183.067978 -154.736615) (xy 183.010085 -154.721102) (xy 182.954712 -154.698166)
			(xy 182.902806 -154.668199) (xy 182.855256 -154.631712) (xy 182.812876 -154.589332) (xy 182.776389 -154.541782)
			(xy 182.746422 -154.489876) (xy 182.723486 -154.434503) (xy 182.707973 -154.37661) (xy 182.70015 -154.317188)
			(xy 182.69966 -154.28722) (xy 81.990055 -154.28722) (xy 81.989694 -154.30933) (xy 81.981866 -154.368786)
			(xy 81.966345 -154.426711) (xy 81.943396 -154.482115) (xy 81.913412 -154.534049) (xy 81.876906 -154.581625)
			(xy 81.834501 -154.62403) (xy 81.786925 -154.660536) (xy 81.734991 -154.69052) (xy 81.679587 -154.713469)
			(xy 81.621662 -154.72899) (xy 81.562206 -154.736818) (xy 81.502238 -154.736818) (xy 81.442782 -154.72899)
			(xy 81.384857 -154.713469) (xy 81.329453 -154.69052) (xy 81.277519 -154.660536) (xy 81.229943 -154.62403)
			(xy 81.187538 -154.581625) (xy 81.151032 -154.534049) (xy 81.121048 -154.482115) (xy 81.098099 -154.426711)
			(xy 81.082578 -154.368786) (xy 81.07475 -154.30933) (xy 81.07426 -154.279346) (xy 80.43926 -154.279346)
			(xy 80.43926 -154.4447) (xy 80.438615 -154.456252) (xy 80.428658 -154.477103) (xy 80.410717 -154.491664)
			(xy 80.399636 -154.494992) (xy 80.387698 -154.496516) (xy 79.651098 -154.496516) (xy 79.640341 -154.495999)
			(xy 79.620652 -154.48733) (xy 79.612998 -154.479752) (xy 79.6068 -154.472353) (xy 79.599886 -154.454346)
			(xy 79.599536 -154.4447) (xy 67.487203 -154.4447) (xy 67.468444 -154.489989) (xy 67.43846 -154.541923)
			(xy 67.401954 -154.589499) (xy 67.359549 -154.631904) (xy 67.311973 -154.66841) (xy 67.260039 -154.698394)
			(xy 67.204635 -154.721343) (xy 67.14671 -154.736864) (xy 67.087254 -154.744692) (xy 67.027286 -154.744692)
			(xy 66.96783 -154.736864) (xy 66.909905 -154.721343) (xy 66.854501 -154.698394) (xy 66.802567 -154.66841)
			(xy 66.754991 -154.631904) (xy 66.712586 -154.589499) (xy 66.67608 -154.541923) (xy 66.646096 -154.489989)
			(xy 66.623147 -154.434585) (xy 66.607626 -154.37666) (xy 66.599798 -154.317204) (xy 66.599308 -154.28722)
			(xy 4.30911 -154.28722) (xy 4.30911 -156.087318) (xy 64.745108 -156.087318) (xy 64.745108 -155.223718)
			(xy 64.745598 -155.193734) (xy 64.753426 -155.134278) (xy 64.768947 -155.076353) (xy 64.791896 -155.020949)
			(xy 64.82188 -154.969015) (xy 64.858386 -154.921439) (xy 64.900791 -154.879034) (xy 64.948367 -154.842528)
			(xy 65.000301 -154.812544) (xy 65.055705 -154.789595) (xy 65.11363 -154.774074) (xy 65.173086 -154.766246)
			(xy 65.233054 -154.766246) (xy 65.29251 -154.774074) (xy 65.350435 -154.789595) (xy 65.405839 -154.812544)
			(xy 65.457773 -154.842528) (xy 65.505349 -154.879034) (xy 65.547754 -154.921439) (xy 65.58426 -154.969015)
			(xy 65.614244 -155.020949) (xy 65.637193 -155.076353) (xy 65.652714 -155.134278) (xy 65.660542 -155.193734)
			(xy 65.661032 -155.223718) (xy 65.661032 -156.087318) (xy 65.660542 -156.117302) (xy 65.655159 -156.158184)
			(xy 68.047108 -156.158184) (xy 68.047108 -155.151836) (xy 68.047546 -155.141715) (xy 68.055284 -155.123011)
			(xy 68.069594 -155.108695) (xy 68.088295 -155.10095) (xy 68.098416 -155.100528) (xy 69.27977 -155.100528)
			(xy 69.289893 -155.101051) (xy 69.308612 -155.108766) (xy 69.322969 -155.123042) (xy 69.330791 -155.141716)
			(xy 69.331332 -155.151836) (xy 69.331332 -156.158184) (xy 72.584056 -156.158184) (xy 72.584056 -155.151836)
			(xy 72.584614 -155.141735) (xy 72.592331 -155.123066) (xy 72.606606 -155.108772) (xy 72.625264 -155.101028)
			(xy 72.635364 -155.100528) (xy 73.816464 -155.100528) (xy 73.826588 -155.100946) (xy 73.845296 -155.108688)
			(xy 73.859612 -155.123004) (xy 73.867354 -155.141712) (xy 73.867772 -155.151836) (xy 73.867772 -156.158184)
			(xy 73.86737 -156.168309) (xy 73.859622 -156.187018) (xy 73.845301 -156.201333) (xy 73.826589 -156.209074)
			(xy 73.816464 -156.209492) (xy 72.635364 -156.209492) (xy 72.625252 -156.209044) (xy 72.606571 -156.201293)
			(xy 72.592278 -156.186985) (xy 72.584546 -156.168297) (xy 72.584056 -156.158184) (xy 69.331332 -156.158184)
			(xy 69.330803 -156.168288) (xy 69.323076 -156.18696) (xy 69.308793 -156.201254) (xy 69.290127 -156.208995)
			(xy 69.280024 -156.209492) (xy 68.09867 -156.209492) (xy 68.088545 -156.208999) (xy 68.069829 -156.201267)
			(xy 68.055475 -156.186984) (xy 68.047652 -156.168306) (xy 68.047108 -156.158184) (xy 65.655159 -156.158184)
			(xy 65.652714 -156.176758) (xy 65.637193 -156.234683) (xy 65.630373 -156.251148) (xy 82.241644 -156.251148)
			(xy 82.241644 -156.008324) (xy 82.360516 -155.826968) (xy 82.423 -155.731464) (xy 82.44713 -155.694634)
			(xy 82.450996 -155.688305) (xy 82.455258 -155.674106) (xy 82.455512 -155.666694) (xy 82.455512 -155.640786)
			(xy 82.45533 -155.634635) (xy 82.452369 -155.622694) (xy 82.44967 -155.617164) (xy 82.336132 -155.443174)
			(xy 82.316066 -155.412186) (xy 82.310478 -155.40355) (xy 82.250026 -155.31084) (xy 82.249518 -155.310078)
			(xy 82.24901 -155.309316) (xy 82.248756 -155.308808) (xy 82.248248 -155.308046) (xy 82.241644 -155.297632)
			(xy 82.241644 -155.054808) (xy 82.242293 -155.043256) (xy 82.252247 -155.022405) (xy 82.270188 -155.007844)
			(xy 82.281268 -155.004516) (xy 82.293206 -155.002992) (xy 83.029806 -155.002992) (xy 83.040564 -155.003504)
			(xy 83.060253 -155.012177) (xy 83.067906 -155.019756) (xy 83.074108 -155.027152) (xy 83.081019 -155.045162)
			(xy 83.081368 -155.054808) (xy 83.081368 -155.297632) (xy 82.865468 -155.628086) (xy 82.861439 -155.636304)
			(xy 82.858901 -155.654416) (xy 82.862848 -155.672274) (xy 82.8675 -155.680156) (xy 82.899758 -155.72994)
			(xy 83.081368 -156.007054) (xy 83.081368 -156.085794) (xy 83.716368 -156.085794) (xy 83.716368 -155.222194)
			(xy 83.716858 -155.19221) (xy 83.724686 -155.132754) (xy 83.740207 -155.074829) (xy 83.763156 -155.019425)
			(xy 83.79314 -154.967491) (xy 83.829646 -154.919915) (xy 83.872051 -154.87751) (xy 83.919627 -154.841004)
			(xy 83.971561 -154.81102) (xy 84.026965 -154.788071) (xy 84.08489 -154.77255) (xy 84.144346 -154.764722)
			(xy 84.204314 -154.764722) (xy 84.26377 -154.77255) (xy 84.321695 -154.788071) (xy 84.377099 -154.81102)
			(xy 84.429033 -154.841004) (xy 84.476609 -154.87751) (xy 84.519014 -154.919915) (xy 84.55552 -154.967491)
			(xy 84.585504 -155.019425) (xy 84.608453 -155.074829) (xy 84.623974 -155.132754) (xy 84.631802 -155.19221)
			(xy 84.632292 -155.222194) (xy 84.632292 -156.085794) (xy 84.632267 -156.087318) (xy 180.84546 -156.087318)
			(xy 180.84546 -155.223718) (xy 180.84595 -155.19375) (xy 180.853773 -155.134328) (xy 180.869286 -155.076435)
			(xy 180.892222 -155.021062) (xy 180.922189 -154.969156) (xy 180.958676 -154.921606) (xy 181.001056 -154.879226)
			(xy 181.048606 -154.842739) (xy 181.100512 -154.812772) (xy 181.155885 -154.789836) (xy 181.213778 -154.774323)
			(xy 181.2732 -154.7665) (xy 181.333136 -154.7665) (xy 181.392558 -154.774323) (xy 181.450451 -154.789836)
			(xy 181.505824 -154.812772) (xy 181.55773 -154.842739) (xy 181.60528 -154.879226) (xy 181.64766 -154.921606)
			(xy 181.684147 -154.969156) (xy 181.714114 -155.021062) (xy 181.73705 -155.076435) (xy 181.752563 -155.134328)
			(xy 181.760386 -155.19375) (xy 181.760876 -155.223718) (xy 181.760876 -156.087318) (xy 181.760386 -156.117286)
			(xy 181.755002 -156.158184) (xy 184.146952 -156.158184) (xy 184.146952 -155.151836) (xy 184.147514 -155.141735)
			(xy 184.15523 -155.123067) (xy 184.169504 -155.108773) (xy 184.18816 -155.101029) (xy 184.19826 -155.100528)
			(xy 185.379614 -155.100528) (xy 185.38974 -155.101015) (xy 185.408459 -155.108745) (xy 185.422815 -155.123031)
			(xy 185.430635 -155.141712) (xy 185.431176 -155.151836) (xy 185.431176 -156.158184) (xy 188.6839 -156.158184)
			(xy 188.6839 -155.151836) (xy 188.684346 -155.141716) (xy 188.692082 -155.123013) (xy 188.70639 -155.108698)
			(xy 188.725088 -155.100951) (xy 188.735208 -155.100528) (xy 189.916308 -155.100528) (xy 189.926434 -155.10091)
			(xy 189.945144 -155.108666) (xy 189.959458 -155.122993) (xy 189.967198 -155.141709) (xy 189.967616 -155.151836)
			(xy 189.967616 -156.158184) (xy 189.967171 -156.168303) (xy 189.959431 -156.187004) (xy 189.945124 -156.201318)
			(xy 189.926427 -156.209067) (xy 189.916308 -156.209492) (xy 188.735208 -156.209492) (xy 188.725085 -156.209077)
			(xy 188.70638 -156.20133) (xy 188.692065 -156.187013) (xy 188.684321 -156.168307) (xy 188.6839 -156.158184)
			(xy 185.431176 -156.158184) (xy 185.43077 -156.168308) (xy 185.423023 -156.187016) (xy 185.408703 -156.201332)
			(xy 185.389993 -156.209074) (xy 185.379868 -156.209492) (xy 184.198514 -156.209492) (xy 184.188392 -156.208963)
			(xy 184.169677 -156.201246) (xy 184.155322 -156.186973) (xy 184.147496 -156.168303) (xy 184.146952 -156.158184)
			(xy 181.755002 -156.158184) (xy 181.752563 -156.176708) (xy 181.73705 -156.234601) (xy 181.730196 -156.251148)
			(xy 198.341488 -156.251148) (xy 198.341488 -156.008324) (xy 198.46036 -155.826968) (xy 198.522844 -155.731464)
			(xy 198.546974 -155.694634) (xy 198.550844 -155.688307) (xy 198.555102 -155.674107) (xy 198.555356 -155.666694)
			(xy 198.555356 -155.640786) (xy 198.555169 -155.634636) (xy 198.552211 -155.622695) (xy 198.549514 -155.617164)
			(xy 198.435976 -155.443174) (xy 198.41591 -155.412186) (xy 198.410322 -155.40355) (xy 198.34987 -155.31084)
			(xy 198.349362 -155.310078) (xy 198.348854 -155.309316) (xy 198.3486 -155.308808) (xy 198.348092 -155.308046)
			(xy 198.341488 -155.297632) (xy 198.341488 -155.054808) (xy 198.342178 -155.043262) (xy 198.352119 -155.022418)
			(xy 198.37004 -155.007852) (xy 198.381112 -155.004516) (xy 198.39305 -155.002992) (xy 199.12965 -155.002992)
			(xy 199.140405 -155.003535) (xy 199.160094 -155.012186) (xy 199.16775 -155.019756) (xy 199.173945 -155.027157)
			(xy 199.180862 -155.045163) (xy 199.181212 -155.054808) (xy 199.181212 -155.297632) (xy 198.965312 -155.628086)
			(xy 198.961279 -155.636303) (xy 198.958738 -155.654416) (xy 198.962689 -155.672275) (xy 198.967344 -155.680156)
			(xy 198.999602 -155.72994) (xy 199.181212 -156.007054) (xy 199.181212 -156.085794) (xy 199.81672 -156.085794)
			(xy 199.81672 -155.222194) (xy 199.81721 -155.192226) (xy 199.825033 -155.132804) (xy 199.840546 -155.074911)
			(xy 199.863482 -155.019538) (xy 199.893449 -154.967632) (xy 199.929936 -154.920082) (xy 199.972316 -154.877702)
			(xy 200.019866 -154.841215) (xy 200.071772 -154.811248) (xy 200.127145 -154.788312) (xy 200.185038 -154.772799)
			(xy 200.24446 -154.764976) (xy 200.304396 -154.764976) (xy 200.363818 -154.772799) (xy 200.421711 -154.788312)
			(xy 200.477084 -154.811248) (xy 200.52899 -154.841215) (xy 200.57654 -154.877702) (xy 200.61892 -154.920082)
			(xy 200.655407 -154.967632) (xy 200.685374 -155.019538) (xy 200.70831 -155.074911) (xy 200.723823 -155.132804)
			(xy 200.731646 -155.192226) (xy 200.732136 -155.222194) (xy 200.732136 -156.085794) (xy 200.732111 -156.087318)
			(xy 296.945304 -156.087318) (xy 296.945304 -155.223718) (xy 296.945794 -155.19375) (xy 296.953617 -155.134328)
			(xy 296.96913 -155.076435) (xy 296.992066 -155.021062) (xy 297.022033 -154.969156) (xy 297.05852 -154.921606)
			(xy 297.1009 -154.879226) (xy 297.14845 -154.842739) (xy 297.200356 -154.812772) (xy 297.255729 -154.789836)
			(xy 297.313622 -154.774323) (xy 297.373044 -154.7665) (xy 297.43298 -154.7665) (xy 297.492402 -154.774323)
			(xy 297.550295 -154.789836) (xy 297.605668 -154.812772) (xy 297.657574 -154.842739) (xy 297.705124 -154.879226)
			(xy 297.747504 -154.921606) (xy 297.783991 -154.969156) (xy 297.813958 -155.021062) (xy 297.836894 -155.076435)
			(xy 297.852407 -155.134328) (xy 297.86023 -155.19375) (xy 297.86072 -155.223718) (xy 297.86072 -156.087318)
			(xy 297.86023 -156.117286) (xy 297.854846 -156.158184) (xy 300.247304 -156.158184) (xy 300.247304 -155.151836)
			(xy 300.247746 -155.141715) (xy 300.255483 -155.123012) (xy 300.269792 -155.108696) (xy 300.288492 -155.10095)
			(xy 300.298612 -155.100528) (xy 301.479712 -155.100528) (xy 301.489839 -155.100907) (xy 301.508548 -155.108664)
			(xy 301.522863 -155.122992) (xy 301.530603 -155.141709) (xy 301.53102 -155.151836) (xy 301.53102 -156.158184)
			(xy 304.783744 -156.158184) (xy 304.783744 -155.151836) (xy 304.78425 -155.141691) (xy 304.792023 -155.12295)
			(xy 304.806393 -155.108628) (xy 304.82516 -155.100917) (xy 304.835306 -155.100528) (xy 306.016406 -155.100528)
			(xy 306.026532 -155.101021) (xy 306.045251 -155.108749) (xy 306.059606 -155.123033) (xy 306.067427 -155.141713)
			(xy 306.067968 -155.151836) (xy 306.067968 -156.158184) (xy 306.067565 -156.168341) (xy 306.059768 -156.187099)
			(xy 306.045366 -156.201424) (xy 306.026565 -156.209119) (xy 306.016406 -156.209492) (xy 304.835306 -156.209492)
			(xy 304.825184 -156.208969) (xy 304.806469 -156.20125) (xy 304.792113 -156.186975) (xy 304.784288 -156.168303)
			(xy 304.783744 -156.158184) (xy 301.53102 -156.158184) (xy 301.530571 -156.168303) (xy 301.522832 -156.187002)
			(xy 301.508526 -156.201317) (xy 301.489831 -156.209066) (xy 301.479712 -156.209492) (xy 300.298612 -156.209492)
			(xy 300.288489 -156.209074) (xy 300.269784 -156.201328) (xy 300.255469 -156.187012) (xy 300.247725 -156.168307)
			(xy 300.247304 -156.158184) (xy 297.854846 -156.158184) (xy 297.852407 -156.176708) (xy 297.836894 -156.234601)
			(xy 297.83004 -156.251148) (xy 314.441332 -156.251148) (xy 314.441332 -156.023564) (xy 314.441586 -156.0195)
			(xy 314.44184 -156.01696) (xy 314.44184 -156.008324) (xy 314.447428 -155.999688) (xy 314.448698 -155.997656)
			(xy 314.449714 -155.995624) (xy 314.647072 -155.694634) (xy 314.650942 -155.688307) (xy 314.6552 -155.674107)
			(xy 314.655454 -155.666694) (xy 314.655454 -155.64104) (xy 314.65525 -155.633706) (xy 314.651119 -155.619635)
			(xy 314.647326 -155.613354) (xy 314.44946 -155.310332) (xy 314.447174 -155.306522) (xy 314.44692 -155.306014)
			(xy 314.445904 -155.304236) (xy 314.44184 -155.297632) (xy 314.44184 -155.289504) (xy 314.441586 -155.286964)
			(xy 314.441332 -155.2829) (xy 314.441332 -155.054808) (xy 314.44172 -155.044581) (xy 314.44955 -155.025685)
			(xy 314.464018 -155.011227) (xy 314.482921 -155.003412) (xy 314.493148 -155.002992) (xy 315.229748 -155.002992)
			(xy 315.23996 -155.003443) (xy 315.258824 -155.011273) (xy 315.273259 -155.025723) (xy 315.281068 -155.044596)
			(xy 315.281564 -155.054808) (xy 315.281564 -155.282392) (xy 315.28131 -155.286456) (xy 315.281056 -155.288996)
			(xy 315.281056 -155.297632) (xy 315.275214 -155.30703) (xy 315.274452 -155.3083) (xy 315.273182 -155.310332)
			(xy 315.067442 -155.625038) (xy 315.062409 -155.633569) (xy 315.058588 -155.652981) (xy 315.062395 -155.672397)
			(xy 315.067442 -155.680918) (xy 315.273182 -155.994354) (xy 315.274198 -155.996386) (xy 315.275468 -155.998418)
			(xy 315.281056 -156.007054) (xy 315.281056 -156.01569) (xy 315.28131 -156.01823) (xy 315.281564 -156.022294)
			(xy 315.281564 -156.085794) (xy 315.916564 -156.085794) (xy 315.916564 -155.222194) (xy 315.917054 -155.192226)
			(xy 315.924877 -155.132804) (xy 315.94039 -155.074911) (xy 315.963326 -155.019538) (xy 315.993293 -154.967632)
			(xy 316.02978 -154.920082) (xy 316.07216 -154.877702) (xy 316.11971 -154.841215) (xy 316.171616 -154.811248)
			(xy 316.226989 -154.788312) (xy 316.284882 -154.772799) (xy 316.344304 -154.764976) (xy 316.40424 -154.764976)
			(xy 316.463662 -154.772799) (xy 316.521555 -154.788312) (xy 316.576928 -154.811248) (xy 316.628834 -154.841215)
			(xy 316.676384 -154.877702) (xy 316.718764 -154.920082) (xy 316.755251 -154.967632) (xy 316.785218 -155.019538)
			(xy 316.808154 -155.074911) (xy 316.823667 -155.132804) (xy 316.83149 -155.192226) (xy 316.83198 -155.222194)
			(xy 316.83198 -156.085794) (xy 316.831955 -156.087318) (xy 413.045148 -156.087318) (xy 413.045148 -155.223718)
			(xy 413.045638 -155.193734) (xy 413.053466 -155.134278) (xy 413.068987 -155.076353) (xy 413.091936 -155.020949)
			(xy 413.12192 -154.969015) (xy 413.158426 -154.921439) (xy 413.200831 -154.879034) (xy 413.248407 -154.842528)
			(xy 413.300341 -154.812544) (xy 413.355745 -154.789595) (xy 413.41367 -154.774074) (xy 413.473126 -154.766246)
			(xy 413.533094 -154.766246) (xy 413.59255 -154.774074) (xy 413.650475 -154.789595) (xy 413.705879 -154.812544)
			(xy 413.757813 -154.842528) (xy 413.805389 -154.879034) (xy 413.847794 -154.921439) (xy 413.8843 -154.969015)
			(xy 413.914284 -155.020949) (xy 413.937233 -155.076353) (xy 413.952754 -155.134278) (xy 413.960582 -155.193734)
			(xy 413.961072 -155.223718) (xy 413.961072 -156.087318) (xy 413.960582 -156.117302) (xy 413.955199 -156.158184)
			(xy 416.347148 -156.158184) (xy 416.347148 -155.151836) (xy 416.347714 -155.141736) (xy 416.35543 -155.123069)
			(xy 416.369701 -155.108774) (xy 416.388357 -155.101029) (xy 416.398456 -155.100528) (xy 417.57981 -155.100528)
			(xy 417.589936 -155.101018) (xy 417.608655 -155.108747) (xy 417.62301 -155.123032) (xy 417.630831 -155.141713)
			(xy 417.631372 -155.151836) (xy 417.631372 -156.158184) (xy 420.884096 -156.158184) (xy 420.884096 -155.151836)
			(xy 420.884546 -155.141716) (xy 420.892281 -155.123014) (xy 420.906587 -155.108699) (xy 420.925285 -155.100952)
			(xy 420.935404 -155.100528) (xy 422.116504 -155.100528) (xy 422.12663 -155.100914) (xy 422.145339 -155.108668)
			(xy 422.159654 -155.122994) (xy 422.167394 -155.141709) (xy 422.167812 -155.151836) (xy 422.167812 -156.158184)
			(xy 422.167371 -156.168304) (xy 422.159631 -156.187005) (xy 422.145322 -156.201319) (xy 422.126624 -156.209067)
			(xy 422.116504 -156.209492) (xy 420.935404 -156.209492) (xy 420.925281 -156.20908) (xy 420.906576 -156.201332)
			(xy 420.892261 -156.187014) (xy 420.884517 -156.168307) (xy 420.884096 -156.158184) (xy 417.631372 -156.158184)
			(xy 417.63097 -156.168309) (xy 417.623222 -156.187018) (xy 417.608901 -156.201333) (xy 417.590189 -156.209074)
			(xy 417.580064 -156.209492) (xy 416.39871 -156.209492) (xy 416.388588 -156.208966) (xy 416.369873 -156.201248)
			(xy 416.355517 -156.186974) (xy 416.347692 -156.168303) (xy 416.347148 -156.158184) (xy 413.955199 -156.158184)
			(xy 413.952754 -156.176758) (xy 413.937233 -156.234683) (xy 413.930413 -156.251148) (xy 430.541684 -156.251148)
			(xy 430.541684 -156.008324) (xy 430.660556 -155.826968) (xy 430.72304 -155.731464) (xy 430.74717 -155.694634)
			(xy 430.751039 -155.688307) (xy 430.755298 -155.674107) (xy 430.755552 -155.666694) (xy 430.755552 -155.640786)
			(xy 430.755365 -155.634636) (xy 430.752407 -155.622695) (xy 430.74971 -155.617164) (xy 430.636172 -155.443174)
			(xy 430.616106 -155.412186) (xy 430.610518 -155.40355) (xy 430.550066 -155.31084) (xy 430.549558 -155.310078)
			(xy 430.54905 -155.309316) (xy 430.548796 -155.308808) (xy 430.548288 -155.308046) (xy 430.541684 -155.297632)
			(xy 430.541684 -155.054808) (xy 430.542377 -155.043263) (xy 430.552317 -155.022419) (xy 430.570237 -155.007853)
			(xy 430.581308 -155.004516) (xy 430.593246 -155.002992) (xy 431.329846 -155.002992) (xy 431.3406 -155.003537)
			(xy 431.360289 -155.012187) (xy 431.367946 -155.019756) (xy 431.374141 -155.027158) (xy 431.381058 -155.045163)
			(xy 431.381408 -155.054808) (xy 431.381408 -155.297632) (xy 431.165508 -155.628086) (xy 431.161476 -155.636303)
			(xy 431.158935 -155.654416) (xy 431.162885 -155.672275) (xy 431.16754 -155.680156) (xy 431.199798 -155.72994)
			(xy 431.381408 -156.007054) (xy 431.381408 -156.085794) (xy 432.016408 -156.085794) (xy 432.016408 -155.222194)
			(xy 432.016898 -155.19221) (xy 432.024726 -155.132754) (xy 432.040247 -155.074829) (xy 432.063196 -155.019425)
			(xy 432.09318 -154.967491) (xy 432.129686 -154.919915) (xy 432.172091 -154.87751) (xy 432.219667 -154.841004)
			(xy 432.271601 -154.81102) (xy 432.327005 -154.788071) (xy 432.38493 -154.77255) (xy 432.444386 -154.764722)
			(xy 432.504354 -154.764722) (xy 432.56381 -154.77255) (xy 432.621735 -154.788071) (xy 432.677139 -154.81102)
			(xy 432.729073 -154.841004) (xy 432.776649 -154.87751) (xy 432.819054 -154.919915) (xy 432.85556 -154.967491)
			(xy 432.885544 -155.019425) (xy 432.908493 -155.074829) (xy 432.924014 -155.132754) (xy 432.931842 -155.19221)
			(xy 432.932332 -155.222194) (xy 432.932332 -156.085794) (xy 432.931842 -156.115778) (xy 432.924014 -156.175234)
			(xy 432.908493 -156.233159) (xy 432.885544 -156.288563) (xy 432.85556 -156.340497) (xy 432.819054 -156.388073)
			(xy 432.776649 -156.430478) (xy 432.729073 -156.466984) (xy 432.677139 -156.496968) (xy 432.621735 -156.519917)
			(xy 432.56381 -156.535438) (xy 432.504354 -156.543266) (xy 432.444386 -156.543266) (xy 432.38493 -156.535438)
			(xy 432.327005 -156.519917) (xy 432.271601 -156.496968) (xy 432.219667 -156.466984) (xy 432.172091 -156.430478)
			(xy 432.129686 -156.388073) (xy 432.09318 -156.340497) (xy 432.063196 -156.288563) (xy 432.040247 -156.233159)
			(xy 432.024726 -156.175234) (xy 432.016898 -156.115778) (xy 432.016408 -156.085794) (xy 431.381408 -156.085794)
			(xy 431.381408 -156.251148) (xy 431.380764 -156.262699) (xy 431.3708 -156.283544) (xy 431.352862 -156.298107)
			(xy 431.341784 -156.30144) (xy 431.329846 -156.302964) (xy 430.593246 -156.302964) (xy 430.582489 -156.302436)
			(xy 430.5628 -156.293776) (xy 430.555146 -156.2862) (xy 430.548931 -156.278813) (xy 430.542027 -156.260797)
			(xy 430.541684 -156.251148) (xy 413.930413 -156.251148) (xy 413.914284 -156.290087) (xy 413.8843 -156.342021)
			(xy 413.847794 -156.389597) (xy 413.805389 -156.432002) (xy 413.757813 -156.468508) (xy 413.705879 -156.498492)
			(xy 413.650475 -156.521441) (xy 413.59255 -156.536962) (xy 413.533094 -156.54479) (xy 413.473126 -156.54479)
			(xy 413.41367 -156.536962) (xy 413.355745 -156.521441) (xy 413.300341 -156.498492) (xy 413.248407 -156.468508)
			(xy 413.200831 -156.432002) (xy 413.158426 -156.389597) (xy 413.12192 -156.342021) (xy 413.091936 -156.290087)
			(xy 413.068987 -156.234683) (xy 413.053466 -156.176758) (xy 413.045638 -156.117302) (xy 413.045148 -156.087318)
			(xy 316.831955 -156.087318) (xy 316.83149 -156.115762) (xy 316.823667 -156.175184) (xy 316.808154 -156.233077)
			(xy 316.785218 -156.28845) (xy 316.755251 -156.340356) (xy 316.718764 -156.387906) (xy 316.676384 -156.430286)
			(xy 316.628834 -156.466773) (xy 316.576928 -156.49674) (xy 316.521555 -156.519676) (xy 316.463662 -156.535189)
			(xy 316.40424 -156.543012) (xy 316.344304 -156.543012) (xy 316.284882 -156.535189) (xy 316.226989 -156.519676)
			(xy 316.171616 -156.49674) (xy 316.11971 -156.466773) (xy 316.07216 -156.430286) (xy 316.02978 -156.387906)
			(xy 315.993293 -156.340356) (xy 315.963326 -156.28845) (xy 315.94039 -156.233077) (xy 315.924877 -156.175184)
			(xy 315.917054 -156.115762) (xy 315.916564 -156.085794) (xy 315.281564 -156.085794) (xy 315.281564 -156.251148)
			(xy 315.281059 -156.261353) (xy 315.273239 -156.280206) (xy 315.258806 -156.294639) (xy 315.239953 -156.302459)
			(xy 315.229748 -156.302964) (xy 314.493148 -156.302964) (xy 314.482949 -156.30238) (xy 314.464098 -156.294592)
			(xy 314.449662 -156.280183) (xy 314.441839 -156.261346) (xy 314.441332 -156.251148) (xy 297.83004 -156.251148)
			(xy 297.813958 -156.289974) (xy 297.783991 -156.34188) (xy 297.747504 -156.38943) (xy 297.705124 -156.43181)
			(xy 297.657574 -156.468297) (xy 297.605668 -156.498264) (xy 297.550295 -156.5212) (xy 297.492402 -156.536713)
			(xy 297.43298 -156.544536) (xy 297.373044 -156.544536) (xy 297.313622 -156.536713) (xy 297.255729 -156.5212)
			(xy 297.200356 -156.498264) (xy 297.14845 -156.468297) (xy 297.1009 -156.43181) (xy 297.05852 -156.38943)
			(xy 297.022033 -156.34188) (xy 296.992066 -156.289974) (xy 296.96913 -156.234601) (xy 296.953617 -156.176708)
			(xy 296.945794 -156.117286) (xy 296.945304 -156.087318) (xy 200.732111 -156.087318) (xy 200.731646 -156.115762)
			(xy 200.723823 -156.175184) (xy 200.70831 -156.233077) (xy 200.685374 -156.28845) (xy 200.655407 -156.340356)
			(xy 200.61892 -156.387906) (xy 200.57654 -156.430286) (xy 200.52899 -156.466773) (xy 200.477084 -156.49674)
			(xy 200.421711 -156.519676) (xy 200.363818 -156.535189) (xy 200.304396 -156.543012) (xy 200.24446 -156.543012)
			(xy 200.185038 -156.535189) (xy 200.127145 -156.519676) (xy 200.071772 -156.49674) (xy 200.019866 -156.466773)
			(xy 199.972316 -156.430286) (xy 199.929936 -156.387906) (xy 199.893449 -156.340356) (xy 199.863482 -156.28845)
			(xy 199.840546 -156.233077) (xy 199.825033 -156.175184) (xy 199.81721 -156.115762) (xy 199.81672 -156.085794)
			(xy 199.181212 -156.085794) (xy 199.181212 -156.251148) (xy 199.180565 -156.262698) (xy 199.170602 -156.283543)
			(xy 199.152666 -156.298106) (xy 199.141588 -156.30144) (xy 199.12965 -156.302964) (xy 198.39305 -156.302964)
			(xy 198.382294 -156.302434) (xy 198.362604 -156.293775) (xy 198.35495 -156.2862) (xy 198.348736 -156.278812)
			(xy 198.341831 -156.260797) (xy 198.341488 -156.251148) (xy 181.730196 -156.251148) (xy 181.714114 -156.289974)
			(xy 181.684147 -156.34188) (xy 181.64766 -156.38943) (xy 181.60528 -156.43181) (xy 181.55773 -156.468297)
			(xy 181.505824 -156.498264) (xy 181.450451 -156.5212) (xy 181.392558 -156.536713) (xy 181.333136 -156.544536)
			(xy 181.2732 -156.544536) (xy 181.213778 -156.536713) (xy 181.155885 -156.5212) (xy 181.100512 -156.498264)
			(xy 181.048606 -156.468297) (xy 181.001056 -156.43181) (xy 180.958676 -156.38943) (xy 180.922189 -156.34188)
			(xy 180.892222 -156.289974) (xy 180.869286 -156.234601) (xy 180.853773 -156.176708) (xy 180.84595 -156.117286)
			(xy 180.84546 -156.087318) (xy 84.632267 -156.087318) (xy 84.631802 -156.115778) (xy 84.623974 -156.175234)
			(xy 84.608453 -156.233159) (xy 84.585504 -156.288563) (xy 84.55552 -156.340497) (xy 84.519014 -156.388073)
			(xy 84.476609 -156.430478) (xy 84.429033 -156.466984) (xy 84.377099 -156.496968) (xy 84.321695 -156.519917)
			(xy 84.26377 -156.535438) (xy 84.204314 -156.543266) (xy 84.144346 -156.543266) (xy 84.08489 -156.535438)
			(xy 84.026965 -156.519917) (xy 83.971561 -156.496968) (xy 83.919627 -156.466984) (xy 83.872051 -156.430478)
			(xy 83.829646 -156.388073) (xy 83.79314 -156.340497) (xy 83.763156 -156.288563) (xy 83.740207 -156.233159)
			(xy 83.724686 -156.175234) (xy 83.716858 -156.115778) (xy 83.716368 -156.085794) (xy 83.081368 -156.085794)
			(xy 83.081368 -156.251148) (xy 83.080753 -156.262703) (xy 83.07078 -156.283554) (xy 83.052829 -156.298113)
			(xy 83.041744 -156.30144) (xy 83.029806 -156.302964) (xy 82.293206 -156.302964) (xy 82.282447 -156.302458)
			(xy 82.262758 -156.293782) (xy 82.255106 -156.2862) (xy 82.248886 -156.278817) (xy 82.241986 -156.260797)
			(xy 82.241644 -156.251148) (xy 65.630373 -156.251148) (xy 65.614244 -156.290087) (xy 65.58426 -156.342021)
			(xy 65.547754 -156.389597) (xy 65.505349 -156.432002) (xy 65.457773 -156.468508) (xy 65.405839 -156.498492)
			(xy 65.350435 -156.521441) (xy 65.29251 -156.536962) (xy 65.233054 -156.54479) (xy 65.173086 -156.54479)
			(xy 65.11363 -156.536962) (xy 65.055705 -156.521441) (xy 65.000301 -156.498492) (xy 64.948367 -156.468508)
			(xy 64.900791 -156.432002) (xy 64.858386 -156.389597) (xy 64.82188 -156.342021) (xy 64.791896 -156.290087)
			(xy 64.768947 -156.234683) (xy 64.753426 -156.176758) (xy 64.745598 -156.117302) (xy 64.745108 -156.087318)
			(xy 4.30911 -156.087318) (xy 4.30911 -157.900066) (xy 228.314505 -157.900066) (xy 228.314505 -157.840134)
			(xy 228.322328 -157.780714) (xy 228.33784 -157.722823) (xy 228.360775 -157.667453) (xy 228.390741 -157.61555)
			(xy 228.427226 -157.568002) (xy 228.469605 -157.525624) (xy 228.517153 -157.489139) (xy 228.569056 -157.459173)
			(xy 228.624427 -157.436238) (xy 228.682318 -157.420727) (xy 228.741738 -157.412905) (xy 228.771704 -157.412436)
			(xy 229.635304 -157.412436) (xy 229.665274 -157.412838) (xy 229.724702 -157.420663) (xy 229.7826 -157.436177)
			(xy 229.837978 -157.459116) (xy 229.889888 -157.489086) (xy 229.937442 -157.525576) (xy 229.979827 -157.567961)
			(xy 230.016316 -157.615515) (xy 230.046286 -157.667425) (xy 230.069224 -157.722803) (xy 230.084738 -157.780702)
			(xy 230.092562 -157.84013) (xy 230.092562 -157.90007) (xy 230.089876 -157.920473) (xy 230.557725 -157.920473)
			(xy 230.557725 -157.860527) (xy 230.56555 -157.801095) (xy 230.581066 -157.743192) (xy 230.604007 -157.68781)
			(xy 230.633981 -157.635897) (xy 230.670475 -157.58834) (xy 230.712864 -157.545953) (xy 230.760423 -157.509463)
			(xy 230.812339 -157.479493) (xy 230.867722 -157.456555) (xy 230.925626 -157.441044) (xy 230.985059 -157.433223)
			(xy 231.015032 -157.432756) (xy 231.878632 -157.432756) (xy 231.908596 -157.43332) (xy 231.968011 -157.441146)
			(xy 232.025896 -157.45666) (xy 232.081261 -157.479596) (xy 232.133158 -157.509563) (xy 232.180701 -157.546046)
			(xy 232.223075 -157.588423) (xy 232.259555 -157.635968) (xy 232.289518 -157.687868) (xy 232.31245 -157.743235)
			(xy 232.32796 -157.801121) (xy 232.335782 -157.860536) (xy 232.335782 -157.920464) (xy 232.32796 -157.979879)
			(xy 232.31245 -158.037765) (xy 232.289518 -158.093132) (xy 232.259555 -158.145032) (xy 232.223075 -158.192577)
			(xy 232.180701 -158.234954) (xy 232.133158 -158.271437) (xy 232.081261 -158.301404) (xy 232.025896 -158.32434)
			(xy 231.968011 -158.339854) (xy 231.908596 -158.34768) (xy 231.878632 -158.348172) (xy 231.015032 -158.348172)
			(xy 230.985059 -158.347777) (xy 230.925626 -158.339956) (xy 230.867722 -158.324445) (xy 230.812339 -158.301507)
			(xy 230.760423 -158.271537) (xy 230.712864 -158.235047) (xy 230.670475 -158.19266) (xy 230.633981 -158.145103)
			(xy 230.604007 -158.09319) (xy 230.581066 -158.037808) (xy 230.56555 -157.979905) (xy 230.557725 -157.920473)
			(xy 230.089876 -157.920473) (xy 230.084738 -157.959498) (xy 230.069224 -158.017397) (xy 230.046286 -158.072775)
			(xy 230.016316 -158.124685) (xy 229.979827 -158.172239) (xy 229.937442 -158.214624) (xy 229.889888 -158.251114)
			(xy 229.837978 -158.281084) (xy 229.7826 -158.304023) (xy 229.724702 -158.319537) (xy 229.665274 -158.327362)
			(xy 229.635304 -158.327852) (xy 228.771704 -158.327852) (xy 228.741738 -158.327295) (xy 228.682318 -158.319473)
			(xy 228.624427 -158.303962) (xy 228.569056 -158.281027) (xy 228.517153 -158.251061) (xy 228.469605 -158.214576)
			(xy 228.427226 -158.172198) (xy 228.390741 -158.12465) (xy 228.360775 -158.072747) (xy 228.33784 -158.017377)
			(xy 228.322328 -157.959486) (xy 228.314505 -157.900066) (xy 4.30911 -157.900066) (xy 4.30911 -160.1851)
			(xy 45.524179 -160.1851) (xy 45.528134 -160.093263) (xy 45.539969 -160.002106) (xy 45.559596 -159.912303)
			(xy 45.58687 -159.824521) (xy 45.62159 -159.739407) (xy 45.663498 -159.657594) (xy 45.712284 -159.579686)
			(xy 45.767587 -159.506261) (xy 45.828997 -159.437861) (xy 45.896059 -159.374994) (xy 45.968278 -159.318124)
			(xy 46.045118 -159.267673) (xy 46.126011 -159.224014) (xy 46.210357 -159.187471) (xy 46.297533 -159.158314)
			(xy 46.386892 -159.13676) (xy 46.477773 -159.122966) (xy 46.569504 -159.117036) (xy 46.661405 -159.119014)
			(xy 46.752796 -159.128885) (xy 46.843 -159.146575) (xy 46.931349 -159.171955) (xy 47.017189 -159.204835)
			(xy 47.099885 -159.244973) (xy 47.178825 -159.292072) (xy 47.253423 -159.345782) (xy 47.323129 -159.405706)
			(xy 47.387424 -159.4714) (xy 47.445835 -159.542378) (xy 47.497927 -159.618115) (xy 47.543316 -159.69805)
			(xy 47.581666 -159.78159) (xy 47.612691 -159.868118) (xy 47.636164 -159.956993) (xy 47.65191 -160.047557)
			(xy 47.659812 -160.139139) (xy 47.660306 -160.1851) (xy 69.888875 -160.1851) (xy 69.892831 -160.093241)
			(xy 69.904668 -160.002062) (xy 69.9243 -159.912238) (xy 69.951581 -159.824435) (xy 69.986309 -159.739302)
			(xy 70.028227 -159.657469) (xy 70.077025 -159.579542) (xy 70.13234 -159.506099) (xy 70.193765 -159.437683)
			(xy 70.260844 -159.374801) (xy 70.333079 -159.317918) (xy 70.409938 -159.267455) (xy 70.49085 -159.223786)
			(xy 70.575216 -159.187234) (xy 70.662412 -159.15807) (xy 70.751793 -159.13651) (xy 70.842696 -159.122714)
			(xy 70.934449 -159.116782) (xy 71.026371 -159.118761) (xy 71.117784 -159.128634) (xy 71.208009 -159.146329)
			(xy 71.29638 -159.171714) (xy 71.38224 -159.204602) (xy 71.464956 -159.24475) (xy 71.543914 -159.291859)
			(xy 71.618531 -159.345582) (xy 71.688252 -159.40552) (xy 71.752563 -159.47123) (xy 71.810988 -159.542226)
			(xy 71.863093 -159.61798) (xy 71.908492 -159.697934) (xy 71.946851 -159.781494) (xy 71.977884 -159.868043)
			(xy 72.001362 -159.956939) (xy 72.017112 -160.047524) (xy 72.025016 -160.139128) (xy 72.02551 -160.1851)
			(xy 161.624277 -160.1851) (xy 161.628232 -160.093263) (xy 161.640067 -160.002106) (xy 161.659694 -159.912303)
			(xy 161.686968 -159.824521) (xy 161.721688 -159.739407) (xy 161.763596 -159.657594) (xy 161.812382 -159.579686)
			(xy 161.867685 -159.506261) (xy 161.929095 -159.437861) (xy 161.996157 -159.374994) (xy 162.068376 -159.318124)
			(xy 162.145216 -159.267673) (xy 162.226109 -159.224014) (xy 162.310455 -159.187471) (xy 162.397631 -159.158314)
			(xy 162.48699 -159.13676) (xy 162.577871 -159.122966) (xy 162.669602 -159.117036) (xy 162.761503 -159.119014)
			(xy 162.852894 -159.128885) (xy 162.943098 -159.146575) (xy 163.031447 -159.171955) (xy 163.117287 -159.204835)
			(xy 163.199983 -159.244973) (xy 163.278923 -159.292072) (xy 163.353521 -159.345782) (xy 163.423227 -159.405706)
			(xy 163.487522 -159.4714) (xy 163.545933 -159.542378) (xy 163.598025 -159.618115) (xy 163.643414 -159.69805)
			(xy 163.681764 -159.78159) (xy 163.712789 -159.868118) (xy 163.736262 -159.956993) (xy 163.752008 -160.047557)
			(xy 163.75991 -160.139139) (xy 163.760404 -160.1851) (xy 185.988973 -160.1851) (xy 185.992929 -160.093241)
			(xy 186.004766 -160.002062) (xy 186.024398 -159.912238) (xy 186.051679 -159.824435) (xy 186.086407 -159.739302)
			(xy 186.128325 -159.657469) (xy 186.177123 -159.579542) (xy 186.232438 -159.506099) (xy 186.293863 -159.437683)
			(xy 186.360942 -159.374801) (xy 186.433177 -159.317918) (xy 186.510036 -159.267455) (xy 186.590948 -159.223786)
			(xy 186.675314 -159.187234) (xy 186.76251 -159.15807) (xy 186.851891 -159.13651) (xy 186.942794 -159.122714)
			(xy 187.034547 -159.116782) (xy 187.126469 -159.118761) (xy 187.217882 -159.128634) (xy 187.308107 -159.146329)
			(xy 187.396478 -159.171714) (xy 187.482338 -159.204602) (xy 187.565054 -159.24475) (xy 187.644012 -159.291859)
			(xy 187.718629 -159.345582) (xy 187.78835 -159.40552) (xy 187.852661 -159.47123) (xy 187.911086 -159.542226)
			(xy 187.963191 -159.61798) (xy 188.00859 -159.697934) (xy 188.046949 -159.781494) (xy 188.077982 -159.868043)
			(xy 188.10146 -159.956939) (xy 188.11721 -160.047524) (xy 188.125114 -160.139128) (xy 188.125608 -160.1851)
			(xy 277.724121 -160.1851) (xy 277.728076 -160.093263) (xy 277.739911 -160.002106) (xy 277.759538 -159.912303)
			(xy 277.786812 -159.824521) (xy 277.821532 -159.739407) (xy 277.86344 -159.657594) (xy 277.912226 -159.579686)
			(xy 277.967529 -159.506261) (xy 278.028939 -159.437861) (xy 278.096001 -159.374994) (xy 278.16822 -159.318124)
			(xy 278.24506 -159.267673) (xy 278.325953 -159.224014) (xy 278.410299 -159.187471) (xy 278.497475 -159.158314)
			(xy 278.586834 -159.13676) (xy 278.677715 -159.122966) (xy 278.769446 -159.117036) (xy 278.861347 -159.119014)
			(xy 278.952738 -159.128885) (xy 279.042942 -159.146575) (xy 279.131291 -159.171955) (xy 279.217131 -159.204835)
			(xy 279.299827 -159.244973) (xy 279.378767 -159.292072) (xy 279.453365 -159.345782) (xy 279.523071 -159.405706)
			(xy 279.587366 -159.4714) (xy 279.645777 -159.542378) (xy 279.697869 -159.618115) (xy 279.743258 -159.69805)
			(xy 279.781608 -159.78159) (xy 279.812633 -159.868118) (xy 279.836106 -159.956993) (xy 279.851852 -160.047557)
			(xy 279.859754 -160.139139) (xy 279.860248 -160.1851) (xy 302.088817 -160.1851) (xy 302.092773 -160.093241)
			(xy 302.10461 -160.002062) (xy 302.124242 -159.912238) (xy 302.151523 -159.824435) (xy 302.186251 -159.739302)
			(xy 302.228169 -159.657469) (xy 302.276967 -159.579542) (xy 302.332282 -159.506099) (xy 302.393707 -159.437683)
			(xy 302.460786 -159.374801) (xy 302.533021 -159.317918) (xy 302.60988 -159.267455) (xy 302.690792 -159.223786)
			(xy 302.775158 -159.187234) (xy 302.862354 -159.15807) (xy 302.951735 -159.13651) (xy 303.042638 -159.122714)
			(xy 303.134391 -159.116782) (xy 303.226313 -159.118761) (xy 303.317726 -159.128634) (xy 303.407951 -159.146329)
			(xy 303.496322 -159.171714) (xy 303.582182 -159.204602) (xy 303.664898 -159.24475) (xy 303.743856 -159.291859)
			(xy 303.818473 -159.345582) (xy 303.888194 -159.40552) (xy 303.952505 -159.47123) (xy 304.01093 -159.542226)
			(xy 304.063035 -159.61798) (xy 304.108434 -159.697934) (xy 304.146793 -159.781494) (xy 304.177826 -159.868043)
			(xy 304.201304 -159.956939) (xy 304.217054 -160.047524) (xy 304.224958 -160.139128) (xy 304.225452 -160.1851)
			(xy 393.824219 -160.1851) (xy 393.828174 -160.093263) (xy 393.840009 -160.002106) (xy 393.859636 -159.912303)
			(xy 393.88691 -159.824521) (xy 393.92163 -159.739407) (xy 393.963538 -159.657594) (xy 394.012324 -159.579686)
			(xy 394.067627 -159.506261) (xy 394.129037 -159.437861) (xy 394.196099 -159.374994) (xy 394.268318 -159.318124)
			(xy 394.345158 -159.267673) (xy 394.426051 -159.224014) (xy 394.510397 -159.187471) (xy 394.597573 -159.158314)
			(xy 394.686932 -159.13676) (xy 394.777813 -159.122966) (xy 394.869544 -159.117036) (xy 394.961445 -159.119014)
			(xy 395.052836 -159.128885) (xy 395.14304 -159.146575) (xy 395.231389 -159.171955) (xy 395.317229 -159.204835)
			(xy 395.399925 -159.244973) (xy 395.478865 -159.292072) (xy 395.553463 -159.345782) (xy 395.623169 -159.405706)
			(xy 395.687464 -159.4714) (xy 395.745875 -159.542378) (xy 395.797967 -159.618115) (xy 395.843356 -159.69805)
			(xy 395.881706 -159.78159) (xy 395.912731 -159.868118) (xy 395.936204 -159.956993) (xy 395.95195 -160.047557)
			(xy 395.959852 -160.139139) (xy 395.960346 -160.1851) (xy 418.188915 -160.1851) (xy 418.192871 -160.093241)
			(xy 418.204708 -160.002062) (xy 418.22434 -159.912238) (xy 418.251621 -159.824435) (xy 418.286349 -159.739302)
			(xy 418.328267 -159.657469) (xy 418.377065 -159.579542) (xy 418.43238 -159.506099) (xy 418.493805 -159.437683)
			(xy 418.560884 -159.374801) (xy 418.633119 -159.317918) (xy 418.709978 -159.267455) (xy 418.79089 -159.223786)
			(xy 418.875256 -159.187234) (xy 418.962452 -159.15807) (xy 419.051833 -159.13651) (xy 419.142736 -159.122714)
			(xy 419.234489 -159.116782) (xy 419.326411 -159.118761) (xy 419.417824 -159.128634) (xy 419.508049 -159.146329)
			(xy 419.59642 -159.171714) (xy 419.68228 -159.204602) (xy 419.764996 -159.24475) (xy 419.843954 -159.291859)
			(xy 419.918571 -159.345582) (xy 419.988292 -159.40552) (xy 420.052603 -159.47123) (xy 420.111028 -159.542226)
			(xy 420.163133 -159.61798) (xy 420.208532 -159.697934) (xy 420.246891 -159.781494) (xy 420.277924 -159.868043)
			(xy 420.301402 -159.956939) (xy 420.317152 -160.047524) (xy 420.325056 -160.139128) (xy 420.32555 -160.1851)
			(xy 420.325056 -160.231072) (xy 420.317152 -160.322676) (xy 420.301402 -160.413261) (xy 420.277924 -160.502157)
			(xy 420.246891 -160.588706) (xy 420.208532 -160.672266) (xy 420.163133 -160.75222) (xy 420.111028 -160.827974)
			(xy 420.052603 -160.89897) (xy 419.988292 -160.96468) (xy 419.918571 -161.024618) (xy 419.843954 -161.078341)
			(xy 419.764996 -161.12545) (xy 419.68228 -161.165598) (xy 419.59642 -161.198486) (xy 419.508049 -161.223871)
			(xy 419.417824 -161.241566) (xy 419.326411 -161.251439) (xy 419.234489 -161.253418) (xy 419.142736 -161.247486)
			(xy 419.051833 -161.23369) (xy 418.962452 -161.21213) (xy 418.875256 -161.182966) (xy 418.79089 -161.146414)
			(xy 418.709978 -161.102745) (xy 418.633119 -161.052282) (xy 418.560884 -160.995399) (xy 418.493805 -160.932517)
			(xy 418.43238 -160.864101) (xy 418.377065 -160.790658) (xy 418.328267 -160.712731) (xy 418.286349 -160.630898)
			(xy 418.251621 -160.545765) (xy 418.22434 -160.457962) (xy 418.204708 -160.368138) (xy 418.192871 -160.276959)
			(xy 418.188915 -160.1851) (xy 395.960346 -160.1851) (xy 395.959852 -160.231061) (xy 395.95195 -160.322643)
			(xy 395.936204 -160.413207) (xy 395.912731 -160.502082) (xy 395.881706 -160.58861) (xy 395.843356 -160.67215)
			(xy 395.797967 -160.752085) (xy 395.745875 -160.827822) (xy 395.687464 -160.8988) (xy 395.623169 -160.964494)
			(xy 395.553463 -161.024418) (xy 395.478865 -161.078128) (xy 395.399925 -161.125227) (xy 395.317229 -161.165365)
			(xy 395.231389 -161.198245) (xy 395.14304 -161.223625) (xy 395.052836 -161.241315) (xy 394.961445 -161.251186)
			(xy 394.869544 -161.253164) (xy 394.777813 -161.247234) (xy 394.686932 -161.23344) (xy 394.597573 -161.211886)
			(xy 394.510397 -161.182729) (xy 394.426051 -161.146186) (xy 394.345158 -161.102527) (xy 394.268318 -161.052076)
			(xy 394.196099 -160.995206) (xy 394.129037 -160.932339) (xy 394.067627 -160.863939) (xy 394.012324 -160.790514)
			(xy 393.963538 -160.712606) (xy 393.92163 -160.630793) (xy 393.88691 -160.545679) (xy 393.859636 -160.457897)
			(xy 393.840009 -160.368094) (xy 393.828174 -160.276937) (xy 393.824219 -160.1851) (xy 304.225452 -160.1851)
			(xy 304.224958 -160.231072) (xy 304.217054 -160.322676) (xy 304.201304 -160.413261) (xy 304.177826 -160.502157)
			(xy 304.146793 -160.588706) (xy 304.108434 -160.672266) (xy 304.063035 -160.75222) (xy 304.01093 -160.827974)
			(xy 303.952505 -160.89897) (xy 303.888194 -160.96468) (xy 303.818473 -161.024618) (xy 303.743856 -161.078341)
			(xy 303.664898 -161.12545) (xy 303.582182 -161.165598) (xy 303.496322 -161.198486) (xy 303.407951 -161.223871)
			(xy 303.317726 -161.241566) (xy 303.226313 -161.251439) (xy 303.134391 -161.253418) (xy 303.042638 -161.247486)
			(xy 302.951735 -161.23369) (xy 302.862354 -161.21213) (xy 302.775158 -161.182966) (xy 302.690792 -161.146414)
			(xy 302.60988 -161.102745) (xy 302.533021 -161.052282) (xy 302.460786 -160.995399) (xy 302.393707 -160.932517)
			(xy 302.332282 -160.864101) (xy 302.276967 -160.790658) (xy 302.228169 -160.712731) (xy 302.186251 -160.630898)
			(xy 302.151523 -160.545765) (xy 302.124242 -160.457962) (xy 302.10461 -160.368138) (xy 302.092773 -160.276959)
			(xy 302.088817 -160.1851) (xy 279.860248 -160.1851) (xy 279.859754 -160.231061) (xy 279.851852 -160.322643)
			(xy 279.836106 -160.413207) (xy 279.812633 -160.502082) (xy 279.781608 -160.58861) (xy 279.743258 -160.67215)
			(xy 279.697869 -160.752085) (xy 279.645777 -160.827822) (xy 279.587366 -160.8988) (xy 279.523071 -160.964494)
			(xy 279.453365 -161.024418) (xy 279.378767 -161.078128) (xy 279.299827 -161.125227) (xy 279.217131 -161.165365)
			(xy 279.131291 -161.198245) (xy 279.042942 -161.223625) (xy 278.952738 -161.241315) (xy 278.861347 -161.251186)
			(xy 278.769446 -161.253164) (xy 278.677715 -161.247234) (xy 278.586834 -161.23344) (xy 278.497475 -161.211886)
			(xy 278.410299 -161.182729) (xy 278.325953 -161.146186) (xy 278.24506 -161.102527) (xy 278.16822 -161.052076)
			(xy 278.096001 -160.995206) (xy 278.028939 -160.932339) (xy 277.967529 -160.863939) (xy 277.912226 -160.790514)
			(xy 277.86344 -160.712606) (xy 277.821532 -160.630793) (xy 277.786812 -160.545679) (xy 277.759538 -160.457897)
			(xy 277.739911 -160.368094) (xy 277.728076 -160.276937) (xy 277.724121 -160.1851) (xy 188.125608 -160.1851)
			(xy 188.125114 -160.231072) (xy 188.11721 -160.322676) (xy 188.10146 -160.413261) (xy 188.077982 -160.502157)
			(xy 188.046949 -160.588706) (xy 188.00859 -160.672266) (xy 187.963191 -160.75222) (xy 187.911086 -160.827974)
			(xy 187.852661 -160.89897) (xy 187.78835 -160.96468) (xy 187.718629 -161.024618) (xy 187.644012 -161.078341)
			(xy 187.565054 -161.12545) (xy 187.482338 -161.165598) (xy 187.396478 -161.198486) (xy 187.308107 -161.223871)
			(xy 187.217882 -161.241566) (xy 187.126469 -161.251439) (xy 187.034547 -161.253418) (xy 186.942794 -161.247486)
			(xy 186.851891 -161.23369) (xy 186.76251 -161.21213) (xy 186.675314 -161.182966) (xy 186.590948 -161.146414)
			(xy 186.510036 -161.102745) (xy 186.433177 -161.052282) (xy 186.360942 -160.995399) (xy 186.293863 -160.932517)
			(xy 186.232438 -160.864101) (xy 186.177123 -160.790658) (xy 186.128325 -160.712731) (xy 186.086407 -160.630898)
			(xy 186.051679 -160.545765) (xy 186.024398 -160.457962) (xy 186.004766 -160.368138) (xy 185.992929 -160.276959)
			(xy 185.988973 -160.1851) (xy 163.760404 -160.1851) (xy 163.75991 -160.231061) (xy 163.752008 -160.322643)
			(xy 163.736262 -160.413207) (xy 163.712789 -160.502082) (xy 163.681764 -160.58861) (xy 163.643414 -160.67215)
			(xy 163.598025 -160.752085) (xy 163.545933 -160.827822) (xy 163.487522 -160.8988) (xy 163.423227 -160.964494)
			(xy 163.353521 -161.024418) (xy 163.278923 -161.078128) (xy 163.199983 -161.125227) (xy 163.117287 -161.165365)
			(xy 163.031447 -161.198245) (xy 162.943098 -161.223625) (xy 162.852894 -161.241315) (xy 162.761503 -161.251186)
			(xy 162.669602 -161.253164) (xy 162.577871 -161.247234) (xy 162.48699 -161.23344) (xy 162.397631 -161.211886)
			(xy 162.310455 -161.182729) (xy 162.226109 -161.146186) (xy 162.145216 -161.102527) (xy 162.068376 -161.052076)
			(xy 161.996157 -160.995206) (xy 161.929095 -160.932339) (xy 161.867685 -160.863939) (xy 161.812382 -160.790514)
			(xy 161.763596 -160.712606) (xy 161.721688 -160.630793) (xy 161.686968 -160.545679) (xy 161.659694 -160.457897)
			(xy 161.640067 -160.368094) (xy 161.628232 -160.276937) (xy 161.624277 -160.1851) (xy 72.02551 -160.1851)
			(xy 72.025016 -160.231072) (xy 72.017112 -160.322676) (xy 72.001362 -160.413261) (xy 71.977884 -160.502157)
			(xy 71.946851 -160.588706) (xy 71.908492 -160.672266) (xy 71.863093 -160.75222) (xy 71.810988 -160.827974)
			(xy 71.752563 -160.89897) (xy 71.688252 -160.96468) (xy 71.618531 -161.024618) (xy 71.543914 -161.078341)
			(xy 71.464956 -161.12545) (xy 71.38224 -161.165598) (xy 71.29638 -161.198486) (xy 71.208009 -161.223871)
			(xy 71.117784 -161.241566) (xy 71.026371 -161.251439) (xy 70.934449 -161.253418) (xy 70.842696 -161.247486)
			(xy 70.751793 -161.23369) (xy 70.662412 -161.21213) (xy 70.575216 -161.182966) (xy 70.49085 -161.146414)
			(xy 70.409938 -161.102745) (xy 70.333079 -161.052282) (xy 70.260844 -160.995399) (xy 70.193765 -160.932517)
			(xy 70.13234 -160.864101) (xy 70.077025 -160.790658) (xy 70.028227 -160.712731) (xy 69.986309 -160.630898)
			(xy 69.951581 -160.545765) (xy 69.9243 -160.457962) (xy 69.904668 -160.368138) (xy 69.892831 -160.276959)
			(xy 69.888875 -160.1851) (xy 47.660306 -160.1851) (xy 47.659812 -160.231061) (xy 47.65191 -160.322643)
			(xy 47.636164 -160.413207) (xy 47.612691 -160.502082) (xy 47.581666 -160.58861) (xy 47.543316 -160.67215)
			(xy 47.497927 -160.752085) (xy 47.445835 -160.827822) (xy 47.387424 -160.8988) (xy 47.323129 -160.964494)
			(xy 47.253423 -161.024418) (xy 47.178825 -161.078128) (xy 47.099885 -161.125227) (xy 47.017189 -161.165365)
			(xy 46.931349 -161.198245) (xy 46.843 -161.223625) (xy 46.752796 -161.241315) (xy 46.661405 -161.251186)
			(xy 46.569504 -161.253164) (xy 46.477773 -161.247234) (xy 46.386892 -161.23344) (xy 46.297533 -161.211886)
			(xy 46.210357 -161.182729) (xy 46.126011 -161.146186) (xy 46.045118 -161.102527) (xy 45.968278 -161.052076)
			(xy 45.896059 -160.995206) (xy 45.828997 -160.932339) (xy 45.767587 -160.863939) (xy 45.712284 -160.790514)
			(xy 45.663498 -160.712606) (xy 45.62159 -160.630793) (xy 45.58687 -160.545679) (xy 45.559596 -160.457897)
			(xy 45.539969 -160.368094) (xy 45.528134 -160.276937) (xy 45.524179 -160.1851) (xy 4.30911 -160.1851)
			(xy 4.30911 -168.065164) (xy 135.245906 -168.065164) (xy 135.245906 -168.005236) (xy 135.253728 -167.94582)
			(xy 135.269237 -167.887933) (xy 135.29217 -167.832566) (xy 135.322132 -167.780665) (xy 135.358612 -167.733119)
			(xy 135.400986 -167.690742) (xy 135.448529 -167.654257) (xy 135.500426 -167.624289) (xy 135.555791 -167.601351)
			(xy 135.613677 -167.585836) (xy 135.673092 -167.578009) (xy 135.703056 -167.577516) (xy 136.566656 -167.577516)
			(xy 136.596628 -167.577934) (xy 136.656061 -167.585754) (xy 136.713965 -167.601264) (xy 136.769348 -167.6242)
			(xy 136.821264 -167.654169) (xy 136.868823 -167.690658) (xy 136.911213 -167.733044) (xy 136.947707 -167.7806)
			(xy 136.977681 -167.832512) (xy 137.000622 -167.887894) (xy 137.016138 -167.945796) (xy 137.023963 -168.005228)
			(xy 137.023963 -168.065172) (xy 137.016138 -168.124604) (xy 137.000622 -168.182506) (xy 136.977681 -168.237888)
			(xy 136.947707 -168.2898) (xy 136.911213 -168.337356) (xy 136.868823 -168.379742) (xy 136.821264 -168.416231)
			(xy 136.769348 -168.4462) (xy 136.713965 -168.469136) (xy 136.656061 -168.484646) (xy 136.596628 -168.492466)
			(xy 136.566656 -168.492932) (xy 135.703056 -168.492932) (xy 135.673092 -168.492391) (xy 135.613677 -168.484564)
			(xy 135.555791 -168.469049) (xy 135.500426 -168.446111) (xy 135.448529 -168.416143) (xy 135.400986 -168.379658)
			(xy 135.358612 -168.337281) (xy 135.322132 -168.289735) (xy 135.29217 -168.237834) (xy 135.269237 -168.182467)
			(xy 135.253728 -168.12458) (xy 135.245906 -168.065164) (xy 4.30911 -168.065164) (xy 4.30911 -168.700164)
			(xy 133.213906 -168.700164) (xy 133.213906 -168.640236) (xy 133.221728 -168.58082) (xy 133.237237 -168.522933)
			(xy 133.26017 -168.467566) (xy 133.290132 -168.415665) (xy 133.326612 -168.368119) (xy 133.368986 -168.325742)
			(xy 133.416529 -168.289257) (xy 133.468426 -168.259289) (xy 133.523791 -168.236351) (xy 133.581677 -168.220836)
			(xy 133.641092 -168.213009) (xy 133.671056 -168.212516) (xy 134.534656 -168.212516) (xy 134.564628 -168.212934)
			(xy 134.624061 -168.220754) (xy 134.681965 -168.236264) (xy 134.737348 -168.2592) (xy 134.789264 -168.289169)
			(xy 134.836823 -168.325658) (xy 134.879213 -168.368044) (xy 134.915707 -168.4156) (xy 134.945681 -168.467512)
			(xy 134.968622 -168.522894) (xy 134.984138 -168.580796) (xy 134.991963 -168.640228) (xy 134.991963 -168.700172)
			(xy 134.984138 -168.759604) (xy 134.968622 -168.817506) (xy 134.945681 -168.872888) (xy 134.915707 -168.9248)
			(xy 134.879213 -168.972356) (xy 134.836823 -169.014742) (xy 134.789264 -169.051231) (xy 134.737348 -169.0812)
			(xy 134.681965 -169.104136) (xy 134.624061 -169.119646) (xy 134.564628 -169.127466) (xy 134.534656 -169.127932)
			(xy 133.671056 -169.127932) (xy 133.641092 -169.127391) (xy 133.581677 -169.119564) (xy 133.523791 -169.104049)
			(xy 133.468426 -169.081111) (xy 133.416529 -169.051143) (xy 133.368986 -169.014658) (xy 133.326612 -168.972281)
			(xy 133.290132 -168.924735) (xy 133.26017 -168.872834) (xy 133.237237 -168.817467) (xy 133.221728 -168.75958)
			(xy 133.213906 -168.700164) (xy 4.30911 -168.700164) (xy 4.30911 -169.61389) (xy 245.108869 -169.61389)
			(xy 245.108869 -169.55391) (xy 245.116699 -169.494444) (xy 245.132223 -169.436508) (xy 245.155178 -169.381095)
			(xy 245.185169 -169.329152) (xy 245.221684 -169.281569) (xy 245.264097 -169.239158) (xy 245.311684 -169.202648)
			(xy 245.363629 -169.172661) (xy 245.419045 -169.149711) (xy 245.476981 -169.134191) (xy 245.536448 -169.126367)
			(xy 245.566438 -169.1259) (xy 246.430038 -169.1259) (xy 246.460018 -169.126468) (xy 246.519465 -169.134299)
			(xy 246.577381 -169.149822) (xy 246.632776 -169.172772) (xy 246.684702 -169.202755) (xy 246.73227 -169.239259)
			(xy 246.774667 -169.281659) (xy 246.811166 -169.32923) (xy 246.841145 -169.381158) (xy 246.86409 -169.436555)
			(xy 246.879608 -169.494472) (xy 246.887434 -169.55392) (xy 246.887434 -169.61388) (xy 246.879608 -169.673328)
			(xy 246.86409 -169.731245) (xy 246.841145 -169.786642) (xy 246.811166 -169.83857) (xy 246.774667 -169.886141)
			(xy 246.73227 -169.928541) (xy 246.684702 -169.965045) (xy 246.632776 -169.995028) (xy 246.577381 -170.017978)
			(xy 246.519465 -170.033501) (xy 246.460018 -170.041332) (xy 246.430038 -170.041824) (xy 245.566438 -170.041824)
			(xy 245.536448 -170.041433) (xy 245.476981 -170.033609) (xy 245.419045 -170.018089) (xy 245.363629 -169.995139)
			(xy 245.311684 -169.965152) (xy 245.264097 -169.928642) (xy 245.221684 -169.886231) (xy 245.185169 -169.838648)
			(xy 245.155178 -169.786705) (xy 245.132223 -169.731292) (xy 245.116699 -169.673356) (xy 245.108869 -169.61389)
			(xy 4.30911 -169.61389) (xy 4.30911 -174.805086) (xy 141.546072 -174.805086) (xy 141.546072 -173.941486)
			(xy 141.546562 -173.911518) (xy 141.554385 -173.852096) (xy 141.569898 -173.794203) (xy 141.592834 -173.73883)
			(xy 141.622801 -173.686924) (xy 141.659288 -173.639374) (xy 141.701668 -173.596994) (xy 141.749218 -173.560507)
			(xy 141.801124 -173.53054) (xy 141.856497 -173.507604) (xy 141.91439 -173.492091) (xy 141.973812 -173.484268)
			(xy 142.033748 -173.484268) (xy 142.09317 -173.492091) (xy 142.106698 -173.495716) (xy 257.519424 -173.495716)
			(xy 257.519424 -172.632116) (xy 257.519914 -172.602132) (xy 257.527742 -172.542676) (xy 257.543263 -172.484751)
			(xy 257.566212 -172.429347) (xy 257.596196 -172.377413) (xy 257.632702 -172.329837) (xy 257.675107 -172.287432)
			(xy 257.722683 -172.250926) (xy 257.774617 -172.220942) (xy 257.830021 -172.197993) (xy 257.887946 -172.182472)
			(xy 257.947402 -172.174644) (xy 258.00737 -172.174644) (xy 258.066826 -172.182472) (xy 258.124751 -172.197993)
			(xy 258.180155 -172.220942) (xy 258.232089 -172.250926) (xy 258.279665 -172.287432) (xy 258.32207 -172.329837)
			(xy 258.358576 -172.377413) (xy 258.38856 -172.429347) (xy 258.411509 -172.484751) (xy 258.42703 -172.542676)
			(xy 258.434858 -172.602132) (xy 258.435348 -172.632116) (xy 258.435348 -173.495716) (xy 258.434858 -173.5257)
			(xy 258.42703 -173.585156) (xy 258.411509 -173.643081) (xy 258.38856 -173.698485) (xy 258.358576 -173.750419)
			(xy 258.32207 -173.797995) (xy 258.279665 -173.8404) (xy 258.232089 -173.876906) (xy 258.180155 -173.90689)
			(xy 258.124751 -173.929839) (xy 258.066826 -173.94536) (xy 258.00737 -173.953188) (xy 257.947402 -173.953188)
			(xy 257.887946 -173.94536) (xy 257.830021 -173.929839) (xy 257.774617 -173.90689) (xy 257.722683 -173.876906)
			(xy 257.675107 -173.8404) (xy 257.632702 -173.797995) (xy 257.596196 -173.750419) (xy 257.566212 -173.698485)
			(xy 257.543263 -173.643081) (xy 257.527742 -173.585156) (xy 257.519914 -173.5257) (xy 257.519424 -173.495716)
			(xy 142.106698 -173.495716) (xy 142.151063 -173.507604) (xy 142.206436 -173.53054) (xy 142.258342 -173.560507)
			(xy 142.305892 -173.596994) (xy 142.348272 -173.639374) (xy 142.384759 -173.686924) (xy 142.414726 -173.73883)
			(xy 142.437662 -173.794203) (xy 142.453175 -173.852096) (xy 142.460998 -173.911518) (xy 142.461488 -173.941486)
			(xy 142.461488 -174.805086) (xy 142.460998 -174.835054) (xy 142.453175 -174.894476) (xy 142.437662 -174.952369)
			(xy 142.414726 -175.007742) (xy 142.384759 -175.059648) (xy 142.348272 -175.107198) (xy 142.305892 -175.149578)
			(xy 142.258342 -175.186065) (xy 142.206436 -175.216032) (xy 142.151063 -175.238968) (xy 142.09317 -175.254481)
			(xy 142.033748 -175.262304) (xy 141.973812 -175.262304) (xy 141.91439 -175.254481) (xy 141.856497 -175.238968)
			(xy 141.801124 -175.216032) (xy 141.749218 -175.186065) (xy 141.701668 -175.149578) (xy 141.659288 -175.107198)
			(xy 141.622801 -175.059648) (xy 141.592834 -175.007742) (xy 141.569898 -174.952369) (xy 141.554385 -174.894476)
			(xy 141.546562 -174.835054) (xy 141.546072 -174.805086) (xy 4.30911 -174.805086) (xy 4.30911 -176.837086)
			(xy 142.181072 -176.837086) (xy 142.181072 -175.973486) (xy 142.181562 -175.943518) (xy 142.189385 -175.884096)
			(xy 142.204898 -175.826203) (xy 142.227834 -175.77083) (xy 142.257801 -175.718924) (xy 142.294288 -175.671374)
			(xy 142.336668 -175.628994) (xy 142.384218 -175.592507) (xy 142.436124 -175.56254) (xy 142.491497 -175.539604)
			(xy 142.54939 -175.524091) (xy 142.608812 -175.516268) (xy 142.668748 -175.516268) (xy 142.72817 -175.524091)
			(xy 142.786063 -175.539604) (xy 142.841436 -175.56254) (xy 142.893342 -175.592507) (xy 142.940892 -175.628994)
			(xy 142.983272 -175.671374) (xy 143.019759 -175.718924) (xy 143.049726 -175.77083) (xy 143.072662 -175.826203)
			(xy 143.088175 -175.884096) (xy 143.095998 -175.943518) (xy 143.096488 -175.973486) (xy 143.096488 -176.837086)
			(xy 143.095998 -176.867054) (xy 143.088175 -176.926476) (xy 143.072662 -176.984369) (xy 143.049726 -177.039742)
			(xy 143.019759 -177.091648) (xy 142.983272 -177.139198) (xy 142.940892 -177.181578) (xy 142.893342 -177.218065)
			(xy 142.841436 -177.248032) (xy 142.786063 -177.270968) (xy 142.72817 -177.286481) (xy 142.668748 -177.294304)
			(xy 142.608812 -177.294304) (xy 142.54939 -177.286481) (xy 142.491497 -177.270968) (xy 142.436124 -177.248032)
			(xy 142.384218 -177.218065) (xy 142.336668 -177.181578) (xy 142.294288 -177.139198) (xy 142.257801 -177.091648)
			(xy 142.227834 -177.039742) (xy 142.204898 -176.984369) (xy 142.189385 -176.926476) (xy 142.181562 -176.867054)
			(xy 142.181072 -176.837086) (xy 4.30911 -176.837086) (xy 4.30911 -178.995324) (xy 123.198636 -178.995324)
			(xy 123.198636 -178.131724) (xy 123.199126 -178.10174) (xy 123.206954 -178.042284) (xy 123.222475 -177.984359)
			(xy 123.245424 -177.928955) (xy 123.275408 -177.877021) (xy 123.311914 -177.829445) (xy 123.354319 -177.78704)
			(xy 123.401895 -177.750534) (xy 123.453829 -177.72055) (xy 123.509233 -177.697601) (xy 123.567158 -177.68208)
			(xy 123.626614 -177.674252) (xy 123.686582 -177.674252) (xy 123.746038 -177.68208) (xy 123.803963 -177.697601)
			(xy 123.859367 -177.72055) (xy 123.911301 -177.750534) (xy 123.958877 -177.78704) (xy 124.001282 -177.829445)
			(xy 124.037788 -177.877021) (xy 124.067772 -177.928955) (xy 124.090721 -177.984359) (xy 124.106242 -178.042284)
			(xy 124.11407 -178.10174) (xy 124.11456 -178.131724) (xy 124.11456 -178.869086) (xy 141.546072 -178.869086)
			(xy 141.546072 -178.005486) (xy 141.546562 -177.975518) (xy 141.554385 -177.916096) (xy 141.569898 -177.858203)
			(xy 141.592834 -177.80283) (xy 141.622801 -177.750924) (xy 141.659288 -177.703374) (xy 141.701668 -177.660994)
			(xy 141.749218 -177.624507) (xy 141.801124 -177.59454) (xy 141.856497 -177.571604) (xy 141.91439 -177.556091)
			(xy 141.973812 -177.548268) (xy 142.033748 -177.548268) (xy 142.09317 -177.556091) (xy 142.151063 -177.571604)
			(xy 142.206436 -177.59454) (xy 142.258342 -177.624507) (xy 142.305892 -177.660994) (xy 142.348272 -177.703374)
			(xy 142.384759 -177.750924) (xy 142.414726 -177.80283) (xy 142.437662 -177.858203) (xy 142.453175 -177.916096)
			(xy 142.460998 -177.975518) (xy 142.461488 -178.005486) (xy 142.461488 -178.869086) (xy 142.460998 -178.899054)
			(xy 142.453175 -178.958476) (xy 142.437662 -179.016369) (xy 142.414726 -179.071742) (xy 142.384759 -179.123648)
			(xy 142.348272 -179.171198) (xy 142.305892 -179.213578) (xy 142.258342 -179.250065) (xy 142.206436 -179.280032)
			(xy 142.151063 -179.302968) (xy 142.09317 -179.318481) (xy 142.033748 -179.326304) (xy 141.973812 -179.326304)
			(xy 141.91439 -179.318481) (xy 141.856497 -179.302968) (xy 141.801124 -179.280032) (xy 141.749218 -179.250065)
			(xy 141.701668 -179.213578) (xy 141.659288 -179.171198) (xy 141.622801 -179.123648) (xy 141.592834 -179.071742)
			(xy 141.569898 -179.016369) (xy 141.554385 -178.958476) (xy 141.546562 -178.899054) (xy 141.546072 -178.869086)
			(xy 124.11456 -178.869086) (xy 124.11456 -178.995324) (xy 124.11407 -179.025308) (xy 124.106242 -179.084764)
			(xy 124.090721 -179.142689) (xy 124.067772 -179.198093) (xy 124.037788 -179.250027) (xy 124.001282 -179.297603)
			(xy 123.958877 -179.340008) (xy 123.911301 -179.376514) (xy 123.859367 -179.406498) (xy 123.803963 -179.429447)
			(xy 123.746038 -179.444968) (xy 123.686582 -179.452796) (xy 123.626614 -179.452796) (xy 123.567158 -179.444968)
			(xy 123.509233 -179.429447) (xy 123.453829 -179.406498) (xy 123.401895 -179.376514) (xy 123.354319 -179.340008)
			(xy 123.311914 -179.297603) (xy 123.275408 -179.250027) (xy 123.245424 -179.198093) (xy 123.222475 -179.142689)
			(xy 123.206954 -179.084764) (xy 123.199126 -179.025308) (xy 123.198636 -178.995324) (xy 4.30911 -178.995324)
			(xy 4.30911 -180.901086) (xy 142.181072 -180.901086) (xy 142.181072 -180.037486) (xy 142.181562 -180.007518)
			(xy 142.189385 -179.948096) (xy 142.204898 -179.890203) (xy 142.227834 -179.83483) (xy 142.257801 -179.782924)
			(xy 142.294288 -179.735374) (xy 142.336668 -179.692994) (xy 142.384218 -179.656507) (xy 142.436124 -179.62654)
			(xy 142.491497 -179.603604) (xy 142.54939 -179.588091) (xy 142.608812 -179.580268) (xy 142.668748 -179.580268)
			(xy 142.72817 -179.588091) (xy 142.786063 -179.603604) (xy 142.841436 -179.62654) (xy 142.893342 -179.656507)
			(xy 142.940892 -179.692994) (xy 142.983272 -179.735374) (xy 143.019759 -179.782924) (xy 143.049726 -179.83483)
			(xy 143.072662 -179.890203) (xy 143.088175 -179.948096) (xy 143.095998 -180.007518) (xy 143.096488 -180.037486)
			(xy 143.096488 -180.901086) (xy 143.095998 -180.931054) (xy 143.088175 -180.990476) (xy 143.072662 -181.048369)
			(xy 143.049726 -181.103742) (xy 143.019759 -181.155648) (xy 142.983272 -181.203198) (xy 142.940892 -181.245578)
			(xy 142.893342 -181.282065) (xy 142.841436 -181.312032) (xy 142.786063 -181.334968) (xy 142.72817 -181.350481)
			(xy 142.668748 -181.358304) (xy 142.608812 -181.358304) (xy 142.54939 -181.350481) (xy 142.491497 -181.334968)
			(xy 142.436124 -181.312032) (xy 142.384218 -181.282065) (xy 142.336668 -181.245578) (xy 142.294288 -181.203198)
			(xy 142.257801 -181.155648) (xy 142.227834 -181.103742) (xy 142.204898 -181.048369) (xy 142.189385 -180.990476)
			(xy 142.181562 -180.931054) (xy 142.181072 -180.901086) (xy 4.30911 -180.901086) (xy 4.30911 -182.933086)
			(xy 141.546072 -182.933086) (xy 141.546072 -182.069486) (xy 141.546562 -182.039518) (xy 141.554385 -181.980096)
			(xy 141.569898 -181.922203) (xy 141.592834 -181.86683) (xy 141.622801 -181.814924) (xy 141.659288 -181.767374)
			(xy 141.701668 -181.724994) (xy 141.749218 -181.688507) (xy 141.801124 -181.65854) (xy 141.856497 -181.635604)
			(xy 141.91439 -181.620091) (xy 141.973812 -181.612268) (xy 142.033748 -181.612268) (xy 142.09317 -181.620091)
			(xy 142.151063 -181.635604) (xy 142.206436 -181.65854) (xy 142.258342 -181.688507) (xy 142.305892 -181.724994)
			(xy 142.348272 -181.767374) (xy 142.384759 -181.814924) (xy 142.414726 -181.86683) (xy 142.437662 -181.922203)
			(xy 142.453175 -181.980096) (xy 142.460998 -182.039518) (xy 142.461488 -182.069486) (xy 142.461488 -182.933086)
			(xy 142.460998 -182.963054) (xy 142.453175 -183.022476) (xy 142.437662 -183.080369) (xy 142.414726 -183.135742)
			(xy 142.384759 -183.187648) (xy 142.348272 -183.235198) (xy 142.305892 -183.277578) (xy 142.258342 -183.314065)
			(xy 142.206436 -183.344032) (xy 142.151063 -183.366968) (xy 142.09317 -183.382481) (xy 142.033748 -183.390304)
			(xy 141.973812 -183.390304) (xy 141.91439 -183.382481) (xy 141.856497 -183.366968) (xy 141.801124 -183.344032)
			(xy 141.749218 -183.314065) (xy 141.701668 -183.277578) (xy 141.659288 -183.235198) (xy 141.622801 -183.187648)
			(xy 141.592834 -183.135742) (xy 141.569898 -183.080369) (xy 141.554385 -183.022476) (xy 141.546562 -182.963054)
			(xy 141.546072 -182.933086) (xy 4.30911 -182.933086) (xy 4.30911 -187.124582) (xy 135.58115 -187.124582)
			(xy 135.58115 -187.064618) (xy 135.588977 -187.005166) (xy 135.604497 -186.947244) (xy 135.627444 -186.891844)
			(xy 135.657426 -186.839912) (xy 135.69393 -186.792339) (xy 135.736331 -186.749937) (xy 135.783904 -186.713432)
			(xy 135.835835 -186.683448) (xy 135.891235 -186.6605) (xy 135.949156 -186.644979) (xy 136.008608 -186.637151)
			(xy 136.03859 -186.63666) (xy 136.90219 -186.63666) (xy 136.932178 -186.637085) (xy 136.99164 -186.644912)
			(xy 137.049571 -186.660433) (xy 137.104981 -186.683384) (xy 137.156922 -186.713371) (xy 137.204504 -186.749881)
			(xy 137.246913 -186.792289) (xy 137.283424 -186.83987) (xy 137.313412 -186.89181) (xy 137.336363 -186.947219)
			(xy 137.351886 -187.005151) (xy 137.359715 -187.064612) (xy 137.359715 -187.124588) (xy 137.351886 -187.184049)
			(xy 137.336363 -187.241981) (xy 137.313412 -187.29739) (xy 137.283424 -187.34933) (xy 137.246913 -187.396911)
			(xy 137.204504 -187.439319) (xy 137.156922 -187.475829) (xy 137.104981 -187.505816) (xy 137.049571 -187.528767)
			(xy 136.99164 -187.544288) (xy 136.932178 -187.552115) (xy 136.90219 -187.552584) (xy 136.03859 -187.552584)
			(xy 136.008608 -187.552049) (xy 135.949156 -187.544221) (xy 135.891235 -187.5287) (xy 135.835835 -187.505752)
			(xy 135.783904 -187.475768) (xy 135.736331 -187.439263) (xy 135.69393 -187.396861) (xy 135.657426 -187.349288)
			(xy 135.627444 -187.297356) (xy 135.604497 -187.241956) (xy 135.588977 -187.184034) (xy 135.58115 -187.124582)
			(xy 4.30911 -187.124582) (xy 4.30911 -188.252885) (xy 128.656818 -188.252885) (xy 128.656818 -188.192915)
			(xy 128.664646 -188.133459) (xy 128.680167 -188.075533) (xy 128.703116 -188.020128) (xy 128.733101 -187.968193)
			(xy 128.769608 -187.920615) (xy 128.812012 -187.87821) (xy 128.859589 -187.841703) (xy 128.911524 -187.811718)
			(xy 128.966929 -187.788768) (xy 129.024855 -187.773246) (xy 129.084311 -187.765418) (xy 129.114296 -187.764928)
			(xy 129.977896 -187.764928) (xy 130.007881 -187.765417) (xy 130.067339 -187.773244) (xy 130.125266 -187.788765)
			(xy 130.180671 -187.811714) (xy 130.232607 -187.841699) (xy 130.280185 -187.878207) (xy 130.322591 -187.920612)
			(xy 130.359098 -187.96819) (xy 130.389084 -188.020125) (xy 130.412034 -188.075531) (xy 130.427555 -188.133458)
			(xy 130.435383 -188.192915) (xy 130.435383 -188.252885) (xy 130.434185 -188.261981) (xy 131.046262 -188.261981)
			(xy 131.046262 -188.202019) (xy 131.054088 -188.14257) (xy 131.069607 -188.084651) (xy 131.092553 -188.029253)
			(xy 131.122533 -187.977324) (xy 131.159034 -187.929752) (xy 131.201432 -187.887351) (xy 131.249002 -187.850847)
			(xy 131.30093 -187.820864) (xy 131.356326 -187.797915) (xy 131.414244 -187.782393) (xy 131.473693 -187.774564)
			(xy 131.503674 -187.774072) (xy 132.367274 -187.774072) (xy 132.397263 -187.774472) (xy 132.456728 -187.782297)
			(xy 132.514663 -187.797818) (xy 132.570077 -187.820768) (xy 132.62202 -187.850755) (xy 132.669605 -187.887266)
			(xy 132.712017 -187.929675) (xy 132.74853 -187.977258) (xy 132.77852 -188.0292) (xy 132.801474 -188.084612)
			(xy 132.816998 -188.142546) (xy 132.824827 -188.202011) (xy 132.824827 -188.261989) (xy 132.816998 -188.321454)
			(xy 132.801474 -188.379388) (xy 132.79518 -188.394582) (xy 133.54915 -188.394582) (xy 133.54915 -188.334618)
			(xy 133.556977 -188.275166) (xy 133.572497 -188.217244) (xy 133.595444 -188.161844) (xy 133.625426 -188.109912)
			(xy 133.66193 -188.062339) (xy 133.704331 -188.019937) (xy 133.751904 -187.983432) (xy 133.803835 -187.953448)
			(xy 133.859235 -187.9305) (xy 133.917156 -187.914979) (xy 133.976608 -187.907151) (xy 134.00659 -187.90666)
			(xy 134.87019 -187.90666) (xy 134.900178 -187.907085) (xy 134.95964 -187.914912) (xy 135.017571 -187.930433)
			(xy 135.072981 -187.953384) (xy 135.124922 -187.983371) (xy 135.172504 -188.019881) (xy 135.214913 -188.062289)
			(xy 135.251424 -188.10987) (xy 135.281412 -188.16181) (xy 135.304363 -188.217219) (xy 135.319886 -188.275151)
			(xy 135.327715 -188.334612) (xy 135.327715 -188.394588) (xy 135.319886 -188.454049) (xy 135.304363 -188.511981)
			(xy 135.281412 -188.56739) (xy 135.251424 -188.61933) (xy 135.214913 -188.666911) (xy 135.172504 -188.709319)
			(xy 135.124922 -188.745829) (xy 135.072981 -188.775816) (xy 135.017571 -188.798767) (xy 134.95964 -188.814288)
			(xy 134.900178 -188.822115) (xy 134.87019 -188.822584) (xy 134.00659 -188.822584) (xy 133.976608 -188.822049)
			(xy 133.917156 -188.814221) (xy 133.859235 -188.7987) (xy 133.803835 -188.775752) (xy 133.751904 -188.745768)
			(xy 133.704331 -188.709263) (xy 133.66193 -188.666861) (xy 133.625426 -188.619288) (xy 133.595444 -188.567356)
			(xy 133.572497 -188.511956) (xy 133.556977 -188.454034) (xy 133.54915 -188.394582) (xy 132.79518 -188.394582)
			(xy 132.77852 -188.4348) (xy 132.74853 -188.486742) (xy 132.712017 -188.534325) (xy 132.669605 -188.576734)
			(xy 132.62202 -188.613245) (xy 132.570077 -188.643232) (xy 132.514663 -188.666182) (xy 132.456728 -188.681703)
			(xy 132.397263 -188.689528) (xy 132.367274 -188.689996) (xy 131.503674 -188.689996) (xy 131.473693 -188.689436)
			(xy 131.414244 -188.681607) (xy 131.356326 -188.666085) (xy 131.30093 -188.643136) (xy 131.249002 -188.613153)
			(xy 131.201432 -188.576649) (xy 131.159034 -188.534248) (xy 131.122533 -188.486676) (xy 131.092553 -188.434747)
			(xy 131.069607 -188.379349) (xy 131.054088 -188.32143) (xy 131.046262 -188.261981) (xy 130.434185 -188.261981)
			(xy 130.427555 -188.312342) (xy 130.412034 -188.370269) (xy 130.389084 -188.425675) (xy 130.359098 -188.47761)
			(xy 130.322591 -188.525188) (xy 130.280185 -188.567593) (xy 130.232607 -188.604101) (xy 130.180671 -188.634086)
			(xy 130.125266 -188.657035) (xy 130.067339 -188.672556) (xy 130.007881 -188.680383) (xy 129.977896 -188.680852)
			(xy 129.114296 -188.680852) (xy 129.084311 -188.680382) (xy 129.024855 -188.672554) (xy 128.966929 -188.657032)
			(xy 128.911524 -188.634082) (xy 128.859589 -188.604097) (xy 128.812012 -188.56759) (xy 128.769608 -188.525185)
			(xy 128.733101 -188.477607) (xy 128.703116 -188.425672) (xy 128.680167 -188.370267) (xy 128.664646 -188.312341)
			(xy 128.656818 -188.252885) (xy 4.30911 -188.252885) (xy 4.30911 -195.726088) (xy 126.922185 -195.726088)
			(xy 126.922185 -195.666112) (xy 126.930014 -195.606648) (xy 126.945538 -195.548715) (xy 126.968491 -195.493304)
			(xy 126.99848 -195.441364) (xy 127.034993 -195.393782) (xy 127.077404 -195.351373) (xy 127.124989 -195.314864)
			(xy 127.176931 -195.284878) (xy 127.232344 -195.261928) (xy 127.290278 -195.246408) (xy 127.349742 -195.238583)
			(xy 127.37973 -195.238116) (xy 128.24333 -195.238116) (xy 128.273312 -195.238652) (xy 128.332761 -195.246482)
			(xy 128.39068 -195.262005) (xy 128.446078 -195.284955) (xy 128.498007 -195.314939) (xy 128.545577 -195.351444)
			(xy 128.587976 -195.393845) (xy 128.624478 -195.441418) (xy 128.654459 -195.493349) (xy 128.677405 -195.548748)
			(xy 128.692924 -195.606668) (xy 128.70075 -195.666118) (xy 128.70075 -195.726082) (xy 128.692924 -195.785532)
			(xy 128.677405 -195.843452) (xy 128.654459 -195.898851) (xy 128.624478 -195.950782) (xy 128.587976 -195.998355)
			(xy 128.545577 -196.040756) (xy 128.498007 -196.077261) (xy 128.446078 -196.107245) (xy 128.39068 -196.130195)
			(xy 128.332761 -196.145718) (xy 128.273312 -196.153548) (xy 128.24333 -196.15404) (xy 127.37973 -196.15404)
			(xy 127.349742 -196.153617) (xy 127.290278 -196.145792) (xy 127.232344 -196.130272) (xy 127.176931 -196.107322)
			(xy 127.124989 -196.077336) (xy 127.077404 -196.040827) (xy 127.034993 -195.998418) (xy 126.99848 -195.950836)
			(xy 126.968491 -195.898896) (xy 126.945538 -195.843485) (xy 126.930014 -195.785552) (xy 126.922185 -195.726088)
			(xy 4.30911 -195.726088) (xy 4.30911 -198.50608) (xy 100.317808 -198.50608) (xy 100.317808 -197.89648)
			(xy 100.318317 -197.879784) (xy 100.326954 -197.847528) (xy 100.343635 -197.818601) (xy 100.367227 -197.794969)
			(xy 100.396126 -197.778238) (xy 100.428367 -197.769546) (xy 100.445062 -197.768972) (xy 100.970842 -197.768972)
			(xy 100.987574 -197.769445) (xy 101.019898 -197.778106) (xy 101.048884 -197.794828) (xy 101.072564 -197.818474)
			(xy 101.089326 -197.847437) (xy 101.098031 -197.879749) (xy 101.098604 -197.89648) (xy 101.098604 -198.50608)
			(xy 101.098048 -198.522773) (xy 101.09244 -198.543743) (xy 138.243774 -198.543743) (xy 138.24519 -198.489257)
			(xy 138.254343 -198.435528) (xy 138.271047 -198.383647) (xy 138.294963 -198.33467) (xy 138.325603 -198.289594)
			(xy 138.362344 -198.249336) (xy 138.40444 -198.214715) (xy 138.451033 -198.186434) (xy 138.501175 -198.165071)
			(xy 138.553847 -198.151058) (xy 138.607977 -198.144682) (xy 138.635232 -198.144892) (xy 138.636502 -198.144892)
			(xy 139.488672 -198.144892) (xy 139.515926 -198.145353) (xy 139.56988 -198.153107) (xy 139.622181 -198.168461)
			(xy 139.671765 -198.191102) (xy 139.717622 -198.220569) (xy 139.758818 -198.256263) (xy 139.794514 -198.297456)
			(xy 139.823985 -198.34331) (xy 139.846629 -198.392892) (xy 139.861987 -198.445192) (xy 139.869745 -198.499146)
			(xy 139.869745 -198.553654) (xy 139.861987 -198.607608) (xy 139.846629 -198.659908) (xy 139.823985 -198.70949)
			(xy 139.794514 -198.755344) (xy 139.758818 -198.796537) (xy 139.717622 -198.832231) (xy 139.671765 -198.861698)
			(xy 139.622181 -198.884339) (xy 139.56988 -198.899693) (xy 139.515926 -198.907447) (xy 139.488672 -198.907908)
			(xy 139.477343 -198.907862) (xy 139.454723 -198.90659) (xy 139.44346 -198.905368) (xy 139.440412 -198.90486)
			(xy 138.672824 -198.90486) (xy 138.669776 -198.905368) (xy 138.642662 -198.908134) (xy 138.588177 -198.906693)
			(xy 138.534452 -198.897514) (xy 138.482579 -198.880785) (xy 138.433613 -198.856847) (xy 138.388552 -198.826185)
			(xy 138.348311 -198.789424) (xy 138.31371 -198.747312) (xy 138.285452 -198.700706) (xy 138.264112 -198.650554)
			(xy 138.250125 -198.597875) (xy 138.243774 -198.543743) (xy 101.09244 -198.543743) (xy 101.089422 -198.555026)
			(xy 101.07275 -198.583952) (xy 101.049168 -198.607585) (xy 101.020277 -198.624318) (xy 100.988042 -198.633012)
			(xy 100.97135 -198.633588) (xy 100.44557 -198.633588) (xy 100.428844 -198.633045) (xy 100.396529 -198.624392)
			(xy 100.367548 -198.607683) (xy 100.34387 -198.584051) (xy 100.327104 -198.555103) (xy 100.318388 -198.522805)
			(xy 100.317808 -198.50608) (xy 4.30911 -198.50608) (xy 4.30911 -201.379368) (xy 98.428551 -201.379368)
			(xy 98.428551 -201.324832) (xy 98.436313 -201.270851) (xy 98.451678 -201.218525) (xy 98.474333 -201.168917)
			(xy 98.503818 -201.123039) (xy 98.539531 -201.081824) (xy 98.580747 -201.046112) (xy 98.626626 -201.016628)
			(xy 98.676234 -200.993974) (xy 98.728561 -200.978611) (xy 98.782542 -200.970851) (xy 98.80981 -200.970388)
			(xy 99.67341 -200.970388) (xy 99.700682 -200.970775) (xy 99.754672 -200.978539) (xy 99.807007 -200.993907)
			(xy 99.856623 -201.016567) (xy 99.902508 -201.046057) (xy 99.94373 -201.081777) (xy 99.979449 -201.123)
			(xy 99.980782 -201.125074) (xy 138.664696 -201.125074) (xy 138.664696 -199.854058) (xy 138.665191 -199.843934)
			(xy 138.672924 -199.82522) (xy 138.687207 -199.810867) (xy 138.705883 -199.803042) (xy 138.716004 -199.802496)
			(xy 139.395708 -199.802496) (xy 139.405862 -199.802915) (xy 139.424614 -199.810713) (xy 139.438937 -199.82511)
			(xy 139.446637 -199.843902) (xy 139.447016 -199.854058) (xy 139.447016 -201.125074) (xy 139.446551 -201.135204)
			(xy 139.438824 -201.153933) (xy 139.42453 -201.168292) (xy 139.405836 -201.176105) (xy 139.395708 -201.176636)
			(xy 138.716004 -201.176636) (xy 138.705855 -201.176176) (xy 138.687109 -201.168388) (xy 138.672787 -201.154004)
			(xy 138.665081 -201.135225) (xy 138.664696 -201.125074) (xy 99.980782 -201.125074) (xy 100.008938 -201.168886)
			(xy 100.031596 -201.218502) (xy 100.046963 -201.270838) (xy 100.054725 -201.324828) (xy 100.054725 -201.379372)
			(xy 100.046963 -201.433362) (xy 100.031596 -201.485698) (xy 100.008938 -201.535314) (xy 99.979449 -201.5812)
			(xy 99.94373 -201.622423) (xy 99.902508 -201.658143) (xy 99.856623 -201.687633) (xy 99.807007 -201.710293)
			(xy 99.754672 -201.725661) (xy 99.700682 -201.733425) (xy 99.67341 -201.733912) (xy 98.80981 -201.733912)
			(xy 98.782542 -201.733349) (xy 98.728561 -201.725589) (xy 98.676234 -201.710226) (xy 98.626626 -201.687572)
			(xy 98.580747 -201.658088) (xy 98.539531 -201.622376) (xy 98.503818 -201.581161) (xy 98.474333 -201.535283)
			(xy 98.451678 -201.485675) (xy 98.436313 -201.433349) (xy 98.428551 -201.379368) (xy 4.30911 -201.379368)
			(xy 4.30911 -209.380836) (xy 445.288416 -209.380836) (xy 445.288416 -208.517236) (xy 445.288906 -208.487268)
			(xy 445.296729 -208.427846) (xy 445.312242 -208.369953) (xy 445.335178 -208.31458) (xy 445.365145 -208.262674)
			(xy 445.401632 -208.215124) (xy 445.444012 -208.172744) (xy 445.491562 -208.136257) (xy 445.543468 -208.10629)
			(xy 445.598841 -208.083354) (xy 445.656734 -208.067841) (xy 445.716156 -208.060018) (xy 445.776092 -208.060018)
			(xy 445.835514 -208.067841) (xy 445.893407 -208.083354) (xy 445.94878 -208.10629) (xy 446.000686 -208.136257)
			(xy 446.048236 -208.172744) (xy 446.090616 -208.215124) (xy 446.127103 -208.262674) (xy 446.15707 -208.31458)
			(xy 446.180006 -208.369953) (xy 446.195519 -208.427846) (xy 446.203342 -208.487268) (xy 446.203832 -208.517236)
			(xy 446.203832 -208.705958) (xy 447.047112 -208.705958) (xy 447.047112 -208.303622) (xy 447.047644 -208.2935)
			(xy 447.055359 -208.274785) (xy 447.069631 -208.260429) (xy 447.088301 -208.252604) (xy 447.09842 -208.25206)
			(xy 447.505074 -208.25206) (xy 447.515247 -208.252486) (xy 447.534045 -208.260266) (xy 447.548431 -208.274652)
			(xy 447.556213 -208.293449) (xy 447.556636 -208.303622) (xy 447.556636 -208.704942) (xy 447.79692 -208.704942)
			(xy 447.79692 -208.302606) (xy 447.797438 -208.292451) (xy 447.805207 -208.273685) (xy 447.819565 -208.25932)
			(xy 447.838327 -208.251543) (xy 447.848482 -208.251044) (xy 448.255136 -208.251044) (xy 448.265285 -208.251491)
			(xy 448.268485 -208.252822) (xy 452.695564 -208.252822) (xy 452.695564 -207.643984) (xy 452.696071 -207.633879)
			(xy 452.703808 -207.615207) (xy 452.718097 -207.600914) (xy 452.736767 -207.593174) (xy 452.746872 -207.592676)
			(xy 453.25411 -207.592676) (xy 453.264242 -207.59312) (xy 453.28297 -207.600857) (xy 453.297327 -207.615157)
			(xy 453.305139 -207.633854) (xy 453.305672 -207.643984) (xy 453.305672 -208.252822) (xy 453.305185 -208.26298)
			(xy 453.297405 -208.281748) (xy 453.283038 -208.296112) (xy 453.264268 -208.303887) (xy 453.25411 -208.304384)
			(xy 452.746872 -208.304384) (xy 452.736714 -208.304001) (xy 452.717958 -208.296193) (xy 452.703635 -208.281785)
			(xy 452.695939 -208.262982) (xy 452.695564 -208.252822) (xy 448.268485 -208.252822) (xy 448.284028 -208.259288)
			(xy 448.298348 -208.273676) (xy 448.306056 -208.292455) (xy 448.306444 -208.302606) (xy 448.306444 -208.704942)
			(xy 448.306007 -208.715073) (xy 448.298263 -208.733799) (xy 448.283961 -208.748154) (xy 448.265265 -208.755969)
			(xy 448.255136 -208.756504) (xy 447.848482 -208.756504) (xy 447.838328 -208.755983) (xy 447.819567 -208.74821)
			(xy 447.805203 -208.733854) (xy 447.797422 -208.715096) (xy 447.79692 -208.704942) (xy 447.556636 -208.704942)
			(xy 447.556636 -208.705958) (xy 447.556201 -208.71613) (xy 447.548425 -208.734929) (xy 447.534042 -208.749316)
			(xy 447.515246 -208.757098) (xy 447.505074 -208.75752) (xy 447.09842 -208.75752) (xy 447.08827 -208.757063)
			(xy 447.069521 -208.749277) (xy 447.055198 -208.734892) (xy 447.047494 -208.71611) (xy 447.047112 -208.705958)
			(xy 446.203832 -208.705958) (xy 446.203832 -209.380836) (xy 446.203342 -209.410804) (xy 446.195519 -209.470226)
			(xy 446.180006 -209.528119) (xy 446.15707 -209.583492) (xy 446.15045 -209.594958) (xy 447.047112 -209.594958)
			(xy 447.047112 -209.192622) (xy 447.047644 -209.1825) (xy 447.055359 -209.163785) (xy 447.069631 -209.149429)
			(xy 447.088301 -209.141604) (xy 447.09842 -209.14106) (xy 447.505074 -209.14106) (xy 447.515247 -209.141486)
			(xy 447.534045 -209.149266) (xy 447.548431 -209.163652) (xy 447.556213 -209.182449) (xy 447.556636 -209.192622)
			(xy 447.556636 -209.593942) (xy 447.79692 -209.593942) (xy 447.79692 -209.191606) (xy 447.797438 -209.181451)
			(xy 447.805207 -209.162685) (xy 447.819565 -209.14832) (xy 447.838327 -209.140543) (xy 447.848482 -209.140044)
			(xy 448.255136 -209.140044) (xy 448.265285 -209.140491) (xy 448.284028 -209.148288) (xy 448.298348 -209.162676)
			(xy 448.306056 -209.181455) (xy 448.306444 -209.191606) (xy 448.306444 -209.439764) (xy 455.544936 -209.439764)
			(xy 455.544936 -208.454752) (xy 455.545347 -208.444636) (xy 455.553107 -208.42595) (xy 455.567427 -208.411655)
			(xy 455.586127 -208.403929) (xy 455.596244 -208.403444) (xy 456.99426 -208.403444) (xy 457.004359 -208.404017)
			(xy 457.023026 -208.411731) (xy 457.03732 -208.426) (xy 457.045066 -208.444654) (xy 457.045568 -208.454752)
			(xy 457.045568 -209.439764) (xy 457.045154 -209.449888) (xy 457.037411 -209.468597) (xy 457.023094 -209.482914)
			(xy 457.004384 -209.490654) (xy 456.99426 -209.491072) (xy 455.596244 -209.491072) (xy 455.586121 -209.490647)
			(xy 455.567413 -209.482908) (xy 455.553096 -209.468594) (xy 455.545354 -209.449887) (xy 455.544936 -209.439764)
			(xy 448.306444 -209.439764) (xy 448.306444 -209.593942) (xy 448.306007 -209.604073) (xy 448.298263 -209.622799)
			(xy 448.283961 -209.637154) (xy 448.265265 -209.644969) (xy 448.255136 -209.645504) (xy 447.848482 -209.645504)
			(xy 447.838328 -209.644983) (xy 447.819567 -209.63721) (xy 447.805203 -209.622854) (xy 447.797422 -209.604096)
			(xy 447.79692 -209.593942) (xy 447.556636 -209.593942) (xy 447.556636 -209.594958) (xy 447.556201 -209.60513)
			(xy 447.548425 -209.623929) (xy 447.534042 -209.638316) (xy 447.515246 -209.646098) (xy 447.505074 -209.64652)
			(xy 447.09842 -209.64652) (xy 447.08827 -209.646063) (xy 447.069521 -209.638277) (xy 447.055198 -209.623892)
			(xy 447.047494 -209.60511) (xy 447.047112 -209.594958) (xy 446.15045 -209.594958) (xy 446.127103 -209.635398)
			(xy 446.090616 -209.682948) (xy 446.048236 -209.725328) (xy 446.000686 -209.761815) (xy 445.94878 -209.791782)
			(xy 445.893407 -209.814718) (xy 445.835514 -209.830231) (xy 445.776092 -209.838054) (xy 445.716156 -209.838054)
			(xy 445.656734 -209.830231) (xy 445.598841 -209.814718) (xy 445.543468 -209.791782) (xy 445.491562 -209.761815)
			(xy 445.444012 -209.725328) (xy 445.401632 -209.682948) (xy 445.365145 -209.635398) (xy 445.335178 -209.583492)
			(xy 445.312242 -209.528119) (xy 445.296729 -209.470226) (xy 445.288906 -209.410804) (xy 445.288416 -209.380836)
			(xy 4.30911 -209.380836) (xy 4.30911 -210.259422) (xy 452.684896 -210.259422) (xy 452.684896 -209.705194)
			(xy 452.68542 -209.695072) (xy 452.693142 -209.676359) (xy 452.707416 -209.662005) (xy 452.726085 -209.654178)
			(xy 452.736204 -209.653632) (xy 453.265794 -209.653632) (xy 453.275951 -209.654138) (xy 453.294719 -209.661909)
			(xy 453.309084 -209.676271) (xy 453.316859 -209.695037) (xy 453.317356 -209.705194) (xy 453.317356 -210.259422)
			(xy 453.316885 -210.269582) (xy 453.309102 -210.288353) (xy 453.294729 -210.302718) (xy 453.275954 -210.31049)
			(xy 453.265794 -210.310984) (xy 452.736204 -210.310984) (xy 452.726048 -210.310575) (xy 452.707293 -210.302778)
			(xy 452.692969 -210.288377) (xy 452.685272 -210.26958) (xy 452.684896 -210.259422) (xy 4.30911 -210.259422)
			(xy 4.30911 -225.261473) (xy 239.822113 -225.261473) (xy 239.822113 -225.201527) (xy 239.829938 -225.142093)
			(xy 239.845454 -225.084189) (xy 239.868395 -225.028806) (xy 239.89837 -224.976891) (xy 239.934864 -224.929333)
			(xy 239.977254 -224.886945) (xy 240.024814 -224.850454) (xy 240.076731 -224.820483) (xy 240.132115 -224.797545)
			(xy 240.19002 -224.782032) (xy 240.249455 -224.774211) (xy 240.279428 -224.773744) (xy 241.143028 -224.773744)
			(xy 241.172991 -224.774332) (xy 241.232405 -224.782157) (xy 241.290289 -224.79767) (xy 241.345653 -224.820606)
			(xy 241.39755 -224.850571) (xy 241.445091 -224.887054) (xy 241.487465 -224.92943) (xy 241.523944 -224.976974)
			(xy 241.553907 -225.028872) (xy 241.576839 -225.084238) (xy 241.592348 -225.142123) (xy 241.60017 -225.201537)
			(xy 241.60017 -225.261463) (xy 241.592348 -225.320877) (xy 241.576839 -225.378762) (xy 241.553907 -225.434128)
			(xy 241.523944 -225.486026) (xy 241.487465 -225.53357) (xy 241.445091 -225.575946) (xy 241.39755 -225.612429)
			(xy 241.345653 -225.642394) (xy 241.290289 -225.66533) (xy 241.232405 -225.680843) (xy 241.172991 -225.688668)
			(xy 241.143028 -225.68916) (xy 240.279428 -225.68916) (xy 240.249455 -225.688789) (xy 240.19002 -225.680968)
			(xy 240.132115 -225.665455) (xy 240.076731 -225.642517) (xy 240.024814 -225.612546) (xy 239.977254 -225.576055)
			(xy 239.934864 -225.533667) (xy 239.89837 -225.486109) (xy 239.868395 -225.434194) (xy 239.845454 -225.378811)
			(xy 239.829938 -225.320907) (xy 239.822113 -225.261473) (xy 4.30911 -225.261473) (xy 4.30911 -228.77272)
			(xy 240.509552 -228.77272) (xy 240.509552 -228.370384) (xy 240.510071 -228.36028) (xy 240.517805 -228.341611)
			(xy 240.532091 -228.327318) (xy 240.550756 -228.319576) (xy 240.56086 -228.319076) (xy 240.967514 -228.319076)
			(xy 240.977646 -228.319516) (xy 240.996374 -228.327255) (xy 241.010731 -228.341556) (xy 241.018543 -228.360254)
			(xy 241.019076 -228.370384) (xy 241.019076 -228.77272) (xy 241.019038 -228.773736) (xy 241.575336 -228.773736)
			(xy 241.575336 -228.3714) (xy 241.575722 -228.361241) (xy 241.583525 -228.342482) (xy 241.597933 -228.328157)
			(xy 241.616737 -228.320464) (xy 241.626898 -228.320092) (xy 242.033552 -228.320092) (xy 242.04367 -228.320555)
			(xy 242.062371 -228.328286) (xy 242.076687 -228.342588) (xy 242.084435 -228.361282) (xy 242.08486 -228.3714)
			(xy 242.08486 -228.773736) (xy 242.084513 -228.783866) (xy 242.076745 -228.802578) (xy 242.062407 -228.816892)
			(xy 242.043682 -228.824629) (xy 242.033552 -228.825044) (xy 241.626898 -228.825044) (xy 241.616769 -228.824574)
			(xy 241.598045 -228.816843) (xy 241.583688 -228.802551) (xy 241.575872 -228.783862) (xy 241.575336 -228.773736)
			(xy 241.019038 -228.773736) (xy 241.018694 -228.782878) (xy 241.010888 -228.801636) (xy 240.996479 -228.81596)
			(xy 240.977675 -228.823654) (xy 240.967514 -228.824028) (xy 240.56086 -228.824028) (xy 240.550752 -228.823548)
			(xy 240.532078 -228.815803) (xy 240.517786 -228.801505) (xy 240.510048 -228.782828) (xy 240.509552 -228.77272)
			(xy 4.30911 -228.77272) (xy 4.30911 -230.903589) (xy 383.216061 -230.903589) (xy 383.216061 -230.843611)
			(xy 383.22389 -230.784147) (xy 383.239413 -230.726213) (xy 383.262366 -230.670801) (xy 383.292355 -230.618858)
			(xy 383.328867 -230.571275) (xy 383.371278 -230.528865) (xy 383.418862 -230.492353) (xy 383.470804 -230.462364)
			(xy 383.526216 -230.439412) (xy 383.584151 -230.423889) (xy 383.643615 -230.416061) (xy 383.673604 -230.415592)
			(xy 384.537204 -230.415592) (xy 384.567185 -230.416174) (xy 384.626634 -230.424001) (xy 384.684553 -230.439521)
			(xy 384.739951 -230.462468) (xy 384.79188 -230.492449) (xy 384.839451 -230.528952) (xy 384.88185 -230.571352)
			(xy 384.918353 -230.618924) (xy 384.948334 -230.670853) (xy 384.97128 -230.726251) (xy 384.986799 -230.78417)
			(xy 384.994626 -230.843619) (xy 384.994626 -230.903581) (xy 384.986799 -230.96303) (xy 384.97128 -231.020949)
			(xy 384.948334 -231.076347) (xy 384.918353 -231.128276) (xy 384.88185 -231.175848) (xy 384.839451 -231.218248)
			(xy 384.79188 -231.254751) (xy 384.739951 -231.284732) (xy 384.684553 -231.307679) (xy 384.626634 -231.323199)
			(xy 384.567185 -231.331026) (xy 384.537204 -231.331516) (xy 383.673604 -231.331516) (xy 383.643615 -231.331139)
			(xy 383.584151 -231.323311) (xy 383.526216 -231.307788) (xy 383.470804 -231.284836) (xy 383.418862 -231.254847)
			(xy 383.371278 -231.218335) (xy 383.328867 -231.175925) (xy 383.292355 -231.128342) (xy 383.262366 -231.076399)
			(xy 383.239413 -231.020987) (xy 383.22389 -230.963053) (xy 383.216061 -230.903589) (xy 4.30911 -230.903589)
			(xy 4.30911 -233.48188) (xy 383.712212 -233.48188) (xy 383.712212 -232.200958) (xy 383.712698 -232.190801)
			(xy 383.720482 -232.172036) (xy 383.734849 -232.157673) (xy 383.753617 -232.149895) (xy 383.763774 -232.149396)
			(xy 384.44424 -232.149396) (xy 384.454396 -232.149789) (xy 384.473149 -232.157597) (xy 384.48747 -232.172002)
			(xy 384.4934 -232.18648) (xy 448.983608 -232.18648) (xy 448.983608 -231.57688) (xy 448.984117 -231.560184)
			(xy 448.992754 -231.527928) (xy 449.009435 -231.499001) (xy 449.033027 -231.475369) (xy 449.061926 -231.458638)
			(xy 449.094167 -231.449946) (xy 449.110862 -231.449372) (xy 449.636642 -231.449372) (xy 449.653374 -231.449845)
			(xy 449.685698 -231.458506) (xy 449.714684 -231.475228) (xy 449.738364 -231.498874) (xy 449.755126 -231.527837)
			(xy 449.763831 -231.560149) (xy 449.764404 -231.57688) (xy 449.764404 -232.18648) (xy 449.763848 -232.203173)
			(xy 449.755222 -232.235426) (xy 449.73855 -232.264352) (xy 449.714968 -232.287985) (xy 449.686077 -232.304718)
			(xy 449.653842 -232.313412) (xy 449.63715 -232.313988) (xy 449.11137 -232.313988) (xy 449.094644 -232.313445)
			(xy 449.062329 -232.304792) (xy 449.033348 -232.288083) (xy 449.00967 -232.264451) (xy 448.992904 -232.235503)
			(xy 448.984188 -232.203205) (xy 448.983608 -232.18648) (xy 384.4934 -232.18648) (xy 384.495169 -232.190799)
			(xy 384.495548 -232.200958) (xy 384.495548 -233.48188) (xy 384.495 -233.491982) (xy 384.487278 -233.51065)
			(xy 384.473001 -233.524944) (xy 384.454341 -233.532688) (xy 384.44424 -233.533188) (xy 383.763774 -233.533188)
			(xy 383.753649 -233.532696) (xy 383.734933 -233.524965) (xy 383.720578 -233.510681) (xy 383.712755 -233.492002)
			(xy 383.712212 -233.48188) (xy 4.30911 -233.48188) (xy 4.30911 -234.655869) (xy 448.021157 -234.655869)
			(xy 448.021157 -234.595931) (xy 448.028981 -234.536505) (xy 448.044494 -234.478608) (xy 448.067432 -234.423232)
			(xy 448.097401 -234.371324) (xy 448.13389 -234.323771) (xy 448.176273 -234.281388) (xy 448.223825 -234.2449)
			(xy 448.275734 -234.214931) (xy 448.33111 -234.191993) (xy 448.389007 -234.17648) (xy 448.448433 -234.168657)
			(xy 448.478402 -234.168188) (xy 449.342002 -234.168188) (xy 449.371969 -234.168686) (xy 449.431391 -234.176509)
			(xy 449.489283 -234.192022) (xy 449.544656 -234.214958) (xy 449.596561 -234.244925) (xy 449.64411 -234.281411)
			(xy 449.68649 -234.323792) (xy 449.722976 -234.371341) (xy 449.752943 -234.423246) (xy 449.775879 -234.478618)
			(xy 449.791391 -234.536511) (xy 449.799214 -234.595933) (xy 449.799214 -234.655867) (xy 449.791391 -234.715289)
			(xy 449.775879 -234.773182) (xy 449.752943 -234.828554) (xy 449.722976 -234.880459) (xy 449.68649 -234.928008)
			(xy 449.64411 -234.970389) (xy 449.596561 -235.006875) (xy 449.544656 -235.036842) (xy 449.489283 -235.059778)
			(xy 449.431391 -235.075291) (xy 449.371969 -235.083114) (xy 449.342002 -235.083604) (xy 448.478402 -235.083604)
			(xy 448.448433 -235.083143) (xy 448.389007 -235.07532) (xy 448.33111 -235.059807) (xy 448.275734 -235.036869)
			(xy 448.223825 -235.0069) (xy 448.176273 -234.970412) (xy 448.13389 -234.928029) (xy 448.097401 -234.880476)
			(xy 448.067432 -234.828568) (xy 448.044494 -234.773192) (xy 448.028981 -234.715295) (xy 448.021157 -234.655869)
			(xy 4.30911 -234.655869) (xy 4.30911 -239.07907) (xy 153.398934 -239.07907) (xy 153.398934 -239.01913)
			(xy 153.406758 -238.959703) (xy 153.422271 -238.901805) (xy 153.445208 -238.846427) (xy 153.475178 -238.794517)
			(xy 153.511666 -238.746963) (xy 153.554049 -238.704578) (xy 153.601602 -238.668088) (xy 153.653511 -238.638116)
			(xy 153.708888 -238.615177) (xy 153.766785 -238.599661) (xy 153.826212 -238.591835) (xy 153.856182 -238.591344)
			(xy 154.719782 -238.591344) (xy 154.749749 -238.591908) (xy 154.809169 -238.599729) (xy 154.867061 -238.615239)
			(xy 154.922433 -238.638172) (xy 154.974337 -238.668138) (xy 155.021886 -238.704622) (xy 155.064267 -238.747)
			(xy 155.100752 -238.794548) (xy 155.13072 -238.846451) (xy 155.153656 -238.901822) (xy 155.169168 -238.959713)
			(xy 155.176991 -239.019133) (xy 155.176991 -239.079067) (xy 155.169168 -239.138487) (xy 155.153656 -239.196378)
			(xy 155.13072 -239.251749) (xy 155.100752 -239.303652) (xy 155.064267 -239.3512) (xy 155.021886 -239.393578)
			(xy 154.974337 -239.430062) (xy 154.922433 -239.460028) (xy 154.867061 -239.482961) (xy 154.809169 -239.498471)
			(xy 154.749749 -239.506292) (xy 154.719782 -239.50676) (xy 153.856182 -239.50676) (xy 153.826212 -239.506365)
			(xy 153.766785 -239.498539) (xy 153.708888 -239.483023) (xy 153.653511 -239.460084) (xy 153.601602 -239.430112)
			(xy 153.554049 -239.393622) (xy 153.511666 -239.351237) (xy 153.475178 -239.303683) (xy 153.445208 -239.251773)
			(xy 153.422271 -239.196395) (xy 153.406758 -239.138497) (xy 153.398934 -239.07907) (xy 4.30911 -239.07907)
			(xy 4.30911 -241.031522) (xy 4.308609 -241.101909) (xy 4.300702 -241.24246) (xy 4.284927 -241.382347)
			(xy 4.261334 -241.521129) (xy 4.229996 -241.65837) (xy 4.191013 -241.793638) (xy 4.144506 -241.926507)
			(xy 4.090623 -242.05656) (xy 4.029533 -242.183387) (xy 3.961428 -242.30659) (xy 3.886522 -242.42578)
			(xy 3.805051 -242.540582) (xy 3.717272 -242.650636) (xy 3.623459 -242.755596) (xy 3.574034 -242.805712)
			(xy 0.945642 -245.434104) (xy 0.908331 -245.472065) (xy 0.838615 -245.55251) (xy 0.774816 -245.637725)
			(xy 0.717261 -245.727274) (xy 0.666242 -245.820703) (xy 0.62202 -245.917533) (xy 0.584819 -246.017272)
			(xy 0.554831 -246.119412) (xy 0.532207 -246.22343) (xy 0.517063 -246.328799) (xy 0.509476 -246.434979)
			(xy 0.509016 -246.488204) (xy 0.509016 -270.89989) (xy 26.882353 -270.89989) (xy 26.886342 -270.75135)
			(xy 26.898299 -270.603237) (xy 26.918189 -270.45598) (xy 26.945954 -270.310004) (xy 26.981515 -270.165727)
			(xy 27.024769 -270.023568) (xy 27.075591 -269.883935) (xy 27.133835 -269.747232) (xy 27.199333 -269.613852)
			(xy 27.271896 -269.48418) (xy 27.351314 -269.35859) (xy 27.437359 -269.237443) (xy 27.529783 -269.12109)
			(xy 27.628319 -269.009866) (xy 27.732683 -268.904091) (xy 27.842575 -268.804071) (xy 27.957676 -268.710093)
			(xy 28.077656 -268.622429) (xy 28.202169 -268.541332) (xy 28.330855 -268.467035) (xy 28.463344 -268.399753)
			(xy 28.599253 -268.339679) (xy 28.738191 -268.286987) (xy 28.879757 -268.241828) (xy 29.023543 -268.204333)
			(xy 29.169134 -268.174611) (xy 29.31611 -268.152746) (xy 29.464049 -268.138802) (xy 29.612522 -268.132818)
			(xy 29.761103 -268.134813) (xy 29.909362 -268.144781) (xy 30.056873 -268.162692) (xy 30.203209 -268.188495)
			(xy 30.34795 -268.222115) (xy 30.490677 -268.263457) (xy 30.63098 -268.3124) (xy 30.768453 -268.368803)
			(xy 30.9027 -268.432504) (xy 31.033335 -268.50332) (xy 31.15998 -268.581045) (xy 31.28227 -268.665456)
			(xy 31.399853 -268.756309) (xy 31.51239 -268.853343) (xy 31.619557 -268.956278) (xy 31.721044 -269.064817)
			(xy 31.816558 -269.178646) (xy 31.905825 -269.297439) (xy 31.988586 -269.420851) (xy 32.064604 -269.548529)
			(xy 32.133659 -269.680102) (xy 32.195552 -269.815193) (xy 32.250105 -269.95341) (xy 32.29716 -270.094357)
			(xy 32.336582 -270.237627) (xy 32.368256 -270.382806) (xy 32.392092 -270.529475) (xy 32.408021 -270.677213)
			(xy 32.415997 -270.825593) (xy 32.416496 -270.89989) (xy 86.882487 -270.89989) (xy 86.886476 -270.75135)
			(xy 86.898433 -270.603237) (xy 86.918323 -270.45598) (xy 86.946088 -270.310004) (xy 86.981649 -270.165727)
			(xy 87.024903 -270.023568) (xy 87.075725 -269.883935) (xy 87.133969 -269.747232) (xy 87.199467 -269.613852)
			(xy 87.27203 -269.48418) (xy 87.351448 -269.35859) (xy 87.437493 -269.237443) (xy 87.529917 -269.12109)
			(xy 87.628453 -269.009866) (xy 87.732817 -268.904091) (xy 87.842709 -268.804071) (xy 87.95781 -268.710093)
			(xy 88.07779 -268.622429) (xy 88.202303 -268.541332) (xy 88.330989 -268.467035) (xy 88.463478 -268.399753)
			(xy 88.599387 -268.339679) (xy 88.738325 -268.286987) (xy 88.879891 -268.241828) (xy 89.023677 -268.204333)
			(xy 89.169268 -268.174611) (xy 89.316244 -268.152746) (xy 89.464183 -268.138802) (xy 89.612656 -268.132818)
			(xy 89.761237 -268.134813) (xy 89.909496 -268.144781) (xy 90.057007 -268.162692) (xy 90.203343 -268.188495)
			(xy 90.348084 -268.222115) (xy 90.490811 -268.263457) (xy 90.631114 -268.3124) (xy 90.768587 -268.368803)
			(xy 90.902834 -268.432504) (xy 91.033469 -268.50332) (xy 91.160114 -268.581045) (xy 91.282404 -268.665456)
			(xy 91.399987 -268.756309) (xy 91.512524 -268.853343) (xy 91.619691 -268.956278) (xy 91.721178 -269.064817)
			(xy 91.816692 -269.178646) (xy 91.905959 -269.297439) (xy 91.98872 -269.420851) (xy 92.064738 -269.548529)
			(xy 92.133793 -269.680102) (xy 92.195686 -269.815193) (xy 92.250239 -269.95341) (xy 92.297294 -270.094357)
			(xy 92.336716 -270.237627) (xy 92.36839 -270.382806) (xy 92.392226 -270.529475) (xy 92.408155 -270.677213)
			(xy 92.416131 -270.825593) (xy 92.41663 -270.89989) (xy 142.982451 -270.89989) (xy 142.98644 -270.75135)
			(xy 142.998397 -270.603237) (xy 143.018287 -270.45598) (xy 143.046052 -270.310004) (xy 143.081613 -270.165727)
			(xy 143.124867 -270.023568) (xy 143.175689 -269.883935) (xy 143.233933 -269.747232) (xy 143.299431 -269.613852)
			(xy 143.371994 -269.48418) (xy 143.451412 -269.35859) (xy 143.537457 -269.237443) (xy 143.629881 -269.12109)
			(xy 143.728417 -269.009866) (xy 143.832781 -268.904091) (xy 143.942673 -268.804071) (xy 144.057774 -268.710093)
			(xy 144.177754 -268.622429) (xy 144.302267 -268.541332) (xy 144.430953 -268.467035) (xy 144.563442 -268.399753)
			(xy 144.699351 -268.339679) (xy 144.838289 -268.286987) (xy 144.979855 -268.241828) (xy 145.123641 -268.204333)
			(xy 145.269232 -268.174611) (xy 145.416208 -268.152746) (xy 145.564147 -268.138802) (xy 145.71262 -268.132818)
			(xy 145.861201 -268.134813) (xy 146.00946 -268.144781) (xy 146.156971 -268.162692) (xy 146.303307 -268.188495)
			(xy 146.448048 -268.222115) (xy 146.590775 -268.263457) (xy 146.731078 -268.3124) (xy 146.868551 -268.368803)
			(xy 147.002798 -268.432504) (xy 147.133433 -268.50332) (xy 147.260078 -268.581045) (xy 147.382368 -268.665456)
			(xy 147.499951 -268.756309) (xy 147.612488 -268.853343) (xy 147.719655 -268.956278) (xy 147.821142 -269.064817)
			(xy 147.916656 -269.178646) (xy 148.005923 -269.297439) (xy 148.088684 -269.420851) (xy 148.164702 -269.548529)
			(xy 148.233757 -269.680102) (xy 148.29565 -269.815193) (xy 148.350203 -269.95341) (xy 148.397258 -270.094357)
			(xy 148.43668 -270.237627) (xy 148.468354 -270.382806) (xy 148.49219 -270.529475) (xy 148.508119 -270.677213)
			(xy 148.516095 -270.825593) (xy 148.516594 -270.89989) (xy 202.982331 -270.89989) (xy 202.98632 -270.75135)
			(xy 202.998277 -270.603237) (xy 203.018167 -270.45598) (xy 203.045932 -270.310004) (xy 203.081493 -270.165727)
			(xy 203.124747 -270.023568) (xy 203.175569 -269.883935) (xy 203.233813 -269.747232) (xy 203.299311 -269.613852)
			(xy 203.371874 -269.48418) (xy 203.451292 -269.35859) (xy 203.537337 -269.237443) (xy 203.629761 -269.12109)
			(xy 203.728297 -269.009866) (xy 203.832661 -268.904091) (xy 203.942553 -268.804071) (xy 204.057654 -268.710093)
			(xy 204.177634 -268.622429) (xy 204.302147 -268.541332) (xy 204.430833 -268.467035) (xy 204.563322 -268.399753)
			(xy 204.699231 -268.339679) (xy 204.838169 -268.286987) (xy 204.979735 -268.241828) (xy 205.123521 -268.204333)
			(xy 205.269112 -268.174611) (xy 205.416088 -268.152746) (xy 205.564027 -268.138802) (xy 205.7125 -268.132818)
			(xy 205.861081 -268.134813) (xy 206.00934 -268.144781) (xy 206.156851 -268.162692) (xy 206.303187 -268.188495)
			(xy 206.447928 -268.222115) (xy 206.590655 -268.263457) (xy 206.730958 -268.3124) (xy 206.868431 -268.368803)
			(xy 207.002678 -268.432504) (xy 207.133313 -268.50332) (xy 207.259958 -268.581045) (xy 207.382248 -268.665456)
			(xy 207.499831 -268.756309) (xy 207.612368 -268.853343) (xy 207.719535 -268.956278) (xy 207.821022 -269.064817)
			(xy 207.916536 -269.178646) (xy 208.005803 -269.297439) (xy 208.088564 -269.420851) (xy 208.164582 -269.548529)
			(xy 208.233637 -269.680102) (xy 208.29553 -269.815193) (xy 208.350083 -269.95341) (xy 208.397138 -270.094357)
			(xy 208.43656 -270.237627) (xy 208.468234 -270.382806) (xy 208.49207 -270.529475) (xy 208.507999 -270.677213)
			(xy 208.515975 -270.825593) (xy 208.516474 -270.89989) (xy 259.082549 -270.89989) (xy 259.086538 -270.75135)
			(xy 259.098495 -270.603237) (xy 259.118385 -270.45598) (xy 259.14615 -270.310004) (xy 259.181711 -270.165727)
			(xy 259.224965 -270.023568) (xy 259.275787 -269.883935) (xy 259.334031 -269.747232) (xy 259.399529 -269.613852)
			(xy 259.472092 -269.48418) (xy 259.55151 -269.35859) (xy 259.637555 -269.237443) (xy 259.729979 -269.12109)
			(xy 259.828515 -269.009866) (xy 259.932879 -268.904091) (xy 260.042771 -268.804071) (xy 260.157872 -268.710093)
			(xy 260.277852 -268.622429) (xy 260.402365 -268.541332) (xy 260.531051 -268.467035) (xy 260.66354 -268.399753)
			(xy 260.799449 -268.339679) (xy 260.938387 -268.286987) (xy 261.079953 -268.241828) (xy 261.223739 -268.204333)
			(xy 261.36933 -268.174611) (xy 261.516306 -268.152746) (xy 261.664245 -268.138802) (xy 261.812718 -268.132818)
			(xy 261.961299 -268.134813) (xy 262.109558 -268.144781) (xy 262.257069 -268.162692) (xy 262.403405 -268.188495)
			(xy 262.548146 -268.222115) (xy 262.690873 -268.263457) (xy 262.831176 -268.3124) (xy 262.968649 -268.368803)
			(xy 263.102896 -268.432504) (xy 263.233531 -268.50332) (xy 263.360176 -268.581045) (xy 263.482466 -268.665456)
			(xy 263.600049 -268.756309) (xy 263.712586 -268.853343) (xy 263.819753 -268.956278) (xy 263.92124 -269.064817)
			(xy 264.016754 -269.178646) (xy 264.106021 -269.297439) (xy 264.188782 -269.420851) (xy 264.2648 -269.548529)
			(xy 264.333855 -269.680102) (xy 264.395748 -269.815193) (xy 264.450301 -269.95341) (xy 264.497356 -270.094357)
			(xy 264.536778 -270.237627) (xy 264.568452 -270.382806) (xy 264.592288 -270.529475) (xy 264.608217 -270.677213)
			(xy 264.616193 -270.825593) (xy 264.616692 -270.89989) (xy 319.082429 -270.89989) (xy 319.086418 -270.75135)
			(xy 319.098375 -270.603237) (xy 319.118265 -270.45598) (xy 319.14603 -270.310004) (xy 319.181591 -270.165727)
			(xy 319.224845 -270.023568) (xy 319.275667 -269.883935) (xy 319.333911 -269.747232) (xy 319.399409 -269.613852)
			(xy 319.471972 -269.48418) (xy 319.55139 -269.35859) (xy 319.637435 -269.237443) (xy 319.729859 -269.12109)
			(xy 319.828395 -269.009866) (xy 319.932759 -268.904091) (xy 320.042651 -268.804071) (xy 320.157752 -268.710093)
			(xy 320.277732 -268.622429) (xy 320.402245 -268.541332) (xy 320.530931 -268.467035) (xy 320.66342 -268.399753)
			(xy 320.799329 -268.339679) (xy 320.938267 -268.286987) (xy 321.079833 -268.241828) (xy 321.223619 -268.204333)
			(xy 321.36921 -268.174611) (xy 321.516186 -268.152746) (xy 321.664125 -268.138802) (xy 321.812598 -268.132818)
			(xy 321.961179 -268.134813) (xy 322.109438 -268.144781) (xy 322.256949 -268.162692) (xy 322.403285 -268.188495)
			(xy 322.548026 -268.222115) (xy 322.690753 -268.263457) (xy 322.831056 -268.3124) (xy 322.968529 -268.368803)
			(xy 323.102776 -268.432504) (xy 323.233411 -268.50332) (xy 323.360056 -268.581045) (xy 323.482346 -268.665456)
			(xy 323.599929 -268.756309) (xy 323.712466 -268.853343) (xy 323.819633 -268.956278) (xy 323.92112 -269.064817)
			(xy 324.016634 -269.178646) (xy 324.105901 -269.297439) (xy 324.188662 -269.420851) (xy 324.26468 -269.548529)
			(xy 324.333735 -269.680102) (xy 324.395628 -269.815193) (xy 324.450181 -269.95341) (xy 324.497236 -270.094357)
			(xy 324.536658 -270.237627) (xy 324.568332 -270.382806) (xy 324.592168 -270.529475) (xy 324.608097 -270.677213)
			(xy 324.616073 -270.825593) (xy 324.616572 -270.89989) (xy 375.182393 -270.89989) (xy 375.186382 -270.75135)
			(xy 375.198339 -270.603237) (xy 375.218229 -270.45598) (xy 375.245994 -270.310004) (xy 375.281555 -270.165727)
			(xy 375.324809 -270.023568) (xy 375.375631 -269.883935) (xy 375.433875 -269.747232) (xy 375.499373 -269.613852)
			(xy 375.571936 -269.48418) (xy 375.651354 -269.35859) (xy 375.737399 -269.237443) (xy 375.829823 -269.12109)
			(xy 375.928359 -269.009866) (xy 376.032723 -268.904091) (xy 376.142615 -268.804071) (xy 376.257716 -268.710093)
			(xy 376.377696 -268.622429) (xy 376.502209 -268.541332) (xy 376.630895 -268.467035) (xy 376.763384 -268.399753)
			(xy 376.899293 -268.339679) (xy 377.038231 -268.286987) (xy 377.179797 -268.241828) (xy 377.323583 -268.204333)
			(xy 377.469174 -268.174611) (xy 377.61615 -268.152746) (xy 377.764089 -268.138802) (xy 377.912562 -268.132818)
			(xy 378.061143 -268.134813) (xy 378.209402 -268.144781) (xy 378.356913 -268.162692) (xy 378.503249 -268.188495)
			(xy 378.64799 -268.222115) (xy 378.790717 -268.263457) (xy 378.93102 -268.3124) (xy 379.068493 -268.368803)
			(xy 379.20274 -268.432504) (xy 379.333375 -268.50332) (xy 379.46002 -268.581045) (xy 379.58231 -268.665456)
			(xy 379.699893 -268.756309) (xy 379.81243 -268.853343) (xy 379.919597 -268.956278) (xy 380.021084 -269.064817)
			(xy 380.116598 -269.178646) (xy 380.205865 -269.297439) (xy 380.288626 -269.420851) (xy 380.364644 -269.548529)
			(xy 380.433699 -269.680102) (xy 380.495592 -269.815193) (xy 380.550145 -269.95341) (xy 380.5972 -270.094357)
			(xy 380.636622 -270.237627) (xy 380.668296 -270.382806) (xy 380.692132 -270.529475) (xy 380.708061 -270.677213)
			(xy 380.716037 -270.825593) (xy 380.716536 -270.89989) (xy 435.182527 -270.89989) (xy 435.186516 -270.75135)
			(xy 435.198473 -270.603237) (xy 435.218363 -270.45598) (xy 435.246128 -270.310004) (xy 435.281689 -270.165727)
			(xy 435.324943 -270.023568) (xy 435.375765 -269.883935) (xy 435.434009 -269.747232) (xy 435.499507 -269.613852)
			(xy 435.57207 -269.48418) (xy 435.651488 -269.35859) (xy 435.737533 -269.237443) (xy 435.829957 -269.12109)
			(xy 435.928493 -269.009866) (xy 436.032857 -268.904091) (xy 436.142749 -268.804071) (xy 436.25785 -268.710093)
			(xy 436.37783 -268.622429) (xy 436.502343 -268.541332) (xy 436.631029 -268.467035) (xy 436.763518 -268.399753)
			(xy 436.899427 -268.339679) (xy 437.038365 -268.286987) (xy 437.179931 -268.241828) (xy 437.323717 -268.204333)
			(xy 437.469308 -268.174611) (xy 437.616284 -268.152746) (xy 437.764223 -268.138802) (xy 437.912696 -268.132818)
			(xy 438.061277 -268.134813) (xy 438.209536 -268.144781) (xy 438.357047 -268.162692) (xy 438.503383 -268.188495)
			(xy 438.648124 -268.222115) (xy 438.790851 -268.263457) (xy 438.931154 -268.3124) (xy 439.068627 -268.368803)
			(xy 439.202874 -268.432504) (xy 439.333509 -268.50332) (xy 439.460154 -268.581045) (xy 439.582444 -268.665456)
			(xy 439.700027 -268.756309) (xy 439.812564 -268.853343) (xy 439.919731 -268.956278) (xy 440.021218 -269.064817)
			(xy 440.116732 -269.178646) (xy 440.205999 -269.297439) (xy 440.28876 -269.420851) (xy 440.364778 -269.548529)
			(xy 440.433833 -269.680102) (xy 440.495726 -269.815193) (xy 440.550279 -269.95341) (xy 440.597334 -270.094357)
			(xy 440.636756 -270.237627) (xy 440.66843 -270.382806) (xy 440.692266 -270.529475) (xy 440.708195 -270.677213)
			(xy 440.716171 -270.825593) (xy 440.71667 -270.89989) (xy 440.716171 -270.974187) (xy 440.708195 -271.122567)
			(xy 440.692266 -271.270305) (xy 440.66843 -271.416974) (xy 440.636756 -271.562153) (xy 440.597334 -271.705423)
			(xy 440.550279 -271.84637) (xy 440.495726 -271.984587) (xy 440.433833 -272.119678) (xy 440.364778 -272.251251)
			(xy 440.28876 -272.378929) (xy 440.205999 -272.502341) (xy 440.116732 -272.621134) (xy 440.021218 -272.734963)
			(xy 439.919731 -272.843502) (xy 439.812564 -272.946437) (xy 439.700027 -273.043471) (xy 439.582444 -273.134324)
			(xy 439.460154 -273.218735) (xy 439.333509 -273.29646) (xy 439.202874 -273.367276) (xy 439.068627 -273.430977)
			(xy 438.931154 -273.48738) (xy 438.790851 -273.536323) (xy 438.648124 -273.577665) (xy 438.503383 -273.611285)
			(xy 438.357047 -273.637088) (xy 438.209536 -273.654999) (xy 438.061277 -273.664967) (xy 437.912696 -273.666962)
			(xy 437.764223 -273.660978) (xy 437.616284 -273.647034) (xy 437.469308 -273.625169) (xy 437.323717 -273.595447)
			(xy 437.179931 -273.557952) (xy 437.038365 -273.512793) (xy 436.899427 -273.460101) (xy 436.763518 -273.400027)
			(xy 436.631029 -273.332745) (xy 436.502343 -273.258448) (xy 436.37783 -273.177351) (xy 436.25785 -273.089687)
			(xy 436.142749 -272.995709) (xy 436.032857 -272.895689) (xy 435.928493 -272.789914) (xy 435.829957 -272.67869)
			(xy 435.737533 -272.562337) (xy 435.651488 -272.44119) (xy 435.57207 -272.3156) (xy 435.499507 -272.185928)
			(xy 435.434009 -272.052548) (xy 435.375765 -271.915845) (xy 435.324943 -271.776212) (xy 435.281689 -271.634053)
			(xy 435.246128 -271.489776) (xy 435.218363 -271.3438) (xy 435.198473 -271.196543) (xy 435.186516 -271.04843)
			(xy 435.182527 -270.89989) (xy 380.716536 -270.89989) (xy 380.716037 -270.974187) (xy 380.708061 -271.122567)
			(xy 380.692132 -271.270305) (xy 380.668296 -271.416974) (xy 380.636622 -271.562153) (xy 380.5972 -271.705423)
			(xy 380.550145 -271.84637) (xy 380.495592 -271.984587) (xy 380.433699 -272.119678) (xy 380.364644 -272.251251)
			(xy 380.288626 -272.378929) (xy 380.205865 -272.502341) (xy 380.116598 -272.621134) (xy 380.021084 -272.734963)
			(xy 379.919597 -272.843502) (xy 379.81243 -272.946437) (xy 379.699893 -273.043471) (xy 379.627012 -273.099784)
			(xy 392.443982 -273.099784) (xy 392.447942 -273.05073) (xy 392.459719 -273.002946) (xy 392.47901 -272.95767)
			(xy 392.505313 -272.916074) (xy 392.537948 -272.879237) (xy 392.576069 -272.848112) (xy 392.61869 -272.823505)
			(xy 392.664706 -272.806053) (xy 392.712925 -272.796209) (xy 392.7621 -272.794228) (xy 392.810955 -272.80016)
			(xy 392.858226 -272.813852) (xy 392.902688 -272.83495) (xy 392.943191 -272.862906) (xy 392.978684 -272.896998)
			(xy 393.008249 -272.936342) (xy 393.03112 -272.979919) (xy 393.046704 -273.0266) (xy 393.054599 -273.075177)
			(xy 393.055094 -273.099784) (xy 394.344156 -273.099784) (xy 394.348116 -273.05073) (xy 394.359893 -273.002946)
			(xy 394.379184 -272.95767) (xy 394.405487 -272.916074) (xy 394.438122 -272.879237) (xy 394.476243 -272.848112)
			(xy 394.518864 -272.823505) (xy 394.56488 -272.806053) (xy 394.613099 -272.796209) (xy 394.662274 -272.794228)
			(xy 394.711129 -272.80016) (xy 394.7584 -272.813852) (xy 394.802862 -272.83495) (xy 394.843365 -272.862906)
			(xy 394.878858 -272.896998) (xy 394.908423 -272.936342) (xy 394.931294 -272.979919) (xy 394.946878 -273.0266)
			(xy 394.954773 -273.075177) (xy 394.955268 -273.099784) (xy 396.244076 -273.099784) (xy 396.248036 -273.05073)
			(xy 396.259813 -273.002946) (xy 396.279104 -272.95767) (xy 396.305407 -272.916074) (xy 396.338042 -272.879237)
			(xy 396.376163 -272.848112) (xy 396.418784 -272.823505) (xy 396.4648 -272.806053) (xy 396.513019 -272.796209)
			(xy 396.562194 -272.794228) (xy 396.611049 -272.80016) (xy 396.65832 -272.813852) (xy 396.702782 -272.83495)
			(xy 396.743285 -272.862906) (xy 396.778778 -272.896998) (xy 396.808343 -272.936342) (xy 396.831214 -272.979919)
			(xy 396.846798 -273.0266) (xy 396.854693 -273.075177) (xy 396.855188 -273.099784) (xy 398.143996 -273.099784)
			(xy 398.147956 -273.05073) (xy 398.159733 -273.002946) (xy 398.179024 -272.95767) (xy 398.205327 -272.916074)
			(xy 398.237962 -272.879237) (xy 398.276083 -272.848112) (xy 398.318704 -272.823505) (xy 398.36472 -272.806053)
			(xy 398.412939 -272.796209) (xy 398.462114 -272.794228) (xy 398.510969 -272.80016) (xy 398.55824 -272.813852)
			(xy 398.602702 -272.83495) (xy 398.643205 -272.862906) (xy 398.678698 -272.896998) (xy 398.708263 -272.936342)
			(xy 398.731134 -272.979919) (xy 398.746718 -273.0266) (xy 398.754613 -273.075177) (xy 398.755108 -273.099784)
			(xy 400.04417 -273.099784) (xy 400.04813 -273.05073) (xy 400.059907 -273.002946) (xy 400.079198 -272.95767)
			(xy 400.105501 -272.916074) (xy 400.138136 -272.879237) (xy 400.176257 -272.848112) (xy 400.218878 -272.823505)
			(xy 400.264894 -272.806053) (xy 400.313113 -272.796209) (xy 400.362288 -272.794228) (xy 400.411143 -272.80016)
			(xy 400.458414 -272.813852) (xy 400.502876 -272.83495) (xy 400.543379 -272.862906) (xy 400.578872 -272.896998)
			(xy 400.608437 -272.936342) (xy 400.631308 -272.979919) (xy 400.646892 -273.0266) (xy 400.654787 -273.075177)
			(xy 400.655282 -273.099784) (xy 401.94409 -273.099784) (xy 401.94805 -273.05073) (xy 401.959827 -273.002946)
			(xy 401.979118 -272.95767) (xy 402.005421 -272.916074) (xy 402.038056 -272.879237) (xy 402.076177 -272.848112)
			(xy 402.118798 -272.823505) (xy 402.164814 -272.806053) (xy 402.213033 -272.796209) (xy 402.262208 -272.794228)
			(xy 402.311063 -272.80016) (xy 402.358334 -272.813852) (xy 402.402796 -272.83495) (xy 402.443299 -272.862906)
			(xy 402.478792 -272.896998) (xy 402.508357 -272.936342) (xy 402.531228 -272.979919) (xy 402.546812 -273.0266)
			(xy 402.554707 -273.075177) (xy 402.555202 -273.099784) (xy 403.84401 -273.099784) (xy 403.84797 -273.05073)
			(xy 403.859747 -273.002946) (xy 403.879038 -272.95767) (xy 403.905341 -272.916074) (xy 403.937976 -272.879237)
			(xy 403.976097 -272.848112) (xy 404.018718 -272.823505) (xy 404.064734 -272.806053) (xy 404.112953 -272.796209)
			(xy 404.162128 -272.794228) (xy 404.210983 -272.80016) (xy 404.258254 -272.813852) (xy 404.302716 -272.83495)
			(xy 404.343219 -272.862906) (xy 404.378712 -272.896998) (xy 404.408277 -272.936342) (xy 404.431148 -272.979919)
			(xy 404.446732 -273.0266) (xy 404.454627 -273.075177) (xy 404.455122 -273.099784) (xy 405.744184 -273.099784)
			(xy 405.748144 -273.05073) (xy 405.759921 -273.002946) (xy 405.779212 -272.95767) (xy 405.805515 -272.916074)
			(xy 405.83815 -272.879237) (xy 405.876271 -272.848112) (xy 405.918892 -272.823505) (xy 405.964908 -272.806053)
			(xy 406.013127 -272.796209) (xy 406.062302 -272.794228) (xy 406.111157 -272.80016) (xy 406.158428 -272.813852)
			(xy 406.20289 -272.83495) (xy 406.243393 -272.862906) (xy 406.278886 -272.896998) (xy 406.308451 -272.936342)
			(xy 406.331322 -272.979919) (xy 406.346906 -273.0266) (xy 406.354801 -273.075177) (xy 406.355291 -273.09953)
			(xy 407.64385 -273.09953) (xy 407.64781 -273.050476) (xy 407.659587 -273.002692) (xy 407.678878 -272.957416)
			(xy 407.705181 -272.91582) (xy 407.737816 -272.878983) (xy 407.775937 -272.847858) (xy 407.818558 -272.823251)
			(xy 407.864574 -272.805799) (xy 407.912793 -272.795955) (xy 407.961968 -272.793974) (xy 408.010823 -272.799906)
			(xy 408.058094 -272.813598) (xy 408.102556 -272.834696) (xy 408.143059 -272.862652) (xy 408.178552 -272.896744)
			(xy 408.208117 -272.936088) (xy 408.230988 -272.979665) (xy 408.246572 -273.026346) (xy 408.254467 -273.074923)
			(xy 408.254962 -273.09953) (xy 408.254957 -273.099784) (xy 409.54377 -273.099784) (xy 409.54773 -273.05073)
			(xy 409.559507 -273.002946) (xy 409.578798 -272.95767) (xy 409.605101 -272.916074) (xy 409.637736 -272.879237)
			(xy 409.675857 -272.848112) (xy 409.718478 -272.823505) (xy 409.764494 -272.806053) (xy 409.812713 -272.796209)
			(xy 409.861888 -272.794228) (xy 409.910743 -272.80016) (xy 409.958014 -272.813852) (xy 410.002476 -272.83495)
			(xy 410.042979 -272.862906) (xy 410.078472 -272.896998) (xy 410.108037 -272.936342) (xy 410.130908 -272.979919)
			(xy 410.146492 -273.0266) (xy 410.154387 -273.075177) (xy 410.154882 -273.099784) (xy 411.443944 -273.099784)
			(xy 411.447904 -273.05073) (xy 411.459681 -273.002946) (xy 411.478972 -272.95767) (xy 411.505275 -272.916074)
			(xy 411.53791 -272.879237) (xy 411.576031 -272.848112) (xy 411.618652 -272.823505) (xy 411.664668 -272.806053)
			(xy 411.712887 -272.796209) (xy 411.762062 -272.794228) (xy 411.810917 -272.80016) (xy 411.858188 -272.813852)
			(xy 411.90265 -272.83495) (xy 411.943153 -272.862906) (xy 411.978646 -272.896998) (xy 412.008211 -272.936342)
			(xy 412.031082 -272.979919) (xy 412.046666 -273.0266) (xy 412.054561 -273.075177) (xy 412.055056 -273.099784)
			(xy 413.343864 -273.099784) (xy 413.347824 -273.05073) (xy 413.359601 -273.002946) (xy 413.378892 -272.95767)
			(xy 413.405195 -272.916074) (xy 413.43783 -272.879237) (xy 413.475951 -272.848112) (xy 413.518572 -272.823505)
			(xy 413.564588 -272.806053) (xy 413.612807 -272.796209) (xy 413.661982 -272.794228) (xy 413.710837 -272.80016)
			(xy 413.758108 -272.813852) (xy 413.80257 -272.83495) (xy 413.843073 -272.862906) (xy 413.878566 -272.896998)
			(xy 413.908131 -272.936342) (xy 413.931002 -272.979919) (xy 413.946586 -273.0266) (xy 413.954481 -273.075177)
			(xy 413.954976 -273.099784) (xy 415.243784 -273.099784) (xy 415.247744 -273.05073) (xy 415.259521 -273.002946)
			(xy 415.278812 -272.95767) (xy 415.305115 -272.916074) (xy 415.33775 -272.879237) (xy 415.375871 -272.848112)
			(xy 415.418492 -272.823505) (xy 415.464508 -272.806053) (xy 415.512727 -272.796209) (xy 415.561902 -272.794228)
			(xy 415.610757 -272.80016) (xy 415.658028 -272.813852) (xy 415.70249 -272.83495) (xy 415.742993 -272.862906)
			(xy 415.778486 -272.896998) (xy 415.808051 -272.936342) (xy 415.830922 -272.979919) (xy 415.846506 -273.0266)
			(xy 415.854401 -273.075177) (xy 415.854896 -273.099784) (xy 417.143958 -273.099784) (xy 417.147918 -273.05073)
			(xy 417.159695 -273.002946) (xy 417.178986 -272.95767) (xy 417.205289 -272.916074) (xy 417.237924 -272.879237)
			(xy 417.276045 -272.848112) (xy 417.318666 -272.823505) (xy 417.364682 -272.806053) (xy 417.412901 -272.796209)
			(xy 417.462076 -272.794228) (xy 417.510931 -272.80016) (xy 417.558202 -272.813852) (xy 417.602664 -272.83495)
			(xy 417.643167 -272.862906) (xy 417.67866 -272.896998) (xy 417.708225 -272.936342) (xy 417.731096 -272.979919)
			(xy 417.74668 -273.0266) (xy 417.754575 -273.075177) (xy 417.75507 -273.099784) (xy 419.043878 -273.099784)
			(xy 419.047838 -273.05073) (xy 419.059615 -273.002946) (xy 419.078906 -272.95767) (xy 419.105209 -272.916074)
			(xy 419.137844 -272.879237) (xy 419.175965 -272.848112) (xy 419.218586 -272.823505) (xy 419.264602 -272.806053)
			(xy 419.312821 -272.796209) (xy 419.361996 -272.794228) (xy 419.410851 -272.80016) (xy 419.458122 -272.813852)
			(xy 419.502584 -272.83495) (xy 419.543087 -272.862906) (xy 419.57858 -272.896998) (xy 419.608145 -272.936342)
			(xy 419.631016 -272.979919) (xy 419.6466 -273.0266) (xy 419.654495 -273.075177) (xy 419.65499 -273.099784)
			(xy 420.943798 -273.099784) (xy 420.947758 -273.05073) (xy 420.959535 -273.002946) (xy 420.978826 -272.95767)
			(xy 421.005129 -272.916074) (xy 421.037764 -272.879237) (xy 421.075885 -272.848112) (xy 421.118506 -272.823505)
			(xy 421.164522 -272.806053) (xy 421.212741 -272.796209) (xy 421.261916 -272.794228) (xy 421.310771 -272.80016)
			(xy 421.358042 -272.813852) (xy 421.402504 -272.83495) (xy 421.443007 -272.862906) (xy 421.4785 -272.896998)
			(xy 421.508065 -272.936342) (xy 421.530936 -272.979919) (xy 421.54652 -273.0266) (xy 421.554415 -273.075177)
			(xy 421.55491 -273.099784) (xy 422.843972 -273.099784) (xy 422.847932 -273.05073) (xy 422.859709 -273.002946)
			(xy 422.879 -272.95767) (xy 422.905303 -272.916074) (xy 422.937938 -272.879237) (xy 422.976059 -272.848112)
			(xy 423.01868 -272.823505) (xy 423.064696 -272.806053) (xy 423.112915 -272.796209) (xy 423.16209 -272.794228)
			(xy 423.210945 -272.80016) (xy 423.258216 -272.813852) (xy 423.302678 -272.83495) (xy 423.343181 -272.862906)
			(xy 423.378674 -272.896998) (xy 423.408239 -272.936342) (xy 423.43111 -272.979919) (xy 423.446694 -273.0266)
			(xy 423.454589 -273.075177) (xy 423.455084 -273.099784) (xy 424.743892 -273.099784) (xy 424.747852 -273.05073)
			(xy 424.759629 -273.002946) (xy 424.77892 -272.95767) (xy 424.805223 -272.916074) (xy 424.837858 -272.879237)
			(xy 424.875979 -272.848112) (xy 424.9186 -272.823505) (xy 424.964616 -272.806053) (xy 425.012835 -272.796209)
			(xy 425.06201 -272.794228) (xy 425.110865 -272.80016) (xy 425.158136 -272.813852) (xy 425.202598 -272.83495)
			(xy 425.243101 -272.862906) (xy 425.278594 -272.896998) (xy 425.308159 -272.936342) (xy 425.33103 -272.979919)
			(xy 425.346614 -273.0266) (xy 425.354509 -273.075177) (xy 425.355004 -273.099784) (xy 426.643812 -273.099784)
			(xy 426.647772 -273.05073) (xy 426.659549 -273.002946) (xy 426.67884 -272.95767) (xy 426.705143 -272.916074)
			(xy 426.737778 -272.879237) (xy 426.775899 -272.848112) (xy 426.81852 -272.823505) (xy 426.864536 -272.806053)
			(xy 426.912755 -272.796209) (xy 426.96193 -272.794228) (xy 427.010785 -272.80016) (xy 427.058056 -272.813852)
			(xy 427.102518 -272.83495) (xy 427.143021 -272.862906) (xy 427.178514 -272.896998) (xy 427.208079 -272.936342)
			(xy 427.23095 -272.979919) (xy 427.246534 -273.0266) (xy 427.254429 -273.075177) (xy 427.254924 -273.099784)
			(xy 428.543732 -273.099784) (xy 428.547692 -273.05073) (xy 428.559469 -273.002946) (xy 428.57876 -272.95767)
			(xy 428.605063 -272.916074) (xy 428.637698 -272.879237) (xy 428.675819 -272.848112) (xy 428.71844 -272.823505)
			(xy 428.764456 -272.806053) (xy 428.812675 -272.796209) (xy 428.86185 -272.794228) (xy 428.910705 -272.80016)
			(xy 428.957976 -272.813852) (xy 429.002438 -272.83495) (xy 429.042941 -272.862906) (xy 429.078434 -272.896998)
			(xy 429.107999 -272.936342) (xy 429.13087 -272.979919) (xy 429.146454 -273.0266) (xy 429.154349 -273.075177)
			(xy 429.154844 -273.099784) (xy 429.154349 -273.124391) (xy 429.146454 -273.172968) (xy 429.13087 -273.219649)
			(xy 429.107999 -273.263226) (xy 429.078434 -273.30257) (xy 429.042941 -273.336662) (xy 429.002438 -273.364618)
			(xy 428.957976 -273.385716) (xy 428.910705 -273.399408) (xy 428.86185 -273.40534) (xy 428.812675 -273.403359)
			(xy 428.764456 -273.393515) (xy 428.71844 -273.376063) (xy 428.675819 -273.351456) (xy 428.637698 -273.320331)
			(xy 428.605063 -273.283494) (xy 428.57876 -273.241898) (xy 428.559469 -273.196622) (xy 428.547692 -273.148838)
			(xy 428.543732 -273.099784) (xy 427.254924 -273.099784) (xy 427.254429 -273.124391) (xy 427.246534 -273.172968)
			(xy 427.23095 -273.219649) (xy 427.208079 -273.263226) (xy 427.178514 -273.30257) (xy 427.143021 -273.336662)
			(xy 427.102518 -273.364618) (xy 427.058056 -273.385716) (xy 427.010785 -273.399408) (xy 426.96193 -273.40534)
			(xy 426.912755 -273.403359) (xy 426.864536 -273.393515) (xy 426.81852 -273.376063) (xy 426.775899 -273.351456)
			(xy 426.737778 -273.320331) (xy 426.705143 -273.283494) (xy 426.67884 -273.241898) (xy 426.659549 -273.196622)
			(xy 426.647772 -273.148838) (xy 426.643812 -273.099784) (xy 425.355004 -273.099784) (xy 425.354509 -273.124391)
			(xy 425.346614 -273.172968) (xy 425.33103 -273.219649) (xy 425.308159 -273.263226) (xy 425.278594 -273.30257)
			(xy 425.243101 -273.336662) (xy 425.202598 -273.364618) (xy 425.158136 -273.385716) (xy 425.110865 -273.399408)
			(xy 425.06201 -273.40534) (xy 425.012835 -273.403359) (xy 424.964616 -273.393515) (xy 424.9186 -273.376063)
			(xy 424.875979 -273.351456) (xy 424.837858 -273.320331) (xy 424.805223 -273.283494) (xy 424.77892 -273.241898)
			(xy 424.759629 -273.196622) (xy 424.747852 -273.148838) (xy 424.743892 -273.099784) (xy 423.455084 -273.099784)
			(xy 423.454589 -273.124391) (xy 423.446694 -273.172968) (xy 423.43111 -273.219649) (xy 423.408239 -273.263226)
			(xy 423.378674 -273.30257) (xy 423.343181 -273.336662) (xy 423.302678 -273.364618) (xy 423.258216 -273.385716)
			(xy 423.210945 -273.399408) (xy 423.16209 -273.40534) (xy 423.112915 -273.403359) (xy 423.064696 -273.393515)
			(xy 423.01868 -273.376063) (xy 422.976059 -273.351456) (xy 422.937938 -273.320331) (xy 422.905303 -273.283494)
			(xy 422.879 -273.241898) (xy 422.859709 -273.196622) (xy 422.847932 -273.148838) (xy 422.843972 -273.099784)
			(xy 421.55491 -273.099784) (xy 421.554415 -273.124391) (xy 421.54652 -273.172968) (xy 421.530936 -273.219649)
			(xy 421.508065 -273.263226) (xy 421.4785 -273.30257) (xy 421.443007 -273.336662) (xy 421.402504 -273.364618)
			(xy 421.358042 -273.385716) (xy 421.310771 -273.399408) (xy 421.261916 -273.40534) (xy 421.212741 -273.403359)
			(xy 421.164522 -273.393515) (xy 421.118506 -273.376063) (xy 421.075885 -273.351456) (xy 421.037764 -273.320331)
			(xy 421.005129 -273.283494) (xy 420.978826 -273.241898) (xy 420.959535 -273.196622) (xy 420.947758 -273.148838)
			(xy 420.943798 -273.099784) (xy 419.65499 -273.099784) (xy 419.654495 -273.124391) (xy 419.6466 -273.172968)
			(xy 419.631016 -273.219649) (xy 419.608145 -273.263226) (xy 419.57858 -273.30257) (xy 419.543087 -273.336662)
			(xy 419.502584 -273.364618) (xy 419.458122 -273.385716) (xy 419.410851 -273.399408) (xy 419.361996 -273.40534)
			(xy 419.312821 -273.403359) (xy 419.264602 -273.393515) (xy 419.218586 -273.376063) (xy 419.175965 -273.351456)
			(xy 419.137844 -273.320331) (xy 419.105209 -273.283494) (xy 419.078906 -273.241898) (xy 419.059615 -273.196622)
			(xy 419.047838 -273.148838) (xy 419.043878 -273.099784) (xy 417.75507 -273.099784) (xy 417.754575 -273.124391)
			(xy 417.74668 -273.172968) (xy 417.731096 -273.219649) (xy 417.708225 -273.263226) (xy 417.67866 -273.30257)
			(xy 417.643167 -273.336662) (xy 417.602664 -273.364618) (xy 417.558202 -273.385716) (xy 417.510931 -273.399408)
			(xy 417.462076 -273.40534) (xy 417.412901 -273.403359) (xy 417.364682 -273.393515) (xy 417.318666 -273.376063)
			(xy 417.276045 -273.351456) (xy 417.237924 -273.320331) (xy 417.205289 -273.283494) (xy 417.178986 -273.241898)
			(xy 417.159695 -273.196622) (xy 417.147918 -273.148838) (xy 417.143958 -273.099784) (xy 415.854896 -273.099784)
			(xy 415.854401 -273.124391) (xy 415.846506 -273.172968) (xy 415.830922 -273.219649) (xy 415.808051 -273.263226)
			(xy 415.778486 -273.30257) (xy 415.742993 -273.336662) (xy 415.70249 -273.364618) (xy 415.658028 -273.385716)
			(xy 415.610757 -273.399408) (xy 415.561902 -273.40534) (xy 415.512727 -273.403359) (xy 415.464508 -273.393515)
			(xy 415.418492 -273.376063) (xy 415.375871 -273.351456) (xy 415.33775 -273.320331) (xy 415.305115 -273.283494)
			(xy 415.278812 -273.241898) (xy 415.259521 -273.196622) (xy 415.247744 -273.148838) (xy 415.243784 -273.099784)
			(xy 413.954976 -273.099784) (xy 413.954481 -273.124391) (xy 413.946586 -273.172968) (xy 413.931002 -273.219649)
			(xy 413.908131 -273.263226) (xy 413.878566 -273.30257) (xy 413.843073 -273.336662) (xy 413.80257 -273.364618)
			(xy 413.758108 -273.385716) (xy 413.710837 -273.399408) (xy 413.661982 -273.40534) (xy 413.612807 -273.403359)
			(xy 413.564588 -273.393515) (xy 413.518572 -273.376063) (xy 413.475951 -273.351456) (xy 413.43783 -273.320331)
			(xy 413.405195 -273.283494) (xy 413.378892 -273.241898) (xy 413.359601 -273.196622) (xy 413.347824 -273.148838)
			(xy 413.343864 -273.099784) (xy 412.055056 -273.099784) (xy 412.054561 -273.124391) (xy 412.046666 -273.172968)
			(xy 412.031082 -273.219649) (xy 412.008211 -273.263226) (xy 411.978646 -273.30257) (xy 411.943153 -273.336662)
			(xy 411.90265 -273.364618) (xy 411.858188 -273.385716) (xy 411.810917 -273.399408) (xy 411.762062 -273.40534)
			(xy 411.712887 -273.403359) (xy 411.664668 -273.393515) (xy 411.618652 -273.376063) (xy 411.576031 -273.351456)
			(xy 411.53791 -273.320331) (xy 411.505275 -273.283494) (xy 411.478972 -273.241898) (xy 411.459681 -273.196622)
			(xy 411.447904 -273.148838) (xy 411.443944 -273.099784) (xy 410.154882 -273.099784) (xy 410.154387 -273.124391)
			(xy 410.146492 -273.172968) (xy 410.130908 -273.219649) (xy 410.108037 -273.263226) (xy 410.078472 -273.30257)
			(xy 410.042979 -273.336662) (xy 410.002476 -273.364618) (xy 409.958014 -273.385716) (xy 409.910743 -273.399408)
			(xy 409.861888 -273.40534) (xy 409.812713 -273.403359) (xy 409.764494 -273.393515) (xy 409.718478 -273.376063)
			(xy 409.675857 -273.351456) (xy 409.637736 -273.320331) (xy 409.605101 -273.283494) (xy 409.578798 -273.241898)
			(xy 409.559507 -273.196622) (xy 409.54773 -273.148838) (xy 409.54377 -273.099784) (xy 408.254957 -273.099784)
			(xy 408.254467 -273.124137) (xy 408.246572 -273.172714) (xy 408.230988 -273.219395) (xy 408.208117 -273.262972)
			(xy 408.178552 -273.302316) (xy 408.143059 -273.336408) (xy 408.102556 -273.364364) (xy 408.058094 -273.385462)
			(xy 408.010823 -273.399154) (xy 407.961968 -273.405086) (xy 407.912793 -273.403105) (xy 407.864574 -273.393261)
			(xy 407.818558 -273.375809) (xy 407.775937 -273.351202) (xy 407.737816 -273.320077) (xy 407.705181 -273.28324)
			(xy 407.678878 -273.241644) (xy 407.659587 -273.196368) (xy 407.64781 -273.148584) (xy 407.64385 -273.09953)
			(xy 406.355291 -273.09953) (xy 406.355296 -273.099784) (xy 406.354801 -273.124391) (xy 406.346906 -273.172968)
			(xy 406.331322 -273.219649) (xy 406.308451 -273.263226) (xy 406.278886 -273.30257) (xy 406.243393 -273.336662)
			(xy 406.20289 -273.364618) (xy 406.158428 -273.385716) (xy 406.111157 -273.399408) (xy 406.062302 -273.40534)
			(xy 406.013127 -273.403359) (xy 405.964908 -273.393515) (xy 405.918892 -273.376063) (xy 405.876271 -273.351456)
			(xy 405.83815 -273.320331) (xy 405.805515 -273.283494) (xy 405.779212 -273.241898) (xy 405.759921 -273.196622)
			(xy 405.748144 -273.148838) (xy 405.744184 -273.099784) (xy 404.455122 -273.099784) (xy 404.454627 -273.124391)
			(xy 404.446732 -273.172968) (xy 404.431148 -273.219649) (xy 404.408277 -273.263226) (xy 404.378712 -273.30257)
			(xy 404.343219 -273.336662) (xy 404.302716 -273.364618) (xy 404.258254 -273.385716) (xy 404.210983 -273.399408)
			(xy 404.162128 -273.40534) (xy 404.112953 -273.403359) (xy 404.064734 -273.393515) (xy 404.018718 -273.376063)
			(xy 403.976097 -273.351456) (xy 403.937976 -273.320331) (xy 403.905341 -273.283494) (xy 403.879038 -273.241898)
			(xy 403.859747 -273.196622) (xy 403.84797 -273.148838) (xy 403.84401 -273.099784) (xy 402.555202 -273.099784)
			(xy 402.554707 -273.124391) (xy 402.546812 -273.172968) (xy 402.531228 -273.219649) (xy 402.508357 -273.263226)
			(xy 402.478792 -273.30257) (xy 402.443299 -273.336662) (xy 402.402796 -273.364618) (xy 402.358334 -273.385716)
			(xy 402.311063 -273.399408) (xy 402.262208 -273.40534) (xy 402.213033 -273.403359) (xy 402.164814 -273.393515)
			(xy 402.118798 -273.376063) (xy 402.076177 -273.351456) (xy 402.038056 -273.320331) (xy 402.005421 -273.283494)
			(xy 401.979118 -273.241898) (xy 401.959827 -273.196622) (xy 401.94805 -273.148838) (xy 401.94409 -273.099784)
			(xy 400.655282 -273.099784) (xy 400.654787 -273.124391) (xy 400.646892 -273.172968) (xy 400.631308 -273.219649)
			(xy 400.608437 -273.263226) (xy 400.578872 -273.30257) (xy 400.543379 -273.336662) (xy 400.502876 -273.364618)
			(xy 400.458414 -273.385716) (xy 400.411143 -273.399408) (xy 400.362288 -273.40534) (xy 400.313113 -273.403359)
			(xy 400.264894 -273.393515) (xy 400.218878 -273.376063) (xy 400.176257 -273.351456) (xy 400.138136 -273.320331)
			(xy 400.105501 -273.283494) (xy 400.079198 -273.241898) (xy 400.059907 -273.196622) (xy 400.04813 -273.148838)
			(xy 400.04417 -273.099784) (xy 398.755108 -273.099784) (xy 398.754613 -273.124391) (xy 398.746718 -273.172968)
			(xy 398.731134 -273.219649) (xy 398.708263 -273.263226) (xy 398.678698 -273.30257) (xy 398.643205 -273.336662)
			(xy 398.602702 -273.364618) (xy 398.55824 -273.385716) (xy 398.510969 -273.399408) (xy 398.462114 -273.40534)
			(xy 398.412939 -273.403359) (xy 398.36472 -273.393515) (xy 398.318704 -273.376063) (xy 398.276083 -273.351456)
			(xy 398.237962 -273.320331) (xy 398.205327 -273.283494) (xy 398.179024 -273.241898) (xy 398.159733 -273.196622)
			(xy 398.147956 -273.148838) (xy 398.143996 -273.099784) (xy 396.855188 -273.099784) (xy 396.854693 -273.124391)
			(xy 396.846798 -273.172968) (xy 396.831214 -273.219649) (xy 396.808343 -273.263226) (xy 396.778778 -273.30257)
			(xy 396.743285 -273.336662) (xy 396.702782 -273.364618) (xy 396.65832 -273.385716) (xy 396.611049 -273.399408)
			(xy 396.562194 -273.40534) (xy 396.513019 -273.403359) (xy 396.4648 -273.393515) (xy 396.418784 -273.376063)
			(xy 396.376163 -273.351456) (xy 396.338042 -273.320331) (xy 396.305407 -273.283494) (xy 396.279104 -273.241898)
			(xy 396.259813 -273.196622) (xy 396.248036 -273.148838) (xy 396.244076 -273.099784) (xy 394.955268 -273.099784)
			(xy 394.954773 -273.124391) (xy 394.946878 -273.172968) (xy 394.931294 -273.219649) (xy 394.908423 -273.263226)
			(xy 394.878858 -273.30257) (xy 394.843365 -273.336662) (xy 394.802862 -273.364618) (xy 394.7584 -273.385716)
			(xy 394.711129 -273.399408) (xy 394.662274 -273.40534) (xy 394.613099 -273.403359) (xy 394.56488 -273.393515)
			(xy 394.518864 -273.376063) (xy 394.476243 -273.351456) (xy 394.438122 -273.320331) (xy 394.405487 -273.283494)
			(xy 394.379184 -273.241898) (xy 394.359893 -273.196622) (xy 394.348116 -273.148838) (xy 394.344156 -273.099784)
			(xy 393.055094 -273.099784) (xy 393.054599 -273.124391) (xy 393.046704 -273.172968) (xy 393.03112 -273.219649)
			(xy 393.008249 -273.263226) (xy 392.978684 -273.30257) (xy 392.943191 -273.336662) (xy 392.902688 -273.364618)
			(xy 392.858226 -273.385716) (xy 392.810955 -273.399408) (xy 392.7621 -273.40534) (xy 392.712925 -273.403359)
			(xy 392.664706 -273.393515) (xy 392.61869 -273.376063) (xy 392.576069 -273.351456) (xy 392.537948 -273.320331)
			(xy 392.505313 -273.283494) (xy 392.47901 -273.241898) (xy 392.459719 -273.196622) (xy 392.447942 -273.148838)
			(xy 392.443982 -273.099784) (xy 379.627012 -273.099784) (xy 379.58231 -273.134324) (xy 379.46002 -273.218735)
			(xy 379.333375 -273.29646) (xy 379.20274 -273.367276) (xy 379.068493 -273.430977) (xy 378.93102 -273.48738)
			(xy 378.790717 -273.536323) (xy 378.64799 -273.577665) (xy 378.503249 -273.611285) (xy 378.356913 -273.637088)
			(xy 378.209402 -273.654999) (xy 378.061143 -273.664967) (xy 377.912562 -273.666962) (xy 377.764089 -273.660978)
			(xy 377.61615 -273.647034) (xy 377.469174 -273.625169) (xy 377.323583 -273.595447) (xy 377.179797 -273.557952)
			(xy 377.038231 -273.512793) (xy 376.899293 -273.460101) (xy 376.763384 -273.400027) (xy 376.630895 -273.332745)
			(xy 376.502209 -273.258448) (xy 376.377696 -273.177351) (xy 376.257716 -273.089687) (xy 376.142615 -272.995709)
			(xy 376.032723 -272.895689) (xy 375.928359 -272.789914) (xy 375.829823 -272.67869) (xy 375.737399 -272.562337)
			(xy 375.651354 -272.44119) (xy 375.571936 -272.3156) (xy 375.499373 -272.185928) (xy 375.433875 -272.052548)
			(xy 375.375631 -271.915845) (xy 375.324809 -271.776212) (xy 375.281555 -271.634053) (xy 375.245994 -271.489776)
			(xy 375.218229 -271.3438) (xy 375.198339 -271.196543) (xy 375.186382 -271.04843) (xy 375.182393 -270.89989)
			(xy 324.616572 -270.89989) (xy 324.616073 -270.974187) (xy 324.608097 -271.122567) (xy 324.592168 -271.270305)
			(xy 324.568332 -271.416974) (xy 324.536658 -271.562153) (xy 324.497236 -271.705423) (xy 324.450181 -271.84637)
			(xy 324.395628 -271.984587) (xy 324.333735 -272.119678) (xy 324.26468 -272.251251) (xy 324.188662 -272.378929)
			(xy 324.105901 -272.502341) (xy 324.016634 -272.621134) (xy 323.92112 -272.734963) (xy 323.819633 -272.843502)
			(xy 323.712466 -272.946437) (xy 323.599929 -273.043471) (xy 323.482346 -273.134324) (xy 323.360056 -273.218735)
			(xy 323.233411 -273.29646) (xy 323.102776 -273.367276) (xy 322.968529 -273.430977) (xy 322.831056 -273.48738)
			(xy 322.690753 -273.536323) (xy 322.548026 -273.577665) (xy 322.403285 -273.611285) (xy 322.256949 -273.637088)
			(xy 322.109438 -273.654999) (xy 321.961179 -273.664967) (xy 321.812598 -273.666962) (xy 321.664125 -273.660978)
			(xy 321.516186 -273.647034) (xy 321.36921 -273.625169) (xy 321.223619 -273.595447) (xy 321.079833 -273.557952)
			(xy 320.938267 -273.512793) (xy 320.799329 -273.460101) (xy 320.66342 -273.400027) (xy 320.530931 -273.332745)
			(xy 320.402245 -273.258448) (xy 320.277732 -273.177351) (xy 320.157752 -273.089687) (xy 320.042651 -272.995709)
			(xy 319.932759 -272.895689) (xy 319.828395 -272.789914) (xy 319.729859 -272.67869) (xy 319.637435 -272.562337)
			(xy 319.55139 -272.44119) (xy 319.471972 -272.3156) (xy 319.399409 -272.185928) (xy 319.333911 -272.052548)
			(xy 319.275667 -271.915845) (xy 319.224845 -271.776212) (xy 319.181591 -271.634053) (xy 319.14603 -271.489776)
			(xy 319.118265 -271.3438) (xy 319.098375 -271.196543) (xy 319.086418 -271.04843) (xy 319.082429 -270.89989)
			(xy 264.616692 -270.89989) (xy 264.616193 -270.974187) (xy 264.608217 -271.122567) (xy 264.592288 -271.270305)
			(xy 264.568452 -271.416974) (xy 264.536778 -271.562153) (xy 264.497356 -271.705423) (xy 264.450301 -271.84637)
			(xy 264.395748 -271.984587) (xy 264.333855 -272.119678) (xy 264.2648 -272.251251) (xy 264.188782 -272.378929)
			(xy 264.106021 -272.502341) (xy 264.016754 -272.621134) (xy 263.92124 -272.734963) (xy 263.819753 -272.843502)
			(xy 263.712586 -272.946437) (xy 263.600049 -273.043471) (xy 263.527168 -273.099784) (xy 276.343884 -273.099784)
			(xy 276.347844 -273.05073) (xy 276.359621 -273.002946) (xy 276.378912 -272.95767) (xy 276.405215 -272.916074)
			(xy 276.43785 -272.879237) (xy 276.475971 -272.848112) (xy 276.518592 -272.823505) (xy 276.564608 -272.806053)
			(xy 276.612827 -272.796209) (xy 276.662002 -272.794228) (xy 276.710857 -272.80016) (xy 276.758128 -272.813852)
			(xy 276.80259 -272.83495) (xy 276.843093 -272.862906) (xy 276.878586 -272.896998) (xy 276.908151 -272.936342)
			(xy 276.931022 -272.979919) (xy 276.946606 -273.0266) (xy 276.954501 -273.075177) (xy 276.954996 -273.099784)
			(xy 278.244058 -273.099784) (xy 278.248018 -273.05073) (xy 278.259795 -273.002946) (xy 278.279086 -272.95767)
			(xy 278.305389 -272.916074) (xy 278.338024 -272.879237) (xy 278.376145 -272.848112) (xy 278.418766 -272.823505)
			(xy 278.464782 -272.806053) (xy 278.513001 -272.796209) (xy 278.562176 -272.794228) (xy 278.611031 -272.80016)
			(xy 278.658302 -272.813852) (xy 278.702764 -272.83495) (xy 278.743267 -272.862906) (xy 278.77876 -272.896998)
			(xy 278.808325 -272.936342) (xy 278.831196 -272.979919) (xy 278.84678 -273.0266) (xy 278.854675 -273.075177)
			(xy 278.85517 -273.099784) (xy 280.143978 -273.099784) (xy 280.147938 -273.05073) (xy 280.159715 -273.002946)
			(xy 280.179006 -272.95767) (xy 280.205309 -272.916074) (xy 280.237944 -272.879237) (xy 280.276065 -272.848112)
			(xy 280.318686 -272.823505) (xy 280.364702 -272.806053) (xy 280.412921 -272.796209) (xy 280.462096 -272.794228)
			(xy 280.510951 -272.80016) (xy 280.558222 -272.813852) (xy 280.602684 -272.83495) (xy 280.643187 -272.862906)
			(xy 280.67868 -272.896998) (xy 280.708245 -272.936342) (xy 280.731116 -272.979919) (xy 280.7467 -273.0266)
			(xy 280.754595 -273.075177) (xy 280.75509 -273.099784) (xy 282.043898 -273.099784) (xy 282.047858 -273.05073)
			(xy 282.059635 -273.002946) (xy 282.078926 -272.95767) (xy 282.105229 -272.916074) (xy 282.137864 -272.879237)
			(xy 282.175985 -272.848112) (xy 282.218606 -272.823505) (xy 282.264622 -272.806053) (xy 282.312841 -272.796209)
			(xy 282.362016 -272.794228) (xy 282.410871 -272.80016) (xy 282.458142 -272.813852) (xy 282.502604 -272.83495)
			(xy 282.543107 -272.862906) (xy 282.5786 -272.896998) (xy 282.608165 -272.936342) (xy 282.631036 -272.979919)
			(xy 282.64662 -273.0266) (xy 282.654515 -273.075177) (xy 282.65501 -273.099784) (xy 283.944072 -273.099784)
			(xy 283.948032 -273.05073) (xy 283.959809 -273.002946) (xy 283.9791 -272.95767) (xy 284.005403 -272.916074)
			(xy 284.038038 -272.879237) (xy 284.076159 -272.848112) (xy 284.11878 -272.823505) (xy 284.164796 -272.806053)
			(xy 284.213015 -272.796209) (xy 284.26219 -272.794228) (xy 284.311045 -272.80016) (xy 284.358316 -272.813852)
			(xy 284.402778 -272.83495) (xy 284.443281 -272.862906) (xy 284.478774 -272.896998) (xy 284.508339 -272.936342)
			(xy 284.53121 -272.979919) (xy 284.546794 -273.0266) (xy 284.554689 -273.075177) (xy 284.555184 -273.099784)
			(xy 285.843992 -273.099784) (xy 285.847952 -273.05073) (xy 285.859729 -273.002946) (xy 285.87902 -272.95767)
			(xy 285.905323 -272.916074) (xy 285.937958 -272.879237) (xy 285.976079 -272.848112) (xy 286.0187 -272.823505)
			(xy 286.064716 -272.806053) (xy 286.112935 -272.796209) (xy 286.16211 -272.794228) (xy 286.210965 -272.80016)
			(xy 286.258236 -272.813852) (xy 286.302698 -272.83495) (xy 286.343201 -272.862906) (xy 286.378694 -272.896998)
			(xy 286.408259 -272.936342) (xy 286.43113 -272.979919) (xy 286.446714 -273.0266) (xy 286.454609 -273.075177)
			(xy 286.455104 -273.099784) (xy 287.743912 -273.099784) (xy 287.747872 -273.05073) (xy 287.759649 -273.002946)
			(xy 287.77894 -272.95767) (xy 287.805243 -272.916074) (xy 287.837878 -272.879237) (xy 287.875999 -272.848112)
			(xy 287.91862 -272.823505) (xy 287.964636 -272.806053) (xy 288.012855 -272.796209) (xy 288.06203 -272.794228)
			(xy 288.110885 -272.80016) (xy 288.158156 -272.813852) (xy 288.202618 -272.83495) (xy 288.243121 -272.862906)
			(xy 288.278614 -272.896998) (xy 288.308179 -272.936342) (xy 288.33105 -272.979919) (xy 288.346634 -273.0266)
			(xy 288.354529 -273.075177) (xy 288.355024 -273.099784) (xy 289.644086 -273.099784) (xy 289.648046 -273.05073)
			(xy 289.659823 -273.002946) (xy 289.679114 -272.95767) (xy 289.705417 -272.916074) (xy 289.738052 -272.879237)
			(xy 289.776173 -272.848112) (xy 289.818794 -272.823505) (xy 289.86481 -272.806053) (xy 289.913029 -272.796209)
			(xy 289.962204 -272.794228) (xy 290.011059 -272.80016) (xy 290.05833 -272.813852) (xy 290.102792 -272.83495)
			(xy 290.143295 -272.862906) (xy 290.178788 -272.896998) (xy 290.208353 -272.936342) (xy 290.231224 -272.979919)
			(xy 290.246808 -273.0266) (xy 290.254703 -273.075177) (xy 290.255193 -273.09953) (xy 291.543752 -273.09953)
			(xy 291.547712 -273.050476) (xy 291.559489 -273.002692) (xy 291.57878 -272.957416) (xy 291.605083 -272.91582)
			(xy 291.637718 -272.878983) (xy 291.675839 -272.847858) (xy 291.71846 -272.823251) (xy 291.764476 -272.805799)
			(xy 291.812695 -272.795955) (xy 291.86187 -272.793974) (xy 291.910725 -272.799906) (xy 291.957996 -272.813598)
			(xy 292.002458 -272.834696) (xy 292.042961 -272.862652) (xy 292.078454 -272.896744) (xy 292.108019 -272.936088)
			(xy 292.13089 -272.979665) (xy 292.146474 -273.026346) (xy 292.154369 -273.074923) (xy 292.154864 -273.09953)
			(xy 292.154859 -273.099784) (xy 293.443672 -273.099784) (xy 293.447632 -273.05073) (xy 293.459409 -273.002946)
			(xy 293.4787 -272.95767) (xy 293.505003 -272.916074) (xy 293.537638 -272.879237) (xy 293.575759 -272.848112)
			(xy 293.61838 -272.823505) (xy 293.664396 -272.806053) (xy 293.712615 -272.796209) (xy 293.76179 -272.794228)
			(xy 293.810645 -272.80016) (xy 293.857916 -272.813852) (xy 293.902378 -272.83495) (xy 293.942881 -272.862906)
			(xy 293.978374 -272.896998) (xy 294.007939 -272.936342) (xy 294.03081 -272.979919) (xy 294.046394 -273.0266)
			(xy 294.054289 -273.075177) (xy 294.054784 -273.099784) (xy 295.343846 -273.099784) (xy 295.347806 -273.05073)
			(xy 295.359583 -273.002946) (xy 295.378874 -272.95767) (xy 295.405177 -272.916074) (xy 295.437812 -272.879237)
			(xy 295.475933 -272.848112) (xy 295.518554 -272.823505) (xy 295.56457 -272.806053) (xy 295.612789 -272.796209)
			(xy 295.661964 -272.794228) (xy 295.710819 -272.80016) (xy 295.75809 -272.813852) (xy 295.802552 -272.83495)
			(xy 295.843055 -272.862906) (xy 295.878548 -272.896998) (xy 295.908113 -272.936342) (xy 295.930984 -272.979919)
			(xy 295.946568 -273.0266) (xy 295.954463 -273.075177) (xy 295.954958 -273.099784) (xy 297.243766 -273.099784)
			(xy 297.247726 -273.05073) (xy 297.259503 -273.002946) (xy 297.278794 -272.95767) (xy 297.305097 -272.916074)
			(xy 297.337732 -272.879237) (xy 297.375853 -272.848112) (xy 297.418474 -272.823505) (xy 297.46449 -272.806053)
			(xy 297.512709 -272.796209) (xy 297.561884 -272.794228) (xy 297.610739 -272.80016) (xy 297.65801 -272.813852)
			(xy 297.702472 -272.83495) (xy 297.742975 -272.862906) (xy 297.778468 -272.896998) (xy 297.808033 -272.936342)
			(xy 297.830904 -272.979919) (xy 297.846488 -273.0266) (xy 297.854383 -273.075177) (xy 297.854878 -273.099784)
			(xy 299.143686 -273.099784) (xy 299.147646 -273.05073) (xy 299.159423 -273.002946) (xy 299.178714 -272.95767)
			(xy 299.205017 -272.916074) (xy 299.237652 -272.879237) (xy 299.275773 -272.848112) (xy 299.318394 -272.823505)
			(xy 299.36441 -272.806053) (xy 299.412629 -272.796209) (xy 299.461804 -272.794228) (xy 299.510659 -272.80016)
			(xy 299.55793 -272.813852) (xy 299.602392 -272.83495) (xy 299.642895 -272.862906) (xy 299.678388 -272.896998)
			(xy 299.707953 -272.936342) (xy 299.730824 -272.979919) (xy 299.746408 -273.0266) (xy 299.754303 -273.075177)
			(xy 299.754798 -273.099784) (xy 301.04386 -273.099784) (xy 301.04782 -273.05073) (xy 301.059597 -273.002946)
			(xy 301.078888 -272.95767) (xy 301.105191 -272.916074) (xy 301.137826 -272.879237) (xy 301.175947 -272.848112)
			(xy 301.218568 -272.823505) (xy 301.264584 -272.806053) (xy 301.312803 -272.796209) (xy 301.361978 -272.794228)
			(xy 301.410833 -272.80016) (xy 301.458104 -272.813852) (xy 301.502566 -272.83495) (xy 301.543069 -272.862906)
			(xy 301.578562 -272.896998) (xy 301.608127 -272.936342) (xy 301.630998 -272.979919) (xy 301.646582 -273.0266)
			(xy 301.654477 -273.075177) (xy 301.654972 -273.099784) (xy 302.94378 -273.099784) (xy 302.94774 -273.05073)
			(xy 302.959517 -273.002946) (xy 302.978808 -272.95767) (xy 303.005111 -272.916074) (xy 303.037746 -272.879237)
			(xy 303.075867 -272.848112) (xy 303.118488 -272.823505) (xy 303.164504 -272.806053) (xy 303.212723 -272.796209)
			(xy 303.261898 -272.794228) (xy 303.310753 -272.80016) (xy 303.358024 -272.813852) (xy 303.402486 -272.83495)
			(xy 303.442989 -272.862906) (xy 303.478482 -272.896998) (xy 303.508047 -272.936342) (xy 303.530918 -272.979919)
			(xy 303.546502 -273.0266) (xy 303.554397 -273.075177) (xy 303.554892 -273.099784) (xy 304.8437 -273.099784)
			(xy 304.84766 -273.05073) (xy 304.859437 -273.002946) (xy 304.878728 -272.95767) (xy 304.905031 -272.916074)
			(xy 304.937666 -272.879237) (xy 304.975787 -272.848112) (xy 305.018408 -272.823505) (xy 305.064424 -272.806053)
			(xy 305.112643 -272.796209) (xy 305.161818 -272.794228) (xy 305.210673 -272.80016) (xy 305.257944 -272.813852)
			(xy 305.302406 -272.83495) (xy 305.342909 -272.862906) (xy 305.378402 -272.896998) (xy 305.407967 -272.936342)
			(xy 305.430838 -272.979919) (xy 305.446422 -273.0266) (xy 305.454317 -273.075177) (xy 305.454812 -273.099784)
			(xy 306.743874 -273.099784) (xy 306.747834 -273.05073) (xy 306.759611 -273.002946) (xy 306.778902 -272.95767)
			(xy 306.805205 -272.916074) (xy 306.83784 -272.879237) (xy 306.875961 -272.848112) (xy 306.918582 -272.823505)
			(xy 306.964598 -272.806053) (xy 307.012817 -272.796209) (xy 307.061992 -272.794228) (xy 307.110847 -272.80016)
			(xy 307.158118 -272.813852) (xy 307.20258 -272.83495) (xy 307.243083 -272.862906) (xy 307.278576 -272.896998)
			(xy 307.308141 -272.936342) (xy 307.331012 -272.979919) (xy 307.346596 -273.0266) (xy 307.354491 -273.075177)
			(xy 307.354986 -273.099784) (xy 308.643794 -273.099784) (xy 308.647754 -273.05073) (xy 308.659531 -273.002946)
			(xy 308.678822 -272.95767) (xy 308.705125 -272.916074) (xy 308.73776 -272.879237) (xy 308.775881 -272.848112)
			(xy 308.818502 -272.823505) (xy 308.864518 -272.806053) (xy 308.912737 -272.796209) (xy 308.961912 -272.794228)
			(xy 309.010767 -272.80016) (xy 309.058038 -272.813852) (xy 309.1025 -272.83495) (xy 309.143003 -272.862906)
			(xy 309.178496 -272.896998) (xy 309.208061 -272.936342) (xy 309.230932 -272.979919) (xy 309.246516 -273.0266)
			(xy 309.254411 -273.075177) (xy 309.254906 -273.099784) (xy 310.543714 -273.099784) (xy 310.547674 -273.05073)
			(xy 310.559451 -273.002946) (xy 310.578742 -272.95767) (xy 310.605045 -272.916074) (xy 310.63768 -272.879237)
			(xy 310.675801 -272.848112) (xy 310.718422 -272.823505) (xy 310.764438 -272.806053) (xy 310.812657 -272.796209)
			(xy 310.861832 -272.794228) (xy 310.910687 -272.80016) (xy 310.957958 -272.813852) (xy 311.00242 -272.83495)
			(xy 311.042923 -272.862906) (xy 311.078416 -272.896998) (xy 311.107981 -272.936342) (xy 311.130852 -272.979919)
			(xy 311.146436 -273.0266) (xy 311.154331 -273.075177) (xy 311.154826 -273.099784) (xy 312.443634 -273.099784)
			(xy 312.447594 -273.05073) (xy 312.459371 -273.002946) (xy 312.478662 -272.95767) (xy 312.504965 -272.916074)
			(xy 312.5376 -272.879237) (xy 312.575721 -272.848112) (xy 312.618342 -272.823505) (xy 312.664358 -272.806053)
			(xy 312.712577 -272.796209) (xy 312.761752 -272.794228) (xy 312.810607 -272.80016) (xy 312.857878 -272.813852)
			(xy 312.90234 -272.83495) (xy 312.942843 -272.862906) (xy 312.978336 -272.896998) (xy 313.007901 -272.936342)
			(xy 313.030772 -272.979919) (xy 313.046356 -273.0266) (xy 313.054251 -273.075177) (xy 313.054746 -273.099784)
			(xy 313.054251 -273.124391) (xy 313.046356 -273.172968) (xy 313.030772 -273.219649) (xy 313.007901 -273.263226)
			(xy 312.978336 -273.30257) (xy 312.942843 -273.336662) (xy 312.90234 -273.364618) (xy 312.857878 -273.385716)
			(xy 312.810607 -273.399408) (xy 312.761752 -273.40534) (xy 312.712577 -273.403359) (xy 312.664358 -273.393515)
			(xy 312.618342 -273.376063) (xy 312.575721 -273.351456) (xy 312.5376 -273.320331) (xy 312.504965 -273.283494)
			(xy 312.478662 -273.241898) (xy 312.459371 -273.196622) (xy 312.447594 -273.148838) (xy 312.443634 -273.099784)
			(xy 311.154826 -273.099784) (xy 311.154331 -273.124391) (xy 311.146436 -273.172968) (xy 311.130852 -273.219649)
			(xy 311.107981 -273.263226) (xy 311.078416 -273.30257) (xy 311.042923 -273.336662) (xy 311.00242 -273.364618)
			(xy 310.957958 -273.385716) (xy 310.910687 -273.399408) (xy 310.861832 -273.40534) (xy 310.812657 -273.403359)
			(xy 310.764438 -273.393515) (xy 310.718422 -273.376063) (xy 310.675801 -273.351456) (xy 310.63768 -273.320331)
			(xy 310.605045 -273.283494) (xy 310.578742 -273.241898) (xy 310.559451 -273.196622) (xy 310.547674 -273.148838)
			(xy 310.543714 -273.099784) (xy 309.254906 -273.099784) (xy 309.254411 -273.124391) (xy 309.246516 -273.172968)
			(xy 309.230932 -273.219649) (xy 309.208061 -273.263226) (xy 309.178496 -273.30257) (xy 309.143003 -273.336662)
			(xy 309.1025 -273.364618) (xy 309.058038 -273.385716) (xy 309.010767 -273.399408) (xy 308.961912 -273.40534)
			(xy 308.912737 -273.403359) (xy 308.864518 -273.393515) (xy 308.818502 -273.376063) (xy 308.775881 -273.351456)
			(xy 308.73776 -273.320331) (xy 308.705125 -273.283494) (xy 308.678822 -273.241898) (xy 308.659531 -273.196622)
			(xy 308.647754 -273.148838) (xy 308.643794 -273.099784) (xy 307.354986 -273.099784) (xy 307.354491 -273.124391)
			(xy 307.346596 -273.172968) (xy 307.331012 -273.219649) (xy 307.308141 -273.263226) (xy 307.278576 -273.30257)
			(xy 307.243083 -273.336662) (xy 307.20258 -273.364618) (xy 307.158118 -273.385716) (xy 307.110847 -273.399408)
			(xy 307.061992 -273.40534) (xy 307.012817 -273.403359) (xy 306.964598 -273.393515) (xy 306.918582 -273.376063)
			(xy 306.875961 -273.351456) (xy 306.83784 -273.320331) (xy 306.805205 -273.283494) (xy 306.778902 -273.241898)
			(xy 306.759611 -273.196622) (xy 306.747834 -273.148838) (xy 306.743874 -273.099784) (xy 305.454812 -273.099784)
			(xy 305.454317 -273.124391) (xy 305.446422 -273.172968) (xy 305.430838 -273.219649) (xy 305.407967 -273.263226)
			(xy 305.378402 -273.30257) (xy 305.342909 -273.336662) (xy 305.302406 -273.364618) (xy 305.257944 -273.385716)
			(xy 305.210673 -273.399408) (xy 305.161818 -273.40534) (xy 305.112643 -273.403359) (xy 305.064424 -273.393515)
			(xy 305.018408 -273.376063) (xy 304.975787 -273.351456) (xy 304.937666 -273.320331) (xy 304.905031 -273.283494)
			(xy 304.878728 -273.241898) (xy 304.859437 -273.196622) (xy 304.84766 -273.148838) (xy 304.8437 -273.099784)
			(xy 303.554892 -273.099784) (xy 303.554397 -273.124391) (xy 303.546502 -273.172968) (xy 303.530918 -273.219649)
			(xy 303.508047 -273.263226) (xy 303.478482 -273.30257) (xy 303.442989 -273.336662) (xy 303.402486 -273.364618)
			(xy 303.358024 -273.385716) (xy 303.310753 -273.399408) (xy 303.261898 -273.40534) (xy 303.212723 -273.403359)
			(xy 303.164504 -273.393515) (xy 303.118488 -273.376063) (xy 303.075867 -273.351456) (xy 303.037746 -273.320331)
			(xy 303.005111 -273.283494) (xy 302.978808 -273.241898) (xy 302.959517 -273.196622) (xy 302.94774 -273.148838)
			(xy 302.94378 -273.099784) (xy 301.654972 -273.099784) (xy 301.654477 -273.124391) (xy 301.646582 -273.172968)
			(xy 301.630998 -273.219649) (xy 301.608127 -273.263226) (xy 301.578562 -273.30257) (xy 301.543069 -273.336662)
			(xy 301.502566 -273.364618) (xy 301.458104 -273.385716) (xy 301.410833 -273.399408) (xy 301.361978 -273.40534)
			(xy 301.312803 -273.403359) (xy 301.264584 -273.393515) (xy 301.218568 -273.376063) (xy 301.175947 -273.351456)
			(xy 301.137826 -273.320331) (xy 301.105191 -273.283494) (xy 301.078888 -273.241898) (xy 301.059597 -273.196622)
			(xy 301.04782 -273.148838) (xy 301.04386 -273.099784) (xy 299.754798 -273.099784) (xy 299.754303 -273.124391)
			(xy 299.746408 -273.172968) (xy 299.730824 -273.219649) (xy 299.707953 -273.263226) (xy 299.678388 -273.30257)
			(xy 299.642895 -273.336662) (xy 299.602392 -273.364618) (xy 299.55793 -273.385716) (xy 299.510659 -273.399408)
			(xy 299.461804 -273.40534) (xy 299.412629 -273.403359) (xy 299.36441 -273.393515) (xy 299.318394 -273.376063)
			(xy 299.275773 -273.351456) (xy 299.237652 -273.320331) (xy 299.205017 -273.283494) (xy 299.178714 -273.241898)
			(xy 299.159423 -273.196622) (xy 299.147646 -273.148838) (xy 299.143686 -273.099784) (xy 297.854878 -273.099784)
			(xy 297.854383 -273.124391) (xy 297.846488 -273.172968) (xy 297.830904 -273.219649) (xy 297.808033 -273.263226)
			(xy 297.778468 -273.30257) (xy 297.742975 -273.336662) (xy 297.702472 -273.364618) (xy 297.65801 -273.385716)
			(xy 297.610739 -273.399408) (xy 297.561884 -273.40534) (xy 297.512709 -273.403359) (xy 297.46449 -273.393515)
			(xy 297.418474 -273.376063) (xy 297.375853 -273.351456) (xy 297.337732 -273.320331) (xy 297.305097 -273.283494)
			(xy 297.278794 -273.241898) (xy 297.259503 -273.196622) (xy 297.247726 -273.148838) (xy 297.243766 -273.099784)
			(xy 295.954958 -273.099784) (xy 295.954463 -273.124391) (xy 295.946568 -273.172968) (xy 295.930984 -273.219649)
			(xy 295.908113 -273.263226) (xy 295.878548 -273.30257) (xy 295.843055 -273.336662) (xy 295.802552 -273.364618)
			(xy 295.75809 -273.385716) (xy 295.710819 -273.399408) (xy 295.661964 -273.40534) (xy 295.612789 -273.403359)
			(xy 295.56457 -273.393515) (xy 295.518554 -273.376063) (xy 295.475933 -273.351456) (xy 295.437812 -273.320331)
			(xy 295.405177 -273.283494) (xy 295.378874 -273.241898) (xy 295.359583 -273.196622) (xy 295.347806 -273.148838)
			(xy 295.343846 -273.099784) (xy 294.054784 -273.099784) (xy 294.054289 -273.124391) (xy 294.046394 -273.172968)
			(xy 294.03081 -273.219649) (xy 294.007939 -273.263226) (xy 293.978374 -273.30257) (xy 293.942881 -273.336662)
			(xy 293.902378 -273.364618) (xy 293.857916 -273.385716) (xy 293.810645 -273.399408) (xy 293.76179 -273.40534)
			(xy 293.712615 -273.403359) (xy 293.664396 -273.393515) (xy 293.61838 -273.376063) (xy 293.575759 -273.351456)
			(xy 293.537638 -273.320331) (xy 293.505003 -273.283494) (xy 293.4787 -273.241898) (xy 293.459409 -273.196622)
			(xy 293.447632 -273.148838) (xy 293.443672 -273.099784) (xy 292.154859 -273.099784) (xy 292.154369 -273.124137)
			(xy 292.146474 -273.172714) (xy 292.13089 -273.219395) (xy 292.108019 -273.262972) (xy 292.078454 -273.302316)
			(xy 292.042961 -273.336408) (xy 292.002458 -273.364364) (xy 291.957996 -273.385462) (xy 291.910725 -273.399154)
			(xy 291.86187 -273.405086) (xy 291.812695 -273.403105) (xy 291.764476 -273.393261) (xy 291.71846 -273.375809)
			(xy 291.675839 -273.351202) (xy 291.637718 -273.320077) (xy 291.605083 -273.28324) (xy 291.57878 -273.241644)
			(xy 291.559489 -273.196368) (xy 291.547712 -273.148584) (xy 291.543752 -273.09953) (xy 290.255193 -273.09953)
			(xy 290.255198 -273.099784) (xy 290.254703 -273.124391) (xy 290.246808 -273.172968) (xy 290.231224 -273.219649)
			(xy 290.208353 -273.263226) (xy 290.178788 -273.30257) (xy 290.143295 -273.336662) (xy 290.102792 -273.364618)
			(xy 290.05833 -273.385716) (xy 290.011059 -273.399408) (xy 289.962204 -273.40534) (xy 289.913029 -273.403359)
			(xy 289.86481 -273.393515) (xy 289.818794 -273.376063) (xy 289.776173 -273.351456) (xy 289.738052 -273.320331)
			(xy 289.705417 -273.283494) (xy 289.679114 -273.241898) (xy 289.659823 -273.196622) (xy 289.648046 -273.148838)
			(xy 289.644086 -273.099784) (xy 288.355024 -273.099784) (xy 288.354529 -273.124391) (xy 288.346634 -273.172968)
			(xy 288.33105 -273.219649) (xy 288.308179 -273.263226) (xy 288.278614 -273.30257) (xy 288.243121 -273.336662)
			(xy 288.202618 -273.364618) (xy 288.158156 -273.385716) (xy 288.110885 -273.399408) (xy 288.06203 -273.40534)
			(xy 288.012855 -273.403359) (xy 287.964636 -273.393515) (xy 287.91862 -273.376063) (xy 287.875999 -273.351456)
			(xy 287.837878 -273.320331) (xy 287.805243 -273.283494) (xy 287.77894 -273.241898) (xy 287.759649 -273.196622)
			(xy 287.747872 -273.148838) (xy 287.743912 -273.099784) (xy 286.455104 -273.099784) (xy 286.454609 -273.124391)
			(xy 286.446714 -273.172968) (xy 286.43113 -273.219649) (xy 286.408259 -273.263226) (xy 286.378694 -273.30257)
			(xy 286.343201 -273.336662) (xy 286.302698 -273.364618) (xy 286.258236 -273.385716) (xy 286.210965 -273.399408)
			(xy 286.16211 -273.40534) (xy 286.112935 -273.403359) (xy 286.064716 -273.393515) (xy 286.0187 -273.376063)
			(xy 285.976079 -273.351456) (xy 285.937958 -273.320331) (xy 285.905323 -273.283494) (xy 285.87902 -273.241898)
			(xy 285.859729 -273.196622) (xy 285.847952 -273.148838) (xy 285.843992 -273.099784) (xy 284.555184 -273.099784)
			(xy 284.554689 -273.124391) (xy 284.546794 -273.172968) (xy 284.53121 -273.219649) (xy 284.508339 -273.263226)
			(xy 284.478774 -273.30257) (xy 284.443281 -273.336662) (xy 284.402778 -273.364618) (xy 284.358316 -273.385716)
			(xy 284.311045 -273.399408) (xy 284.26219 -273.40534) (xy 284.213015 -273.403359) (xy 284.164796 -273.393515)
			(xy 284.11878 -273.376063) (xy 284.076159 -273.351456) (xy 284.038038 -273.320331) (xy 284.005403 -273.283494)
			(xy 283.9791 -273.241898) (xy 283.959809 -273.196622) (xy 283.948032 -273.148838) (xy 283.944072 -273.099784)
			(xy 282.65501 -273.099784) (xy 282.654515 -273.124391) (xy 282.64662 -273.172968) (xy 282.631036 -273.219649)
			(xy 282.608165 -273.263226) (xy 282.5786 -273.30257) (xy 282.543107 -273.336662) (xy 282.502604 -273.364618)
			(xy 282.458142 -273.385716) (xy 282.410871 -273.399408) (xy 282.362016 -273.40534) (xy 282.312841 -273.403359)
			(xy 282.264622 -273.393515) (xy 282.218606 -273.376063) (xy 282.175985 -273.351456) (xy 282.137864 -273.320331)
			(xy 282.105229 -273.283494) (xy 282.078926 -273.241898) (xy 282.059635 -273.196622) (xy 282.047858 -273.148838)
			(xy 282.043898 -273.099784) (xy 280.75509 -273.099784) (xy 280.754595 -273.124391) (xy 280.7467 -273.172968)
			(xy 280.731116 -273.219649) (xy 280.708245 -273.263226) (xy 280.67868 -273.30257) (xy 280.643187 -273.336662)
			(xy 280.602684 -273.364618) (xy 280.558222 -273.385716) (xy 280.510951 -273.399408) (xy 280.462096 -273.40534)
			(xy 280.412921 -273.403359) (xy 280.364702 -273.393515) (xy 280.318686 -273.376063) (xy 280.276065 -273.351456)
			(xy 280.237944 -273.320331) (xy 280.205309 -273.283494) (xy 280.179006 -273.241898) (xy 280.159715 -273.196622)
			(xy 280.147938 -273.148838) (xy 280.143978 -273.099784) (xy 278.85517 -273.099784) (xy 278.854675 -273.124391)
			(xy 278.84678 -273.172968) (xy 278.831196 -273.219649) (xy 278.808325 -273.263226) (xy 278.77876 -273.30257)
			(xy 278.743267 -273.336662) (xy 278.702764 -273.364618) (xy 278.658302 -273.385716) (xy 278.611031 -273.399408)
			(xy 278.562176 -273.40534) (xy 278.513001 -273.403359) (xy 278.464782 -273.393515) (xy 278.418766 -273.376063)
			(xy 278.376145 -273.351456) (xy 278.338024 -273.320331) (xy 278.305389 -273.283494) (xy 278.279086 -273.241898)
			(xy 278.259795 -273.196622) (xy 278.248018 -273.148838) (xy 278.244058 -273.099784) (xy 276.954996 -273.099784)
			(xy 276.954501 -273.124391) (xy 276.946606 -273.172968) (xy 276.931022 -273.219649) (xy 276.908151 -273.263226)
			(xy 276.878586 -273.30257) (xy 276.843093 -273.336662) (xy 276.80259 -273.364618) (xy 276.758128 -273.385716)
			(xy 276.710857 -273.399408) (xy 276.662002 -273.40534) (xy 276.612827 -273.403359) (xy 276.564608 -273.393515)
			(xy 276.518592 -273.376063) (xy 276.475971 -273.351456) (xy 276.43785 -273.320331) (xy 276.405215 -273.283494)
			(xy 276.378912 -273.241898) (xy 276.359621 -273.196622) (xy 276.347844 -273.148838) (xy 276.343884 -273.099784)
			(xy 263.527168 -273.099784) (xy 263.482466 -273.134324) (xy 263.360176 -273.218735) (xy 263.233531 -273.29646)
			(xy 263.102896 -273.367276) (xy 262.968649 -273.430977) (xy 262.831176 -273.48738) (xy 262.690873 -273.536323)
			(xy 262.548146 -273.577665) (xy 262.403405 -273.611285) (xy 262.257069 -273.637088) (xy 262.109558 -273.654999)
			(xy 261.961299 -273.664967) (xy 261.812718 -273.666962) (xy 261.664245 -273.660978) (xy 261.516306 -273.647034)
			(xy 261.36933 -273.625169) (xy 261.223739 -273.595447) (xy 261.079953 -273.557952) (xy 260.938387 -273.512793)
			(xy 260.799449 -273.460101) (xy 260.66354 -273.400027) (xy 260.531051 -273.332745) (xy 260.402365 -273.258448)
			(xy 260.277852 -273.177351) (xy 260.157872 -273.089687) (xy 260.042771 -272.995709) (xy 259.932879 -272.895689)
			(xy 259.828515 -272.789914) (xy 259.729979 -272.67869) (xy 259.637555 -272.562337) (xy 259.55151 -272.44119)
			(xy 259.472092 -272.3156) (xy 259.399529 -272.185928) (xy 259.334031 -272.052548) (xy 259.275787 -271.915845)
			(xy 259.224965 -271.776212) (xy 259.181711 -271.634053) (xy 259.14615 -271.489776) (xy 259.118385 -271.3438)
			(xy 259.098495 -271.196543) (xy 259.086538 -271.04843) (xy 259.082549 -270.89989) (xy 208.516474 -270.89989)
			(xy 208.515975 -270.974187) (xy 208.507999 -271.122567) (xy 208.49207 -271.270305) (xy 208.468234 -271.416974)
			(xy 208.43656 -271.562153) (xy 208.397138 -271.705423) (xy 208.350083 -271.84637) (xy 208.29553 -271.984587)
			(xy 208.233637 -272.119678) (xy 208.164582 -272.251251) (xy 208.088564 -272.378929) (xy 208.005803 -272.502341)
			(xy 207.916536 -272.621134) (xy 207.821022 -272.734963) (xy 207.719535 -272.843502) (xy 207.612368 -272.946437)
			(xy 207.499831 -273.043471) (xy 207.382248 -273.134324) (xy 207.259958 -273.218735) (xy 207.133313 -273.29646)
			(xy 207.002678 -273.367276) (xy 206.868431 -273.430977) (xy 206.730958 -273.48738) (xy 206.590655 -273.536323)
			(xy 206.447928 -273.577665) (xy 206.303187 -273.611285) (xy 206.156851 -273.637088) (xy 206.00934 -273.654999)
			(xy 205.861081 -273.664967) (xy 205.7125 -273.666962) (xy 205.564027 -273.660978) (xy 205.416088 -273.647034)
			(xy 205.269112 -273.625169) (xy 205.123521 -273.595447) (xy 204.979735 -273.557952) (xy 204.838169 -273.512793)
			(xy 204.699231 -273.460101) (xy 204.563322 -273.400027) (xy 204.430833 -273.332745) (xy 204.302147 -273.258448)
			(xy 204.177634 -273.177351) (xy 204.057654 -273.089687) (xy 203.942553 -272.995709) (xy 203.832661 -272.895689)
			(xy 203.728297 -272.789914) (xy 203.629761 -272.67869) (xy 203.537337 -272.562337) (xy 203.451292 -272.44119)
			(xy 203.371874 -272.3156) (xy 203.299311 -272.185928) (xy 203.233813 -272.052548) (xy 203.175569 -271.915845)
			(xy 203.124747 -271.776212) (xy 203.081493 -271.634053) (xy 203.045932 -271.489776) (xy 203.018167 -271.3438)
			(xy 202.998277 -271.196543) (xy 202.98632 -271.04843) (xy 202.982331 -270.89989) (xy 148.516594 -270.89989)
			(xy 148.516095 -270.974187) (xy 148.508119 -271.122567) (xy 148.49219 -271.270305) (xy 148.468354 -271.416974)
			(xy 148.43668 -271.562153) (xy 148.397258 -271.705423) (xy 148.350203 -271.84637) (xy 148.29565 -271.984587)
			(xy 148.233757 -272.119678) (xy 148.164702 -272.251251) (xy 148.088684 -272.378929) (xy 148.005923 -272.502341)
			(xy 147.916656 -272.621134) (xy 147.821142 -272.734963) (xy 147.719655 -272.843502) (xy 147.612488 -272.946437)
			(xy 147.499951 -273.043471) (xy 147.42707 -273.099784) (xy 160.24404 -273.099784) (xy 160.248 -273.05073)
			(xy 160.259777 -273.002946) (xy 160.279068 -272.95767) (xy 160.305371 -272.916074) (xy 160.338006 -272.879237)
			(xy 160.376127 -272.848112) (xy 160.418748 -272.823505) (xy 160.464764 -272.806053) (xy 160.512983 -272.796209)
			(xy 160.562158 -272.794228) (xy 160.611013 -272.80016) (xy 160.658284 -272.813852) (xy 160.702746 -272.83495)
			(xy 160.743249 -272.862906) (xy 160.778742 -272.896998) (xy 160.808307 -272.936342) (xy 160.831178 -272.979919)
			(xy 160.846762 -273.0266) (xy 160.854657 -273.075177) (xy 160.855152 -273.099784) (xy 162.144214 -273.099784)
			(xy 162.148174 -273.05073) (xy 162.159951 -273.002946) (xy 162.179242 -272.95767) (xy 162.205545 -272.916074)
			(xy 162.23818 -272.879237) (xy 162.276301 -272.848112) (xy 162.318922 -272.823505) (xy 162.364938 -272.806053)
			(xy 162.413157 -272.796209) (xy 162.462332 -272.794228) (xy 162.511187 -272.80016) (xy 162.558458 -272.813852)
			(xy 162.60292 -272.83495) (xy 162.643423 -272.862906) (xy 162.678916 -272.896998) (xy 162.708481 -272.936342)
			(xy 162.731352 -272.979919) (xy 162.746936 -273.0266) (xy 162.754831 -273.075177) (xy 162.755326 -273.099784)
			(xy 164.044134 -273.099784) (xy 164.048094 -273.05073) (xy 164.059871 -273.002946) (xy 164.079162 -272.95767)
			(xy 164.105465 -272.916074) (xy 164.1381 -272.879237) (xy 164.176221 -272.848112) (xy 164.218842 -272.823505)
			(xy 164.264858 -272.806053) (xy 164.313077 -272.796209) (xy 164.362252 -272.794228) (xy 164.411107 -272.80016)
			(xy 164.458378 -272.813852) (xy 164.50284 -272.83495) (xy 164.543343 -272.862906) (xy 164.578836 -272.896998)
			(xy 164.608401 -272.936342) (xy 164.631272 -272.979919) (xy 164.646856 -273.0266) (xy 164.654751 -273.075177)
			(xy 164.655246 -273.099784) (xy 165.944054 -273.099784) (xy 165.948014 -273.05073) (xy 165.959791 -273.002946)
			(xy 165.979082 -272.95767) (xy 166.005385 -272.916074) (xy 166.03802 -272.879237) (xy 166.076141 -272.848112)
			(xy 166.118762 -272.823505) (xy 166.164778 -272.806053) (xy 166.212997 -272.796209) (xy 166.262172 -272.794228)
			(xy 166.311027 -272.80016) (xy 166.358298 -272.813852) (xy 166.40276 -272.83495) (xy 166.443263 -272.862906)
			(xy 166.478756 -272.896998) (xy 166.508321 -272.936342) (xy 166.531192 -272.979919) (xy 166.546776 -273.0266)
			(xy 166.554671 -273.075177) (xy 166.555166 -273.099784) (xy 167.844228 -273.099784) (xy 167.848188 -273.05073)
			(xy 167.859965 -273.002946) (xy 167.879256 -272.95767) (xy 167.905559 -272.916074) (xy 167.938194 -272.879237)
			(xy 167.976315 -272.848112) (xy 168.018936 -272.823505) (xy 168.064952 -272.806053) (xy 168.113171 -272.796209)
			(xy 168.162346 -272.794228) (xy 168.211201 -272.80016) (xy 168.258472 -272.813852) (xy 168.302934 -272.83495)
			(xy 168.343437 -272.862906) (xy 168.37893 -272.896998) (xy 168.408495 -272.936342) (xy 168.431366 -272.979919)
			(xy 168.44695 -273.0266) (xy 168.454845 -273.075177) (xy 168.45534 -273.099784) (xy 169.744148 -273.099784)
			(xy 169.748108 -273.05073) (xy 169.759885 -273.002946) (xy 169.779176 -272.95767) (xy 169.805479 -272.916074)
			(xy 169.838114 -272.879237) (xy 169.876235 -272.848112) (xy 169.918856 -272.823505) (xy 169.964872 -272.806053)
			(xy 170.013091 -272.796209) (xy 170.062266 -272.794228) (xy 170.111121 -272.80016) (xy 170.158392 -272.813852)
			(xy 170.202854 -272.83495) (xy 170.243357 -272.862906) (xy 170.27885 -272.896998) (xy 170.308415 -272.936342)
			(xy 170.331286 -272.979919) (xy 170.34687 -273.0266) (xy 170.354765 -273.075177) (xy 170.35526 -273.099784)
			(xy 171.644068 -273.099784) (xy 171.648028 -273.05073) (xy 171.659805 -273.002946) (xy 171.679096 -272.95767)
			(xy 171.705399 -272.916074) (xy 171.738034 -272.879237) (xy 171.776155 -272.848112) (xy 171.818776 -272.823505)
			(xy 171.864792 -272.806053) (xy 171.913011 -272.796209) (xy 171.962186 -272.794228) (xy 172.011041 -272.80016)
			(xy 172.058312 -272.813852) (xy 172.102774 -272.83495) (xy 172.143277 -272.862906) (xy 172.17877 -272.896998)
			(xy 172.208335 -272.936342) (xy 172.231206 -272.979919) (xy 172.24679 -273.0266) (xy 172.254685 -273.075177)
			(xy 172.25518 -273.099784) (xy 173.544242 -273.099784) (xy 173.548202 -273.05073) (xy 173.559979 -273.002946)
			(xy 173.57927 -272.95767) (xy 173.605573 -272.916074) (xy 173.638208 -272.879237) (xy 173.676329 -272.848112)
			(xy 173.71895 -272.823505) (xy 173.764966 -272.806053) (xy 173.813185 -272.796209) (xy 173.86236 -272.794228)
			(xy 173.911215 -272.80016) (xy 173.958486 -272.813852) (xy 174.002948 -272.83495) (xy 174.043451 -272.862906)
			(xy 174.078944 -272.896998) (xy 174.108509 -272.936342) (xy 174.13138 -272.979919) (xy 174.146964 -273.0266)
			(xy 174.154859 -273.075177) (xy 174.155349 -273.09953) (xy 175.443908 -273.09953) (xy 175.447868 -273.050476)
			(xy 175.459645 -273.002692) (xy 175.478936 -272.957416) (xy 175.505239 -272.91582) (xy 175.537874 -272.878983)
			(xy 175.575995 -272.847858) (xy 175.618616 -272.823251) (xy 175.664632 -272.805799) (xy 175.712851 -272.795955)
			(xy 175.762026 -272.793974) (xy 175.810881 -272.799906) (xy 175.858152 -272.813598) (xy 175.902614 -272.834696)
			(xy 175.943117 -272.862652) (xy 175.97861 -272.896744) (xy 176.008175 -272.936088) (xy 176.031046 -272.979665)
			(xy 176.04663 -273.026346) (xy 176.054525 -273.074923) (xy 176.05502 -273.09953) (xy 176.055015 -273.099784)
			(xy 177.343828 -273.099784) (xy 177.347788 -273.05073) (xy 177.359565 -273.002946) (xy 177.378856 -272.95767)
			(xy 177.405159 -272.916074) (xy 177.437794 -272.879237) (xy 177.475915 -272.848112) (xy 177.518536 -272.823505)
			(xy 177.564552 -272.806053) (xy 177.612771 -272.796209) (xy 177.661946 -272.794228) (xy 177.710801 -272.80016)
			(xy 177.758072 -272.813852) (xy 177.802534 -272.83495) (xy 177.843037 -272.862906) (xy 177.87853 -272.896998)
			(xy 177.908095 -272.936342) (xy 177.930966 -272.979919) (xy 177.94655 -273.0266) (xy 177.954445 -273.075177)
			(xy 177.95494 -273.099784) (xy 179.244002 -273.099784) (xy 179.247962 -273.05073) (xy 179.259739 -273.002946)
			(xy 179.27903 -272.95767) (xy 179.305333 -272.916074) (xy 179.337968 -272.879237) (xy 179.376089 -272.848112)
			(xy 179.41871 -272.823505) (xy 179.464726 -272.806053) (xy 179.512945 -272.796209) (xy 179.56212 -272.794228)
			(xy 179.610975 -272.80016) (xy 179.658246 -272.813852) (xy 179.702708 -272.83495) (xy 179.743211 -272.862906)
			(xy 179.778704 -272.896998) (xy 179.808269 -272.936342) (xy 179.83114 -272.979919) (xy 179.846724 -273.0266)
			(xy 179.854619 -273.075177) (xy 179.855114 -273.099784) (xy 181.143922 -273.099784) (xy 181.147882 -273.05073)
			(xy 181.159659 -273.002946) (xy 181.17895 -272.95767) (xy 181.205253 -272.916074) (xy 181.237888 -272.879237)
			(xy 181.276009 -272.848112) (xy 181.31863 -272.823505) (xy 181.364646 -272.806053) (xy 181.412865 -272.796209)
			(xy 181.46204 -272.794228) (xy 181.510895 -272.80016) (xy 181.558166 -272.813852) (xy 181.602628 -272.83495)
			(xy 181.643131 -272.862906) (xy 181.678624 -272.896998) (xy 181.708189 -272.936342) (xy 181.73106 -272.979919)
			(xy 181.746644 -273.0266) (xy 181.754539 -273.075177) (xy 181.755034 -273.099784) (xy 183.043842 -273.099784)
			(xy 183.047802 -273.05073) (xy 183.059579 -273.002946) (xy 183.07887 -272.95767) (xy 183.105173 -272.916074)
			(xy 183.137808 -272.879237) (xy 183.175929 -272.848112) (xy 183.21855 -272.823505) (xy 183.264566 -272.806053)
			(xy 183.312785 -272.796209) (xy 183.36196 -272.794228) (xy 183.410815 -272.80016) (xy 183.458086 -272.813852)
			(xy 183.502548 -272.83495) (xy 183.543051 -272.862906) (xy 183.578544 -272.896998) (xy 183.608109 -272.936342)
			(xy 183.63098 -272.979919) (xy 183.646564 -273.0266) (xy 183.654459 -273.075177) (xy 183.654954 -273.099784)
			(xy 184.944016 -273.099784) (xy 184.947976 -273.05073) (xy 184.959753 -273.002946) (xy 184.979044 -272.95767)
			(xy 185.005347 -272.916074) (xy 185.037982 -272.879237) (xy 185.076103 -272.848112) (xy 185.118724 -272.823505)
			(xy 185.16474 -272.806053) (xy 185.212959 -272.796209) (xy 185.262134 -272.794228) (xy 185.310989 -272.80016)
			(xy 185.35826 -272.813852) (xy 185.402722 -272.83495) (xy 185.443225 -272.862906) (xy 185.478718 -272.896998)
			(xy 185.508283 -272.936342) (xy 185.531154 -272.979919) (xy 185.546738 -273.0266) (xy 185.554633 -273.075177)
			(xy 185.555128 -273.099784) (xy 186.843936 -273.099784) (xy 186.847896 -273.05073) (xy 186.859673 -273.002946)
			(xy 186.878964 -272.95767) (xy 186.905267 -272.916074) (xy 186.937902 -272.879237) (xy 186.976023 -272.848112)
			(xy 187.018644 -272.823505) (xy 187.06466 -272.806053) (xy 187.112879 -272.796209) (xy 187.162054 -272.794228)
			(xy 187.210909 -272.80016) (xy 187.25818 -272.813852) (xy 187.302642 -272.83495) (xy 187.343145 -272.862906)
			(xy 187.378638 -272.896998) (xy 187.408203 -272.936342) (xy 187.431074 -272.979919) (xy 187.446658 -273.0266)
			(xy 187.454553 -273.075177) (xy 187.455048 -273.099784) (xy 188.743856 -273.099784) (xy 188.747816 -273.05073)
			(xy 188.759593 -273.002946) (xy 188.778884 -272.95767) (xy 188.805187 -272.916074) (xy 188.837822 -272.879237)
			(xy 188.875943 -272.848112) (xy 188.918564 -272.823505) (xy 188.96458 -272.806053) (xy 189.012799 -272.796209)
			(xy 189.061974 -272.794228) (xy 189.110829 -272.80016) (xy 189.1581 -272.813852) (xy 189.202562 -272.83495)
			(xy 189.243065 -272.862906) (xy 189.278558 -272.896998) (xy 189.308123 -272.936342) (xy 189.330994 -272.979919)
			(xy 189.346578 -273.0266) (xy 189.354473 -273.075177) (xy 189.354968 -273.099784) (xy 190.64403 -273.099784)
			(xy 190.64799 -273.05073) (xy 190.659767 -273.002946) (xy 190.679058 -272.95767) (xy 190.705361 -272.916074)
			(xy 190.737996 -272.879237) (xy 190.776117 -272.848112) (xy 190.818738 -272.823505) (xy 190.864754 -272.806053)
			(xy 190.912973 -272.796209) (xy 190.962148 -272.794228) (xy 191.011003 -272.80016) (xy 191.058274 -272.813852)
			(xy 191.102736 -272.83495) (xy 191.143239 -272.862906) (xy 191.178732 -272.896998) (xy 191.208297 -272.936342)
			(xy 191.231168 -272.979919) (xy 191.246752 -273.0266) (xy 191.254647 -273.075177) (xy 191.255142 -273.099784)
			(xy 192.54395 -273.099784) (xy 192.54791 -273.05073) (xy 192.559687 -273.002946) (xy 192.578978 -272.95767)
			(xy 192.605281 -272.916074) (xy 192.637916 -272.879237) (xy 192.676037 -272.848112) (xy 192.718658 -272.823505)
			(xy 192.764674 -272.806053) (xy 192.812893 -272.796209) (xy 192.862068 -272.794228) (xy 192.910923 -272.80016)
			(xy 192.958194 -272.813852) (xy 193.002656 -272.83495) (xy 193.043159 -272.862906) (xy 193.078652 -272.896998)
			(xy 193.108217 -272.936342) (xy 193.131088 -272.979919) (xy 193.146672 -273.0266) (xy 193.154567 -273.075177)
			(xy 193.155062 -273.099784) (xy 194.44387 -273.099784) (xy 194.44783 -273.05073) (xy 194.459607 -273.002946)
			(xy 194.478898 -272.95767) (xy 194.505201 -272.916074) (xy 194.537836 -272.879237) (xy 194.575957 -272.848112)
			(xy 194.618578 -272.823505) (xy 194.664594 -272.806053) (xy 194.712813 -272.796209) (xy 194.761988 -272.794228)
			(xy 194.810843 -272.80016) (xy 194.858114 -272.813852) (xy 194.902576 -272.83495) (xy 194.943079 -272.862906)
			(xy 194.978572 -272.896998) (xy 195.008137 -272.936342) (xy 195.031008 -272.979919) (xy 195.046592 -273.0266)
			(xy 195.054487 -273.075177) (xy 195.054982 -273.099784) (xy 196.34379 -273.099784) (xy 196.34775 -273.05073)
			(xy 196.359527 -273.002946) (xy 196.378818 -272.95767) (xy 196.405121 -272.916074) (xy 196.437756 -272.879237)
			(xy 196.475877 -272.848112) (xy 196.518498 -272.823505) (xy 196.564514 -272.806053) (xy 196.612733 -272.796209)
			(xy 196.661908 -272.794228) (xy 196.710763 -272.80016) (xy 196.758034 -272.813852) (xy 196.802496 -272.83495)
			(xy 196.842999 -272.862906) (xy 196.878492 -272.896998) (xy 196.908057 -272.936342) (xy 196.930928 -272.979919)
			(xy 196.946512 -273.0266) (xy 196.954407 -273.075177) (xy 196.954902 -273.099784) (xy 196.954407 -273.124391)
			(xy 196.946512 -273.172968) (xy 196.930928 -273.219649) (xy 196.908057 -273.263226) (xy 196.878492 -273.30257)
			(xy 196.842999 -273.336662) (xy 196.802496 -273.364618) (xy 196.758034 -273.385716) (xy 196.710763 -273.399408)
			(xy 196.661908 -273.40534) (xy 196.612733 -273.403359) (xy 196.564514 -273.393515) (xy 196.518498 -273.376063)
			(xy 196.475877 -273.351456) (xy 196.437756 -273.320331) (xy 196.405121 -273.283494) (xy 196.378818 -273.241898)
			(xy 196.359527 -273.196622) (xy 196.34775 -273.148838) (xy 196.34379 -273.099784) (xy 195.054982 -273.099784)
			(xy 195.054487 -273.124391) (xy 195.046592 -273.172968) (xy 195.031008 -273.219649) (xy 195.008137 -273.263226)
			(xy 194.978572 -273.30257) (xy 194.943079 -273.336662) (xy 194.902576 -273.364618) (xy 194.858114 -273.385716)
			(xy 194.810843 -273.399408) (xy 194.761988 -273.40534) (xy 194.712813 -273.403359) (xy 194.664594 -273.393515)
			(xy 194.618578 -273.376063) (xy 194.575957 -273.351456) (xy 194.537836 -273.320331) (xy 194.505201 -273.283494)
			(xy 194.478898 -273.241898) (xy 194.459607 -273.196622) (xy 194.44783 -273.148838) (xy 194.44387 -273.099784)
			(xy 193.155062 -273.099784) (xy 193.154567 -273.124391) (xy 193.146672 -273.172968) (xy 193.131088 -273.219649)
			(xy 193.108217 -273.263226) (xy 193.078652 -273.30257) (xy 193.043159 -273.336662) (xy 193.002656 -273.364618)
			(xy 192.958194 -273.385716) (xy 192.910923 -273.399408) (xy 192.862068 -273.40534) (xy 192.812893 -273.403359)
			(xy 192.764674 -273.393515) (xy 192.718658 -273.376063) (xy 192.676037 -273.351456) (xy 192.637916 -273.320331)
			(xy 192.605281 -273.283494) (xy 192.578978 -273.241898) (xy 192.559687 -273.196622) (xy 192.54791 -273.148838)
			(xy 192.54395 -273.099784) (xy 191.255142 -273.099784) (xy 191.254647 -273.124391) (xy 191.246752 -273.172968)
			(xy 191.231168 -273.219649) (xy 191.208297 -273.263226) (xy 191.178732 -273.30257) (xy 191.143239 -273.336662)
			(xy 191.102736 -273.364618) (xy 191.058274 -273.385716) (xy 191.011003 -273.399408) (xy 190.962148 -273.40534)
			(xy 190.912973 -273.403359) (xy 190.864754 -273.393515) (xy 190.818738 -273.376063) (xy 190.776117 -273.351456)
			(xy 190.737996 -273.320331) (xy 190.705361 -273.283494) (xy 190.679058 -273.241898) (xy 190.659767 -273.196622)
			(xy 190.64799 -273.148838) (xy 190.64403 -273.099784) (xy 189.354968 -273.099784) (xy 189.354473 -273.124391)
			(xy 189.346578 -273.172968) (xy 189.330994 -273.219649) (xy 189.308123 -273.263226) (xy 189.278558 -273.30257)
			(xy 189.243065 -273.336662) (xy 189.202562 -273.364618) (xy 189.1581 -273.385716) (xy 189.110829 -273.399408)
			(xy 189.061974 -273.40534) (xy 189.012799 -273.403359) (xy 188.96458 -273.393515) (xy 188.918564 -273.376063)
			(xy 188.875943 -273.351456) (xy 188.837822 -273.320331) (xy 188.805187 -273.283494) (xy 188.778884 -273.241898)
			(xy 188.759593 -273.196622) (xy 188.747816 -273.148838) (xy 188.743856 -273.099784) (xy 187.455048 -273.099784)
			(xy 187.454553 -273.124391) (xy 187.446658 -273.172968) (xy 187.431074 -273.219649) (xy 187.408203 -273.263226)
			(xy 187.378638 -273.30257) (xy 187.343145 -273.336662) (xy 187.302642 -273.364618) (xy 187.25818 -273.385716)
			(xy 187.210909 -273.399408) (xy 187.162054 -273.40534) (xy 187.112879 -273.403359) (xy 187.06466 -273.393515)
			(xy 187.018644 -273.376063) (xy 186.976023 -273.351456) (xy 186.937902 -273.320331) (xy 186.905267 -273.283494)
			(xy 186.878964 -273.241898) (xy 186.859673 -273.196622) (xy 186.847896 -273.148838) (xy 186.843936 -273.099784)
			(xy 185.555128 -273.099784) (xy 185.554633 -273.124391) (xy 185.546738 -273.172968) (xy 185.531154 -273.219649)
			(xy 185.508283 -273.263226) (xy 185.478718 -273.30257) (xy 185.443225 -273.336662) (xy 185.402722 -273.364618)
			(xy 185.35826 -273.385716) (xy 185.310989 -273.399408) (xy 185.262134 -273.40534) (xy 185.212959 -273.403359)
			(xy 185.16474 -273.393515) (xy 185.118724 -273.376063) (xy 185.076103 -273.351456) (xy 185.037982 -273.320331)
			(xy 185.005347 -273.283494) (xy 184.979044 -273.241898) (xy 184.959753 -273.196622) (xy 184.947976 -273.148838)
			(xy 184.944016 -273.099784) (xy 183.654954 -273.099784) (xy 183.654459 -273.124391) (xy 183.646564 -273.172968)
			(xy 183.63098 -273.219649) (xy 183.608109 -273.263226) (xy 183.578544 -273.30257) (xy 183.543051 -273.336662)
			(xy 183.502548 -273.364618) (xy 183.458086 -273.385716) (xy 183.410815 -273.399408) (xy 183.36196 -273.40534)
			(xy 183.312785 -273.403359) (xy 183.264566 -273.393515) (xy 183.21855 -273.376063) (xy 183.175929 -273.351456)
			(xy 183.137808 -273.320331) (xy 183.105173 -273.283494) (xy 183.07887 -273.241898) (xy 183.059579 -273.196622)
			(xy 183.047802 -273.148838) (xy 183.043842 -273.099784) (xy 181.755034 -273.099784) (xy 181.754539 -273.124391)
			(xy 181.746644 -273.172968) (xy 181.73106 -273.219649) (xy 181.708189 -273.263226) (xy 181.678624 -273.30257)
			(xy 181.643131 -273.336662) (xy 181.602628 -273.364618) (xy 181.558166 -273.385716) (xy 181.510895 -273.399408)
			(xy 181.46204 -273.40534) (xy 181.412865 -273.403359) (xy 181.364646 -273.393515) (xy 181.31863 -273.376063)
			(xy 181.276009 -273.351456) (xy 181.237888 -273.320331) (xy 181.205253 -273.283494) (xy 181.17895 -273.241898)
			(xy 181.159659 -273.196622) (xy 181.147882 -273.148838) (xy 181.143922 -273.099784) (xy 179.855114 -273.099784)
			(xy 179.854619 -273.124391) (xy 179.846724 -273.172968) (xy 179.83114 -273.219649) (xy 179.808269 -273.263226)
			(xy 179.778704 -273.30257) (xy 179.743211 -273.336662) (xy 179.702708 -273.364618) (xy 179.658246 -273.385716)
			(xy 179.610975 -273.399408) (xy 179.56212 -273.40534) (xy 179.512945 -273.403359) (xy 179.464726 -273.393515)
			(xy 179.41871 -273.376063) (xy 179.376089 -273.351456) (xy 179.337968 -273.320331) (xy 179.305333 -273.283494)
			(xy 179.27903 -273.241898) (xy 179.259739 -273.196622) (xy 179.247962 -273.148838) (xy 179.244002 -273.099784)
			(xy 177.95494 -273.099784) (xy 177.954445 -273.124391) (xy 177.94655 -273.172968) (xy 177.930966 -273.219649)
			(xy 177.908095 -273.263226) (xy 177.87853 -273.30257) (xy 177.843037 -273.336662) (xy 177.802534 -273.364618)
			(xy 177.758072 -273.385716) (xy 177.710801 -273.399408) (xy 177.661946 -273.40534) (xy 177.612771 -273.403359)
			(xy 177.564552 -273.393515) (xy 177.518536 -273.376063) (xy 177.475915 -273.351456) (xy 177.437794 -273.320331)
			(xy 177.405159 -273.283494) (xy 177.378856 -273.241898) (xy 177.359565 -273.196622) (xy 177.347788 -273.148838)
			(xy 177.343828 -273.099784) (xy 176.055015 -273.099784) (xy 176.054525 -273.124137) (xy 176.04663 -273.172714)
			(xy 176.031046 -273.219395) (xy 176.008175 -273.262972) (xy 175.97861 -273.302316) (xy 175.943117 -273.336408)
			(xy 175.902614 -273.364364) (xy 175.858152 -273.385462) (xy 175.810881 -273.399154) (xy 175.762026 -273.405086)
			(xy 175.712851 -273.403105) (xy 175.664632 -273.393261) (xy 175.618616 -273.375809) (xy 175.575995 -273.351202)
			(xy 175.537874 -273.320077) (xy 175.505239 -273.28324) (xy 175.478936 -273.241644) (xy 175.459645 -273.196368)
			(xy 175.447868 -273.148584) (xy 175.443908 -273.09953) (xy 174.155349 -273.09953) (xy 174.155354 -273.099784)
			(xy 174.154859 -273.124391) (xy 174.146964 -273.172968) (xy 174.13138 -273.219649) (xy 174.108509 -273.263226)
			(xy 174.078944 -273.30257) (xy 174.043451 -273.336662) (xy 174.002948 -273.364618) (xy 173.958486 -273.385716)
			(xy 173.911215 -273.399408) (xy 173.86236 -273.40534) (xy 173.813185 -273.403359) (xy 173.764966 -273.393515)
			(xy 173.71895 -273.376063) (xy 173.676329 -273.351456) (xy 173.638208 -273.320331) (xy 173.605573 -273.283494)
			(xy 173.57927 -273.241898) (xy 173.559979 -273.196622) (xy 173.548202 -273.148838) (xy 173.544242 -273.099784)
			(xy 172.25518 -273.099784) (xy 172.254685 -273.124391) (xy 172.24679 -273.172968) (xy 172.231206 -273.219649)
			(xy 172.208335 -273.263226) (xy 172.17877 -273.30257) (xy 172.143277 -273.336662) (xy 172.102774 -273.364618)
			(xy 172.058312 -273.385716) (xy 172.011041 -273.399408) (xy 171.962186 -273.40534) (xy 171.913011 -273.403359)
			(xy 171.864792 -273.393515) (xy 171.818776 -273.376063) (xy 171.776155 -273.351456) (xy 171.738034 -273.320331)
			(xy 171.705399 -273.283494) (xy 171.679096 -273.241898) (xy 171.659805 -273.196622) (xy 171.648028 -273.148838)
			(xy 171.644068 -273.099784) (xy 170.35526 -273.099784) (xy 170.354765 -273.124391) (xy 170.34687 -273.172968)
			(xy 170.331286 -273.219649) (xy 170.308415 -273.263226) (xy 170.27885 -273.30257) (xy 170.243357 -273.336662)
			(xy 170.202854 -273.364618) (xy 170.158392 -273.385716) (xy 170.111121 -273.399408) (xy 170.062266 -273.40534)
			(xy 170.013091 -273.403359) (xy 169.964872 -273.393515) (xy 169.918856 -273.376063) (xy 169.876235 -273.351456)
			(xy 169.838114 -273.320331) (xy 169.805479 -273.283494) (xy 169.779176 -273.241898) (xy 169.759885 -273.196622)
			(xy 169.748108 -273.148838) (xy 169.744148 -273.099784) (xy 168.45534 -273.099784) (xy 168.454845 -273.124391)
			(xy 168.44695 -273.172968) (xy 168.431366 -273.219649) (xy 168.408495 -273.263226) (xy 168.37893 -273.30257)
			(xy 168.343437 -273.336662) (xy 168.302934 -273.364618) (xy 168.258472 -273.385716) (xy 168.211201 -273.399408)
			(xy 168.162346 -273.40534) (xy 168.113171 -273.403359) (xy 168.064952 -273.393515) (xy 168.018936 -273.376063)
			(xy 167.976315 -273.351456) (xy 167.938194 -273.320331) (xy 167.905559 -273.283494) (xy 167.879256 -273.241898)
			(xy 167.859965 -273.196622) (xy 167.848188 -273.148838) (xy 167.844228 -273.099784) (xy 166.555166 -273.099784)
			(xy 166.554671 -273.124391) (xy 166.546776 -273.172968) (xy 166.531192 -273.219649) (xy 166.508321 -273.263226)
			(xy 166.478756 -273.30257) (xy 166.443263 -273.336662) (xy 166.40276 -273.364618) (xy 166.358298 -273.385716)
			(xy 166.311027 -273.399408) (xy 166.262172 -273.40534) (xy 166.212997 -273.403359) (xy 166.164778 -273.393515)
			(xy 166.118762 -273.376063) (xy 166.076141 -273.351456) (xy 166.03802 -273.320331) (xy 166.005385 -273.283494)
			(xy 165.979082 -273.241898) (xy 165.959791 -273.196622) (xy 165.948014 -273.148838) (xy 165.944054 -273.099784)
			(xy 164.655246 -273.099784) (xy 164.654751 -273.124391) (xy 164.646856 -273.172968) (xy 164.631272 -273.219649)
			(xy 164.608401 -273.263226) (xy 164.578836 -273.30257) (xy 164.543343 -273.336662) (xy 164.50284 -273.364618)
			(xy 164.458378 -273.385716) (xy 164.411107 -273.399408) (xy 164.362252 -273.40534) (xy 164.313077 -273.403359)
			(xy 164.264858 -273.393515) (xy 164.218842 -273.376063) (xy 164.176221 -273.351456) (xy 164.1381 -273.320331)
			(xy 164.105465 -273.283494) (xy 164.079162 -273.241898) (xy 164.059871 -273.196622) (xy 164.048094 -273.148838)
			(xy 164.044134 -273.099784) (xy 162.755326 -273.099784) (xy 162.754831 -273.124391) (xy 162.746936 -273.172968)
			(xy 162.731352 -273.219649) (xy 162.708481 -273.263226) (xy 162.678916 -273.30257) (xy 162.643423 -273.336662)
			(xy 162.60292 -273.364618) (xy 162.558458 -273.385716) (xy 162.511187 -273.399408) (xy 162.462332 -273.40534)
			(xy 162.413157 -273.403359) (xy 162.364938 -273.393515) (xy 162.318922 -273.376063) (xy 162.276301 -273.351456)
			(xy 162.23818 -273.320331) (xy 162.205545 -273.283494) (xy 162.179242 -273.241898) (xy 162.159951 -273.196622)
			(xy 162.148174 -273.148838) (xy 162.144214 -273.099784) (xy 160.855152 -273.099784) (xy 160.854657 -273.124391)
			(xy 160.846762 -273.172968) (xy 160.831178 -273.219649) (xy 160.808307 -273.263226) (xy 160.778742 -273.30257)
			(xy 160.743249 -273.336662) (xy 160.702746 -273.364618) (xy 160.658284 -273.385716) (xy 160.611013 -273.399408)
			(xy 160.562158 -273.40534) (xy 160.512983 -273.403359) (xy 160.464764 -273.393515) (xy 160.418748 -273.376063)
			(xy 160.376127 -273.351456) (xy 160.338006 -273.320331) (xy 160.305371 -273.283494) (xy 160.279068 -273.241898)
			(xy 160.259777 -273.196622) (xy 160.248 -273.148838) (xy 160.24404 -273.099784) (xy 147.42707 -273.099784)
			(xy 147.382368 -273.134324) (xy 147.260078 -273.218735) (xy 147.133433 -273.29646) (xy 147.002798 -273.367276)
			(xy 146.868551 -273.430977) (xy 146.731078 -273.48738) (xy 146.590775 -273.536323) (xy 146.448048 -273.577665)
			(xy 146.303307 -273.611285) (xy 146.156971 -273.637088) (xy 146.00946 -273.654999) (xy 145.861201 -273.664967)
			(xy 145.71262 -273.666962) (xy 145.564147 -273.660978) (xy 145.416208 -273.647034) (xy 145.269232 -273.625169)
			(xy 145.123641 -273.595447) (xy 144.979855 -273.557952) (xy 144.838289 -273.512793) (xy 144.699351 -273.460101)
			(xy 144.563442 -273.400027) (xy 144.430953 -273.332745) (xy 144.302267 -273.258448) (xy 144.177754 -273.177351)
			(xy 144.057774 -273.089687) (xy 143.942673 -272.995709) (xy 143.832781 -272.895689) (xy 143.728417 -272.789914)
			(xy 143.629881 -272.67869) (xy 143.537457 -272.562337) (xy 143.451412 -272.44119) (xy 143.371994 -272.3156)
			(xy 143.299431 -272.185928) (xy 143.233933 -272.052548) (xy 143.175689 -271.915845) (xy 143.124867 -271.776212)
			(xy 143.081613 -271.634053) (xy 143.046052 -271.489776) (xy 143.018287 -271.3438) (xy 142.998397 -271.196543)
			(xy 142.98644 -271.04843) (xy 142.982451 -270.89989) (xy 92.41663 -270.89989) (xy 92.416131 -270.974187)
			(xy 92.408155 -271.122567) (xy 92.392226 -271.270305) (xy 92.36839 -271.416974) (xy 92.336716 -271.562153)
			(xy 92.297294 -271.705423) (xy 92.250239 -271.84637) (xy 92.195686 -271.984587) (xy 92.133793 -272.119678)
			(xy 92.064738 -272.251251) (xy 91.98872 -272.378929) (xy 91.905959 -272.502341) (xy 91.816692 -272.621134)
			(xy 91.721178 -272.734963) (xy 91.619691 -272.843502) (xy 91.512524 -272.946437) (xy 91.399987 -273.043471)
			(xy 91.282404 -273.134324) (xy 91.160114 -273.218735) (xy 91.033469 -273.29646) (xy 90.902834 -273.367276)
			(xy 90.768587 -273.430977) (xy 90.631114 -273.48738) (xy 90.490811 -273.536323) (xy 90.348084 -273.577665)
			(xy 90.203343 -273.611285) (xy 90.057007 -273.637088) (xy 89.909496 -273.654999) (xy 89.761237 -273.664967)
			(xy 89.612656 -273.666962) (xy 89.464183 -273.660978) (xy 89.316244 -273.647034) (xy 89.169268 -273.625169)
			(xy 89.023677 -273.595447) (xy 88.879891 -273.557952) (xy 88.738325 -273.512793) (xy 88.599387 -273.460101)
			(xy 88.463478 -273.400027) (xy 88.330989 -273.332745) (xy 88.202303 -273.258448) (xy 88.07779 -273.177351)
			(xy 87.95781 -273.089687) (xy 87.842709 -272.995709) (xy 87.732817 -272.895689) (xy 87.628453 -272.789914)
			(xy 87.529917 -272.67869) (xy 87.437493 -272.562337) (xy 87.351448 -272.44119) (xy 87.27203 -272.3156)
			(xy 87.199467 -272.185928) (xy 87.133969 -272.052548) (xy 87.075725 -271.915845) (xy 87.024903 -271.776212)
			(xy 86.981649 -271.634053) (xy 86.946088 -271.489776) (xy 86.918323 -271.3438) (xy 86.898433 -271.196543)
			(xy 86.886476 -271.04843) (xy 86.882487 -270.89989) (xy 32.416496 -270.89989) (xy 32.415997 -270.974187)
			(xy 32.408021 -271.122567) (xy 32.392092 -271.270305) (xy 32.368256 -271.416974) (xy 32.336582 -271.562153)
			(xy 32.29716 -271.705423) (xy 32.250105 -271.84637) (xy 32.195552 -271.984587) (xy 32.133659 -272.119678)
			(xy 32.064604 -272.251251) (xy 31.988586 -272.378929) (xy 31.905825 -272.502341) (xy 31.816558 -272.621134)
			(xy 31.721044 -272.734963) (xy 31.619557 -272.843502) (xy 31.51239 -272.946437) (xy 31.399853 -273.043471)
			(xy 31.326972 -273.099784) (xy 44.143942 -273.099784) (xy 44.147902 -273.05073) (xy 44.159679 -273.002946)
			(xy 44.17897 -272.95767) (xy 44.205273 -272.916074) (xy 44.237908 -272.879237) (xy 44.276029 -272.848112)
			(xy 44.31865 -272.823505) (xy 44.364666 -272.806053) (xy 44.412885 -272.796209) (xy 44.46206 -272.794228)
			(xy 44.510915 -272.80016) (xy 44.558186 -272.813852) (xy 44.602648 -272.83495) (xy 44.643151 -272.862906)
			(xy 44.678644 -272.896998) (xy 44.708209 -272.936342) (xy 44.73108 -272.979919) (xy 44.746664 -273.0266)
			(xy 44.754559 -273.075177) (xy 44.755054 -273.099784) (xy 46.044116 -273.099784) (xy 46.048076 -273.05073)
			(xy 46.059853 -273.002946) (xy 46.079144 -272.95767) (xy 46.105447 -272.916074) (xy 46.138082 -272.879237)
			(xy 46.176203 -272.848112) (xy 46.218824 -272.823505) (xy 46.26484 -272.806053) (xy 46.313059 -272.796209)
			(xy 46.362234 -272.794228) (xy 46.411089 -272.80016) (xy 46.45836 -272.813852) (xy 46.502822 -272.83495)
			(xy 46.543325 -272.862906) (xy 46.578818 -272.896998) (xy 46.608383 -272.936342) (xy 46.631254 -272.979919)
			(xy 46.646838 -273.0266) (xy 46.654733 -273.075177) (xy 46.655228 -273.099784) (xy 47.944036 -273.099784)
			(xy 47.947996 -273.05073) (xy 47.959773 -273.002946) (xy 47.979064 -272.95767) (xy 48.005367 -272.916074)
			(xy 48.038002 -272.879237) (xy 48.076123 -272.848112) (xy 48.118744 -272.823505) (xy 48.16476 -272.806053)
			(xy 48.212979 -272.796209) (xy 48.262154 -272.794228) (xy 48.311009 -272.80016) (xy 48.35828 -272.813852)
			(xy 48.402742 -272.83495) (xy 48.443245 -272.862906) (xy 48.478738 -272.896998) (xy 48.508303 -272.936342)
			(xy 48.531174 -272.979919) (xy 48.546758 -273.0266) (xy 48.554653 -273.075177) (xy 48.555148 -273.099784)
			(xy 49.843956 -273.099784) (xy 49.847916 -273.05073) (xy 49.859693 -273.002946) (xy 49.878984 -272.95767)
			(xy 49.905287 -272.916074) (xy 49.937922 -272.879237) (xy 49.976043 -272.848112) (xy 50.018664 -272.823505)
			(xy 50.06468 -272.806053) (xy 50.112899 -272.796209) (xy 50.162074 -272.794228) (xy 50.210929 -272.80016)
			(xy 50.2582 -272.813852) (xy 50.302662 -272.83495) (xy 50.343165 -272.862906) (xy 50.378658 -272.896998)
			(xy 50.408223 -272.936342) (xy 50.431094 -272.979919) (xy 50.446678 -273.0266) (xy 50.454573 -273.075177)
			(xy 50.455068 -273.099784) (xy 51.74413 -273.099784) (xy 51.74809 -273.05073) (xy 51.759867 -273.002946)
			(xy 51.779158 -272.95767) (xy 51.805461 -272.916074) (xy 51.838096 -272.879237) (xy 51.876217 -272.848112)
			(xy 51.918838 -272.823505) (xy 51.964854 -272.806053) (xy 52.013073 -272.796209) (xy 52.062248 -272.794228)
			(xy 52.111103 -272.80016) (xy 52.158374 -272.813852) (xy 52.202836 -272.83495) (xy 52.243339 -272.862906)
			(xy 52.278832 -272.896998) (xy 52.308397 -272.936342) (xy 52.331268 -272.979919) (xy 52.346852 -273.0266)
			(xy 52.354747 -273.075177) (xy 52.355242 -273.099784) (xy 53.64405 -273.099784) (xy 53.64801 -273.05073)
			(xy 53.659787 -273.002946) (xy 53.679078 -272.95767) (xy 53.705381 -272.916074) (xy 53.738016 -272.879237)
			(xy 53.776137 -272.848112) (xy 53.818758 -272.823505) (xy 53.864774 -272.806053) (xy 53.912993 -272.796209)
			(xy 53.962168 -272.794228) (xy 54.011023 -272.80016) (xy 54.058294 -272.813852) (xy 54.102756 -272.83495)
			(xy 54.143259 -272.862906) (xy 54.178752 -272.896998) (xy 54.208317 -272.936342) (xy 54.231188 -272.979919)
			(xy 54.246772 -273.0266) (xy 54.254667 -273.075177) (xy 54.255162 -273.099784) (xy 55.54397 -273.099784)
			(xy 55.54793 -273.05073) (xy 55.559707 -273.002946) (xy 55.578998 -272.95767) (xy 55.605301 -272.916074)
			(xy 55.637936 -272.879237) (xy 55.676057 -272.848112) (xy 55.718678 -272.823505) (xy 55.764694 -272.806053)
			(xy 55.812913 -272.796209) (xy 55.862088 -272.794228) (xy 55.910943 -272.80016) (xy 55.958214 -272.813852)
			(xy 56.002676 -272.83495) (xy 56.043179 -272.862906) (xy 56.078672 -272.896998) (xy 56.108237 -272.936342)
			(xy 56.131108 -272.979919) (xy 56.146692 -273.0266) (xy 56.154587 -273.075177) (xy 56.155082 -273.099784)
			(xy 57.444144 -273.099784) (xy 57.448104 -273.05073) (xy 57.459881 -273.002946) (xy 57.479172 -272.95767)
			(xy 57.505475 -272.916074) (xy 57.53811 -272.879237) (xy 57.576231 -272.848112) (xy 57.618852 -272.823505)
			(xy 57.664868 -272.806053) (xy 57.713087 -272.796209) (xy 57.762262 -272.794228) (xy 57.811117 -272.80016)
			(xy 57.858388 -272.813852) (xy 57.90285 -272.83495) (xy 57.943353 -272.862906) (xy 57.978846 -272.896998)
			(xy 58.008411 -272.936342) (xy 58.031282 -272.979919) (xy 58.046866 -273.0266) (xy 58.054761 -273.075177)
			(xy 58.055251 -273.09953) (xy 59.34381 -273.09953) (xy 59.34777 -273.050476) (xy 59.359547 -273.002692)
			(xy 59.378838 -272.957416) (xy 59.405141 -272.91582) (xy 59.437776 -272.878983) (xy 59.475897 -272.847858)
			(xy 59.518518 -272.823251) (xy 59.564534 -272.805799) (xy 59.612753 -272.795955) (xy 59.661928 -272.793974)
			(xy 59.710783 -272.799906) (xy 59.758054 -272.813598) (xy 59.802516 -272.834696) (xy 59.843019 -272.862652)
			(xy 59.878512 -272.896744) (xy 59.908077 -272.936088) (xy 59.930948 -272.979665) (xy 59.946532 -273.026346)
			(xy 59.954427 -273.074923) (xy 59.954922 -273.09953) (xy 59.954917 -273.099784) (xy 61.24373 -273.099784)
			(xy 61.24769 -273.05073) (xy 61.259467 -273.002946) (xy 61.278758 -272.95767) (xy 61.305061 -272.916074)
			(xy 61.337696 -272.879237) (xy 61.375817 -272.848112) (xy 61.418438 -272.823505) (xy 61.464454 -272.806053)
			(xy 61.512673 -272.796209) (xy 61.561848 -272.794228) (xy 61.610703 -272.80016) (xy 61.657974 -272.813852)
			(xy 61.702436 -272.83495) (xy 61.742939 -272.862906) (xy 61.778432 -272.896998) (xy 61.807997 -272.936342)
			(xy 61.830868 -272.979919) (xy 61.846452 -273.0266) (xy 61.854347 -273.075177) (xy 61.854842 -273.099784)
			(xy 63.143904 -273.099784) (xy 63.147864 -273.05073) (xy 63.159641 -273.002946) (xy 63.178932 -272.95767)
			(xy 63.205235 -272.916074) (xy 63.23787 -272.879237) (xy 63.275991 -272.848112) (xy 63.318612 -272.823505)
			(xy 63.364628 -272.806053) (xy 63.412847 -272.796209) (xy 63.462022 -272.794228) (xy 63.510877 -272.80016)
			(xy 63.558148 -272.813852) (xy 63.60261 -272.83495) (xy 63.643113 -272.862906) (xy 63.678606 -272.896998)
			(xy 63.708171 -272.936342) (xy 63.731042 -272.979919) (xy 63.746626 -273.0266) (xy 63.754521 -273.075177)
			(xy 63.755016 -273.099784) (xy 65.043824 -273.099784) (xy 65.047784 -273.05073) (xy 65.059561 -273.002946)
			(xy 65.078852 -272.95767) (xy 65.105155 -272.916074) (xy 65.13779 -272.879237) (xy 65.175911 -272.848112)
			(xy 65.218532 -272.823505) (xy 65.264548 -272.806053) (xy 65.312767 -272.796209) (xy 65.361942 -272.794228)
			(xy 65.410797 -272.80016) (xy 65.458068 -272.813852) (xy 65.50253 -272.83495) (xy 65.543033 -272.862906)
			(xy 65.578526 -272.896998) (xy 65.608091 -272.936342) (xy 65.630962 -272.979919) (xy 65.646546 -273.0266)
			(xy 65.654441 -273.075177) (xy 65.654936 -273.099784) (xy 66.943744 -273.099784) (xy 66.947704 -273.05073)
			(xy 66.959481 -273.002946) (xy 66.978772 -272.95767) (xy 67.005075 -272.916074) (xy 67.03771 -272.879237)
			(xy 67.075831 -272.848112) (xy 67.118452 -272.823505) (xy 67.164468 -272.806053) (xy 67.212687 -272.796209)
			(xy 67.261862 -272.794228) (xy 67.310717 -272.80016) (xy 67.357988 -272.813852) (xy 67.40245 -272.83495)
			(xy 67.442953 -272.862906) (xy 67.478446 -272.896998) (xy 67.508011 -272.936342) (xy 67.530882 -272.979919)
			(xy 67.546466 -273.0266) (xy 67.554361 -273.075177) (xy 67.554856 -273.099784) (xy 68.843918 -273.099784)
			(xy 68.847878 -273.05073) (xy 68.859655 -273.002946) (xy 68.878946 -272.95767) (xy 68.905249 -272.916074)
			(xy 68.937884 -272.879237) (xy 68.976005 -272.848112) (xy 69.018626 -272.823505) (xy 69.064642 -272.806053)
			(xy 69.112861 -272.796209) (xy 69.162036 -272.794228) (xy 69.210891 -272.80016) (xy 69.258162 -272.813852)
			(xy 69.302624 -272.83495) (xy 69.343127 -272.862906) (xy 69.37862 -272.896998) (xy 69.408185 -272.936342)
			(xy 69.431056 -272.979919) (xy 69.44664 -273.0266) (xy 69.454535 -273.075177) (xy 69.45503 -273.099784)
			(xy 70.743838 -273.099784) (xy 70.747798 -273.05073) (xy 70.759575 -273.002946) (xy 70.778866 -272.95767)
			(xy 70.805169 -272.916074) (xy 70.837804 -272.879237) (xy 70.875925 -272.848112) (xy 70.918546 -272.823505)
			(xy 70.964562 -272.806053) (xy 71.012781 -272.796209) (xy 71.061956 -272.794228) (xy 71.110811 -272.80016)
			(xy 71.158082 -272.813852) (xy 71.202544 -272.83495) (xy 71.243047 -272.862906) (xy 71.27854 -272.896998)
			(xy 71.308105 -272.936342) (xy 71.330976 -272.979919) (xy 71.34656 -273.0266) (xy 71.354455 -273.075177)
			(xy 71.35495 -273.099784) (xy 72.643758 -273.099784) (xy 72.647718 -273.05073) (xy 72.659495 -273.002946)
			(xy 72.678786 -272.95767) (xy 72.705089 -272.916074) (xy 72.737724 -272.879237) (xy 72.775845 -272.848112)
			(xy 72.818466 -272.823505) (xy 72.864482 -272.806053) (xy 72.912701 -272.796209) (xy 72.961876 -272.794228)
			(xy 73.010731 -272.80016) (xy 73.058002 -272.813852) (xy 73.102464 -272.83495) (xy 73.142967 -272.862906)
			(xy 73.17846 -272.896998) (xy 73.208025 -272.936342) (xy 73.230896 -272.979919) (xy 73.24648 -273.0266)
			(xy 73.254375 -273.075177) (xy 73.25487 -273.099784) (xy 74.543932 -273.099784) (xy 74.547892 -273.05073)
			(xy 74.559669 -273.002946) (xy 74.57896 -272.95767) (xy 74.605263 -272.916074) (xy 74.637898 -272.879237)
			(xy 74.676019 -272.848112) (xy 74.71864 -272.823505) (xy 74.764656 -272.806053) (xy 74.812875 -272.796209)
			(xy 74.86205 -272.794228) (xy 74.910905 -272.80016) (xy 74.958176 -272.813852) (xy 75.002638 -272.83495)
			(xy 75.043141 -272.862906) (xy 75.078634 -272.896998) (xy 75.108199 -272.936342) (xy 75.13107 -272.979919)
			(xy 75.146654 -273.0266) (xy 75.154549 -273.075177) (xy 75.155044 -273.099784) (xy 76.443852 -273.099784)
			(xy 76.447812 -273.05073) (xy 76.459589 -273.002946) (xy 76.47888 -272.95767) (xy 76.505183 -272.916074)
			(xy 76.537818 -272.879237) (xy 76.575939 -272.848112) (xy 76.61856 -272.823505) (xy 76.664576 -272.806053)
			(xy 76.712795 -272.796209) (xy 76.76197 -272.794228) (xy 76.810825 -272.80016) (xy 76.858096 -272.813852)
			(xy 76.902558 -272.83495) (xy 76.943061 -272.862906) (xy 76.978554 -272.896998) (xy 77.008119 -272.936342)
			(xy 77.03099 -272.979919) (xy 77.046574 -273.0266) (xy 77.054469 -273.075177) (xy 77.054964 -273.099784)
			(xy 78.343772 -273.099784) (xy 78.347732 -273.05073) (xy 78.359509 -273.002946) (xy 78.3788 -272.95767)
			(xy 78.405103 -272.916074) (xy 78.437738 -272.879237) (xy 78.475859 -272.848112) (xy 78.51848 -272.823505)
			(xy 78.564496 -272.806053) (xy 78.612715 -272.796209) (xy 78.66189 -272.794228) (xy 78.710745 -272.80016)
			(xy 78.758016 -272.813852) (xy 78.802478 -272.83495) (xy 78.842981 -272.862906) (xy 78.878474 -272.896998)
			(xy 78.908039 -272.936342) (xy 78.93091 -272.979919) (xy 78.946494 -273.0266) (xy 78.954389 -273.075177)
			(xy 78.954884 -273.099784) (xy 80.243692 -273.099784) (xy 80.247652 -273.05073) (xy 80.259429 -273.002946)
			(xy 80.27872 -272.95767) (xy 80.305023 -272.916074) (xy 80.337658 -272.879237) (xy 80.375779 -272.848112)
			(xy 80.4184 -272.823505) (xy 80.464416 -272.806053) (xy 80.512635 -272.796209) (xy 80.56181 -272.794228)
			(xy 80.610665 -272.80016) (xy 80.657936 -272.813852) (xy 80.702398 -272.83495) (xy 80.742901 -272.862906)
			(xy 80.778394 -272.896998) (xy 80.807959 -272.936342) (xy 80.83083 -272.979919) (xy 80.846414 -273.0266)
			(xy 80.854309 -273.075177) (xy 80.854804 -273.099784) (xy 80.854309 -273.124391) (xy 80.846414 -273.172968)
			(xy 80.83083 -273.219649) (xy 80.807959 -273.263226) (xy 80.778394 -273.30257) (xy 80.742901 -273.336662)
			(xy 80.702398 -273.364618) (xy 80.657936 -273.385716) (xy 80.610665 -273.399408) (xy 80.56181 -273.40534)
			(xy 80.512635 -273.403359) (xy 80.464416 -273.393515) (xy 80.4184 -273.376063) (xy 80.375779 -273.351456)
			(xy 80.337658 -273.320331) (xy 80.305023 -273.283494) (xy 80.27872 -273.241898) (xy 80.259429 -273.196622)
			(xy 80.247652 -273.148838) (xy 80.243692 -273.099784) (xy 78.954884 -273.099784) (xy 78.954389 -273.124391)
			(xy 78.946494 -273.172968) (xy 78.93091 -273.219649) (xy 78.908039 -273.263226) (xy 78.878474 -273.30257)
			(xy 78.842981 -273.336662) (xy 78.802478 -273.364618) (xy 78.758016 -273.385716) (xy 78.710745 -273.399408)
			(xy 78.66189 -273.40534) (xy 78.612715 -273.403359) (xy 78.564496 -273.393515) (xy 78.51848 -273.376063)
			(xy 78.475859 -273.351456) (xy 78.437738 -273.320331) (xy 78.405103 -273.283494) (xy 78.3788 -273.241898)
			(xy 78.359509 -273.196622) (xy 78.347732 -273.148838) (xy 78.343772 -273.099784) (xy 77.054964 -273.099784)
			(xy 77.054469 -273.124391) (xy 77.046574 -273.172968) (xy 77.03099 -273.219649) (xy 77.008119 -273.263226)
			(xy 76.978554 -273.30257) (xy 76.943061 -273.336662) (xy 76.902558 -273.364618) (xy 76.858096 -273.385716)
			(xy 76.810825 -273.399408) (xy 76.76197 -273.40534) (xy 76.712795 -273.403359) (xy 76.664576 -273.393515)
			(xy 76.61856 -273.376063) (xy 76.575939 -273.351456) (xy 76.537818 -273.320331) (xy 76.505183 -273.283494)
			(xy 76.47888 -273.241898) (xy 76.459589 -273.196622) (xy 76.447812 -273.148838) (xy 76.443852 -273.099784)
			(xy 75.155044 -273.099784) (xy 75.154549 -273.124391) (xy 75.146654 -273.172968) (xy 75.13107 -273.219649)
			(xy 75.108199 -273.263226) (xy 75.078634 -273.30257) (xy 75.043141 -273.336662) (xy 75.002638 -273.364618)
			(xy 74.958176 -273.385716) (xy 74.910905 -273.399408) (xy 74.86205 -273.40534) (xy 74.812875 -273.403359)
			(xy 74.764656 -273.393515) (xy 74.71864 -273.376063) (xy 74.676019 -273.351456) (xy 74.637898 -273.320331)
			(xy 74.605263 -273.283494) (xy 74.57896 -273.241898) (xy 74.559669 -273.196622) (xy 74.547892 -273.148838)
			(xy 74.543932 -273.099784) (xy 73.25487 -273.099784) (xy 73.254375 -273.124391) (xy 73.24648 -273.172968)
			(xy 73.230896 -273.219649) (xy 73.208025 -273.263226) (xy 73.17846 -273.30257) (xy 73.142967 -273.336662)
			(xy 73.102464 -273.364618) (xy 73.058002 -273.385716) (xy 73.010731 -273.399408) (xy 72.961876 -273.40534)
			(xy 72.912701 -273.403359) (xy 72.864482 -273.393515) (xy 72.818466 -273.376063) (xy 72.775845 -273.351456)
			(xy 72.737724 -273.320331) (xy 72.705089 -273.283494) (xy 72.678786 -273.241898) (xy 72.659495 -273.196622)
			(xy 72.647718 -273.148838) (xy 72.643758 -273.099784) (xy 71.35495 -273.099784) (xy 71.354455 -273.124391)
			(xy 71.34656 -273.172968) (xy 71.330976 -273.219649) (xy 71.308105 -273.263226) (xy 71.27854 -273.30257)
			(xy 71.243047 -273.336662) (xy 71.202544 -273.364618) (xy 71.158082 -273.385716) (xy 71.110811 -273.399408)
			(xy 71.061956 -273.40534) (xy 71.012781 -273.403359) (xy 70.964562 -273.393515) (xy 70.918546 -273.376063)
			(xy 70.875925 -273.351456) (xy 70.837804 -273.320331) (xy 70.805169 -273.283494) (xy 70.778866 -273.241898)
			(xy 70.759575 -273.196622) (xy 70.747798 -273.148838) (xy 70.743838 -273.099784) (xy 69.45503 -273.099784)
			(xy 69.454535 -273.124391) (xy 69.44664 -273.172968) (xy 69.431056 -273.219649) (xy 69.408185 -273.263226)
			(xy 69.37862 -273.30257) (xy 69.343127 -273.336662) (xy 69.302624 -273.364618) (xy 69.258162 -273.385716)
			(xy 69.210891 -273.399408) (xy 69.162036 -273.40534) (xy 69.112861 -273.403359) (xy 69.064642 -273.393515)
			(xy 69.018626 -273.376063) (xy 68.976005 -273.351456) (xy 68.937884 -273.320331) (xy 68.905249 -273.283494)
			(xy 68.878946 -273.241898) (xy 68.859655 -273.196622) (xy 68.847878 -273.148838) (xy 68.843918 -273.099784)
			(xy 67.554856 -273.099784) (xy 67.554361 -273.124391) (xy 67.546466 -273.172968) (xy 67.530882 -273.219649)
			(xy 67.508011 -273.263226) (xy 67.478446 -273.30257) (xy 67.442953 -273.336662) (xy 67.40245 -273.364618)
			(xy 67.357988 -273.385716) (xy 67.310717 -273.399408) (xy 67.261862 -273.40534) (xy 67.212687 -273.403359)
			(xy 67.164468 -273.393515) (xy 67.118452 -273.376063) (xy 67.075831 -273.351456) (xy 67.03771 -273.320331)
			(xy 67.005075 -273.283494) (xy 66.978772 -273.241898) (xy 66.959481 -273.196622) (xy 66.947704 -273.148838)
			(xy 66.943744 -273.099784) (xy 65.654936 -273.099784) (xy 65.654441 -273.124391) (xy 65.646546 -273.172968)
			(xy 65.630962 -273.219649) (xy 65.608091 -273.263226) (xy 65.578526 -273.30257) (xy 65.543033 -273.336662)
			(xy 65.50253 -273.364618) (xy 65.458068 -273.385716) (xy 65.410797 -273.399408) (xy 65.361942 -273.40534)
			(xy 65.312767 -273.403359) (xy 65.264548 -273.393515) (xy 65.218532 -273.376063) (xy 65.175911 -273.351456)
			(xy 65.13779 -273.320331) (xy 65.105155 -273.283494) (xy 65.078852 -273.241898) (xy 65.059561 -273.196622)
			(xy 65.047784 -273.148838) (xy 65.043824 -273.099784) (xy 63.755016 -273.099784) (xy 63.754521 -273.124391)
			(xy 63.746626 -273.172968) (xy 63.731042 -273.219649) (xy 63.708171 -273.263226) (xy 63.678606 -273.30257)
			(xy 63.643113 -273.336662) (xy 63.60261 -273.364618) (xy 63.558148 -273.385716) (xy 63.510877 -273.399408)
			(xy 63.462022 -273.40534) (xy 63.412847 -273.403359) (xy 63.364628 -273.393515) (xy 63.318612 -273.376063)
			(xy 63.275991 -273.351456) (xy 63.23787 -273.320331) (xy 63.205235 -273.283494) (xy 63.178932 -273.241898)
			(xy 63.159641 -273.196622) (xy 63.147864 -273.148838) (xy 63.143904 -273.099784) (xy 61.854842 -273.099784)
			(xy 61.854347 -273.124391) (xy 61.846452 -273.172968) (xy 61.830868 -273.219649) (xy 61.807997 -273.263226)
			(xy 61.778432 -273.30257) (xy 61.742939 -273.336662) (xy 61.702436 -273.364618) (xy 61.657974 -273.385716)
			(xy 61.610703 -273.399408) (xy 61.561848 -273.40534) (xy 61.512673 -273.403359) (xy 61.464454 -273.393515)
			(xy 61.418438 -273.376063) (xy 61.375817 -273.351456) (xy 61.337696 -273.320331) (xy 61.305061 -273.283494)
			(xy 61.278758 -273.241898) (xy 61.259467 -273.196622) (xy 61.24769 -273.148838) (xy 61.24373 -273.099784)
			(xy 59.954917 -273.099784) (xy 59.954427 -273.124137) (xy 59.946532 -273.172714) (xy 59.930948 -273.219395)
			(xy 59.908077 -273.262972) (xy 59.878512 -273.302316) (xy 59.843019 -273.336408) (xy 59.802516 -273.364364)
			(xy 59.758054 -273.385462) (xy 59.710783 -273.399154) (xy 59.661928 -273.405086) (xy 59.612753 -273.403105)
			(xy 59.564534 -273.393261) (xy 59.518518 -273.375809) (xy 59.475897 -273.351202) (xy 59.437776 -273.320077)
			(xy 59.405141 -273.28324) (xy 59.378838 -273.241644) (xy 59.359547 -273.196368) (xy 59.34777 -273.148584)
			(xy 59.34381 -273.09953) (xy 58.055251 -273.09953) (xy 58.055256 -273.099784) (xy 58.054761 -273.124391)
			(xy 58.046866 -273.172968) (xy 58.031282 -273.219649) (xy 58.008411 -273.263226) (xy 57.978846 -273.30257)
			(xy 57.943353 -273.336662) (xy 57.90285 -273.364618) (xy 57.858388 -273.385716) (xy 57.811117 -273.399408)
			(xy 57.762262 -273.40534) (xy 57.713087 -273.403359) (xy 57.664868 -273.393515) (xy 57.618852 -273.376063)
			(xy 57.576231 -273.351456) (xy 57.53811 -273.320331) (xy 57.505475 -273.283494) (xy 57.479172 -273.241898)
			(xy 57.459881 -273.196622) (xy 57.448104 -273.148838) (xy 57.444144 -273.099784) (xy 56.155082 -273.099784)
			(xy 56.154587 -273.124391) (xy 56.146692 -273.172968) (xy 56.131108 -273.219649) (xy 56.108237 -273.263226)
			(xy 56.078672 -273.30257) (xy 56.043179 -273.336662) (xy 56.002676 -273.364618) (xy 55.958214 -273.385716)
			(xy 55.910943 -273.399408) (xy 55.862088 -273.40534) (xy 55.812913 -273.403359) (xy 55.764694 -273.393515)
			(xy 55.718678 -273.376063) (xy 55.676057 -273.351456) (xy 55.637936 -273.320331) (xy 55.605301 -273.283494)
			(xy 55.578998 -273.241898) (xy 55.559707 -273.196622) (xy 55.54793 -273.148838) (xy 55.54397 -273.099784)
			(xy 54.255162 -273.099784) (xy 54.254667 -273.124391) (xy 54.246772 -273.172968) (xy 54.231188 -273.219649)
			(xy 54.208317 -273.263226) (xy 54.178752 -273.30257) (xy 54.143259 -273.336662) (xy 54.102756 -273.364618)
			(xy 54.058294 -273.385716) (xy 54.011023 -273.399408) (xy 53.962168 -273.40534) (xy 53.912993 -273.403359)
			(xy 53.864774 -273.393515) (xy 53.818758 -273.376063) (xy 53.776137 -273.351456) (xy 53.738016 -273.320331)
			(xy 53.705381 -273.283494) (xy 53.679078 -273.241898) (xy 53.659787 -273.196622) (xy 53.64801 -273.148838)
			(xy 53.64405 -273.099784) (xy 52.355242 -273.099784) (xy 52.354747 -273.124391) (xy 52.346852 -273.172968)
			(xy 52.331268 -273.219649) (xy 52.308397 -273.263226) (xy 52.278832 -273.30257) (xy 52.243339 -273.336662)
			(xy 52.202836 -273.364618) (xy 52.158374 -273.385716) (xy 52.111103 -273.399408) (xy 52.062248 -273.40534)
			(xy 52.013073 -273.403359) (xy 51.964854 -273.393515) (xy 51.918838 -273.376063) (xy 51.876217 -273.351456)
			(xy 51.838096 -273.320331) (xy 51.805461 -273.283494) (xy 51.779158 -273.241898) (xy 51.759867 -273.196622)
			(xy 51.74809 -273.148838) (xy 51.74413 -273.099784) (xy 50.455068 -273.099784) (xy 50.454573 -273.124391)
			(xy 50.446678 -273.172968) (xy 50.431094 -273.219649) (xy 50.408223 -273.263226) (xy 50.378658 -273.30257)
			(xy 50.343165 -273.336662) (xy 50.302662 -273.364618) (xy 50.2582 -273.385716) (xy 50.210929 -273.399408)
			(xy 50.162074 -273.40534) (xy 50.112899 -273.403359) (xy 50.06468 -273.393515) (xy 50.018664 -273.376063)
			(xy 49.976043 -273.351456) (xy 49.937922 -273.320331) (xy 49.905287 -273.283494) (xy 49.878984 -273.241898)
			(xy 49.859693 -273.196622) (xy 49.847916 -273.148838) (xy 49.843956 -273.099784) (xy 48.555148 -273.099784)
			(xy 48.554653 -273.124391) (xy 48.546758 -273.172968) (xy 48.531174 -273.219649) (xy 48.508303 -273.263226)
			(xy 48.478738 -273.30257) (xy 48.443245 -273.336662) (xy 48.402742 -273.364618) (xy 48.35828 -273.385716)
			(xy 48.311009 -273.399408) (xy 48.262154 -273.40534) (xy 48.212979 -273.403359) (xy 48.16476 -273.393515)
			(xy 48.118744 -273.376063) (xy 48.076123 -273.351456) (xy 48.038002 -273.320331) (xy 48.005367 -273.283494)
			(xy 47.979064 -273.241898) (xy 47.959773 -273.196622) (xy 47.947996 -273.148838) (xy 47.944036 -273.099784)
			(xy 46.655228 -273.099784) (xy 46.654733 -273.124391) (xy 46.646838 -273.172968) (xy 46.631254 -273.219649)
			(xy 46.608383 -273.263226) (xy 46.578818 -273.30257) (xy 46.543325 -273.336662) (xy 46.502822 -273.364618)
			(xy 46.45836 -273.385716) (xy 46.411089 -273.399408) (xy 46.362234 -273.40534) (xy 46.313059 -273.403359)
			(xy 46.26484 -273.393515) (xy 46.218824 -273.376063) (xy 46.176203 -273.351456) (xy 46.138082 -273.320331)
			(xy 46.105447 -273.283494) (xy 46.079144 -273.241898) (xy 46.059853 -273.196622) (xy 46.048076 -273.148838)
			(xy 46.044116 -273.099784) (xy 44.755054 -273.099784) (xy 44.754559 -273.124391) (xy 44.746664 -273.172968)
			(xy 44.73108 -273.219649) (xy 44.708209 -273.263226) (xy 44.678644 -273.30257) (xy 44.643151 -273.336662)
			(xy 44.602648 -273.364618) (xy 44.558186 -273.385716) (xy 44.510915 -273.399408) (xy 44.46206 -273.40534)
			(xy 44.412885 -273.403359) (xy 44.364666 -273.393515) (xy 44.31865 -273.376063) (xy 44.276029 -273.351456)
			(xy 44.237908 -273.320331) (xy 44.205273 -273.283494) (xy 44.17897 -273.241898) (xy 44.159679 -273.196622)
			(xy 44.147902 -273.148838) (xy 44.143942 -273.099784) (xy 31.326972 -273.099784) (xy 31.28227 -273.134324)
			(xy 31.15998 -273.218735) (xy 31.033335 -273.29646) (xy 30.9027 -273.367276) (xy 30.768453 -273.430977)
			(xy 30.63098 -273.48738) (xy 30.490677 -273.536323) (xy 30.34795 -273.577665) (xy 30.203209 -273.611285)
			(xy 30.056873 -273.637088) (xy 29.909362 -273.654999) (xy 29.761103 -273.664967) (xy 29.612522 -273.666962)
			(xy 29.464049 -273.660978) (xy 29.31611 -273.647034) (xy 29.169134 -273.625169) (xy 29.023543 -273.595447)
			(xy 28.879757 -273.557952) (xy 28.738191 -273.512793) (xy 28.599253 -273.460101) (xy 28.463344 -273.400027)
			(xy 28.330855 -273.332745) (xy 28.202169 -273.258448) (xy 28.077656 -273.177351) (xy 27.957676 -273.089687)
			(xy 27.842575 -272.995709) (xy 27.732683 -272.895689) (xy 27.628319 -272.789914) (xy 27.529783 -272.67869)
			(xy 27.437359 -272.562337) (xy 27.351314 -272.44119) (xy 27.271896 -272.3156) (xy 27.199333 -272.185928)
			(xy 27.133835 -272.052548) (xy 27.075591 -271.915845) (xy 27.024769 -271.776212) (xy 26.981515 -271.634053)
			(xy 26.945954 -271.489776) (xy 26.918189 -271.3438) (xy 26.898299 -271.196543) (xy 26.886342 -271.04843)
			(xy 26.882353 -270.89989) (xy 0.509016 -270.89989) (xy 0.509016 -274.049744) (xy 44.143942 -274.049744)
			(xy 44.147902 -274.00069) (xy 44.159679 -273.952906) (xy 44.17897 -273.90763) (xy 44.205273 -273.866034)
			(xy 44.237908 -273.829197) (xy 44.276029 -273.798072) (xy 44.31865 -273.773465) (xy 44.364666 -273.756013)
			(xy 44.412885 -273.746169) (xy 44.46206 -273.744188) (xy 44.510915 -273.75012) (xy 44.558186 -273.763812)
			(xy 44.602648 -273.78491) (xy 44.643151 -273.812866) (xy 44.678644 -273.846958) (xy 44.708209 -273.886302)
			(xy 44.73108 -273.929879) (xy 44.746664 -273.97656) (xy 44.754559 -274.025137) (xy 44.755054 -274.049744)
			(xy 46.044116 -274.049744) (xy 46.048076 -274.00069) (xy 46.059853 -273.952906) (xy 46.079144 -273.90763)
			(xy 46.105447 -273.866034) (xy 46.138082 -273.829197) (xy 46.176203 -273.798072) (xy 46.218824 -273.773465)
			(xy 46.26484 -273.756013) (xy 46.313059 -273.746169) (xy 46.362234 -273.744188) (xy 46.411089 -273.75012)
			(xy 46.45836 -273.763812) (xy 46.502822 -273.78491) (xy 46.543325 -273.812866) (xy 46.578818 -273.846958)
			(xy 46.608383 -273.886302) (xy 46.631254 -273.929879) (xy 46.646838 -273.97656) (xy 46.654733 -274.025137)
			(xy 46.655228 -274.049744) (xy 47.944036 -274.049744) (xy 47.947996 -274.00069) (xy 47.959773 -273.952906)
			(xy 47.979064 -273.90763) (xy 48.005367 -273.866034) (xy 48.038002 -273.829197) (xy 48.076123 -273.798072)
			(xy 48.118744 -273.773465) (xy 48.16476 -273.756013) (xy 48.212979 -273.746169) (xy 48.262154 -273.744188)
			(xy 48.311009 -273.75012) (xy 48.35828 -273.763812) (xy 48.402742 -273.78491) (xy 48.443245 -273.812866)
			(xy 48.478738 -273.846958) (xy 48.508303 -273.886302) (xy 48.531174 -273.929879) (xy 48.546758 -273.97656)
			(xy 48.554653 -274.025137) (xy 48.555148 -274.049744) (xy 49.843956 -274.049744) (xy 49.847916 -274.00069)
			(xy 49.859693 -273.952906) (xy 49.878984 -273.90763) (xy 49.905287 -273.866034) (xy 49.937922 -273.829197)
			(xy 49.976043 -273.798072) (xy 50.018664 -273.773465) (xy 50.06468 -273.756013) (xy 50.112899 -273.746169)
			(xy 50.162074 -273.744188) (xy 50.210929 -273.75012) (xy 50.2582 -273.763812) (xy 50.302662 -273.78491)
			(xy 50.343165 -273.812866) (xy 50.378658 -273.846958) (xy 50.408223 -273.886302) (xy 50.431094 -273.929879)
			(xy 50.446678 -273.97656) (xy 50.454573 -274.025137) (xy 50.455068 -274.049744) (xy 51.74413 -274.049744)
			(xy 51.74809 -274.00069) (xy 51.759867 -273.952906) (xy 51.779158 -273.90763) (xy 51.805461 -273.866034)
			(xy 51.838096 -273.829197) (xy 51.876217 -273.798072) (xy 51.918838 -273.773465) (xy 51.964854 -273.756013)
			(xy 52.013073 -273.746169) (xy 52.062248 -273.744188) (xy 52.111103 -273.75012) (xy 52.158374 -273.763812)
			(xy 52.202836 -273.78491) (xy 52.243339 -273.812866) (xy 52.278832 -273.846958) (xy 52.308397 -273.886302)
			(xy 52.331268 -273.929879) (xy 52.346852 -273.97656) (xy 52.354747 -274.025137) (xy 52.355242 -274.049744)
			(xy 53.64405 -274.049744) (xy 53.64801 -274.00069) (xy 53.659787 -273.952906) (xy 53.679078 -273.90763)
			(xy 53.705381 -273.866034) (xy 53.738016 -273.829197) (xy 53.776137 -273.798072) (xy 53.818758 -273.773465)
			(xy 53.864774 -273.756013) (xy 53.912993 -273.746169) (xy 53.962168 -273.744188) (xy 54.011023 -273.75012)
			(xy 54.058294 -273.763812) (xy 54.102756 -273.78491) (xy 54.143259 -273.812866) (xy 54.178752 -273.846958)
			(xy 54.208317 -273.886302) (xy 54.231188 -273.929879) (xy 54.246772 -273.97656) (xy 54.254667 -274.025137)
			(xy 54.255162 -274.049744) (xy 55.54397 -274.049744) (xy 55.54793 -274.00069) (xy 55.559707 -273.952906)
			(xy 55.578998 -273.90763) (xy 55.605301 -273.866034) (xy 55.637936 -273.829197) (xy 55.676057 -273.798072)
			(xy 55.718678 -273.773465) (xy 55.764694 -273.756013) (xy 55.812913 -273.746169) (xy 55.862088 -273.744188)
			(xy 55.910943 -273.75012) (xy 55.958214 -273.763812) (xy 56.002676 -273.78491) (xy 56.043179 -273.812866)
			(xy 56.078672 -273.846958) (xy 56.108237 -273.886302) (xy 56.131108 -273.929879) (xy 56.146692 -273.97656)
			(xy 56.154587 -274.025137) (xy 56.155082 -274.049744) (xy 57.444144 -274.049744) (xy 57.448104 -274.00069)
			(xy 57.459881 -273.952906) (xy 57.479172 -273.90763) (xy 57.505475 -273.866034) (xy 57.53811 -273.829197)
			(xy 57.576231 -273.798072) (xy 57.618852 -273.773465) (xy 57.664868 -273.756013) (xy 57.713087 -273.746169)
			(xy 57.762262 -273.744188) (xy 57.811117 -273.75012) (xy 57.858388 -273.763812) (xy 57.90285 -273.78491)
			(xy 57.943353 -273.812866) (xy 57.978846 -273.846958) (xy 58.008411 -273.886302) (xy 58.031282 -273.929879)
			(xy 58.046866 -273.97656) (xy 58.054761 -274.025137) (xy 58.055251 -274.04949) (xy 59.34381 -274.04949)
			(xy 59.34777 -274.000436) (xy 59.359547 -273.952652) (xy 59.378838 -273.907376) (xy 59.405141 -273.86578)
			(xy 59.437776 -273.828943) (xy 59.475897 -273.797818) (xy 59.518518 -273.773211) (xy 59.564534 -273.755759)
			(xy 59.612753 -273.745915) (xy 59.661928 -273.743934) (xy 59.710783 -273.749866) (xy 59.758054 -273.763558)
			(xy 59.802516 -273.784656) (xy 59.843019 -273.812612) (xy 59.878512 -273.846704) (xy 59.908077 -273.886048)
			(xy 59.930948 -273.929625) (xy 59.946532 -273.976306) (xy 59.954427 -274.024883) (xy 59.954922 -274.04949)
			(xy 59.954917 -274.049744) (xy 61.24373 -274.049744) (xy 61.24769 -274.00069) (xy 61.259467 -273.952906)
			(xy 61.278758 -273.90763) (xy 61.305061 -273.866034) (xy 61.337696 -273.829197) (xy 61.375817 -273.798072)
			(xy 61.418438 -273.773465) (xy 61.464454 -273.756013) (xy 61.512673 -273.746169) (xy 61.561848 -273.744188)
			(xy 61.610703 -273.75012) (xy 61.657974 -273.763812) (xy 61.702436 -273.78491) (xy 61.742939 -273.812866)
			(xy 61.778432 -273.846958) (xy 61.807997 -273.886302) (xy 61.830868 -273.929879) (xy 61.846452 -273.97656)
			(xy 61.854347 -274.025137) (xy 61.854842 -274.049744) (xy 63.143904 -274.049744) (xy 63.147864 -274.00069)
			(xy 63.159641 -273.952906) (xy 63.178932 -273.90763) (xy 63.205235 -273.866034) (xy 63.23787 -273.829197)
			(xy 63.275991 -273.798072) (xy 63.318612 -273.773465) (xy 63.364628 -273.756013) (xy 63.412847 -273.746169)
			(xy 63.462022 -273.744188) (xy 63.510877 -273.75012) (xy 63.558148 -273.763812) (xy 63.60261 -273.78491)
			(xy 63.643113 -273.812866) (xy 63.678606 -273.846958) (xy 63.708171 -273.886302) (xy 63.731042 -273.929879)
			(xy 63.746626 -273.97656) (xy 63.754521 -274.025137) (xy 63.755016 -274.049744) (xy 65.043824 -274.049744)
			(xy 65.047784 -274.00069) (xy 65.059561 -273.952906) (xy 65.078852 -273.90763) (xy 65.105155 -273.866034)
			(xy 65.13779 -273.829197) (xy 65.175911 -273.798072) (xy 65.218532 -273.773465) (xy 65.264548 -273.756013)
			(xy 65.312767 -273.746169) (xy 65.361942 -273.744188) (xy 65.410797 -273.75012) (xy 65.458068 -273.763812)
			(xy 65.50253 -273.78491) (xy 65.543033 -273.812866) (xy 65.578526 -273.846958) (xy 65.608091 -273.886302)
			(xy 65.630962 -273.929879) (xy 65.646546 -273.97656) (xy 65.654441 -274.025137) (xy 65.654936 -274.049744)
			(xy 66.943744 -274.049744) (xy 66.947704 -274.00069) (xy 66.959481 -273.952906) (xy 66.978772 -273.90763)
			(xy 67.005075 -273.866034) (xy 67.03771 -273.829197) (xy 67.075831 -273.798072) (xy 67.118452 -273.773465)
			(xy 67.164468 -273.756013) (xy 67.212687 -273.746169) (xy 67.261862 -273.744188) (xy 67.310717 -273.75012)
			(xy 67.357988 -273.763812) (xy 67.40245 -273.78491) (xy 67.442953 -273.812866) (xy 67.478446 -273.846958)
			(xy 67.508011 -273.886302) (xy 67.530882 -273.929879) (xy 67.546466 -273.97656) (xy 67.554361 -274.025137)
			(xy 67.554856 -274.049744) (xy 68.843918 -274.049744) (xy 68.847878 -274.00069) (xy 68.859655 -273.952906)
			(xy 68.878946 -273.90763) (xy 68.905249 -273.866034) (xy 68.937884 -273.829197) (xy 68.976005 -273.798072)
			(xy 69.018626 -273.773465) (xy 69.064642 -273.756013) (xy 69.112861 -273.746169) (xy 69.162036 -273.744188)
			(xy 69.210891 -273.75012) (xy 69.258162 -273.763812) (xy 69.302624 -273.78491) (xy 69.343127 -273.812866)
			(xy 69.37862 -273.846958) (xy 69.408185 -273.886302) (xy 69.431056 -273.929879) (xy 69.44664 -273.97656)
			(xy 69.454535 -274.025137) (xy 69.45503 -274.049744) (xy 70.743838 -274.049744) (xy 70.747798 -274.00069)
			(xy 70.759575 -273.952906) (xy 70.778866 -273.90763) (xy 70.805169 -273.866034) (xy 70.837804 -273.829197)
			(xy 70.875925 -273.798072) (xy 70.918546 -273.773465) (xy 70.964562 -273.756013) (xy 71.012781 -273.746169)
			(xy 71.061956 -273.744188) (xy 71.110811 -273.75012) (xy 71.158082 -273.763812) (xy 71.202544 -273.78491)
			(xy 71.243047 -273.812866) (xy 71.27854 -273.846958) (xy 71.308105 -273.886302) (xy 71.330976 -273.929879)
			(xy 71.34656 -273.97656) (xy 71.354455 -274.025137) (xy 71.35495 -274.049744) (xy 72.643758 -274.049744)
			(xy 72.647718 -274.00069) (xy 72.659495 -273.952906) (xy 72.678786 -273.90763) (xy 72.705089 -273.866034)
			(xy 72.737724 -273.829197) (xy 72.775845 -273.798072) (xy 72.818466 -273.773465) (xy 72.864482 -273.756013)
			(xy 72.912701 -273.746169) (xy 72.961876 -273.744188) (xy 73.010731 -273.75012) (xy 73.058002 -273.763812)
			(xy 73.102464 -273.78491) (xy 73.142967 -273.812866) (xy 73.17846 -273.846958) (xy 73.208025 -273.886302)
			(xy 73.230896 -273.929879) (xy 73.24648 -273.97656) (xy 73.254375 -274.025137) (xy 73.25487 -274.049744)
			(xy 74.543932 -274.049744) (xy 74.547892 -274.00069) (xy 74.559669 -273.952906) (xy 74.57896 -273.90763)
			(xy 74.605263 -273.866034) (xy 74.637898 -273.829197) (xy 74.676019 -273.798072) (xy 74.71864 -273.773465)
			(xy 74.764656 -273.756013) (xy 74.812875 -273.746169) (xy 74.86205 -273.744188) (xy 74.910905 -273.75012)
			(xy 74.958176 -273.763812) (xy 75.002638 -273.78491) (xy 75.043141 -273.812866) (xy 75.078634 -273.846958)
			(xy 75.108199 -273.886302) (xy 75.13107 -273.929879) (xy 75.146654 -273.97656) (xy 75.154549 -274.025137)
			(xy 75.155044 -274.049744) (xy 76.443852 -274.049744) (xy 76.447812 -274.00069) (xy 76.459589 -273.952906)
			(xy 76.47888 -273.90763) (xy 76.505183 -273.866034) (xy 76.537818 -273.829197) (xy 76.575939 -273.798072)
			(xy 76.61856 -273.773465) (xy 76.664576 -273.756013) (xy 76.712795 -273.746169) (xy 76.76197 -273.744188)
			(xy 76.810825 -273.75012) (xy 76.858096 -273.763812) (xy 76.902558 -273.78491) (xy 76.943061 -273.812866)
			(xy 76.978554 -273.846958) (xy 77.008119 -273.886302) (xy 77.03099 -273.929879) (xy 77.046574 -273.97656)
			(xy 77.054469 -274.025137) (xy 77.054964 -274.049744) (xy 78.343772 -274.049744) (xy 78.347732 -274.00069)
			(xy 78.359509 -273.952906) (xy 78.3788 -273.90763) (xy 78.405103 -273.866034) (xy 78.437738 -273.829197)
			(xy 78.475859 -273.798072) (xy 78.51848 -273.773465) (xy 78.564496 -273.756013) (xy 78.612715 -273.746169)
			(xy 78.66189 -273.744188) (xy 78.710745 -273.75012) (xy 78.758016 -273.763812) (xy 78.802478 -273.78491)
			(xy 78.842981 -273.812866) (xy 78.878474 -273.846958) (xy 78.908039 -273.886302) (xy 78.93091 -273.929879)
			(xy 78.946494 -273.97656) (xy 78.954389 -274.025137) (xy 78.954884 -274.049744) (xy 80.243692 -274.049744)
			(xy 80.247652 -274.00069) (xy 80.259429 -273.952906) (xy 80.27872 -273.90763) (xy 80.305023 -273.866034)
			(xy 80.337658 -273.829197) (xy 80.375779 -273.798072) (xy 80.4184 -273.773465) (xy 80.464416 -273.756013)
			(xy 80.512635 -273.746169) (xy 80.56181 -273.744188) (xy 80.610665 -273.75012) (xy 80.657936 -273.763812)
			(xy 80.702398 -273.78491) (xy 80.742901 -273.812866) (xy 80.778394 -273.846958) (xy 80.807959 -273.886302)
			(xy 80.83083 -273.929879) (xy 80.846414 -273.97656) (xy 80.854309 -274.025137) (xy 80.854804 -274.049744)
			(xy 160.24404 -274.049744) (xy 160.248 -274.00069) (xy 160.259777 -273.952906) (xy 160.279068 -273.90763)
			(xy 160.305371 -273.866034) (xy 160.338006 -273.829197) (xy 160.376127 -273.798072) (xy 160.418748 -273.773465)
			(xy 160.464764 -273.756013) (xy 160.512983 -273.746169) (xy 160.562158 -273.744188) (xy 160.611013 -273.75012)
			(xy 160.658284 -273.763812) (xy 160.702746 -273.78491) (xy 160.743249 -273.812866) (xy 160.778742 -273.846958)
			(xy 160.808307 -273.886302) (xy 160.831178 -273.929879) (xy 160.846762 -273.97656) (xy 160.854657 -274.025137)
			(xy 160.855152 -274.049744) (xy 162.144214 -274.049744) (xy 162.148174 -274.00069) (xy 162.159951 -273.952906)
			(xy 162.179242 -273.90763) (xy 162.205545 -273.866034) (xy 162.23818 -273.829197) (xy 162.276301 -273.798072)
			(xy 162.318922 -273.773465) (xy 162.364938 -273.756013) (xy 162.413157 -273.746169) (xy 162.462332 -273.744188)
			(xy 162.511187 -273.75012) (xy 162.558458 -273.763812) (xy 162.60292 -273.78491) (xy 162.643423 -273.812866)
			(xy 162.678916 -273.846958) (xy 162.708481 -273.886302) (xy 162.731352 -273.929879) (xy 162.746936 -273.97656)
			(xy 162.754831 -274.025137) (xy 162.755326 -274.049744) (xy 164.044134 -274.049744) (xy 164.048094 -274.00069)
			(xy 164.059871 -273.952906) (xy 164.079162 -273.90763) (xy 164.105465 -273.866034) (xy 164.1381 -273.829197)
			(xy 164.176221 -273.798072) (xy 164.218842 -273.773465) (xy 164.264858 -273.756013) (xy 164.313077 -273.746169)
			(xy 164.362252 -273.744188) (xy 164.411107 -273.75012) (xy 164.458378 -273.763812) (xy 164.50284 -273.78491)
			(xy 164.543343 -273.812866) (xy 164.578836 -273.846958) (xy 164.608401 -273.886302) (xy 164.631272 -273.929879)
			(xy 164.646856 -273.97656) (xy 164.654751 -274.025137) (xy 164.655246 -274.049744) (xy 165.944054 -274.049744)
			(xy 165.948014 -274.00069) (xy 165.959791 -273.952906) (xy 165.979082 -273.90763) (xy 166.005385 -273.866034)
			(xy 166.03802 -273.829197) (xy 166.076141 -273.798072) (xy 166.118762 -273.773465) (xy 166.164778 -273.756013)
			(xy 166.212997 -273.746169) (xy 166.262172 -273.744188) (xy 166.311027 -273.75012) (xy 166.358298 -273.763812)
			(xy 166.40276 -273.78491) (xy 166.443263 -273.812866) (xy 166.478756 -273.846958) (xy 166.508321 -273.886302)
			(xy 166.531192 -273.929879) (xy 166.546776 -273.97656) (xy 166.554671 -274.025137) (xy 166.555166 -274.049744)
			(xy 167.844228 -274.049744) (xy 167.848188 -274.00069) (xy 167.859965 -273.952906) (xy 167.879256 -273.90763)
			(xy 167.905559 -273.866034) (xy 167.938194 -273.829197) (xy 167.976315 -273.798072) (xy 168.018936 -273.773465)
			(xy 168.064952 -273.756013) (xy 168.113171 -273.746169) (xy 168.162346 -273.744188) (xy 168.211201 -273.75012)
			(xy 168.258472 -273.763812) (xy 168.302934 -273.78491) (xy 168.343437 -273.812866) (xy 168.37893 -273.846958)
			(xy 168.408495 -273.886302) (xy 168.431366 -273.929879) (xy 168.44695 -273.97656) (xy 168.454845 -274.025137)
			(xy 168.45534 -274.049744) (xy 169.744148 -274.049744) (xy 169.748108 -274.00069) (xy 169.759885 -273.952906)
			(xy 169.779176 -273.90763) (xy 169.805479 -273.866034) (xy 169.838114 -273.829197) (xy 169.876235 -273.798072)
			(xy 169.918856 -273.773465) (xy 169.964872 -273.756013) (xy 170.013091 -273.746169) (xy 170.062266 -273.744188)
			(xy 170.111121 -273.75012) (xy 170.158392 -273.763812) (xy 170.202854 -273.78491) (xy 170.243357 -273.812866)
			(xy 170.27885 -273.846958) (xy 170.308415 -273.886302) (xy 170.331286 -273.929879) (xy 170.34687 -273.97656)
			(xy 170.354765 -274.025137) (xy 170.35526 -274.049744) (xy 171.644068 -274.049744) (xy 171.648028 -274.00069)
			(xy 171.659805 -273.952906) (xy 171.679096 -273.90763) (xy 171.705399 -273.866034) (xy 171.738034 -273.829197)
			(xy 171.776155 -273.798072) (xy 171.818776 -273.773465) (xy 171.864792 -273.756013) (xy 171.913011 -273.746169)
			(xy 171.962186 -273.744188) (xy 172.011041 -273.75012) (xy 172.058312 -273.763812) (xy 172.102774 -273.78491)
			(xy 172.143277 -273.812866) (xy 172.17877 -273.846958) (xy 172.208335 -273.886302) (xy 172.231206 -273.929879)
			(xy 172.24679 -273.97656) (xy 172.254685 -274.025137) (xy 172.25518 -274.049744) (xy 173.544242 -274.049744)
			(xy 173.548202 -274.00069) (xy 173.559979 -273.952906) (xy 173.57927 -273.90763) (xy 173.605573 -273.866034)
			(xy 173.638208 -273.829197) (xy 173.676329 -273.798072) (xy 173.71895 -273.773465) (xy 173.764966 -273.756013)
			(xy 173.813185 -273.746169) (xy 173.86236 -273.744188) (xy 173.911215 -273.75012) (xy 173.958486 -273.763812)
			(xy 174.002948 -273.78491) (xy 174.043451 -273.812866) (xy 174.078944 -273.846958) (xy 174.108509 -273.886302)
			(xy 174.13138 -273.929879) (xy 174.146964 -273.97656) (xy 174.154859 -274.025137) (xy 174.155349 -274.04949)
			(xy 175.443908 -274.04949) (xy 175.447868 -274.000436) (xy 175.459645 -273.952652) (xy 175.478936 -273.907376)
			(xy 175.505239 -273.86578) (xy 175.537874 -273.828943) (xy 175.575995 -273.797818) (xy 175.618616 -273.773211)
			(xy 175.664632 -273.755759) (xy 175.712851 -273.745915) (xy 175.762026 -273.743934) (xy 175.810881 -273.749866)
			(xy 175.858152 -273.763558) (xy 175.902614 -273.784656) (xy 175.943117 -273.812612) (xy 175.97861 -273.846704)
			(xy 176.008175 -273.886048) (xy 176.031046 -273.929625) (xy 176.04663 -273.976306) (xy 176.054525 -274.024883)
			(xy 176.05502 -274.04949) (xy 176.055015 -274.049744) (xy 177.343828 -274.049744) (xy 177.347788 -274.00069)
			(xy 177.359565 -273.952906) (xy 177.378856 -273.90763) (xy 177.405159 -273.866034) (xy 177.437794 -273.829197)
			(xy 177.475915 -273.798072) (xy 177.518536 -273.773465) (xy 177.564552 -273.756013) (xy 177.612771 -273.746169)
			(xy 177.661946 -273.744188) (xy 177.710801 -273.75012) (xy 177.758072 -273.763812) (xy 177.802534 -273.78491)
			(xy 177.843037 -273.812866) (xy 177.87853 -273.846958) (xy 177.908095 -273.886302) (xy 177.930966 -273.929879)
			(xy 177.94655 -273.97656) (xy 177.954445 -274.025137) (xy 177.95494 -274.049744) (xy 179.244002 -274.049744)
			(xy 179.247962 -274.00069) (xy 179.259739 -273.952906) (xy 179.27903 -273.90763) (xy 179.305333 -273.866034)
			(xy 179.337968 -273.829197) (xy 179.376089 -273.798072) (xy 179.41871 -273.773465) (xy 179.464726 -273.756013)
			(xy 179.512945 -273.746169) (xy 179.56212 -273.744188) (xy 179.610975 -273.75012) (xy 179.658246 -273.763812)
			(xy 179.702708 -273.78491) (xy 179.743211 -273.812866) (xy 179.778704 -273.846958) (xy 179.808269 -273.886302)
			(xy 179.83114 -273.929879) (xy 179.846724 -273.97656) (xy 179.854619 -274.025137) (xy 179.855114 -274.049744)
			(xy 181.143922 -274.049744) (xy 181.147882 -274.00069) (xy 181.159659 -273.952906) (xy 181.17895 -273.90763)
			(xy 181.205253 -273.866034) (xy 181.237888 -273.829197) (xy 181.276009 -273.798072) (xy 181.31863 -273.773465)
			(xy 181.364646 -273.756013) (xy 181.412865 -273.746169) (xy 181.46204 -273.744188) (xy 181.510895 -273.75012)
			(xy 181.558166 -273.763812) (xy 181.602628 -273.78491) (xy 181.643131 -273.812866) (xy 181.678624 -273.846958)
			(xy 181.708189 -273.886302) (xy 181.73106 -273.929879) (xy 181.746644 -273.97656) (xy 181.754539 -274.025137)
			(xy 181.755034 -274.049744) (xy 183.043842 -274.049744) (xy 183.047802 -274.00069) (xy 183.059579 -273.952906)
			(xy 183.07887 -273.90763) (xy 183.105173 -273.866034) (xy 183.137808 -273.829197) (xy 183.175929 -273.798072)
			(xy 183.21855 -273.773465) (xy 183.264566 -273.756013) (xy 183.312785 -273.746169) (xy 183.36196 -273.744188)
			(xy 183.410815 -273.75012) (xy 183.458086 -273.763812) (xy 183.502548 -273.78491) (xy 183.543051 -273.812866)
			(xy 183.578544 -273.846958) (xy 183.608109 -273.886302) (xy 183.63098 -273.929879) (xy 183.646564 -273.97656)
			(xy 183.654459 -274.025137) (xy 183.654954 -274.049744) (xy 184.944016 -274.049744) (xy 184.947976 -274.00069)
			(xy 184.959753 -273.952906) (xy 184.979044 -273.90763) (xy 185.005347 -273.866034) (xy 185.037982 -273.829197)
			(xy 185.076103 -273.798072) (xy 185.118724 -273.773465) (xy 185.16474 -273.756013) (xy 185.212959 -273.746169)
			(xy 185.262134 -273.744188) (xy 185.310989 -273.75012) (xy 185.35826 -273.763812) (xy 185.402722 -273.78491)
			(xy 185.443225 -273.812866) (xy 185.478718 -273.846958) (xy 185.508283 -273.886302) (xy 185.531154 -273.929879)
			(xy 185.546738 -273.97656) (xy 185.554633 -274.025137) (xy 185.555128 -274.049744) (xy 186.843936 -274.049744)
			(xy 186.847896 -274.00069) (xy 186.859673 -273.952906) (xy 186.878964 -273.90763) (xy 186.905267 -273.866034)
			(xy 186.937902 -273.829197) (xy 186.976023 -273.798072) (xy 187.018644 -273.773465) (xy 187.06466 -273.756013)
			(xy 187.112879 -273.746169) (xy 187.162054 -273.744188) (xy 187.210909 -273.75012) (xy 187.25818 -273.763812)
			(xy 187.302642 -273.78491) (xy 187.343145 -273.812866) (xy 187.378638 -273.846958) (xy 187.408203 -273.886302)
			(xy 187.431074 -273.929879) (xy 187.446658 -273.97656) (xy 187.454553 -274.025137) (xy 187.455048 -274.049744)
			(xy 188.743856 -274.049744) (xy 188.747816 -274.00069) (xy 188.759593 -273.952906) (xy 188.778884 -273.90763)
			(xy 188.805187 -273.866034) (xy 188.837822 -273.829197) (xy 188.875943 -273.798072) (xy 188.918564 -273.773465)
			(xy 188.96458 -273.756013) (xy 189.012799 -273.746169) (xy 189.061974 -273.744188) (xy 189.110829 -273.75012)
			(xy 189.1581 -273.763812) (xy 189.202562 -273.78491) (xy 189.243065 -273.812866) (xy 189.278558 -273.846958)
			(xy 189.308123 -273.886302) (xy 189.330994 -273.929879) (xy 189.346578 -273.97656) (xy 189.354473 -274.025137)
			(xy 189.354968 -274.049744) (xy 190.64403 -274.049744) (xy 190.64799 -274.00069) (xy 190.659767 -273.952906)
			(xy 190.679058 -273.90763) (xy 190.705361 -273.866034) (xy 190.737996 -273.829197) (xy 190.776117 -273.798072)
			(xy 190.818738 -273.773465) (xy 190.864754 -273.756013) (xy 190.912973 -273.746169) (xy 190.962148 -273.744188)
			(xy 191.011003 -273.75012) (xy 191.058274 -273.763812) (xy 191.102736 -273.78491) (xy 191.143239 -273.812866)
			(xy 191.178732 -273.846958) (xy 191.208297 -273.886302) (xy 191.231168 -273.929879) (xy 191.246752 -273.97656)
			(xy 191.254647 -274.025137) (xy 191.255142 -274.049744) (xy 192.54395 -274.049744) (xy 192.54791 -274.00069)
			(xy 192.559687 -273.952906) (xy 192.578978 -273.90763) (xy 192.605281 -273.866034) (xy 192.637916 -273.829197)
			(xy 192.676037 -273.798072) (xy 192.718658 -273.773465) (xy 192.764674 -273.756013) (xy 192.812893 -273.746169)
			(xy 192.862068 -273.744188) (xy 192.910923 -273.75012) (xy 192.958194 -273.763812) (xy 193.002656 -273.78491)
			(xy 193.043159 -273.812866) (xy 193.078652 -273.846958) (xy 193.108217 -273.886302) (xy 193.131088 -273.929879)
			(xy 193.146672 -273.97656) (xy 193.154567 -274.025137) (xy 193.155062 -274.049744) (xy 194.44387 -274.049744)
			(xy 194.44783 -274.00069) (xy 194.459607 -273.952906) (xy 194.478898 -273.90763) (xy 194.505201 -273.866034)
			(xy 194.537836 -273.829197) (xy 194.575957 -273.798072) (xy 194.618578 -273.773465) (xy 194.664594 -273.756013)
			(xy 194.712813 -273.746169) (xy 194.761988 -273.744188) (xy 194.810843 -273.75012) (xy 194.858114 -273.763812)
			(xy 194.902576 -273.78491) (xy 194.943079 -273.812866) (xy 194.978572 -273.846958) (xy 195.008137 -273.886302)
			(xy 195.031008 -273.929879) (xy 195.046592 -273.97656) (xy 195.054487 -274.025137) (xy 195.054982 -274.049744)
			(xy 196.34379 -274.049744) (xy 196.34775 -274.00069) (xy 196.359527 -273.952906) (xy 196.378818 -273.90763)
			(xy 196.405121 -273.866034) (xy 196.437756 -273.829197) (xy 196.475877 -273.798072) (xy 196.518498 -273.773465)
			(xy 196.564514 -273.756013) (xy 196.612733 -273.746169) (xy 196.661908 -273.744188) (xy 196.710763 -273.75012)
			(xy 196.758034 -273.763812) (xy 196.802496 -273.78491) (xy 196.842999 -273.812866) (xy 196.878492 -273.846958)
			(xy 196.908057 -273.886302) (xy 196.930928 -273.929879) (xy 196.946512 -273.97656) (xy 196.954407 -274.025137)
			(xy 196.954902 -274.049744) (xy 276.343884 -274.049744) (xy 276.347844 -274.00069) (xy 276.359621 -273.952906)
			(xy 276.378912 -273.90763) (xy 276.405215 -273.866034) (xy 276.43785 -273.829197) (xy 276.475971 -273.798072)
			(xy 276.518592 -273.773465) (xy 276.564608 -273.756013) (xy 276.612827 -273.746169) (xy 276.662002 -273.744188)
			(xy 276.710857 -273.75012) (xy 276.758128 -273.763812) (xy 276.80259 -273.78491) (xy 276.843093 -273.812866)
			(xy 276.878586 -273.846958) (xy 276.908151 -273.886302) (xy 276.931022 -273.929879) (xy 276.946606 -273.97656)
			(xy 276.954501 -274.025137) (xy 276.954996 -274.049744) (xy 278.244058 -274.049744) (xy 278.248018 -274.00069)
			(xy 278.259795 -273.952906) (xy 278.279086 -273.90763) (xy 278.305389 -273.866034) (xy 278.338024 -273.829197)
			(xy 278.376145 -273.798072) (xy 278.418766 -273.773465) (xy 278.464782 -273.756013) (xy 278.513001 -273.746169)
			(xy 278.562176 -273.744188) (xy 278.611031 -273.75012) (xy 278.658302 -273.763812) (xy 278.702764 -273.78491)
			(xy 278.743267 -273.812866) (xy 278.77876 -273.846958) (xy 278.808325 -273.886302) (xy 278.831196 -273.929879)
			(xy 278.84678 -273.97656) (xy 278.854675 -274.025137) (xy 278.85517 -274.049744) (xy 280.143978 -274.049744)
			(xy 280.147938 -274.00069) (xy 280.159715 -273.952906) (xy 280.179006 -273.90763) (xy 280.205309 -273.866034)
			(xy 280.237944 -273.829197) (xy 280.276065 -273.798072) (xy 280.318686 -273.773465) (xy 280.364702 -273.756013)
			(xy 280.412921 -273.746169) (xy 280.462096 -273.744188) (xy 280.510951 -273.75012) (xy 280.558222 -273.763812)
			(xy 280.602684 -273.78491) (xy 280.643187 -273.812866) (xy 280.67868 -273.846958) (xy 280.708245 -273.886302)
			(xy 280.731116 -273.929879) (xy 280.7467 -273.97656) (xy 280.754595 -274.025137) (xy 280.75509 -274.049744)
			(xy 282.043898 -274.049744) (xy 282.047858 -274.00069) (xy 282.059635 -273.952906) (xy 282.078926 -273.90763)
			(xy 282.105229 -273.866034) (xy 282.137864 -273.829197) (xy 282.175985 -273.798072) (xy 282.218606 -273.773465)
			(xy 282.264622 -273.756013) (xy 282.312841 -273.746169) (xy 282.362016 -273.744188) (xy 282.410871 -273.75012)
			(xy 282.458142 -273.763812) (xy 282.502604 -273.78491) (xy 282.543107 -273.812866) (xy 282.5786 -273.846958)
			(xy 282.608165 -273.886302) (xy 282.631036 -273.929879) (xy 282.64662 -273.97656) (xy 282.654515 -274.025137)
			(xy 282.65501 -274.049744) (xy 283.944072 -274.049744) (xy 283.948032 -274.00069) (xy 283.959809 -273.952906)
			(xy 283.9791 -273.90763) (xy 284.005403 -273.866034) (xy 284.038038 -273.829197) (xy 284.076159 -273.798072)
			(xy 284.11878 -273.773465) (xy 284.164796 -273.756013) (xy 284.213015 -273.746169) (xy 284.26219 -273.744188)
			(xy 284.311045 -273.75012) (xy 284.358316 -273.763812) (xy 284.402778 -273.78491) (xy 284.443281 -273.812866)
			(xy 284.478774 -273.846958) (xy 284.508339 -273.886302) (xy 284.53121 -273.929879) (xy 284.546794 -273.97656)
			(xy 284.554689 -274.025137) (xy 284.555184 -274.049744) (xy 285.843992 -274.049744) (xy 285.847952 -274.00069)
			(xy 285.859729 -273.952906) (xy 285.87902 -273.90763) (xy 285.905323 -273.866034) (xy 285.937958 -273.829197)
			(xy 285.976079 -273.798072) (xy 286.0187 -273.773465) (xy 286.064716 -273.756013) (xy 286.112935 -273.746169)
			(xy 286.16211 -273.744188) (xy 286.210965 -273.75012) (xy 286.258236 -273.763812) (xy 286.302698 -273.78491)
			(xy 286.343201 -273.812866) (xy 286.378694 -273.846958) (xy 286.408259 -273.886302) (xy 286.43113 -273.929879)
			(xy 286.446714 -273.97656) (xy 286.454609 -274.025137) (xy 286.455104 -274.049744) (xy 287.743912 -274.049744)
			(xy 287.747872 -274.00069) (xy 287.759649 -273.952906) (xy 287.77894 -273.90763) (xy 287.805243 -273.866034)
			(xy 287.837878 -273.829197) (xy 287.875999 -273.798072) (xy 287.91862 -273.773465) (xy 287.964636 -273.756013)
			(xy 288.012855 -273.746169) (xy 288.06203 -273.744188) (xy 288.110885 -273.75012) (xy 288.158156 -273.763812)
			(xy 288.202618 -273.78491) (xy 288.243121 -273.812866) (xy 288.278614 -273.846958) (xy 288.308179 -273.886302)
			(xy 288.33105 -273.929879) (xy 288.346634 -273.97656) (xy 288.354529 -274.025137) (xy 288.355024 -274.049744)
			(xy 289.644086 -274.049744) (xy 289.648046 -274.00069) (xy 289.659823 -273.952906) (xy 289.679114 -273.90763)
			(xy 289.705417 -273.866034) (xy 289.738052 -273.829197) (xy 289.776173 -273.798072) (xy 289.818794 -273.773465)
			(xy 289.86481 -273.756013) (xy 289.913029 -273.746169) (xy 289.962204 -273.744188) (xy 290.011059 -273.75012)
			(xy 290.05833 -273.763812) (xy 290.102792 -273.78491) (xy 290.143295 -273.812866) (xy 290.178788 -273.846958)
			(xy 290.208353 -273.886302) (xy 290.231224 -273.929879) (xy 290.246808 -273.97656) (xy 290.254703 -274.025137)
			(xy 290.255193 -274.04949) (xy 291.543752 -274.04949) (xy 291.547712 -274.000436) (xy 291.559489 -273.952652)
			(xy 291.57878 -273.907376) (xy 291.605083 -273.86578) (xy 291.637718 -273.828943) (xy 291.675839 -273.797818)
			(xy 291.71846 -273.773211) (xy 291.764476 -273.755759) (xy 291.812695 -273.745915) (xy 291.86187 -273.743934)
			(xy 291.910725 -273.749866) (xy 291.957996 -273.763558) (xy 292.002458 -273.784656) (xy 292.042961 -273.812612)
			(xy 292.078454 -273.846704) (xy 292.108019 -273.886048) (xy 292.13089 -273.929625) (xy 292.146474 -273.976306)
			(xy 292.154369 -274.024883) (xy 292.154864 -274.04949) (xy 292.154859 -274.049744) (xy 293.443672 -274.049744)
			(xy 293.447632 -274.00069) (xy 293.459409 -273.952906) (xy 293.4787 -273.90763) (xy 293.505003 -273.866034)
			(xy 293.537638 -273.829197) (xy 293.575759 -273.798072) (xy 293.61838 -273.773465) (xy 293.664396 -273.756013)
			(xy 293.712615 -273.746169) (xy 293.76179 -273.744188) (xy 293.810645 -273.75012) (xy 293.857916 -273.763812)
			(xy 293.902378 -273.78491) (xy 293.942881 -273.812866) (xy 293.978374 -273.846958) (xy 294.007939 -273.886302)
			(xy 294.03081 -273.929879) (xy 294.046394 -273.97656) (xy 294.054289 -274.025137) (xy 294.054784 -274.049744)
			(xy 295.343846 -274.049744) (xy 295.347806 -274.00069) (xy 295.359583 -273.952906) (xy 295.378874 -273.90763)
			(xy 295.405177 -273.866034) (xy 295.437812 -273.829197) (xy 295.475933 -273.798072) (xy 295.518554 -273.773465)
			(xy 295.56457 -273.756013) (xy 295.612789 -273.746169) (xy 295.661964 -273.744188) (xy 295.710819 -273.75012)
			(xy 295.75809 -273.763812) (xy 295.802552 -273.78491) (xy 295.843055 -273.812866) (xy 295.878548 -273.846958)
			(xy 295.908113 -273.886302) (xy 295.930984 -273.929879) (xy 295.946568 -273.97656) (xy 295.954463 -274.025137)
			(xy 295.954958 -274.049744) (xy 297.243766 -274.049744) (xy 297.247726 -274.00069) (xy 297.259503 -273.952906)
			(xy 297.278794 -273.90763) (xy 297.305097 -273.866034) (xy 297.337732 -273.829197) (xy 297.375853 -273.798072)
			(xy 297.418474 -273.773465) (xy 297.46449 -273.756013) (xy 297.512709 -273.746169) (xy 297.561884 -273.744188)
			(xy 297.610739 -273.75012) (xy 297.65801 -273.763812) (xy 297.702472 -273.78491) (xy 297.742975 -273.812866)
			(xy 297.778468 -273.846958) (xy 297.808033 -273.886302) (xy 297.830904 -273.929879) (xy 297.846488 -273.97656)
			(xy 297.854383 -274.025137) (xy 297.854878 -274.049744) (xy 299.143686 -274.049744) (xy 299.147646 -274.00069)
			(xy 299.159423 -273.952906) (xy 299.178714 -273.90763) (xy 299.205017 -273.866034) (xy 299.237652 -273.829197)
			(xy 299.275773 -273.798072) (xy 299.318394 -273.773465) (xy 299.36441 -273.756013) (xy 299.412629 -273.746169)
			(xy 299.461804 -273.744188) (xy 299.510659 -273.75012) (xy 299.55793 -273.763812) (xy 299.602392 -273.78491)
			(xy 299.642895 -273.812866) (xy 299.678388 -273.846958) (xy 299.707953 -273.886302) (xy 299.730824 -273.929879)
			(xy 299.746408 -273.97656) (xy 299.754303 -274.025137) (xy 299.754798 -274.049744) (xy 301.04386 -274.049744)
			(xy 301.04782 -274.00069) (xy 301.059597 -273.952906) (xy 301.078888 -273.90763) (xy 301.105191 -273.866034)
			(xy 301.137826 -273.829197) (xy 301.175947 -273.798072) (xy 301.218568 -273.773465) (xy 301.264584 -273.756013)
			(xy 301.312803 -273.746169) (xy 301.361978 -273.744188) (xy 301.410833 -273.75012) (xy 301.458104 -273.763812)
			(xy 301.502566 -273.78491) (xy 301.543069 -273.812866) (xy 301.578562 -273.846958) (xy 301.608127 -273.886302)
			(xy 301.630998 -273.929879) (xy 301.646582 -273.97656) (xy 301.654477 -274.025137) (xy 301.654972 -274.049744)
			(xy 302.94378 -274.049744) (xy 302.94774 -274.00069) (xy 302.959517 -273.952906) (xy 302.978808 -273.90763)
			(xy 303.005111 -273.866034) (xy 303.037746 -273.829197) (xy 303.075867 -273.798072) (xy 303.118488 -273.773465)
			(xy 303.164504 -273.756013) (xy 303.212723 -273.746169) (xy 303.261898 -273.744188) (xy 303.310753 -273.75012)
			(xy 303.358024 -273.763812) (xy 303.402486 -273.78491) (xy 303.442989 -273.812866) (xy 303.478482 -273.846958)
			(xy 303.508047 -273.886302) (xy 303.530918 -273.929879) (xy 303.546502 -273.97656) (xy 303.554397 -274.025137)
			(xy 303.554892 -274.049744) (xy 304.8437 -274.049744) (xy 304.84766 -274.00069) (xy 304.859437 -273.952906)
			(xy 304.878728 -273.90763) (xy 304.905031 -273.866034) (xy 304.937666 -273.829197) (xy 304.975787 -273.798072)
			(xy 305.018408 -273.773465) (xy 305.064424 -273.756013) (xy 305.112643 -273.746169) (xy 305.161818 -273.744188)
			(xy 305.210673 -273.75012) (xy 305.257944 -273.763812) (xy 305.302406 -273.78491) (xy 305.342909 -273.812866)
			(xy 305.378402 -273.846958) (xy 305.407967 -273.886302) (xy 305.430838 -273.929879) (xy 305.446422 -273.97656)
			(xy 305.454317 -274.025137) (xy 305.454812 -274.049744) (xy 306.743874 -274.049744) (xy 306.747834 -274.00069)
			(xy 306.759611 -273.952906) (xy 306.778902 -273.90763) (xy 306.805205 -273.866034) (xy 306.83784 -273.829197)
			(xy 306.875961 -273.798072) (xy 306.918582 -273.773465) (xy 306.964598 -273.756013) (xy 307.012817 -273.746169)
			(xy 307.061992 -273.744188) (xy 307.110847 -273.75012) (xy 307.158118 -273.763812) (xy 307.20258 -273.78491)
			(xy 307.243083 -273.812866) (xy 307.278576 -273.846958) (xy 307.308141 -273.886302) (xy 307.331012 -273.929879)
			(xy 307.346596 -273.97656) (xy 307.354491 -274.025137) (xy 307.354986 -274.049744) (xy 308.643794 -274.049744)
			(xy 308.647754 -274.00069) (xy 308.659531 -273.952906) (xy 308.678822 -273.90763) (xy 308.705125 -273.866034)
			(xy 308.73776 -273.829197) (xy 308.775881 -273.798072) (xy 308.818502 -273.773465) (xy 308.864518 -273.756013)
			(xy 308.912737 -273.746169) (xy 308.961912 -273.744188) (xy 309.010767 -273.75012) (xy 309.058038 -273.763812)
			(xy 309.1025 -273.78491) (xy 309.143003 -273.812866) (xy 309.178496 -273.846958) (xy 309.208061 -273.886302)
			(xy 309.230932 -273.929879) (xy 309.246516 -273.97656) (xy 309.254411 -274.025137) (xy 309.254906 -274.049744)
			(xy 310.543714 -274.049744) (xy 310.547674 -274.00069) (xy 310.559451 -273.952906) (xy 310.578742 -273.90763)
			(xy 310.605045 -273.866034) (xy 310.63768 -273.829197) (xy 310.675801 -273.798072) (xy 310.718422 -273.773465)
			(xy 310.764438 -273.756013) (xy 310.812657 -273.746169) (xy 310.861832 -273.744188) (xy 310.910687 -273.75012)
			(xy 310.957958 -273.763812) (xy 311.00242 -273.78491) (xy 311.042923 -273.812866) (xy 311.078416 -273.846958)
			(xy 311.107981 -273.886302) (xy 311.130852 -273.929879) (xy 311.146436 -273.97656) (xy 311.154331 -274.025137)
			(xy 311.154826 -274.049744) (xy 312.443634 -274.049744) (xy 312.447594 -274.00069) (xy 312.459371 -273.952906)
			(xy 312.478662 -273.90763) (xy 312.504965 -273.866034) (xy 312.5376 -273.829197) (xy 312.575721 -273.798072)
			(xy 312.618342 -273.773465) (xy 312.664358 -273.756013) (xy 312.712577 -273.746169) (xy 312.761752 -273.744188)
			(xy 312.810607 -273.75012) (xy 312.857878 -273.763812) (xy 312.90234 -273.78491) (xy 312.942843 -273.812866)
			(xy 312.978336 -273.846958) (xy 313.007901 -273.886302) (xy 313.030772 -273.929879) (xy 313.046356 -273.97656)
			(xy 313.054251 -274.025137) (xy 313.054746 -274.049744) (xy 392.443982 -274.049744) (xy 392.447942 -274.00069)
			(xy 392.459719 -273.952906) (xy 392.47901 -273.90763) (xy 392.505313 -273.866034) (xy 392.537948 -273.829197)
			(xy 392.576069 -273.798072) (xy 392.61869 -273.773465) (xy 392.664706 -273.756013) (xy 392.712925 -273.746169)
			(xy 392.7621 -273.744188) (xy 392.810955 -273.75012) (xy 392.858226 -273.763812) (xy 392.902688 -273.78491)
			(xy 392.943191 -273.812866) (xy 392.978684 -273.846958) (xy 393.008249 -273.886302) (xy 393.03112 -273.929879)
			(xy 393.046704 -273.97656) (xy 393.054599 -274.025137) (xy 393.055094 -274.049744) (xy 394.344156 -274.049744)
			(xy 394.348116 -274.00069) (xy 394.359893 -273.952906) (xy 394.379184 -273.90763) (xy 394.405487 -273.866034)
			(xy 394.438122 -273.829197) (xy 394.476243 -273.798072) (xy 394.518864 -273.773465) (xy 394.56488 -273.756013)
			(xy 394.613099 -273.746169) (xy 394.662274 -273.744188) (xy 394.711129 -273.75012) (xy 394.7584 -273.763812)
			(xy 394.802862 -273.78491) (xy 394.843365 -273.812866) (xy 394.878858 -273.846958) (xy 394.908423 -273.886302)
			(xy 394.931294 -273.929879) (xy 394.946878 -273.97656) (xy 394.954773 -274.025137) (xy 394.955268 -274.049744)
			(xy 396.244076 -274.049744) (xy 396.248036 -274.00069) (xy 396.259813 -273.952906) (xy 396.279104 -273.90763)
			(xy 396.305407 -273.866034) (xy 396.338042 -273.829197) (xy 396.376163 -273.798072) (xy 396.418784 -273.773465)
			(xy 396.4648 -273.756013) (xy 396.513019 -273.746169) (xy 396.562194 -273.744188) (xy 396.611049 -273.75012)
			(xy 396.65832 -273.763812) (xy 396.702782 -273.78491) (xy 396.743285 -273.812866) (xy 396.778778 -273.846958)
			(xy 396.808343 -273.886302) (xy 396.831214 -273.929879) (xy 396.846798 -273.97656) (xy 396.854693 -274.025137)
			(xy 396.855188 -274.049744) (xy 398.143996 -274.049744) (xy 398.147956 -274.00069) (xy 398.159733 -273.952906)
			(xy 398.179024 -273.90763) (xy 398.205327 -273.866034) (xy 398.237962 -273.829197) (xy 398.276083 -273.798072)
			(xy 398.318704 -273.773465) (xy 398.36472 -273.756013) (xy 398.412939 -273.746169) (xy 398.462114 -273.744188)
			(xy 398.510969 -273.75012) (xy 398.55824 -273.763812) (xy 398.602702 -273.78491) (xy 398.643205 -273.812866)
			(xy 398.678698 -273.846958) (xy 398.708263 -273.886302) (xy 398.731134 -273.929879) (xy 398.746718 -273.97656)
			(xy 398.754613 -274.025137) (xy 398.755108 -274.049744) (xy 400.04417 -274.049744) (xy 400.04813 -274.00069)
			(xy 400.059907 -273.952906) (xy 400.079198 -273.90763) (xy 400.105501 -273.866034) (xy 400.138136 -273.829197)
			(xy 400.176257 -273.798072) (xy 400.218878 -273.773465) (xy 400.264894 -273.756013) (xy 400.313113 -273.746169)
			(xy 400.362288 -273.744188) (xy 400.411143 -273.75012) (xy 400.458414 -273.763812) (xy 400.502876 -273.78491)
			(xy 400.543379 -273.812866) (xy 400.578872 -273.846958) (xy 400.608437 -273.886302) (xy 400.631308 -273.929879)
			(xy 400.646892 -273.97656) (xy 400.654787 -274.025137) (xy 400.655282 -274.049744) (xy 401.94409 -274.049744)
			(xy 401.94805 -274.00069) (xy 401.959827 -273.952906) (xy 401.979118 -273.90763) (xy 402.005421 -273.866034)
			(xy 402.038056 -273.829197) (xy 402.076177 -273.798072) (xy 402.118798 -273.773465) (xy 402.164814 -273.756013)
			(xy 402.213033 -273.746169) (xy 402.262208 -273.744188) (xy 402.311063 -273.75012) (xy 402.358334 -273.763812)
			(xy 402.402796 -273.78491) (xy 402.443299 -273.812866) (xy 402.478792 -273.846958) (xy 402.508357 -273.886302)
			(xy 402.531228 -273.929879) (xy 402.546812 -273.97656) (xy 402.554707 -274.025137) (xy 402.555202 -274.049744)
			(xy 403.84401 -274.049744) (xy 403.84797 -274.00069) (xy 403.859747 -273.952906) (xy 403.879038 -273.90763)
			(xy 403.905341 -273.866034) (xy 403.937976 -273.829197) (xy 403.976097 -273.798072) (xy 404.018718 -273.773465)
			(xy 404.064734 -273.756013) (xy 404.112953 -273.746169) (xy 404.162128 -273.744188) (xy 404.210983 -273.75012)
			(xy 404.258254 -273.763812) (xy 404.302716 -273.78491) (xy 404.343219 -273.812866) (xy 404.378712 -273.846958)
			(xy 404.408277 -273.886302) (xy 404.431148 -273.929879) (xy 404.446732 -273.97656) (xy 404.454627 -274.025137)
			(xy 404.455122 -274.049744) (xy 405.744184 -274.049744) (xy 405.748144 -274.00069) (xy 405.759921 -273.952906)
			(xy 405.779212 -273.90763) (xy 405.805515 -273.866034) (xy 405.83815 -273.829197) (xy 405.876271 -273.798072)
			(xy 405.918892 -273.773465) (xy 405.964908 -273.756013) (xy 406.013127 -273.746169) (xy 406.062302 -273.744188)
			(xy 406.111157 -273.75012) (xy 406.158428 -273.763812) (xy 406.20289 -273.78491) (xy 406.243393 -273.812866)
			(xy 406.278886 -273.846958) (xy 406.308451 -273.886302) (xy 406.331322 -273.929879) (xy 406.346906 -273.97656)
			(xy 406.354801 -274.025137) (xy 406.355291 -274.04949) (xy 407.64385 -274.04949) (xy 407.64781 -274.000436)
			(xy 407.659587 -273.952652) (xy 407.678878 -273.907376) (xy 407.705181 -273.86578) (xy 407.737816 -273.828943)
			(xy 407.775937 -273.797818) (xy 407.818558 -273.773211) (xy 407.864574 -273.755759) (xy 407.912793 -273.745915)
			(xy 407.961968 -273.743934) (xy 408.010823 -273.749866) (xy 408.058094 -273.763558) (xy 408.102556 -273.784656)
			(xy 408.143059 -273.812612) (xy 408.178552 -273.846704) (xy 408.208117 -273.886048) (xy 408.230988 -273.929625)
			(xy 408.246572 -273.976306) (xy 408.254467 -274.024883) (xy 408.254962 -274.04949) (xy 408.254957 -274.049744)
			(xy 409.54377 -274.049744) (xy 409.54773 -274.00069) (xy 409.559507 -273.952906) (xy 409.578798 -273.90763)
			(xy 409.605101 -273.866034) (xy 409.637736 -273.829197) (xy 409.675857 -273.798072) (xy 409.718478 -273.773465)
			(xy 409.764494 -273.756013) (xy 409.812713 -273.746169) (xy 409.861888 -273.744188) (xy 409.910743 -273.75012)
			(xy 409.958014 -273.763812) (xy 410.002476 -273.78491) (xy 410.042979 -273.812866) (xy 410.078472 -273.846958)
			(xy 410.108037 -273.886302) (xy 410.130908 -273.929879) (xy 410.146492 -273.97656) (xy 410.154387 -274.025137)
			(xy 410.154882 -274.049744) (xy 411.443944 -274.049744) (xy 411.447904 -274.00069) (xy 411.459681 -273.952906)
			(xy 411.478972 -273.90763) (xy 411.505275 -273.866034) (xy 411.53791 -273.829197) (xy 411.576031 -273.798072)
			(xy 411.618652 -273.773465) (xy 411.664668 -273.756013) (xy 411.712887 -273.746169) (xy 411.762062 -273.744188)
			(xy 411.810917 -273.75012) (xy 411.858188 -273.763812) (xy 411.90265 -273.78491) (xy 411.943153 -273.812866)
			(xy 411.978646 -273.846958) (xy 412.008211 -273.886302) (xy 412.031082 -273.929879) (xy 412.046666 -273.97656)
			(xy 412.054561 -274.025137) (xy 412.055056 -274.049744) (xy 413.343864 -274.049744) (xy 413.347824 -274.00069)
			(xy 413.359601 -273.952906) (xy 413.378892 -273.90763) (xy 413.405195 -273.866034) (xy 413.43783 -273.829197)
			(xy 413.475951 -273.798072) (xy 413.518572 -273.773465) (xy 413.564588 -273.756013) (xy 413.612807 -273.746169)
			(xy 413.661982 -273.744188) (xy 413.710837 -273.75012) (xy 413.758108 -273.763812) (xy 413.80257 -273.78491)
			(xy 413.843073 -273.812866) (xy 413.878566 -273.846958) (xy 413.908131 -273.886302) (xy 413.931002 -273.929879)
			(xy 413.946586 -273.97656) (xy 413.954481 -274.025137) (xy 413.954976 -274.049744) (xy 415.243784 -274.049744)
			(xy 415.247744 -274.00069) (xy 415.259521 -273.952906) (xy 415.278812 -273.90763) (xy 415.305115 -273.866034)
			(xy 415.33775 -273.829197) (xy 415.375871 -273.798072) (xy 415.418492 -273.773465) (xy 415.464508 -273.756013)
			(xy 415.512727 -273.746169) (xy 415.561902 -273.744188) (xy 415.610757 -273.75012) (xy 415.658028 -273.763812)
			(xy 415.70249 -273.78491) (xy 415.742993 -273.812866) (xy 415.778486 -273.846958) (xy 415.808051 -273.886302)
			(xy 415.830922 -273.929879) (xy 415.846506 -273.97656) (xy 415.854401 -274.025137) (xy 415.854896 -274.049744)
			(xy 417.143958 -274.049744) (xy 417.147918 -274.00069) (xy 417.159695 -273.952906) (xy 417.178986 -273.90763)
			(xy 417.205289 -273.866034) (xy 417.237924 -273.829197) (xy 417.276045 -273.798072) (xy 417.318666 -273.773465)
			(xy 417.364682 -273.756013) (xy 417.412901 -273.746169) (xy 417.462076 -273.744188) (xy 417.510931 -273.75012)
			(xy 417.558202 -273.763812) (xy 417.602664 -273.78491) (xy 417.643167 -273.812866) (xy 417.67866 -273.846958)
			(xy 417.708225 -273.886302) (xy 417.731096 -273.929879) (xy 417.74668 -273.97656) (xy 417.754575 -274.025137)
			(xy 417.75507 -274.049744) (xy 419.043878 -274.049744) (xy 419.047838 -274.00069) (xy 419.059615 -273.952906)
			(xy 419.078906 -273.90763) (xy 419.105209 -273.866034) (xy 419.137844 -273.829197) (xy 419.175965 -273.798072)
			(xy 419.218586 -273.773465) (xy 419.264602 -273.756013) (xy 419.312821 -273.746169) (xy 419.361996 -273.744188)
			(xy 419.410851 -273.75012) (xy 419.458122 -273.763812) (xy 419.502584 -273.78491) (xy 419.543087 -273.812866)
			(xy 419.57858 -273.846958) (xy 419.608145 -273.886302) (xy 419.631016 -273.929879) (xy 419.6466 -273.97656)
			(xy 419.654495 -274.025137) (xy 419.65499 -274.049744) (xy 420.943798 -274.049744) (xy 420.947758 -274.00069)
			(xy 420.959535 -273.952906) (xy 420.978826 -273.90763) (xy 421.005129 -273.866034) (xy 421.037764 -273.829197)
			(xy 421.075885 -273.798072) (xy 421.118506 -273.773465) (xy 421.164522 -273.756013) (xy 421.212741 -273.746169)
			(xy 421.261916 -273.744188) (xy 421.310771 -273.75012) (xy 421.358042 -273.763812) (xy 421.402504 -273.78491)
			(xy 421.443007 -273.812866) (xy 421.4785 -273.846958) (xy 421.508065 -273.886302) (xy 421.530936 -273.929879)
			(xy 421.54652 -273.97656) (xy 421.554415 -274.025137) (xy 421.55491 -274.049744) (xy 422.843972 -274.049744)
			(xy 422.847932 -274.00069) (xy 422.859709 -273.952906) (xy 422.879 -273.90763) (xy 422.905303 -273.866034)
			(xy 422.937938 -273.829197) (xy 422.976059 -273.798072) (xy 423.01868 -273.773465) (xy 423.064696 -273.756013)
			(xy 423.112915 -273.746169) (xy 423.16209 -273.744188) (xy 423.210945 -273.75012) (xy 423.258216 -273.763812)
			(xy 423.302678 -273.78491) (xy 423.343181 -273.812866) (xy 423.378674 -273.846958) (xy 423.408239 -273.886302)
			(xy 423.43111 -273.929879) (xy 423.446694 -273.97656) (xy 423.454589 -274.025137) (xy 423.455084 -274.049744)
			(xy 424.743892 -274.049744) (xy 424.747852 -274.00069) (xy 424.759629 -273.952906) (xy 424.77892 -273.90763)
			(xy 424.805223 -273.866034) (xy 424.837858 -273.829197) (xy 424.875979 -273.798072) (xy 424.9186 -273.773465)
			(xy 424.964616 -273.756013) (xy 425.012835 -273.746169) (xy 425.06201 -273.744188) (xy 425.110865 -273.75012)
			(xy 425.158136 -273.763812) (xy 425.202598 -273.78491) (xy 425.243101 -273.812866) (xy 425.278594 -273.846958)
			(xy 425.308159 -273.886302) (xy 425.33103 -273.929879) (xy 425.346614 -273.97656) (xy 425.354509 -274.025137)
			(xy 425.355004 -274.049744) (xy 426.643812 -274.049744) (xy 426.647772 -274.00069) (xy 426.659549 -273.952906)
			(xy 426.67884 -273.90763) (xy 426.705143 -273.866034) (xy 426.737778 -273.829197) (xy 426.775899 -273.798072)
			(xy 426.81852 -273.773465) (xy 426.864536 -273.756013) (xy 426.912755 -273.746169) (xy 426.96193 -273.744188)
			(xy 427.010785 -273.75012) (xy 427.058056 -273.763812) (xy 427.102518 -273.78491) (xy 427.143021 -273.812866)
			(xy 427.178514 -273.846958) (xy 427.208079 -273.886302) (xy 427.23095 -273.929879) (xy 427.246534 -273.97656)
			(xy 427.254429 -274.025137) (xy 427.254924 -274.049744) (xy 428.543732 -274.049744) (xy 428.547692 -274.00069)
			(xy 428.559469 -273.952906) (xy 428.57876 -273.90763) (xy 428.605063 -273.866034) (xy 428.637698 -273.829197)
			(xy 428.675819 -273.798072) (xy 428.71844 -273.773465) (xy 428.764456 -273.756013) (xy 428.812675 -273.746169)
			(xy 428.86185 -273.744188) (xy 428.910705 -273.75012) (xy 428.957976 -273.763812) (xy 429.002438 -273.78491)
			(xy 429.042941 -273.812866) (xy 429.078434 -273.846958) (xy 429.107999 -273.886302) (xy 429.13087 -273.929879)
			(xy 429.146454 -273.97656) (xy 429.154349 -274.025137) (xy 429.154844 -274.049744) (xy 429.154349 -274.074351)
			(xy 429.146454 -274.122928) (xy 429.13087 -274.169609) (xy 429.107999 -274.213186) (xy 429.078434 -274.25253)
			(xy 429.042941 -274.286622) (xy 429.002438 -274.314578) (xy 428.957976 -274.335676) (xy 428.910705 -274.349368)
			(xy 428.86185 -274.3553) (xy 428.812675 -274.353319) (xy 428.764456 -274.343475) (xy 428.71844 -274.326023)
			(xy 428.675819 -274.301416) (xy 428.637698 -274.270291) (xy 428.605063 -274.233454) (xy 428.57876 -274.191858)
			(xy 428.559469 -274.146582) (xy 428.547692 -274.098798) (xy 428.543732 -274.049744) (xy 427.254924 -274.049744)
			(xy 427.254429 -274.074351) (xy 427.246534 -274.122928) (xy 427.23095 -274.169609) (xy 427.208079 -274.213186)
			(xy 427.178514 -274.25253) (xy 427.143021 -274.286622) (xy 427.102518 -274.314578) (xy 427.058056 -274.335676)
			(xy 427.010785 -274.349368) (xy 426.96193 -274.3553) (xy 426.912755 -274.353319) (xy 426.864536 -274.343475)
			(xy 426.81852 -274.326023) (xy 426.775899 -274.301416) (xy 426.737778 -274.270291) (xy 426.705143 -274.233454)
			(xy 426.67884 -274.191858) (xy 426.659549 -274.146582) (xy 426.647772 -274.098798) (xy 426.643812 -274.049744)
			(xy 425.355004 -274.049744) (xy 425.354509 -274.074351) (xy 425.346614 -274.122928) (xy 425.33103 -274.169609)
			(xy 425.308159 -274.213186) (xy 425.278594 -274.25253) (xy 425.243101 -274.286622) (xy 425.202598 -274.314578)
			(xy 425.158136 -274.335676) (xy 425.110865 -274.349368) (xy 425.06201 -274.3553) (xy 425.012835 -274.353319)
			(xy 424.964616 -274.343475) (xy 424.9186 -274.326023) (xy 424.875979 -274.301416) (xy 424.837858 -274.270291)
			(xy 424.805223 -274.233454) (xy 424.77892 -274.191858) (xy 424.759629 -274.146582) (xy 424.747852 -274.098798)
			(xy 424.743892 -274.049744) (xy 423.455084 -274.049744) (xy 423.454589 -274.074351) (xy 423.446694 -274.122928)
			(xy 423.43111 -274.169609) (xy 423.408239 -274.213186) (xy 423.378674 -274.25253) (xy 423.343181 -274.286622)
			(xy 423.302678 -274.314578) (xy 423.258216 -274.335676) (xy 423.210945 -274.349368) (xy 423.16209 -274.3553)
			(xy 423.112915 -274.353319) (xy 423.064696 -274.343475) (xy 423.01868 -274.326023) (xy 422.976059 -274.301416)
			(xy 422.937938 -274.270291) (xy 422.905303 -274.233454) (xy 422.879 -274.191858) (xy 422.859709 -274.146582)
			(xy 422.847932 -274.098798) (xy 422.843972 -274.049744) (xy 421.55491 -274.049744) (xy 421.554415 -274.074351)
			(xy 421.54652 -274.122928) (xy 421.530936 -274.169609) (xy 421.508065 -274.213186) (xy 421.4785 -274.25253)
			(xy 421.443007 -274.286622) (xy 421.402504 -274.314578) (xy 421.358042 -274.335676) (xy 421.310771 -274.349368)
			(xy 421.261916 -274.3553) (xy 421.212741 -274.353319) (xy 421.164522 -274.343475) (xy 421.118506 -274.326023)
			(xy 421.075885 -274.301416) (xy 421.037764 -274.270291) (xy 421.005129 -274.233454) (xy 420.978826 -274.191858)
			(xy 420.959535 -274.146582) (xy 420.947758 -274.098798) (xy 420.943798 -274.049744) (xy 419.65499 -274.049744)
			(xy 419.654495 -274.074351) (xy 419.6466 -274.122928) (xy 419.631016 -274.169609) (xy 419.608145 -274.213186)
			(xy 419.57858 -274.25253) (xy 419.543087 -274.286622) (xy 419.502584 -274.314578) (xy 419.458122 -274.335676)
			(xy 419.410851 -274.349368) (xy 419.361996 -274.3553) (xy 419.312821 -274.353319) (xy 419.264602 -274.343475)
			(xy 419.218586 -274.326023) (xy 419.175965 -274.301416) (xy 419.137844 -274.270291) (xy 419.105209 -274.233454)
			(xy 419.078906 -274.191858) (xy 419.059615 -274.146582) (xy 419.047838 -274.098798) (xy 419.043878 -274.049744)
			(xy 417.75507 -274.049744) (xy 417.754575 -274.074351) (xy 417.74668 -274.122928) (xy 417.731096 -274.169609)
			(xy 417.708225 -274.213186) (xy 417.67866 -274.25253) (xy 417.643167 -274.286622) (xy 417.602664 -274.314578)
			(xy 417.558202 -274.335676) (xy 417.510931 -274.349368) (xy 417.462076 -274.3553) (xy 417.412901 -274.353319)
			(xy 417.364682 -274.343475) (xy 417.318666 -274.326023) (xy 417.276045 -274.301416) (xy 417.237924 -274.270291)
			(xy 417.205289 -274.233454) (xy 417.178986 -274.191858) (xy 417.159695 -274.146582) (xy 417.147918 -274.098798)
			(xy 417.143958 -274.049744) (xy 415.854896 -274.049744) (xy 415.854401 -274.074351) (xy 415.846506 -274.122928)
			(xy 415.830922 -274.169609) (xy 415.808051 -274.213186) (xy 415.778486 -274.25253) (xy 415.742993 -274.286622)
			(xy 415.70249 -274.314578) (xy 415.658028 -274.335676) (xy 415.610757 -274.349368) (xy 415.561902 -274.3553)
			(xy 415.512727 -274.353319) (xy 415.464508 -274.343475) (xy 415.418492 -274.326023) (xy 415.375871 -274.301416)
			(xy 415.33775 -274.270291) (xy 415.305115 -274.233454) (xy 415.278812 -274.191858) (xy 415.259521 -274.146582)
			(xy 415.247744 -274.098798) (xy 415.243784 -274.049744) (xy 413.954976 -274.049744) (xy 413.954481 -274.074351)
			(xy 413.946586 -274.122928) (xy 413.931002 -274.169609) (xy 413.908131 -274.213186) (xy 413.878566 -274.25253)
			(xy 413.843073 -274.286622) (xy 413.80257 -274.314578) (xy 413.758108 -274.335676) (xy 413.710837 -274.349368)
			(xy 413.661982 -274.3553) (xy 413.612807 -274.353319) (xy 413.564588 -274.343475) (xy 413.518572 -274.326023)
			(xy 413.475951 -274.301416) (xy 413.43783 -274.270291) (xy 413.405195 -274.233454) (xy 413.378892 -274.191858)
			(xy 413.359601 -274.146582) (xy 413.347824 -274.098798) (xy 413.343864 -274.049744) (xy 412.055056 -274.049744)
			(xy 412.054561 -274.074351) (xy 412.046666 -274.122928) (xy 412.031082 -274.169609) (xy 412.008211 -274.213186)
			(xy 411.978646 -274.25253) (xy 411.943153 -274.286622) (xy 411.90265 -274.314578) (xy 411.858188 -274.335676)
			(xy 411.810917 -274.349368) (xy 411.762062 -274.3553) (xy 411.712887 -274.353319) (xy 411.664668 -274.343475)
			(xy 411.618652 -274.326023) (xy 411.576031 -274.301416) (xy 411.53791 -274.270291) (xy 411.505275 -274.233454)
			(xy 411.478972 -274.191858) (xy 411.459681 -274.146582) (xy 411.447904 -274.098798) (xy 411.443944 -274.049744)
			(xy 410.154882 -274.049744) (xy 410.154387 -274.074351) (xy 410.146492 -274.122928) (xy 410.130908 -274.169609)
			(xy 410.108037 -274.213186) (xy 410.078472 -274.25253) (xy 410.042979 -274.286622) (xy 410.002476 -274.314578)
			(xy 409.958014 -274.335676) (xy 409.910743 -274.349368) (xy 409.861888 -274.3553) (xy 409.812713 -274.353319)
			(xy 409.764494 -274.343475) (xy 409.718478 -274.326023) (xy 409.675857 -274.301416) (xy 409.637736 -274.270291)
			(xy 409.605101 -274.233454) (xy 409.578798 -274.191858) (xy 409.559507 -274.146582) (xy 409.54773 -274.098798)
			(xy 409.54377 -274.049744) (xy 408.254957 -274.049744) (xy 408.254467 -274.074097) (xy 408.246572 -274.122674)
			(xy 408.230988 -274.169355) (xy 408.208117 -274.212932) (xy 408.178552 -274.252276) (xy 408.143059 -274.286368)
			(xy 408.102556 -274.314324) (xy 408.058094 -274.335422) (xy 408.010823 -274.349114) (xy 407.961968 -274.355046)
			(xy 407.912793 -274.353065) (xy 407.864574 -274.343221) (xy 407.818558 -274.325769) (xy 407.775937 -274.301162)
			(xy 407.737816 -274.270037) (xy 407.705181 -274.2332) (xy 407.678878 -274.191604) (xy 407.659587 -274.146328)
			(xy 407.64781 -274.098544) (xy 407.64385 -274.04949) (xy 406.355291 -274.04949) (xy 406.355296 -274.049744)
			(xy 406.354801 -274.074351) (xy 406.346906 -274.122928) (xy 406.331322 -274.169609) (xy 406.308451 -274.213186)
			(xy 406.278886 -274.25253) (xy 406.243393 -274.286622) (xy 406.20289 -274.314578) (xy 406.158428 -274.335676)
			(xy 406.111157 -274.349368) (xy 406.062302 -274.3553) (xy 406.013127 -274.353319) (xy 405.964908 -274.343475)
			(xy 405.918892 -274.326023) (xy 405.876271 -274.301416) (xy 405.83815 -274.270291) (xy 405.805515 -274.233454)
			(xy 405.779212 -274.191858) (xy 405.759921 -274.146582) (xy 405.748144 -274.098798) (xy 405.744184 -274.049744)
			(xy 404.455122 -274.049744) (xy 404.454627 -274.074351) (xy 404.446732 -274.122928) (xy 404.431148 -274.169609)
			(xy 404.408277 -274.213186) (xy 404.378712 -274.25253) (xy 404.343219 -274.286622) (xy 404.302716 -274.314578)
			(xy 404.258254 -274.335676) (xy 404.210983 -274.349368) (xy 404.162128 -274.3553) (xy 404.112953 -274.353319)
			(xy 404.064734 -274.343475) (xy 404.018718 -274.326023) (xy 403.976097 -274.301416) (xy 403.937976 -274.270291)
			(xy 403.905341 -274.233454) (xy 403.879038 -274.191858) (xy 403.859747 -274.146582) (xy 403.84797 -274.098798)
			(xy 403.84401 -274.049744) (xy 402.555202 -274.049744) (xy 402.554707 -274.074351) (xy 402.546812 -274.122928)
			(xy 402.531228 -274.169609) (xy 402.508357 -274.213186) (xy 402.478792 -274.25253) (xy 402.443299 -274.286622)
			(xy 402.402796 -274.314578) (xy 402.358334 -274.335676) (xy 402.311063 -274.349368) (xy 402.262208 -274.3553)
			(xy 402.213033 -274.353319) (xy 402.164814 -274.343475) (xy 402.118798 -274.326023) (xy 402.076177 -274.301416)
			(xy 402.038056 -274.270291) (xy 402.005421 -274.233454) (xy 401.979118 -274.191858) (xy 401.959827 -274.146582)
			(xy 401.94805 -274.098798) (xy 401.94409 -274.049744) (xy 400.655282 -274.049744) (xy 400.654787 -274.074351)
			(xy 400.646892 -274.122928) (xy 400.631308 -274.169609) (xy 400.608437 -274.213186) (xy 400.578872 -274.25253)
			(xy 400.543379 -274.286622) (xy 400.502876 -274.314578) (xy 400.458414 -274.335676) (xy 400.411143 -274.349368)
			(xy 400.362288 -274.3553) (xy 400.313113 -274.353319) (xy 400.264894 -274.343475) (xy 400.218878 -274.326023)
			(xy 400.176257 -274.301416) (xy 400.138136 -274.270291) (xy 400.105501 -274.233454) (xy 400.079198 -274.191858)
			(xy 400.059907 -274.146582) (xy 400.04813 -274.098798) (xy 400.04417 -274.049744) (xy 398.755108 -274.049744)
			(xy 398.754613 -274.074351) (xy 398.746718 -274.122928) (xy 398.731134 -274.169609) (xy 398.708263 -274.213186)
			(xy 398.678698 -274.25253) (xy 398.643205 -274.286622) (xy 398.602702 -274.314578) (xy 398.55824 -274.335676)
			(xy 398.510969 -274.349368) (xy 398.462114 -274.3553) (xy 398.412939 -274.353319) (xy 398.36472 -274.343475)
			(xy 398.318704 -274.326023) (xy 398.276083 -274.301416) (xy 398.237962 -274.270291) (xy 398.205327 -274.233454)
			(xy 398.179024 -274.191858) (xy 398.159733 -274.146582) (xy 398.147956 -274.098798) (xy 398.143996 -274.049744)
			(xy 396.855188 -274.049744) (xy 396.854693 -274.074351) (xy 396.846798 -274.122928) (xy 396.831214 -274.169609)
			(xy 396.808343 -274.213186) (xy 396.778778 -274.25253) (xy 396.743285 -274.286622) (xy 396.702782 -274.314578)
			(xy 396.65832 -274.335676) (xy 396.611049 -274.349368) (xy 396.562194 -274.3553) (xy 396.513019 -274.353319)
			(xy 396.4648 -274.343475) (xy 396.418784 -274.326023) (xy 396.376163 -274.301416) (xy 396.338042 -274.270291)
			(xy 396.305407 -274.233454) (xy 396.279104 -274.191858) (xy 396.259813 -274.146582) (xy 396.248036 -274.098798)
			(xy 396.244076 -274.049744) (xy 394.955268 -274.049744) (xy 394.954773 -274.074351) (xy 394.946878 -274.122928)
			(xy 394.931294 -274.169609) (xy 394.908423 -274.213186) (xy 394.878858 -274.25253) (xy 394.843365 -274.286622)
			(xy 394.802862 -274.314578) (xy 394.7584 -274.335676) (xy 394.711129 -274.349368) (xy 394.662274 -274.3553)
			(xy 394.613099 -274.353319) (xy 394.56488 -274.343475) (xy 394.518864 -274.326023) (xy 394.476243 -274.301416)
			(xy 394.438122 -274.270291) (xy 394.405487 -274.233454) (xy 394.379184 -274.191858) (xy 394.359893 -274.146582)
			(xy 394.348116 -274.098798) (xy 394.344156 -274.049744) (xy 393.055094 -274.049744) (xy 393.054599 -274.074351)
			(xy 393.046704 -274.122928) (xy 393.03112 -274.169609) (xy 393.008249 -274.213186) (xy 392.978684 -274.25253)
			(xy 392.943191 -274.286622) (xy 392.902688 -274.314578) (xy 392.858226 -274.335676) (xy 392.810955 -274.349368)
			(xy 392.7621 -274.3553) (xy 392.712925 -274.353319) (xy 392.664706 -274.343475) (xy 392.61869 -274.326023)
			(xy 392.576069 -274.301416) (xy 392.537948 -274.270291) (xy 392.505313 -274.233454) (xy 392.47901 -274.191858)
			(xy 392.459719 -274.146582) (xy 392.447942 -274.098798) (xy 392.443982 -274.049744) (xy 313.054746 -274.049744)
			(xy 313.054251 -274.074351) (xy 313.046356 -274.122928) (xy 313.030772 -274.169609) (xy 313.007901 -274.213186)
			(xy 312.978336 -274.25253) (xy 312.942843 -274.286622) (xy 312.90234 -274.314578) (xy 312.857878 -274.335676)
			(xy 312.810607 -274.349368) (xy 312.761752 -274.3553) (xy 312.712577 -274.353319) (xy 312.664358 -274.343475)
			(xy 312.618342 -274.326023) (xy 312.575721 -274.301416) (xy 312.5376 -274.270291) (xy 312.504965 -274.233454)
			(xy 312.478662 -274.191858) (xy 312.459371 -274.146582) (xy 312.447594 -274.098798) (xy 312.443634 -274.049744)
			(xy 311.154826 -274.049744) (xy 311.154331 -274.074351) (xy 311.146436 -274.122928) (xy 311.130852 -274.169609)
			(xy 311.107981 -274.213186) (xy 311.078416 -274.25253) (xy 311.042923 -274.286622) (xy 311.00242 -274.314578)
			(xy 310.957958 -274.335676) (xy 310.910687 -274.349368) (xy 310.861832 -274.3553) (xy 310.812657 -274.353319)
			(xy 310.764438 -274.343475) (xy 310.718422 -274.326023) (xy 310.675801 -274.301416) (xy 310.63768 -274.270291)
			(xy 310.605045 -274.233454) (xy 310.578742 -274.191858) (xy 310.559451 -274.146582) (xy 310.547674 -274.098798)
			(xy 310.543714 -274.049744) (xy 309.254906 -274.049744) (xy 309.254411 -274.074351) (xy 309.246516 -274.122928)
			(xy 309.230932 -274.169609) (xy 309.208061 -274.213186) (xy 309.178496 -274.25253) (xy 309.143003 -274.286622)
			(xy 309.1025 -274.314578) (xy 309.058038 -274.335676) (xy 309.010767 -274.349368) (xy 308.961912 -274.3553)
			(xy 308.912737 -274.353319) (xy 308.864518 -274.343475) (xy 308.818502 -274.326023) (xy 308.775881 -274.301416)
			(xy 308.73776 -274.270291) (xy 308.705125 -274.233454) (xy 308.678822 -274.191858) (xy 308.659531 -274.146582)
			(xy 308.647754 -274.098798) (xy 308.643794 -274.049744) (xy 307.354986 -274.049744) (xy 307.354491 -274.074351)
			(xy 307.346596 -274.122928) (xy 307.331012 -274.169609) (xy 307.308141 -274.213186) (xy 307.278576 -274.25253)
			(xy 307.243083 -274.286622) (xy 307.20258 -274.314578) (xy 307.158118 -274.335676) (xy 307.110847 -274.349368)
			(xy 307.061992 -274.3553) (xy 307.012817 -274.353319) (xy 306.964598 -274.343475) (xy 306.918582 -274.326023)
			(xy 306.875961 -274.301416) (xy 306.83784 -274.270291) (xy 306.805205 -274.233454) (xy 306.778902 -274.191858)
			(xy 306.759611 -274.146582) (xy 306.747834 -274.098798) (xy 306.743874 -274.049744) (xy 305.454812 -274.049744)
			(xy 305.454317 -274.074351) (xy 305.446422 -274.122928) (xy 305.430838 -274.169609) (xy 305.407967 -274.213186)
			(xy 305.378402 -274.25253) (xy 305.342909 -274.286622) (xy 305.302406 -274.314578) (xy 305.257944 -274.335676)
			(xy 305.210673 -274.349368) (xy 305.161818 -274.3553) (xy 305.112643 -274.353319) (xy 305.064424 -274.343475)
			(xy 305.018408 -274.326023) (xy 304.975787 -274.301416) (xy 304.937666 -274.270291) (xy 304.905031 -274.233454)
			(xy 304.878728 -274.191858) (xy 304.859437 -274.146582) (xy 304.84766 -274.098798) (xy 304.8437 -274.049744)
			(xy 303.554892 -274.049744) (xy 303.554397 -274.074351) (xy 303.546502 -274.122928) (xy 303.530918 -274.169609)
			(xy 303.508047 -274.213186) (xy 303.478482 -274.25253) (xy 303.442989 -274.286622) (xy 303.402486 -274.314578)
			(xy 303.358024 -274.335676) (xy 303.310753 -274.349368) (xy 303.261898 -274.3553) (xy 303.212723 -274.353319)
			(xy 303.164504 -274.343475) (xy 303.118488 -274.326023) (xy 303.075867 -274.301416) (xy 303.037746 -274.270291)
			(xy 303.005111 -274.233454) (xy 302.978808 -274.191858) (xy 302.959517 -274.146582) (xy 302.94774 -274.098798)
			(xy 302.94378 -274.049744) (xy 301.654972 -274.049744) (xy 301.654477 -274.074351) (xy 301.646582 -274.122928)
			(xy 301.630998 -274.169609) (xy 301.608127 -274.213186) (xy 301.578562 -274.25253) (xy 301.543069 -274.286622)
			(xy 301.502566 -274.314578) (xy 301.458104 -274.335676) (xy 301.410833 -274.349368) (xy 301.361978 -274.3553)
			(xy 301.312803 -274.353319) (xy 301.264584 -274.343475) (xy 301.218568 -274.326023) (xy 301.175947 -274.301416)
			(xy 301.137826 -274.270291) (xy 301.105191 -274.233454) (xy 301.078888 -274.191858) (xy 301.059597 -274.146582)
			(xy 301.04782 -274.098798) (xy 301.04386 -274.049744) (xy 299.754798 -274.049744) (xy 299.754303 -274.074351)
			(xy 299.746408 -274.122928) (xy 299.730824 -274.169609) (xy 299.707953 -274.213186) (xy 299.678388 -274.25253)
			(xy 299.642895 -274.286622) (xy 299.602392 -274.314578) (xy 299.55793 -274.335676) (xy 299.510659 -274.349368)
			(xy 299.461804 -274.3553) (xy 299.412629 -274.353319) (xy 299.36441 -274.343475) (xy 299.318394 -274.326023)
			(xy 299.275773 -274.301416) (xy 299.237652 -274.270291) (xy 299.205017 -274.233454) (xy 299.178714 -274.191858)
			(xy 299.159423 -274.146582) (xy 299.147646 -274.098798) (xy 299.143686 -274.049744) (xy 297.854878 -274.049744)
			(xy 297.854383 -274.074351) (xy 297.846488 -274.122928) (xy 297.830904 -274.169609) (xy 297.808033 -274.213186)
			(xy 297.778468 -274.25253) (xy 297.742975 -274.286622) (xy 297.702472 -274.314578) (xy 297.65801 -274.335676)
			(xy 297.610739 -274.349368) (xy 297.561884 -274.3553) (xy 297.512709 -274.353319) (xy 297.46449 -274.343475)
			(xy 297.418474 -274.326023) (xy 297.375853 -274.301416) (xy 297.337732 -274.270291) (xy 297.305097 -274.233454)
			(xy 297.278794 -274.191858) (xy 297.259503 -274.146582) (xy 297.247726 -274.098798) (xy 297.243766 -274.049744)
			(xy 295.954958 -274.049744) (xy 295.954463 -274.074351) (xy 295.946568 -274.122928) (xy 295.930984 -274.169609)
			(xy 295.908113 -274.213186) (xy 295.878548 -274.25253) (xy 295.843055 -274.286622) (xy 295.802552 -274.314578)
			(xy 295.75809 -274.335676) (xy 295.710819 -274.349368) (xy 295.661964 -274.3553) (xy 295.612789 -274.353319)
			(xy 295.56457 -274.343475) (xy 295.518554 -274.326023) (xy 295.475933 -274.301416) (xy 295.437812 -274.270291)
			(xy 295.405177 -274.233454) (xy 295.378874 -274.191858) (xy 295.359583 -274.146582) (xy 295.347806 -274.098798)
			(xy 295.343846 -274.049744) (xy 294.054784 -274.049744) (xy 294.054289 -274.074351) (xy 294.046394 -274.122928)
			(xy 294.03081 -274.169609) (xy 294.007939 -274.213186) (xy 293.978374 -274.25253) (xy 293.942881 -274.286622)
			(xy 293.902378 -274.314578) (xy 293.857916 -274.335676) (xy 293.810645 -274.349368) (xy 293.76179 -274.3553)
			(xy 293.712615 -274.353319) (xy 293.664396 -274.343475) (xy 293.61838 -274.326023) (xy 293.575759 -274.301416)
			(xy 293.537638 -274.270291) (xy 293.505003 -274.233454) (xy 293.4787 -274.191858) (xy 293.459409 -274.146582)
			(xy 293.447632 -274.098798) (xy 293.443672 -274.049744) (xy 292.154859 -274.049744) (xy 292.154369 -274.074097)
			(xy 292.146474 -274.122674) (xy 292.13089 -274.169355) (xy 292.108019 -274.212932) (xy 292.078454 -274.252276)
			(xy 292.042961 -274.286368) (xy 292.002458 -274.314324) (xy 291.957996 -274.335422) (xy 291.910725 -274.349114)
			(xy 291.86187 -274.355046) (xy 291.812695 -274.353065) (xy 291.764476 -274.343221) (xy 291.71846 -274.325769)
			(xy 291.675839 -274.301162) (xy 291.637718 -274.270037) (xy 291.605083 -274.2332) (xy 291.57878 -274.191604)
			(xy 291.559489 -274.146328) (xy 291.547712 -274.098544) (xy 291.543752 -274.04949) (xy 290.255193 -274.04949)
			(xy 290.255198 -274.049744) (xy 290.254703 -274.074351) (xy 290.246808 -274.122928) (xy 290.231224 -274.169609)
			(xy 290.208353 -274.213186) (xy 290.178788 -274.25253) (xy 290.143295 -274.286622) (xy 290.102792 -274.314578)
			(xy 290.05833 -274.335676) (xy 290.011059 -274.349368) (xy 289.962204 -274.3553) (xy 289.913029 -274.353319)
			(xy 289.86481 -274.343475) (xy 289.818794 -274.326023) (xy 289.776173 -274.301416) (xy 289.738052 -274.270291)
			(xy 289.705417 -274.233454) (xy 289.679114 -274.191858) (xy 289.659823 -274.146582) (xy 289.648046 -274.098798)
			(xy 289.644086 -274.049744) (xy 288.355024 -274.049744) (xy 288.354529 -274.074351) (xy 288.346634 -274.122928)
			(xy 288.33105 -274.169609) (xy 288.308179 -274.213186) (xy 288.278614 -274.25253) (xy 288.243121 -274.286622)
			(xy 288.202618 -274.314578) (xy 288.158156 -274.335676) (xy 288.110885 -274.349368) (xy 288.06203 -274.3553)
			(xy 288.012855 -274.353319) (xy 287.964636 -274.343475) (xy 287.91862 -274.326023) (xy 287.875999 -274.301416)
			(xy 287.837878 -274.270291) (xy 287.805243 -274.233454) (xy 287.77894 -274.191858) (xy 287.759649 -274.146582)
			(xy 287.747872 -274.098798) (xy 287.743912 -274.049744) (xy 286.455104 -274.049744) (xy 286.454609 -274.074351)
			(xy 286.446714 -274.122928) (xy 286.43113 -274.169609) (xy 286.408259 -274.213186) (xy 286.378694 -274.25253)
			(xy 286.343201 -274.286622) (xy 286.302698 -274.314578) (xy 286.258236 -274.335676) (xy 286.210965 -274.349368)
			(xy 286.16211 -274.3553) (xy 286.112935 -274.353319) (xy 286.064716 -274.343475) (xy 286.0187 -274.326023)
			(xy 285.976079 -274.301416) (xy 285.937958 -274.270291) (xy 285.905323 -274.233454) (xy 285.87902 -274.191858)
			(xy 285.859729 -274.146582) (xy 285.847952 -274.098798) (xy 285.843992 -274.049744) (xy 284.555184 -274.049744)
			(xy 284.554689 -274.074351) (xy 284.546794 -274.122928) (xy 284.53121 -274.169609) (xy 284.508339 -274.213186)
			(xy 284.478774 -274.25253) (xy 284.443281 -274.286622) (xy 284.402778 -274.314578) (xy 284.358316 -274.335676)
			(xy 284.311045 -274.349368) (xy 284.26219 -274.3553) (xy 284.213015 -274.353319) (xy 284.164796 -274.343475)
			(xy 284.11878 -274.326023) (xy 284.076159 -274.301416) (xy 284.038038 -274.270291) (xy 284.005403 -274.233454)
			(xy 283.9791 -274.191858) (xy 283.959809 -274.146582) (xy 283.948032 -274.098798) (xy 283.944072 -274.049744)
			(xy 282.65501 -274.049744) (xy 282.654515 -274.074351) (xy 282.64662 -274.122928) (xy 282.631036 -274.169609)
			(xy 282.608165 -274.213186) (xy 282.5786 -274.25253) (xy 282.543107 -274.286622) (xy 282.502604 -274.314578)
			(xy 282.458142 -274.335676) (xy 282.410871 -274.349368) (xy 282.362016 -274.3553) (xy 282.312841 -274.353319)
			(xy 282.264622 -274.343475) (xy 282.218606 -274.326023) (xy 282.175985 -274.301416) (xy 282.137864 -274.270291)
			(xy 282.105229 -274.233454) (xy 282.078926 -274.191858) (xy 282.059635 -274.146582) (xy 282.047858 -274.098798)
			(xy 282.043898 -274.049744) (xy 280.75509 -274.049744) (xy 280.754595 -274.074351) (xy 280.7467 -274.122928)
			(xy 280.731116 -274.169609) (xy 280.708245 -274.213186) (xy 280.67868 -274.25253) (xy 280.643187 -274.286622)
			(xy 280.602684 -274.314578) (xy 280.558222 -274.335676) (xy 280.510951 -274.349368) (xy 280.462096 -274.3553)
			(xy 280.412921 -274.353319) (xy 280.364702 -274.343475) (xy 280.318686 -274.326023) (xy 280.276065 -274.301416)
			(xy 280.237944 -274.270291) (xy 280.205309 -274.233454) (xy 280.179006 -274.191858) (xy 280.159715 -274.146582)
			(xy 280.147938 -274.098798) (xy 280.143978 -274.049744) (xy 278.85517 -274.049744) (xy 278.854675 -274.074351)
			(xy 278.84678 -274.122928) (xy 278.831196 -274.169609) (xy 278.808325 -274.213186) (xy 278.77876 -274.25253)
			(xy 278.743267 -274.286622) (xy 278.702764 -274.314578) (xy 278.658302 -274.335676) (xy 278.611031 -274.349368)
			(xy 278.562176 -274.3553) (xy 278.513001 -274.353319) (xy 278.464782 -274.343475) (xy 278.418766 -274.326023)
			(xy 278.376145 -274.301416) (xy 278.338024 -274.270291) (xy 278.305389 -274.233454) (xy 278.279086 -274.191858)
			(xy 278.259795 -274.146582) (xy 278.248018 -274.098798) (xy 278.244058 -274.049744) (xy 276.954996 -274.049744)
			(xy 276.954501 -274.074351) (xy 276.946606 -274.122928) (xy 276.931022 -274.169609) (xy 276.908151 -274.213186)
			(xy 276.878586 -274.25253) (xy 276.843093 -274.286622) (xy 276.80259 -274.314578) (xy 276.758128 -274.335676)
			(xy 276.710857 -274.349368) (xy 276.662002 -274.3553) (xy 276.612827 -274.353319) (xy 276.564608 -274.343475)
			(xy 276.518592 -274.326023) (xy 276.475971 -274.301416) (xy 276.43785 -274.270291) (xy 276.405215 -274.233454)
			(xy 276.378912 -274.191858) (xy 276.359621 -274.146582) (xy 276.347844 -274.098798) (xy 276.343884 -274.049744)
			(xy 196.954902 -274.049744) (xy 196.954407 -274.074351) (xy 196.946512 -274.122928) (xy 196.930928 -274.169609)
			(xy 196.908057 -274.213186) (xy 196.878492 -274.25253) (xy 196.842999 -274.286622) (xy 196.802496 -274.314578)
			(xy 196.758034 -274.335676) (xy 196.710763 -274.349368) (xy 196.661908 -274.3553) (xy 196.612733 -274.353319)
			(xy 196.564514 -274.343475) (xy 196.518498 -274.326023) (xy 196.475877 -274.301416) (xy 196.437756 -274.270291)
			(xy 196.405121 -274.233454) (xy 196.378818 -274.191858) (xy 196.359527 -274.146582) (xy 196.34775 -274.098798)
			(xy 196.34379 -274.049744) (xy 195.054982 -274.049744) (xy 195.054487 -274.074351) (xy 195.046592 -274.122928)
			(xy 195.031008 -274.169609) (xy 195.008137 -274.213186) (xy 194.978572 -274.25253) (xy 194.943079 -274.286622)
			(xy 194.902576 -274.314578) (xy 194.858114 -274.335676) (xy 194.810843 -274.349368) (xy 194.761988 -274.3553)
			(xy 194.712813 -274.353319) (xy 194.664594 -274.343475) (xy 194.618578 -274.326023) (xy 194.575957 -274.301416)
			(xy 194.537836 -274.270291) (xy 194.505201 -274.233454) (xy 194.478898 -274.191858) (xy 194.459607 -274.146582)
			(xy 194.44783 -274.098798) (xy 194.44387 -274.049744) (xy 193.155062 -274.049744) (xy 193.154567 -274.074351)
			(xy 193.146672 -274.122928) (xy 193.131088 -274.169609) (xy 193.108217 -274.213186) (xy 193.078652 -274.25253)
			(xy 193.043159 -274.286622) (xy 193.002656 -274.314578) (xy 192.958194 -274.335676) (xy 192.910923 -274.349368)
			(xy 192.862068 -274.3553) (xy 192.812893 -274.353319) (xy 192.764674 -274.343475) (xy 192.718658 -274.326023)
			(xy 192.676037 -274.301416) (xy 192.637916 -274.270291) (xy 192.605281 -274.233454) (xy 192.578978 -274.191858)
			(xy 192.559687 -274.146582) (xy 192.54791 -274.098798) (xy 192.54395 -274.049744) (xy 191.255142 -274.049744)
			(xy 191.254647 -274.074351) (xy 191.246752 -274.122928) (xy 191.231168 -274.169609) (xy 191.208297 -274.213186)
			(xy 191.178732 -274.25253) (xy 191.143239 -274.286622) (xy 191.102736 -274.314578) (xy 191.058274 -274.335676)
			(xy 191.011003 -274.349368) (xy 190.962148 -274.3553) (xy 190.912973 -274.353319) (xy 190.864754 -274.343475)
			(xy 190.818738 -274.326023) (xy 190.776117 -274.301416) (xy 190.737996 -274.270291) (xy 190.705361 -274.233454)
			(xy 190.679058 -274.191858) (xy 190.659767 -274.146582) (xy 190.64799 -274.098798) (xy 190.64403 -274.049744)
			(xy 189.354968 -274.049744) (xy 189.354473 -274.074351) (xy 189.346578 -274.122928) (xy 189.330994 -274.169609)
			(xy 189.308123 -274.213186) (xy 189.278558 -274.25253) (xy 189.243065 -274.286622) (xy 189.202562 -274.314578)
			(xy 189.1581 -274.335676) (xy 189.110829 -274.349368) (xy 189.061974 -274.3553) (xy 189.012799 -274.353319)
			(xy 188.96458 -274.343475) (xy 188.918564 -274.326023) (xy 188.875943 -274.301416) (xy 188.837822 -274.270291)
			(xy 188.805187 -274.233454) (xy 188.778884 -274.191858) (xy 188.759593 -274.146582) (xy 188.747816 -274.098798)
			(xy 188.743856 -274.049744) (xy 187.455048 -274.049744) (xy 187.454553 -274.074351) (xy 187.446658 -274.122928)
			(xy 187.431074 -274.169609) (xy 187.408203 -274.213186) (xy 187.378638 -274.25253) (xy 187.343145 -274.286622)
			(xy 187.302642 -274.314578) (xy 187.25818 -274.335676) (xy 187.210909 -274.349368) (xy 187.162054 -274.3553)
			(xy 187.112879 -274.353319) (xy 187.06466 -274.343475) (xy 187.018644 -274.326023) (xy 186.976023 -274.301416)
			(xy 186.937902 -274.270291) (xy 186.905267 -274.233454) (xy 186.878964 -274.191858) (xy 186.859673 -274.146582)
			(xy 186.847896 -274.098798) (xy 186.843936 -274.049744) (xy 185.555128 -274.049744) (xy 185.554633 -274.074351)
			(xy 185.546738 -274.122928) (xy 185.531154 -274.169609) (xy 185.508283 -274.213186) (xy 185.478718 -274.25253)
			(xy 185.443225 -274.286622) (xy 185.402722 -274.314578) (xy 185.35826 -274.335676) (xy 185.310989 -274.349368)
			(xy 185.262134 -274.3553) (xy 185.212959 -274.353319) (xy 185.16474 -274.343475) (xy 185.118724 -274.326023)
			(xy 185.076103 -274.301416) (xy 185.037982 -274.270291) (xy 185.005347 -274.233454) (xy 184.979044 -274.191858)
			(xy 184.959753 -274.146582) (xy 184.947976 -274.098798) (xy 184.944016 -274.049744) (xy 183.654954 -274.049744)
			(xy 183.654459 -274.074351) (xy 183.646564 -274.122928) (xy 183.63098 -274.169609) (xy 183.608109 -274.213186)
			(xy 183.578544 -274.25253) (xy 183.543051 -274.286622) (xy 183.502548 -274.314578) (xy 183.458086 -274.335676)
			(xy 183.410815 -274.349368) (xy 183.36196 -274.3553) (xy 183.312785 -274.353319) (xy 183.264566 -274.343475)
			(xy 183.21855 -274.326023) (xy 183.175929 -274.301416) (xy 183.137808 -274.270291) (xy 183.105173 -274.233454)
			(xy 183.07887 -274.191858) (xy 183.059579 -274.146582) (xy 183.047802 -274.098798) (xy 183.043842 -274.049744)
			(xy 181.755034 -274.049744) (xy 181.754539 -274.074351) (xy 181.746644 -274.122928) (xy 181.73106 -274.169609)
			(xy 181.708189 -274.213186) (xy 181.678624 -274.25253) (xy 181.643131 -274.286622) (xy 181.602628 -274.314578)
			(xy 181.558166 -274.335676) (xy 181.510895 -274.349368) (xy 181.46204 -274.3553) (xy 181.412865 -274.353319)
			(xy 181.364646 -274.343475) (xy 181.31863 -274.326023) (xy 181.276009 -274.301416) (xy 181.237888 -274.270291)
			(xy 181.205253 -274.233454) (xy 181.17895 -274.191858) (xy 181.159659 -274.146582) (xy 181.147882 -274.098798)
			(xy 181.143922 -274.049744) (xy 179.855114 -274.049744) (xy 179.854619 -274.074351) (xy 179.846724 -274.122928)
			(xy 179.83114 -274.169609) (xy 179.808269 -274.213186) (xy 179.778704 -274.25253) (xy 179.743211 -274.286622)
			(xy 179.702708 -274.314578) (xy 179.658246 -274.335676) (xy 179.610975 -274.349368) (xy 179.56212 -274.3553)
			(xy 179.512945 -274.353319) (xy 179.464726 -274.343475) (xy 179.41871 -274.326023) (xy 179.376089 -274.301416)
			(xy 179.337968 -274.270291) (xy 179.305333 -274.233454) (xy 179.27903 -274.191858) (xy 179.259739 -274.146582)
			(xy 179.247962 -274.098798) (xy 179.244002 -274.049744) (xy 177.95494 -274.049744) (xy 177.954445 -274.074351)
			(xy 177.94655 -274.122928) (xy 177.930966 -274.169609) (xy 177.908095 -274.213186) (xy 177.87853 -274.25253)
			(xy 177.843037 -274.286622) (xy 177.802534 -274.314578) (xy 177.758072 -274.335676) (xy 177.710801 -274.349368)
			(xy 177.661946 -274.3553) (xy 177.612771 -274.353319) (xy 177.564552 -274.343475) (xy 177.518536 -274.326023)
			(xy 177.475915 -274.301416) (xy 177.437794 -274.270291) (xy 177.405159 -274.233454) (xy 177.378856 -274.191858)
			(xy 177.359565 -274.146582) (xy 177.347788 -274.098798) (xy 177.343828 -274.049744) (xy 176.055015 -274.049744)
			(xy 176.054525 -274.074097) (xy 176.04663 -274.122674) (xy 176.031046 -274.169355) (xy 176.008175 -274.212932)
			(xy 175.97861 -274.252276) (xy 175.943117 -274.286368) (xy 175.902614 -274.314324) (xy 175.858152 -274.335422)
			(xy 175.810881 -274.349114) (xy 175.762026 -274.355046) (xy 175.712851 -274.353065) (xy 175.664632 -274.343221)
			(xy 175.618616 -274.325769) (xy 175.575995 -274.301162) (xy 175.537874 -274.270037) (xy 175.505239 -274.2332)
			(xy 175.478936 -274.191604) (xy 175.459645 -274.146328) (xy 175.447868 -274.098544) (xy 175.443908 -274.04949)
			(xy 174.155349 -274.04949) (xy 174.155354 -274.049744) (xy 174.154859 -274.074351) (xy 174.146964 -274.122928)
			(xy 174.13138 -274.169609) (xy 174.108509 -274.213186) (xy 174.078944 -274.25253) (xy 174.043451 -274.286622)
			(xy 174.002948 -274.314578) (xy 173.958486 -274.335676) (xy 173.911215 -274.349368) (xy 173.86236 -274.3553)
			(xy 173.813185 -274.353319) (xy 173.764966 -274.343475) (xy 173.71895 -274.326023) (xy 173.676329 -274.301416)
			(xy 173.638208 -274.270291) (xy 173.605573 -274.233454) (xy 173.57927 -274.191858) (xy 173.559979 -274.146582)
			(xy 173.548202 -274.098798) (xy 173.544242 -274.049744) (xy 172.25518 -274.049744) (xy 172.254685 -274.074351)
			(xy 172.24679 -274.122928) (xy 172.231206 -274.169609) (xy 172.208335 -274.213186) (xy 172.17877 -274.25253)
			(xy 172.143277 -274.286622) (xy 172.102774 -274.314578) (xy 172.058312 -274.335676) (xy 172.011041 -274.349368)
			(xy 171.962186 -274.3553) (xy 171.913011 -274.353319) (xy 171.864792 -274.343475) (xy 171.818776 -274.326023)
			(xy 171.776155 -274.301416) (xy 171.738034 -274.270291) (xy 171.705399 -274.233454) (xy 171.679096 -274.191858)
			(xy 171.659805 -274.146582) (xy 171.648028 -274.098798) (xy 171.644068 -274.049744) (xy 170.35526 -274.049744)
			(xy 170.354765 -274.074351) (xy 170.34687 -274.122928) (xy 170.331286 -274.169609) (xy 170.308415 -274.213186)
			(xy 170.27885 -274.25253) (xy 170.243357 -274.286622) (xy 170.202854 -274.314578) (xy 170.158392 -274.335676)
			(xy 170.111121 -274.349368) (xy 170.062266 -274.3553) (xy 170.013091 -274.353319) (xy 169.964872 -274.343475)
			(xy 169.918856 -274.326023) (xy 169.876235 -274.301416) (xy 169.838114 -274.270291) (xy 169.805479 -274.233454)
			(xy 169.779176 -274.191858) (xy 169.759885 -274.146582) (xy 169.748108 -274.098798) (xy 169.744148 -274.049744)
			(xy 168.45534 -274.049744) (xy 168.454845 -274.074351) (xy 168.44695 -274.122928) (xy 168.431366 -274.169609)
			(xy 168.408495 -274.213186) (xy 168.37893 -274.25253) (xy 168.343437 -274.286622) (xy 168.302934 -274.314578)
			(xy 168.258472 -274.335676) (xy 168.211201 -274.349368) (xy 168.162346 -274.3553) (xy 168.113171 -274.353319)
			(xy 168.064952 -274.343475) (xy 168.018936 -274.326023) (xy 167.976315 -274.301416) (xy 167.938194 -274.270291)
			(xy 167.905559 -274.233454) (xy 167.879256 -274.191858) (xy 167.859965 -274.146582) (xy 167.848188 -274.098798)
			(xy 167.844228 -274.049744) (xy 166.555166 -274.049744) (xy 166.554671 -274.074351) (xy 166.546776 -274.122928)
			(xy 166.531192 -274.169609) (xy 166.508321 -274.213186) (xy 166.478756 -274.25253) (xy 166.443263 -274.286622)
			(xy 166.40276 -274.314578) (xy 166.358298 -274.335676) (xy 166.311027 -274.349368) (xy 166.262172 -274.3553)
			(xy 166.212997 -274.353319) (xy 166.164778 -274.343475) (xy 166.118762 -274.326023) (xy 166.076141 -274.301416)
			(xy 166.03802 -274.270291) (xy 166.005385 -274.233454) (xy 165.979082 -274.191858) (xy 165.959791 -274.146582)
			(xy 165.948014 -274.098798) (xy 165.944054 -274.049744) (xy 164.655246 -274.049744) (xy 164.654751 -274.074351)
			(xy 164.646856 -274.122928) (xy 164.631272 -274.169609) (xy 164.608401 -274.213186) (xy 164.578836 -274.25253)
			(xy 164.543343 -274.286622) (xy 164.50284 -274.314578) (xy 164.458378 -274.335676) (xy 164.411107 -274.349368)
			(xy 164.362252 -274.3553) (xy 164.313077 -274.353319) (xy 164.264858 -274.343475) (xy 164.218842 -274.326023)
			(xy 164.176221 -274.301416) (xy 164.1381 -274.270291) (xy 164.105465 -274.233454) (xy 164.079162 -274.191858)
			(xy 164.059871 -274.146582) (xy 164.048094 -274.098798) (xy 164.044134 -274.049744) (xy 162.755326 -274.049744)
			(xy 162.754831 -274.074351) (xy 162.746936 -274.122928) (xy 162.731352 -274.169609) (xy 162.708481 -274.213186)
			(xy 162.678916 -274.25253) (xy 162.643423 -274.286622) (xy 162.60292 -274.314578) (xy 162.558458 -274.335676)
			(xy 162.511187 -274.349368) (xy 162.462332 -274.3553) (xy 162.413157 -274.353319) (xy 162.364938 -274.343475)
			(xy 162.318922 -274.326023) (xy 162.276301 -274.301416) (xy 162.23818 -274.270291) (xy 162.205545 -274.233454)
			(xy 162.179242 -274.191858) (xy 162.159951 -274.146582) (xy 162.148174 -274.098798) (xy 162.144214 -274.049744)
			(xy 160.855152 -274.049744) (xy 160.854657 -274.074351) (xy 160.846762 -274.122928) (xy 160.831178 -274.169609)
			(xy 160.808307 -274.213186) (xy 160.778742 -274.25253) (xy 160.743249 -274.286622) (xy 160.702746 -274.314578)
			(xy 160.658284 -274.335676) (xy 160.611013 -274.349368) (xy 160.562158 -274.3553) (xy 160.512983 -274.353319)
			(xy 160.464764 -274.343475) (xy 160.418748 -274.326023) (xy 160.376127 -274.301416) (xy 160.338006 -274.270291)
			(xy 160.305371 -274.233454) (xy 160.279068 -274.191858) (xy 160.259777 -274.146582) (xy 160.248 -274.098798)
			(xy 160.24404 -274.049744) (xy 80.854804 -274.049744) (xy 80.854309 -274.074351) (xy 80.846414 -274.122928)
			(xy 80.83083 -274.169609) (xy 80.807959 -274.213186) (xy 80.778394 -274.25253) (xy 80.742901 -274.286622)
			(xy 80.702398 -274.314578) (xy 80.657936 -274.335676) (xy 80.610665 -274.349368) (xy 80.56181 -274.3553)
			(xy 80.512635 -274.353319) (xy 80.464416 -274.343475) (xy 80.4184 -274.326023) (xy 80.375779 -274.301416)
			(xy 80.337658 -274.270291) (xy 80.305023 -274.233454) (xy 80.27872 -274.191858) (xy 80.259429 -274.146582)
			(xy 80.247652 -274.098798) (xy 80.243692 -274.049744) (xy 78.954884 -274.049744) (xy 78.954389 -274.074351)
			(xy 78.946494 -274.122928) (xy 78.93091 -274.169609) (xy 78.908039 -274.213186) (xy 78.878474 -274.25253)
			(xy 78.842981 -274.286622) (xy 78.802478 -274.314578) (xy 78.758016 -274.335676) (xy 78.710745 -274.349368)
			(xy 78.66189 -274.3553) (xy 78.612715 -274.353319) (xy 78.564496 -274.343475) (xy 78.51848 -274.326023)
			(xy 78.475859 -274.301416) (xy 78.437738 -274.270291) (xy 78.405103 -274.233454) (xy 78.3788 -274.191858)
			(xy 78.359509 -274.146582) (xy 78.347732 -274.098798) (xy 78.343772 -274.049744) (xy 77.054964 -274.049744)
			(xy 77.054469 -274.074351) (xy 77.046574 -274.122928) (xy 77.03099 -274.169609) (xy 77.008119 -274.213186)
			(xy 76.978554 -274.25253) (xy 76.943061 -274.286622) (xy 76.902558 -274.314578) (xy 76.858096 -274.335676)
			(xy 76.810825 -274.349368) (xy 76.76197 -274.3553) (xy 76.712795 -274.353319) (xy 76.664576 -274.343475)
			(xy 76.61856 -274.326023) (xy 76.575939 -274.301416) (xy 76.537818 -274.270291) (xy 76.505183 -274.233454)
			(xy 76.47888 -274.191858) (xy 76.459589 -274.146582) (xy 76.447812 -274.098798) (xy 76.443852 -274.049744)
			(xy 75.155044 -274.049744) (xy 75.154549 -274.074351) (xy 75.146654 -274.122928) (xy 75.13107 -274.169609)
			(xy 75.108199 -274.213186) (xy 75.078634 -274.25253) (xy 75.043141 -274.286622) (xy 75.002638 -274.314578)
			(xy 74.958176 -274.335676) (xy 74.910905 -274.349368) (xy 74.86205 -274.3553) (xy 74.812875 -274.353319)
			(xy 74.764656 -274.343475) (xy 74.71864 -274.326023) (xy 74.676019 -274.301416) (xy 74.637898 -274.270291)
			(xy 74.605263 -274.233454) (xy 74.57896 -274.191858) (xy 74.559669 -274.146582) (xy 74.547892 -274.098798)
			(xy 74.543932 -274.049744) (xy 73.25487 -274.049744) (xy 73.254375 -274.074351) (xy 73.24648 -274.122928)
			(xy 73.230896 -274.169609) (xy 73.208025 -274.213186) (xy 73.17846 -274.25253) (xy 73.142967 -274.286622)
			(xy 73.102464 -274.314578) (xy 73.058002 -274.335676) (xy 73.010731 -274.349368) (xy 72.961876 -274.3553)
			(xy 72.912701 -274.353319) (xy 72.864482 -274.343475) (xy 72.818466 -274.326023) (xy 72.775845 -274.301416)
			(xy 72.737724 -274.270291) (xy 72.705089 -274.233454) (xy 72.678786 -274.191858) (xy 72.659495 -274.146582)
			(xy 72.647718 -274.098798) (xy 72.643758 -274.049744) (xy 71.35495 -274.049744) (xy 71.354455 -274.074351)
			(xy 71.34656 -274.122928) (xy 71.330976 -274.169609) (xy 71.308105 -274.213186) (xy 71.27854 -274.25253)
			(xy 71.243047 -274.286622) (xy 71.202544 -274.314578) (xy 71.158082 -274.335676) (xy 71.110811 -274.349368)
			(xy 71.061956 -274.3553) (xy 71.012781 -274.353319) (xy 70.964562 -274.343475) (xy 70.918546 -274.326023)
			(xy 70.875925 -274.301416) (xy 70.837804 -274.270291) (xy 70.805169 -274.233454) (xy 70.778866 -274.191858)
			(xy 70.759575 -274.146582) (xy 70.747798 -274.098798) (xy 70.743838 -274.049744) (xy 69.45503 -274.049744)
			(xy 69.454535 -274.074351) (xy 69.44664 -274.122928) (xy 69.431056 -274.169609) (xy 69.408185 -274.213186)
			(xy 69.37862 -274.25253) (xy 69.343127 -274.286622) (xy 69.302624 -274.314578) (xy 69.258162 -274.335676)
			(xy 69.210891 -274.349368) (xy 69.162036 -274.3553) (xy 69.112861 -274.353319) (xy 69.064642 -274.343475)
			(xy 69.018626 -274.326023) (xy 68.976005 -274.301416) (xy 68.937884 -274.270291) (xy 68.905249 -274.233454)
			(xy 68.878946 -274.191858) (xy 68.859655 -274.146582) (xy 68.847878 -274.098798) (xy 68.843918 -274.049744)
			(xy 67.554856 -274.049744) (xy 67.554361 -274.074351) (xy 67.546466 -274.122928) (xy 67.530882 -274.169609)
			(xy 67.508011 -274.213186) (xy 67.478446 -274.25253) (xy 67.442953 -274.286622) (xy 67.40245 -274.314578)
			(xy 67.357988 -274.335676) (xy 67.310717 -274.349368) (xy 67.261862 -274.3553) (xy 67.212687 -274.353319)
			(xy 67.164468 -274.343475) (xy 67.118452 -274.326023) (xy 67.075831 -274.301416) (xy 67.03771 -274.270291)
			(xy 67.005075 -274.233454) (xy 66.978772 -274.191858) (xy 66.959481 -274.146582) (xy 66.947704 -274.098798)
			(xy 66.943744 -274.049744) (xy 65.654936 -274.049744) (xy 65.654441 -274.074351) (xy 65.646546 -274.122928)
			(xy 65.630962 -274.169609) (xy 65.608091 -274.213186) (xy 65.578526 -274.25253) (xy 65.543033 -274.286622)
			(xy 65.50253 -274.314578) (xy 65.458068 -274.335676) (xy 65.410797 -274.349368) (xy 65.361942 -274.3553)
			(xy 65.312767 -274.353319) (xy 65.264548 -274.343475) (xy 65.218532 -274.326023) (xy 65.175911 -274.301416)
			(xy 65.13779 -274.270291) (xy 65.105155 -274.233454) (xy 65.078852 -274.191858) (xy 65.059561 -274.146582)
			(xy 65.047784 -274.098798) (xy 65.043824 -274.049744) (xy 63.755016 -274.049744) (xy 63.754521 -274.074351)
			(xy 63.746626 -274.122928) (xy 63.731042 -274.169609) (xy 63.708171 -274.213186) (xy 63.678606 -274.25253)
			(xy 63.643113 -274.286622) (xy 63.60261 -274.314578) (xy 63.558148 -274.335676) (xy 63.510877 -274.349368)
			(xy 63.462022 -274.3553) (xy 63.412847 -274.353319) (xy 63.364628 -274.343475) (xy 63.318612 -274.326023)
			(xy 63.275991 -274.301416) (xy 63.23787 -274.270291) (xy 63.205235 -274.233454) (xy 63.178932 -274.191858)
			(xy 63.159641 -274.146582) (xy 63.147864 -274.098798) (xy 63.143904 -274.049744) (xy 61.854842 -274.049744)
			(xy 61.854347 -274.074351) (xy 61.846452 -274.122928) (xy 61.830868 -274.169609) (xy 61.807997 -274.213186)
			(xy 61.778432 -274.25253) (xy 61.742939 -274.286622) (xy 61.702436 -274.314578) (xy 61.657974 -274.335676)
			(xy 61.610703 -274.349368) (xy 61.561848 -274.3553) (xy 61.512673 -274.353319) (xy 61.464454 -274.343475)
			(xy 61.418438 -274.326023) (xy 61.375817 -274.301416) (xy 61.337696 -274.270291) (xy 61.305061 -274.233454)
			(xy 61.278758 -274.191858) (xy 61.259467 -274.146582) (xy 61.24769 -274.098798) (xy 61.24373 -274.049744)
			(xy 59.954917 -274.049744) (xy 59.954427 -274.074097) (xy 59.946532 -274.122674) (xy 59.930948 -274.169355)
			(xy 59.908077 -274.212932) (xy 59.878512 -274.252276) (xy 59.843019 -274.286368) (xy 59.802516 -274.314324)
			(xy 59.758054 -274.335422) (xy 59.710783 -274.349114) (xy 59.661928 -274.355046) (xy 59.612753 -274.353065)
			(xy 59.564534 -274.343221) (xy 59.518518 -274.325769) (xy 59.475897 -274.301162) (xy 59.437776 -274.270037)
			(xy 59.405141 -274.2332) (xy 59.378838 -274.191604) (xy 59.359547 -274.146328) (xy 59.34777 -274.098544)
			(xy 59.34381 -274.04949) (xy 58.055251 -274.04949) (xy 58.055256 -274.049744) (xy 58.054761 -274.074351)
			(xy 58.046866 -274.122928) (xy 58.031282 -274.169609) (xy 58.008411 -274.213186) (xy 57.978846 -274.25253)
			(xy 57.943353 -274.286622) (xy 57.90285 -274.314578) (xy 57.858388 -274.335676) (xy 57.811117 -274.349368)
			(xy 57.762262 -274.3553) (xy 57.713087 -274.353319) (xy 57.664868 -274.343475) (xy 57.618852 -274.326023)
			(xy 57.576231 -274.301416) (xy 57.53811 -274.270291) (xy 57.505475 -274.233454) (xy 57.479172 -274.191858)
			(xy 57.459881 -274.146582) (xy 57.448104 -274.098798) (xy 57.444144 -274.049744) (xy 56.155082 -274.049744)
			(xy 56.154587 -274.074351) (xy 56.146692 -274.122928) (xy 56.131108 -274.169609) (xy 56.108237 -274.213186)
			(xy 56.078672 -274.25253) (xy 56.043179 -274.286622) (xy 56.002676 -274.314578) (xy 55.958214 -274.335676)
			(xy 55.910943 -274.349368) (xy 55.862088 -274.3553) (xy 55.812913 -274.353319) (xy 55.764694 -274.343475)
			(xy 55.718678 -274.326023) (xy 55.676057 -274.301416) (xy 55.637936 -274.270291) (xy 55.605301 -274.233454)
			(xy 55.578998 -274.191858) (xy 55.559707 -274.146582) (xy 55.54793 -274.098798) (xy 55.54397 -274.049744)
			(xy 54.255162 -274.049744) (xy 54.254667 -274.074351) (xy 54.246772 -274.122928) (xy 54.231188 -274.169609)
			(xy 54.208317 -274.213186) (xy 54.178752 -274.25253) (xy 54.143259 -274.286622) (xy 54.102756 -274.314578)
			(xy 54.058294 -274.335676) (xy 54.011023 -274.349368) (xy 53.962168 -274.3553) (xy 53.912993 -274.353319)
			(xy 53.864774 -274.343475) (xy 53.818758 -274.326023) (xy 53.776137 -274.301416) (xy 53.738016 -274.270291)
			(xy 53.705381 -274.233454) (xy 53.679078 -274.191858) (xy 53.659787 -274.146582) (xy 53.64801 -274.098798)
			(xy 53.64405 -274.049744) (xy 52.355242 -274.049744) (xy 52.354747 -274.074351) (xy 52.346852 -274.122928)
			(xy 52.331268 -274.169609) (xy 52.308397 -274.213186) (xy 52.278832 -274.25253) (xy 52.243339 -274.286622)
			(xy 52.202836 -274.314578) (xy 52.158374 -274.335676) (xy 52.111103 -274.349368) (xy 52.062248 -274.3553)
			(xy 52.013073 -274.353319) (xy 51.964854 -274.343475) (xy 51.918838 -274.326023) (xy 51.876217 -274.301416)
			(xy 51.838096 -274.270291) (xy 51.805461 -274.233454) (xy 51.779158 -274.191858) (xy 51.759867 -274.146582)
			(xy 51.74809 -274.098798) (xy 51.74413 -274.049744) (xy 50.455068 -274.049744) (xy 50.454573 -274.074351)
			(xy 50.446678 -274.122928) (xy 50.431094 -274.169609) (xy 50.408223 -274.213186) (xy 50.378658 -274.25253)
			(xy 50.343165 -274.286622) (xy 50.302662 -274.314578) (xy 50.2582 -274.335676) (xy 50.210929 -274.349368)
			(xy 50.162074 -274.3553) (xy 50.112899 -274.353319) (xy 50.06468 -274.343475) (xy 50.018664 -274.326023)
			(xy 49.976043 -274.301416) (xy 49.937922 -274.270291) (xy 49.905287 -274.233454) (xy 49.878984 -274.191858)
			(xy 49.859693 -274.146582) (xy 49.847916 -274.098798) (xy 49.843956 -274.049744) (xy 48.555148 -274.049744)
			(xy 48.554653 -274.074351) (xy 48.546758 -274.122928) (xy 48.531174 -274.169609) (xy 48.508303 -274.213186)
			(xy 48.478738 -274.25253) (xy 48.443245 -274.286622) (xy 48.402742 -274.314578) (xy 48.35828 -274.335676)
			(xy 48.311009 -274.349368) (xy 48.262154 -274.3553) (xy 48.212979 -274.353319) (xy 48.16476 -274.343475)
			(xy 48.118744 -274.326023) (xy 48.076123 -274.301416) (xy 48.038002 -274.270291) (xy 48.005367 -274.233454)
			(xy 47.979064 -274.191858) (xy 47.959773 -274.146582) (xy 47.947996 -274.098798) (xy 47.944036 -274.049744)
			(xy 46.655228 -274.049744) (xy 46.654733 -274.074351) (xy 46.646838 -274.122928) (xy 46.631254 -274.169609)
			(xy 46.608383 -274.213186) (xy 46.578818 -274.25253) (xy 46.543325 -274.286622) (xy 46.502822 -274.314578)
			(xy 46.45836 -274.335676) (xy 46.411089 -274.349368) (xy 46.362234 -274.3553) (xy 46.313059 -274.353319)
			(xy 46.26484 -274.343475) (xy 46.218824 -274.326023) (xy 46.176203 -274.301416) (xy 46.138082 -274.270291)
			(xy 46.105447 -274.233454) (xy 46.079144 -274.191858) (xy 46.059853 -274.146582) (xy 46.048076 -274.098798)
			(xy 46.044116 -274.049744) (xy 44.755054 -274.049744) (xy 44.754559 -274.074351) (xy 44.746664 -274.122928)
			(xy 44.73108 -274.169609) (xy 44.708209 -274.213186) (xy 44.678644 -274.25253) (xy 44.643151 -274.286622)
			(xy 44.602648 -274.314578) (xy 44.558186 -274.335676) (xy 44.510915 -274.349368) (xy 44.46206 -274.3553)
			(xy 44.412885 -274.353319) (xy 44.364666 -274.343475) (xy 44.31865 -274.326023) (xy 44.276029 -274.301416)
			(xy 44.237908 -274.270291) (xy 44.205273 -274.233454) (xy 44.17897 -274.191858) (xy 44.159679 -274.146582)
			(xy 44.147902 -274.098798) (xy 44.143942 -274.049744) (xy 0.509016 -274.049744) (xy 0.509016 -274.999958)
			(xy 45.094156 -274.999958) (xy 45.098116 -274.950904) (xy 45.109893 -274.90312) (xy 45.129184 -274.857844)
			(xy 45.155487 -274.816248) (xy 45.188122 -274.779411) (xy 45.226243 -274.748286) (xy 45.268864 -274.723679)
			(xy 45.31488 -274.706227) (xy 45.363099 -274.696383) (xy 45.412274 -274.694402) (xy 45.461129 -274.700334)
			(xy 45.5084 -274.714026) (xy 45.552862 -274.735124) (xy 45.593365 -274.76308) (xy 45.628858 -274.797172)
			(xy 45.658423 -274.836516) (xy 45.681294 -274.880093) (xy 45.696878 -274.926774) (xy 45.704773 -274.975351)
			(xy 45.705268 -274.999958) (xy 46.994076 -274.999958) (xy 46.998036 -274.950904) (xy 47.009813 -274.90312)
			(xy 47.029104 -274.857844) (xy 47.055407 -274.816248) (xy 47.088042 -274.779411) (xy 47.126163 -274.748286)
			(xy 47.168784 -274.723679) (xy 47.2148 -274.706227) (xy 47.263019 -274.696383) (xy 47.312194 -274.694402)
			(xy 47.361049 -274.700334) (xy 47.40832 -274.714026) (xy 47.452782 -274.735124) (xy 47.493285 -274.76308)
			(xy 47.528778 -274.797172) (xy 47.558343 -274.836516) (xy 47.581214 -274.880093) (xy 47.596798 -274.926774)
			(xy 47.604693 -274.975351) (xy 47.605188 -274.999958) (xy 48.893996 -274.999958) (xy 48.897956 -274.950904)
			(xy 48.909733 -274.90312) (xy 48.929024 -274.857844) (xy 48.955327 -274.816248) (xy 48.987962 -274.779411)
			(xy 49.026083 -274.748286) (xy 49.068704 -274.723679) (xy 49.11472 -274.706227) (xy 49.162939 -274.696383)
			(xy 49.212114 -274.694402) (xy 49.260969 -274.700334) (xy 49.30824 -274.714026) (xy 49.352702 -274.735124)
			(xy 49.393205 -274.76308) (xy 49.428698 -274.797172) (xy 49.458263 -274.836516) (xy 49.481134 -274.880093)
			(xy 49.496718 -274.926774) (xy 49.504613 -274.975351) (xy 49.505108 -274.999958) (xy 50.79417 -274.999958)
			(xy 50.79813 -274.950904) (xy 50.809907 -274.90312) (xy 50.829198 -274.857844) (xy 50.855501 -274.816248)
			(xy 50.888136 -274.779411) (xy 50.926257 -274.748286) (xy 50.968878 -274.723679) (xy 51.014894 -274.706227)
			(xy 51.063113 -274.696383) (xy 51.112288 -274.694402) (xy 51.161143 -274.700334) (xy 51.208414 -274.714026)
			(xy 51.252876 -274.735124) (xy 51.293379 -274.76308) (xy 51.328872 -274.797172) (xy 51.358437 -274.836516)
			(xy 51.381308 -274.880093) (xy 51.396892 -274.926774) (xy 51.404787 -274.975351) (xy 51.405282 -274.999958)
			(xy 52.69409 -274.999958) (xy 52.69805 -274.950904) (xy 52.709827 -274.90312) (xy 52.729118 -274.857844)
			(xy 52.755421 -274.816248) (xy 52.788056 -274.779411) (xy 52.826177 -274.748286) (xy 52.868798 -274.723679)
			(xy 52.914814 -274.706227) (xy 52.963033 -274.696383) (xy 53.012208 -274.694402) (xy 53.061063 -274.700334)
			(xy 53.108334 -274.714026) (xy 53.152796 -274.735124) (xy 53.193299 -274.76308) (xy 53.228792 -274.797172)
			(xy 53.258357 -274.836516) (xy 53.281228 -274.880093) (xy 53.296812 -274.926774) (xy 53.304707 -274.975351)
			(xy 53.305202 -274.999958) (xy 54.59401 -274.999958) (xy 54.59797 -274.950904) (xy 54.609747 -274.90312)
			(xy 54.629038 -274.857844) (xy 54.655341 -274.816248) (xy 54.687976 -274.779411) (xy 54.726097 -274.748286)
			(xy 54.768718 -274.723679) (xy 54.814734 -274.706227) (xy 54.862953 -274.696383) (xy 54.912128 -274.694402)
			(xy 54.960983 -274.700334) (xy 55.008254 -274.714026) (xy 55.052716 -274.735124) (xy 55.093219 -274.76308)
			(xy 55.128712 -274.797172) (xy 55.158277 -274.836516) (xy 55.181148 -274.880093) (xy 55.196732 -274.926774)
			(xy 55.204627 -274.975351) (xy 55.205122 -274.999958) (xy 56.494184 -274.999958) (xy 56.498144 -274.950904)
			(xy 56.509921 -274.90312) (xy 56.529212 -274.857844) (xy 56.555515 -274.816248) (xy 56.58815 -274.779411)
			(xy 56.626271 -274.748286) (xy 56.668892 -274.723679) (xy 56.714908 -274.706227) (xy 56.763127 -274.696383)
			(xy 56.812302 -274.694402) (xy 56.861157 -274.700334) (xy 56.908428 -274.714026) (xy 56.95289 -274.735124)
			(xy 56.993393 -274.76308) (xy 57.028886 -274.797172) (xy 57.058451 -274.836516) (xy 57.081322 -274.880093)
			(xy 57.096906 -274.926774) (xy 57.104801 -274.975351) (xy 57.105296 -274.999958) (xy 58.394104 -274.999958)
			(xy 58.398064 -274.950904) (xy 58.409841 -274.90312) (xy 58.429132 -274.857844) (xy 58.455435 -274.816248)
			(xy 58.48807 -274.779411) (xy 58.526191 -274.748286) (xy 58.568812 -274.723679) (xy 58.614828 -274.706227)
			(xy 58.663047 -274.696383) (xy 58.712222 -274.694402) (xy 58.761077 -274.700334) (xy 58.808348 -274.714026)
			(xy 58.85281 -274.735124) (xy 58.893313 -274.76308) (xy 58.928806 -274.797172) (xy 58.958371 -274.836516)
			(xy 58.981242 -274.880093) (xy 58.996826 -274.926774) (xy 59.004721 -274.975351) (xy 59.005211 -274.999704)
			(xy 60.29377 -274.999704) (xy 60.29773 -274.95065) (xy 60.309507 -274.902866) (xy 60.328798 -274.85759)
			(xy 60.355101 -274.815994) (xy 60.387736 -274.779157) (xy 60.425857 -274.748032) (xy 60.468478 -274.723425)
			(xy 60.514494 -274.705973) (xy 60.562713 -274.696129) (xy 60.611888 -274.694148) (xy 60.660743 -274.70008)
			(xy 60.708014 -274.713772) (xy 60.752476 -274.73487) (xy 60.792979 -274.762826) (xy 60.828472 -274.796918)
			(xy 60.858037 -274.836262) (xy 60.880908 -274.879839) (xy 60.896492 -274.92652) (xy 60.904387 -274.975097)
			(xy 60.904882 -274.999704) (xy 60.904877 -274.999958) (xy 62.19369 -274.999958) (xy 62.19765 -274.950904)
			(xy 62.209427 -274.90312) (xy 62.228718 -274.857844) (xy 62.255021 -274.816248) (xy 62.287656 -274.779411)
			(xy 62.325777 -274.748286) (xy 62.368398 -274.723679) (xy 62.414414 -274.706227) (xy 62.462633 -274.696383)
			(xy 62.511808 -274.694402) (xy 62.560663 -274.700334) (xy 62.607934 -274.714026) (xy 62.652396 -274.735124)
			(xy 62.692899 -274.76308) (xy 62.728392 -274.797172) (xy 62.757957 -274.836516) (xy 62.780828 -274.880093)
			(xy 62.796412 -274.926774) (xy 62.804307 -274.975351) (xy 62.804797 -274.999704) (xy 64.093864 -274.999704)
			(xy 64.097824 -274.95065) (xy 64.109601 -274.902866) (xy 64.128892 -274.85759) (xy 64.155195 -274.815994)
			(xy 64.18783 -274.779157) (xy 64.225951 -274.748032) (xy 64.268572 -274.723425) (xy 64.314588 -274.705973)
			(xy 64.362807 -274.696129) (xy 64.411982 -274.694148) (xy 64.460837 -274.70008) (xy 64.508108 -274.713772)
			(xy 64.55257 -274.73487) (xy 64.593073 -274.762826) (xy 64.628566 -274.796918) (xy 64.658131 -274.836262)
			(xy 64.681002 -274.879839) (xy 64.696586 -274.92652) (xy 64.704481 -274.975097) (xy 64.704976 -274.999704)
			(xy 64.704971 -274.999958) (xy 65.993784 -274.999958) (xy 65.997744 -274.950904) (xy 66.009521 -274.90312)
			(xy 66.028812 -274.857844) (xy 66.055115 -274.816248) (xy 66.08775 -274.779411) (xy 66.125871 -274.748286)
			(xy 66.168492 -274.723679) (xy 66.214508 -274.706227) (xy 66.262727 -274.696383) (xy 66.311902 -274.694402)
			(xy 66.360757 -274.700334) (xy 66.408028 -274.714026) (xy 66.45249 -274.735124) (xy 66.492993 -274.76308)
			(xy 66.528486 -274.797172) (xy 66.558051 -274.836516) (xy 66.580922 -274.880093) (xy 66.596506 -274.926774)
			(xy 66.604401 -274.975351) (xy 66.604891 -274.999704) (xy 67.893704 -274.999704) (xy 67.897664 -274.95065)
			(xy 67.909441 -274.902866) (xy 67.928732 -274.85759) (xy 67.955035 -274.815994) (xy 67.98767 -274.779157)
			(xy 68.025791 -274.748032) (xy 68.068412 -274.723425) (xy 68.114428 -274.705973) (xy 68.162647 -274.696129)
			(xy 68.211822 -274.694148) (xy 68.260677 -274.70008) (xy 68.307948 -274.713772) (xy 68.35241 -274.73487)
			(xy 68.392913 -274.762826) (xy 68.428406 -274.796918) (xy 68.457971 -274.836262) (xy 68.480842 -274.879839)
			(xy 68.496426 -274.92652) (xy 68.504321 -274.975097) (xy 68.504816 -274.999704) (xy 68.504811 -274.999958)
			(xy 69.793624 -274.999958) (xy 69.797584 -274.950904) (xy 69.809361 -274.90312) (xy 69.828652 -274.857844)
			(xy 69.854955 -274.816248) (xy 69.88759 -274.779411) (xy 69.925711 -274.748286) (xy 69.968332 -274.723679)
			(xy 70.014348 -274.706227) (xy 70.062567 -274.696383) (xy 70.111742 -274.694402) (xy 70.160597 -274.700334)
			(xy 70.207868 -274.714026) (xy 70.25233 -274.735124) (xy 70.292833 -274.76308) (xy 70.328326 -274.797172)
			(xy 70.357891 -274.836516) (xy 70.380762 -274.880093) (xy 70.396346 -274.926774) (xy 70.404241 -274.975351)
			(xy 70.404731 -274.999704) (xy 71.693798 -274.999704) (xy 71.697758 -274.95065) (xy 71.709535 -274.902866)
			(xy 71.728826 -274.85759) (xy 71.755129 -274.815994) (xy 71.787764 -274.779157) (xy 71.825885 -274.748032)
			(xy 71.868506 -274.723425) (xy 71.914522 -274.705973) (xy 71.962741 -274.696129) (xy 72.011916 -274.694148)
			(xy 72.060771 -274.70008) (xy 72.108042 -274.713772) (xy 72.152504 -274.73487) (xy 72.193007 -274.762826)
			(xy 72.2285 -274.796918) (xy 72.258065 -274.836262) (xy 72.280936 -274.879839) (xy 72.29652 -274.92652)
			(xy 72.304415 -274.975097) (xy 72.30491 -274.999704) (xy 72.304905 -274.999958) (xy 73.593718 -274.999958)
			(xy 73.597678 -274.950904) (xy 73.609455 -274.90312) (xy 73.628746 -274.857844) (xy 73.655049 -274.816248)
			(xy 73.687684 -274.779411) (xy 73.725805 -274.748286) (xy 73.768426 -274.723679) (xy 73.814442 -274.706227)
			(xy 73.862661 -274.696383) (xy 73.911836 -274.694402) (xy 73.960691 -274.700334) (xy 74.007962 -274.714026)
			(xy 74.052424 -274.735124) (xy 74.092927 -274.76308) (xy 74.12842 -274.797172) (xy 74.157985 -274.836516)
			(xy 74.180856 -274.880093) (xy 74.19644 -274.926774) (xy 74.204335 -274.975351) (xy 74.204825 -274.999704)
			(xy 75.493892 -274.999704) (xy 75.497852 -274.95065) (xy 75.509629 -274.902866) (xy 75.52892 -274.85759)
			(xy 75.555223 -274.815994) (xy 75.587858 -274.779157) (xy 75.625979 -274.748032) (xy 75.6686 -274.723425)
			(xy 75.714616 -274.705973) (xy 75.762835 -274.696129) (xy 75.81201 -274.694148) (xy 75.860865 -274.70008)
			(xy 75.908136 -274.713772) (xy 75.952598 -274.73487) (xy 75.993101 -274.762826) (xy 76.028594 -274.796918)
			(xy 76.058159 -274.836262) (xy 76.08103 -274.879839) (xy 76.096614 -274.92652) (xy 76.104509 -274.975097)
			(xy 76.105004 -274.999704) (xy 76.104999 -274.999958) (xy 77.393812 -274.999958) (xy 77.397772 -274.950904)
			(xy 77.409549 -274.90312) (xy 77.42884 -274.857844) (xy 77.455143 -274.816248) (xy 77.487778 -274.779411)
			(xy 77.525899 -274.748286) (xy 77.56852 -274.723679) (xy 77.614536 -274.706227) (xy 77.662755 -274.696383)
			(xy 77.71193 -274.694402) (xy 77.760785 -274.700334) (xy 77.808056 -274.714026) (xy 77.852518 -274.735124)
			(xy 77.893021 -274.76308) (xy 77.928514 -274.797172) (xy 77.958079 -274.836516) (xy 77.98095 -274.880093)
			(xy 77.996534 -274.926774) (xy 78.004429 -274.975351) (xy 78.004924 -274.999958) (xy 79.293732 -274.999958)
			(xy 79.297692 -274.950904) (xy 79.309469 -274.90312) (xy 79.32876 -274.857844) (xy 79.355063 -274.816248)
			(xy 79.387698 -274.779411) (xy 79.425819 -274.748286) (xy 79.46844 -274.723679) (xy 79.514456 -274.706227)
			(xy 79.562675 -274.696383) (xy 79.61185 -274.694402) (xy 79.660705 -274.700334) (xy 79.707976 -274.714026)
			(xy 79.752438 -274.735124) (xy 79.792941 -274.76308) (xy 79.828434 -274.797172) (xy 79.857999 -274.836516)
			(xy 79.88087 -274.880093) (xy 79.896454 -274.926774) (xy 79.904349 -274.975351) (xy 79.904839 -274.999704)
			(xy 81.19416 -274.999704) (xy 81.19812 -274.95065) (xy 81.209897 -274.902866) (xy 81.229188 -274.85759)
			(xy 81.255491 -274.815994) (xy 81.288126 -274.779157) (xy 81.326247 -274.748032) (xy 81.368868 -274.723425)
			(xy 81.414884 -274.705973) (xy 81.463103 -274.696129) (xy 81.512278 -274.694148) (xy 81.561133 -274.70008)
			(xy 81.608404 -274.713772) (xy 81.652866 -274.73487) (xy 81.693369 -274.762826) (xy 81.728862 -274.796918)
			(xy 81.758427 -274.836262) (xy 81.781298 -274.879839) (xy 81.796882 -274.92652) (xy 81.804777 -274.975097)
			(xy 81.805272 -274.999704) (xy 82.14412 -274.999704) (xy 82.14808 -274.95065) (xy 82.159857 -274.902866)
			(xy 82.179148 -274.85759) (xy 82.205451 -274.815994) (xy 82.238086 -274.779157) (xy 82.276207 -274.748032)
			(xy 82.318828 -274.723425) (xy 82.364844 -274.705973) (xy 82.413063 -274.696129) (xy 82.462238 -274.694148)
			(xy 82.511093 -274.70008) (xy 82.558364 -274.713772) (xy 82.602826 -274.73487) (xy 82.643329 -274.762826)
			(xy 82.678822 -274.796918) (xy 82.708387 -274.836262) (xy 82.731258 -274.879839) (xy 82.746842 -274.92652)
			(xy 82.754737 -274.975097) (xy 82.755232 -274.999704) (xy 82.755227 -274.999958) (xy 161.194254 -274.999958)
			(xy 161.198214 -274.950904) (xy 161.209991 -274.90312) (xy 161.229282 -274.857844) (xy 161.255585 -274.816248)
			(xy 161.28822 -274.779411) (xy 161.326341 -274.748286) (xy 161.368962 -274.723679) (xy 161.414978 -274.706227)
			(xy 161.463197 -274.696383) (xy 161.512372 -274.694402) (xy 161.561227 -274.700334) (xy 161.608498 -274.714026)
			(xy 161.65296 -274.735124) (xy 161.693463 -274.76308) (xy 161.728956 -274.797172) (xy 161.758521 -274.836516)
			(xy 161.781392 -274.880093) (xy 161.796976 -274.926774) (xy 161.804871 -274.975351) (xy 161.805366 -274.999958)
			(xy 163.094174 -274.999958) (xy 163.098134 -274.950904) (xy 163.109911 -274.90312) (xy 163.129202 -274.857844)
			(xy 163.155505 -274.816248) (xy 163.18814 -274.779411) (xy 163.226261 -274.748286) (xy 163.268882 -274.723679)
			(xy 163.314898 -274.706227) (xy 163.363117 -274.696383) (xy 163.412292 -274.694402) (xy 163.461147 -274.700334)
			(xy 163.508418 -274.714026) (xy 163.55288 -274.735124) (xy 163.593383 -274.76308) (xy 163.628876 -274.797172)
			(xy 163.658441 -274.836516) (xy 163.681312 -274.880093) (xy 163.696896 -274.926774) (xy 163.704791 -274.975351)
			(xy 163.705286 -274.999958) (xy 164.994094 -274.999958) (xy 164.998054 -274.950904) (xy 165.009831 -274.90312)
			(xy 165.029122 -274.857844) (xy 165.055425 -274.816248) (xy 165.08806 -274.779411) (xy 165.126181 -274.748286)
			(xy 165.168802 -274.723679) (xy 165.214818 -274.706227) (xy 165.263037 -274.696383) (xy 165.312212 -274.694402)
			(xy 165.361067 -274.700334) (xy 165.408338 -274.714026) (xy 165.4528 -274.735124) (xy 165.493303 -274.76308)
			(xy 165.528796 -274.797172) (xy 165.558361 -274.836516) (xy 165.581232 -274.880093) (xy 165.596816 -274.926774)
			(xy 165.604711 -274.975351) (xy 165.605206 -274.999958) (xy 166.894268 -274.999958) (xy 166.898228 -274.950904)
			(xy 166.910005 -274.90312) (xy 166.929296 -274.857844) (xy 166.955599 -274.816248) (xy 166.988234 -274.779411)
			(xy 167.026355 -274.748286) (xy 167.068976 -274.723679) (xy 167.114992 -274.706227) (xy 167.163211 -274.696383)
			(xy 167.212386 -274.694402) (xy 167.261241 -274.700334) (xy 167.308512 -274.714026) (xy 167.352974 -274.735124)
			(xy 167.393477 -274.76308) (xy 167.42897 -274.797172) (xy 167.458535 -274.836516) (xy 167.481406 -274.880093)
			(xy 167.49699 -274.926774) (xy 167.504885 -274.975351) (xy 167.50538 -274.999958) (xy 168.794188 -274.999958)
			(xy 168.798148 -274.950904) (xy 168.809925 -274.90312) (xy 168.829216 -274.857844) (xy 168.855519 -274.816248)
			(xy 168.888154 -274.779411) (xy 168.926275 -274.748286) (xy 168.968896 -274.723679) (xy 169.014912 -274.706227)
			(xy 169.063131 -274.696383) (xy 169.112306 -274.694402) (xy 169.161161 -274.700334) (xy 169.208432 -274.714026)
			(xy 169.252894 -274.735124) (xy 169.293397 -274.76308) (xy 169.32889 -274.797172) (xy 169.358455 -274.836516)
			(xy 169.381326 -274.880093) (xy 169.39691 -274.926774) (xy 169.404805 -274.975351) (xy 169.4053 -274.999958)
			(xy 170.694108 -274.999958) (xy 170.698068 -274.950904) (xy 170.709845 -274.90312) (xy 170.729136 -274.857844)
			(xy 170.755439 -274.816248) (xy 170.788074 -274.779411) (xy 170.826195 -274.748286) (xy 170.868816 -274.723679)
			(xy 170.914832 -274.706227) (xy 170.963051 -274.696383) (xy 171.012226 -274.694402) (xy 171.061081 -274.700334)
			(xy 171.108352 -274.714026) (xy 171.152814 -274.735124) (xy 171.193317 -274.76308) (xy 171.22881 -274.797172)
			(xy 171.258375 -274.836516) (xy 171.281246 -274.880093) (xy 171.29683 -274.926774) (xy 171.304725 -274.975351)
			(xy 171.30522 -274.999958) (xy 172.594282 -274.999958) (xy 172.598242 -274.950904) (xy 172.610019 -274.90312)
			(xy 172.62931 -274.857844) (xy 172.655613 -274.816248) (xy 172.688248 -274.779411) (xy 172.726369 -274.748286)
			(xy 172.76899 -274.723679) (xy 172.815006 -274.706227) (xy 172.863225 -274.696383) (xy 172.9124 -274.694402)
			(xy 172.961255 -274.700334) (xy 173.008526 -274.714026) (xy 173.052988 -274.735124) (xy 173.093491 -274.76308)
			(xy 173.128984 -274.797172) (xy 173.158549 -274.836516) (xy 173.18142 -274.880093) (xy 173.197004 -274.926774)
			(xy 173.204899 -274.975351) (xy 173.205394 -274.999958) (xy 174.494202 -274.999958) (xy 174.498162 -274.950904)
			(xy 174.509939 -274.90312) (xy 174.52923 -274.857844) (xy 174.555533 -274.816248) (xy 174.588168 -274.779411)
			(xy 174.626289 -274.748286) (xy 174.66891 -274.723679) (xy 174.714926 -274.706227) (xy 174.763145 -274.696383)
			(xy 174.81232 -274.694402) (xy 174.861175 -274.700334) (xy 174.908446 -274.714026) (xy 174.952908 -274.735124)
			(xy 174.993411 -274.76308) (xy 175.028904 -274.797172) (xy 175.058469 -274.836516) (xy 175.08134 -274.880093)
			(xy 175.096924 -274.926774) (xy 175.104819 -274.975351) (xy 175.105309 -274.999704) (xy 176.393868 -274.999704)
			(xy 176.397828 -274.95065) (xy 176.409605 -274.902866) (xy 176.428896 -274.85759) (xy 176.455199 -274.815994)
			(xy 176.487834 -274.779157) (xy 176.525955 -274.748032) (xy 176.568576 -274.723425) (xy 176.614592 -274.705973)
			(xy 176.662811 -274.696129) (xy 176.711986 -274.694148) (xy 176.760841 -274.70008) (xy 176.808112 -274.713772)
			(xy 176.852574 -274.73487) (xy 176.893077 -274.762826) (xy 176.92857 -274.796918) (xy 176.958135 -274.836262)
			(xy 176.981006 -274.879839) (xy 176.99659 -274.92652) (xy 177.004485 -274.975097) (xy 177.00498 -274.999704)
			(xy 177.004975 -274.999958) (xy 178.293788 -274.999958) (xy 178.297748 -274.950904) (xy 178.309525 -274.90312)
			(xy 178.328816 -274.857844) (xy 178.355119 -274.816248) (xy 178.387754 -274.779411) (xy 178.425875 -274.748286)
			(xy 178.468496 -274.723679) (xy 178.514512 -274.706227) (xy 178.562731 -274.696383) (xy 178.611906 -274.694402)
			(xy 178.660761 -274.700334) (xy 178.708032 -274.714026) (xy 178.752494 -274.735124) (xy 178.792997 -274.76308)
			(xy 178.82849 -274.797172) (xy 178.858055 -274.836516) (xy 178.880926 -274.880093) (xy 178.89651 -274.926774)
			(xy 178.904405 -274.975351) (xy 178.904895 -274.999704) (xy 180.193962 -274.999704) (xy 180.197922 -274.95065)
			(xy 180.209699 -274.902866) (xy 180.22899 -274.85759) (xy 180.255293 -274.815994) (xy 180.287928 -274.779157)
			(xy 180.326049 -274.748032) (xy 180.36867 -274.723425) (xy 180.414686 -274.705973) (xy 180.462905 -274.696129)
			(xy 180.51208 -274.694148) (xy 180.560935 -274.70008) (xy 180.608206 -274.713772) (xy 180.652668 -274.73487)
			(xy 180.693171 -274.762826) (xy 180.728664 -274.796918) (xy 180.758229 -274.836262) (xy 180.7811 -274.879839)
			(xy 180.796684 -274.92652) (xy 180.804579 -274.975097) (xy 180.805074 -274.999704) (xy 180.805069 -274.999958)
			(xy 182.093882 -274.999958) (xy 182.097842 -274.950904) (xy 182.109619 -274.90312) (xy 182.12891 -274.857844)
			(xy 182.155213 -274.816248) (xy 182.187848 -274.779411) (xy 182.225969 -274.748286) (xy 182.26859 -274.723679)
			(xy 182.314606 -274.706227) (xy 182.362825 -274.696383) (xy 182.412 -274.694402) (xy 182.460855 -274.700334)
			(xy 182.508126 -274.714026) (xy 182.552588 -274.735124) (xy 182.593091 -274.76308) (xy 182.628584 -274.797172)
			(xy 182.658149 -274.836516) (xy 182.68102 -274.880093) (xy 182.696604 -274.926774) (xy 182.704499 -274.975351)
			(xy 182.704989 -274.999704) (xy 183.993802 -274.999704) (xy 183.997762 -274.95065) (xy 184.009539 -274.902866)
			(xy 184.02883 -274.85759) (xy 184.055133 -274.815994) (xy 184.087768 -274.779157) (xy 184.125889 -274.748032)
			(xy 184.16851 -274.723425) (xy 184.214526 -274.705973) (xy 184.262745 -274.696129) (xy 184.31192 -274.694148)
			(xy 184.360775 -274.70008) (xy 184.408046 -274.713772) (xy 184.452508 -274.73487) (xy 184.493011 -274.762826)
			(xy 184.528504 -274.796918) (xy 184.558069 -274.836262) (xy 184.58094 -274.879839) (xy 184.596524 -274.92652)
			(xy 184.604419 -274.975097) (xy 184.604914 -274.999704) (xy 184.604909 -274.999958) (xy 185.893722 -274.999958)
			(xy 185.897682 -274.950904) (xy 185.909459 -274.90312) (xy 185.92875 -274.857844) (xy 185.955053 -274.816248)
			(xy 185.987688 -274.779411) (xy 186.025809 -274.748286) (xy 186.06843 -274.723679) (xy 186.114446 -274.706227)
			(xy 186.162665 -274.696383) (xy 186.21184 -274.694402) (xy 186.260695 -274.700334) (xy 186.307966 -274.714026)
			(xy 186.352428 -274.735124) (xy 186.392931 -274.76308) (xy 186.428424 -274.797172) (xy 186.457989 -274.836516)
			(xy 186.48086 -274.880093) (xy 186.496444 -274.926774) (xy 186.504339 -274.975351) (xy 186.504829 -274.999704)
			(xy 187.793896 -274.999704) (xy 187.797856 -274.95065) (xy 187.809633 -274.902866) (xy 187.828924 -274.85759)
			(xy 187.855227 -274.815994) (xy 187.887862 -274.779157) (xy 187.925983 -274.748032) (xy 187.968604 -274.723425)
			(xy 188.01462 -274.705973) (xy 188.062839 -274.696129) (xy 188.112014 -274.694148) (xy 188.160869 -274.70008)
			(xy 188.20814 -274.713772) (xy 188.252602 -274.73487) (xy 188.293105 -274.762826) (xy 188.328598 -274.796918)
			(xy 188.358163 -274.836262) (xy 188.381034 -274.879839) (xy 188.396618 -274.92652) (xy 188.404513 -274.975097)
			(xy 188.405008 -274.999704) (xy 188.405003 -274.999958) (xy 189.693816 -274.999958) (xy 189.697776 -274.950904)
			(xy 189.709553 -274.90312) (xy 189.728844 -274.857844) (xy 189.755147 -274.816248) (xy 189.787782 -274.779411)
			(xy 189.825903 -274.748286) (xy 189.868524 -274.723679) (xy 189.91454 -274.706227) (xy 189.962759 -274.696383)
			(xy 190.011934 -274.694402) (xy 190.060789 -274.700334) (xy 190.10806 -274.714026) (xy 190.152522 -274.735124)
			(xy 190.193025 -274.76308) (xy 190.228518 -274.797172) (xy 190.258083 -274.836516) (xy 190.280954 -274.880093)
			(xy 190.296538 -274.926774) (xy 190.304433 -274.975351) (xy 190.304923 -274.999704) (xy 191.59399 -274.999704)
			(xy 191.59795 -274.95065) (xy 191.609727 -274.902866) (xy 191.629018 -274.85759) (xy 191.655321 -274.815994)
			(xy 191.687956 -274.779157) (xy 191.726077 -274.748032) (xy 191.768698 -274.723425) (xy 191.814714 -274.705973)
			(xy 191.862933 -274.696129) (xy 191.912108 -274.694148) (xy 191.960963 -274.70008) (xy 192.008234 -274.713772)
			(xy 192.052696 -274.73487) (xy 192.093199 -274.762826) (xy 192.128692 -274.796918) (xy 192.158257 -274.836262)
			(xy 192.181128 -274.879839) (xy 192.196712 -274.92652) (xy 192.204607 -274.975097) (xy 192.205102 -274.999704)
			(xy 192.205097 -274.999958) (xy 193.49391 -274.999958) (xy 193.49787 -274.950904) (xy 193.509647 -274.90312)
			(xy 193.528938 -274.857844) (xy 193.555241 -274.816248) (xy 193.587876 -274.779411) (xy 193.625997 -274.748286)
			(xy 193.668618 -274.723679) (xy 193.714634 -274.706227) (xy 193.762853 -274.696383) (xy 193.812028 -274.694402)
			(xy 193.860883 -274.700334) (xy 193.908154 -274.714026) (xy 193.952616 -274.735124) (xy 193.993119 -274.76308)
			(xy 194.028612 -274.797172) (xy 194.058177 -274.836516) (xy 194.081048 -274.880093) (xy 194.096632 -274.926774)
			(xy 194.104527 -274.975351) (xy 194.105022 -274.999958) (xy 195.39383 -274.999958) (xy 195.39779 -274.950904)
			(xy 195.409567 -274.90312) (xy 195.428858 -274.857844) (xy 195.455161 -274.816248) (xy 195.487796 -274.779411)
			(xy 195.525917 -274.748286) (xy 195.568538 -274.723679) (xy 195.614554 -274.706227) (xy 195.662773 -274.696383)
			(xy 195.711948 -274.694402) (xy 195.760803 -274.700334) (xy 195.808074 -274.714026) (xy 195.852536 -274.735124)
			(xy 195.893039 -274.76308) (xy 195.928532 -274.797172) (xy 195.958097 -274.836516) (xy 195.980968 -274.880093)
			(xy 195.996552 -274.926774) (xy 196.004447 -274.975351) (xy 196.004937 -274.999704) (xy 197.294258 -274.999704)
			(xy 197.298218 -274.95065) (xy 197.309995 -274.902866) (xy 197.329286 -274.85759) (xy 197.355589 -274.815994)
			(xy 197.388224 -274.779157) (xy 197.426345 -274.748032) (xy 197.468966 -274.723425) (xy 197.514982 -274.705973)
			(xy 197.563201 -274.696129) (xy 197.612376 -274.694148) (xy 197.661231 -274.70008) (xy 197.708502 -274.713772)
			(xy 197.752964 -274.73487) (xy 197.793467 -274.762826) (xy 197.82896 -274.796918) (xy 197.858525 -274.836262)
			(xy 197.881396 -274.879839) (xy 197.89698 -274.92652) (xy 197.904875 -274.975097) (xy 197.90537 -274.999704)
			(xy 198.244218 -274.999704) (xy 198.248178 -274.95065) (xy 198.259955 -274.902866) (xy 198.279246 -274.85759)
			(xy 198.305549 -274.815994) (xy 198.338184 -274.779157) (xy 198.376305 -274.748032) (xy 198.418926 -274.723425)
			(xy 198.464942 -274.705973) (xy 198.513161 -274.696129) (xy 198.562336 -274.694148) (xy 198.611191 -274.70008)
			(xy 198.658462 -274.713772) (xy 198.702924 -274.73487) (xy 198.743427 -274.762826) (xy 198.77892 -274.796918)
			(xy 198.808485 -274.836262) (xy 198.831356 -274.879839) (xy 198.84694 -274.92652) (xy 198.854835 -274.975097)
			(xy 198.85533 -274.999704) (xy 198.855325 -274.999958) (xy 277.294098 -274.999958) (xy 277.298058 -274.950904)
			(xy 277.309835 -274.90312) (xy 277.329126 -274.857844) (xy 277.355429 -274.816248) (xy 277.388064 -274.779411)
			(xy 277.426185 -274.748286) (xy 277.468806 -274.723679) (xy 277.514822 -274.706227) (xy 277.563041 -274.696383)
			(xy 277.612216 -274.694402) (xy 277.661071 -274.700334) (xy 277.708342 -274.714026) (xy 277.752804 -274.735124)
			(xy 277.793307 -274.76308) (xy 277.8288 -274.797172) (xy 277.858365 -274.836516) (xy 277.881236 -274.880093)
			(xy 277.89682 -274.926774) (xy 277.904715 -274.975351) (xy 277.90521 -274.999958) (xy 279.194018 -274.999958)
			(xy 279.197978 -274.950904) (xy 279.209755 -274.90312) (xy 279.229046 -274.857844) (xy 279.255349 -274.816248)
			(xy 279.287984 -274.779411) (xy 279.326105 -274.748286) (xy 279.368726 -274.723679) (xy 279.414742 -274.706227)
			(xy 279.462961 -274.696383) (xy 279.512136 -274.694402) (xy 279.560991 -274.700334) (xy 279.608262 -274.714026)
			(xy 279.652724 -274.735124) (xy 279.693227 -274.76308) (xy 279.72872 -274.797172) (xy 279.758285 -274.836516)
			(xy 279.781156 -274.880093) (xy 279.79674 -274.926774) (xy 279.804635 -274.975351) (xy 279.80513 -274.999958)
			(xy 281.093938 -274.999958) (xy 281.097898 -274.950904) (xy 281.109675 -274.90312) (xy 281.128966 -274.857844)
			(xy 281.155269 -274.816248) (xy 281.187904 -274.779411) (xy 281.226025 -274.748286) (xy 281.268646 -274.723679)
			(xy 281.314662 -274.706227) (xy 281.362881 -274.696383) (xy 281.412056 -274.694402) (xy 281.460911 -274.700334)
			(xy 281.508182 -274.714026) (xy 281.552644 -274.735124) (xy 281.593147 -274.76308) (xy 281.62864 -274.797172)
			(xy 281.658205 -274.836516) (xy 281.681076 -274.880093) (xy 281.69666 -274.926774) (xy 281.704555 -274.975351)
			(xy 281.70505 -274.999958) (xy 282.994112 -274.999958) (xy 282.998072 -274.950904) (xy 283.009849 -274.90312)
			(xy 283.02914 -274.857844) (xy 283.055443 -274.816248) (xy 283.088078 -274.779411) (xy 283.126199 -274.748286)
			(xy 283.16882 -274.723679) (xy 283.214836 -274.706227) (xy 283.263055 -274.696383) (xy 283.31223 -274.694402)
			(xy 283.361085 -274.700334) (xy 283.408356 -274.714026) (xy 283.452818 -274.735124) (xy 283.493321 -274.76308)
			(xy 283.528814 -274.797172) (xy 283.558379 -274.836516) (xy 283.58125 -274.880093) (xy 283.596834 -274.926774)
			(xy 283.604729 -274.975351) (xy 283.605224 -274.999958) (xy 284.894032 -274.999958) (xy 284.897992 -274.950904)
			(xy 284.909769 -274.90312) (xy 284.92906 -274.857844) (xy 284.955363 -274.816248) (xy 284.987998 -274.779411)
			(xy 285.026119 -274.748286) (xy 285.06874 -274.723679) (xy 285.114756 -274.706227) (xy 285.162975 -274.696383)
			(xy 285.21215 -274.694402) (xy 285.261005 -274.700334) (xy 285.308276 -274.714026) (xy 285.352738 -274.735124)
			(xy 285.393241 -274.76308) (xy 285.428734 -274.797172) (xy 285.458299 -274.836516) (xy 285.48117 -274.880093)
			(xy 285.496754 -274.926774) (xy 285.504649 -274.975351) (xy 285.505144 -274.999958) (xy 286.793952 -274.999958)
			(xy 286.797912 -274.950904) (xy 286.809689 -274.90312) (xy 286.82898 -274.857844) (xy 286.855283 -274.816248)
			(xy 286.887918 -274.779411) (xy 286.926039 -274.748286) (xy 286.96866 -274.723679) (xy 287.014676 -274.706227)
			(xy 287.062895 -274.696383) (xy 287.11207 -274.694402) (xy 287.160925 -274.700334) (xy 287.208196 -274.714026)
			(xy 287.252658 -274.735124) (xy 287.293161 -274.76308) (xy 287.328654 -274.797172) (xy 287.358219 -274.836516)
			(xy 287.38109 -274.880093) (xy 287.396674 -274.926774) (xy 287.404569 -274.975351) (xy 287.405064 -274.999958)
			(xy 288.694126 -274.999958) (xy 288.698086 -274.950904) (xy 288.709863 -274.90312) (xy 288.729154 -274.857844)
			(xy 288.755457 -274.816248) (xy 288.788092 -274.779411) (xy 288.826213 -274.748286) (xy 288.868834 -274.723679)
			(xy 288.91485 -274.706227) (xy 288.963069 -274.696383) (xy 289.012244 -274.694402) (xy 289.061099 -274.700334)
			(xy 289.10837 -274.714026) (xy 289.152832 -274.735124) (xy 289.193335 -274.76308) (xy 289.228828 -274.797172)
			(xy 289.258393 -274.836516) (xy 289.281264 -274.880093) (xy 289.296848 -274.926774) (xy 289.304743 -274.975351)
			(xy 289.305238 -274.999958) (xy 290.594046 -274.999958) (xy 290.598006 -274.950904) (xy 290.609783 -274.90312)
			(xy 290.629074 -274.857844) (xy 290.655377 -274.816248) (xy 290.688012 -274.779411) (xy 290.726133 -274.748286)
			(xy 290.768754 -274.723679) (xy 290.81477 -274.706227) (xy 290.862989 -274.696383) (xy 290.912164 -274.694402)
			(xy 290.961019 -274.700334) (xy 291.00829 -274.714026) (xy 291.052752 -274.735124) (xy 291.093255 -274.76308)
			(xy 291.128748 -274.797172) (xy 291.158313 -274.836516) (xy 291.181184 -274.880093) (xy 291.196768 -274.926774)
			(xy 291.204663 -274.975351) (xy 291.205153 -274.999704) (xy 292.493712 -274.999704) (xy 292.497672 -274.95065)
			(xy 292.509449 -274.902866) (xy 292.52874 -274.85759) (xy 292.555043 -274.815994) (xy 292.587678 -274.779157)
			(xy 292.625799 -274.748032) (xy 292.66842 -274.723425) (xy 292.714436 -274.705973) (xy 292.762655 -274.696129)
			(xy 292.81183 -274.694148) (xy 292.860685 -274.70008) (xy 292.907956 -274.713772) (xy 292.952418 -274.73487)
			(xy 292.992921 -274.762826) (xy 293.028414 -274.796918) (xy 293.057979 -274.836262) (xy 293.08085 -274.879839)
			(xy 293.096434 -274.92652) (xy 293.104329 -274.975097) (xy 293.104824 -274.999704) (xy 293.104819 -274.999958)
			(xy 294.393632 -274.999958) (xy 294.397592 -274.950904) (xy 294.409369 -274.90312) (xy 294.42866 -274.857844)
			(xy 294.454963 -274.816248) (xy 294.487598 -274.779411) (xy 294.525719 -274.748286) (xy 294.56834 -274.723679)
			(xy 294.614356 -274.706227) (xy 294.662575 -274.696383) (xy 294.71175 -274.694402) (xy 294.760605 -274.700334)
			(xy 294.807876 -274.714026) (xy 294.852338 -274.735124) (xy 294.892841 -274.76308) (xy 294.928334 -274.797172)
			(xy 294.957899 -274.836516) (xy 294.98077 -274.880093) (xy 294.996354 -274.926774) (xy 295.004249 -274.975351)
			(xy 295.004739 -274.999704) (xy 296.293806 -274.999704) (xy 296.297766 -274.95065) (xy 296.309543 -274.902866)
			(xy 296.328834 -274.85759) (xy 296.355137 -274.815994) (xy 296.387772 -274.779157) (xy 296.425893 -274.748032)
			(xy 296.468514 -274.723425) (xy 296.51453 -274.705973) (xy 296.562749 -274.696129) (xy 296.611924 -274.694148)
			(xy 296.660779 -274.70008) (xy 296.70805 -274.713772) (xy 296.752512 -274.73487) (xy 296.793015 -274.762826)
			(xy 296.828508 -274.796918) (xy 296.858073 -274.836262) (xy 296.880944 -274.879839) (xy 296.896528 -274.92652)
			(xy 296.904423 -274.975097) (xy 296.904918 -274.999704) (xy 296.904913 -274.999958) (xy 298.193726 -274.999958)
			(xy 298.197686 -274.950904) (xy 298.209463 -274.90312) (xy 298.228754 -274.857844) (xy 298.255057 -274.816248)
			(xy 298.287692 -274.779411) (xy 298.325813 -274.748286) (xy 298.368434 -274.723679) (xy 298.41445 -274.706227)
			(xy 298.462669 -274.696383) (xy 298.511844 -274.694402) (xy 298.560699 -274.700334) (xy 298.60797 -274.714026)
			(xy 298.652432 -274.735124) (xy 298.692935 -274.76308) (xy 298.728428 -274.797172) (xy 298.757993 -274.836516)
			(xy 298.780864 -274.880093) (xy 298.796448 -274.926774) (xy 298.804343 -274.975351) (xy 298.804833 -274.999704)
			(xy 300.093646 -274.999704) (xy 300.097606 -274.95065) (xy 300.109383 -274.902866) (xy 300.128674 -274.85759)
			(xy 300.154977 -274.815994) (xy 300.187612 -274.779157) (xy 300.225733 -274.748032) (xy 300.268354 -274.723425)
			(xy 300.31437 -274.705973) (xy 300.362589 -274.696129) (xy 300.411764 -274.694148) (xy 300.460619 -274.70008)
			(xy 300.50789 -274.713772) (xy 300.552352 -274.73487) (xy 300.592855 -274.762826) (xy 300.628348 -274.796918)
			(xy 300.657913 -274.836262) (xy 300.680784 -274.879839) (xy 300.696368 -274.92652) (xy 300.704263 -274.975097)
			(xy 300.704758 -274.999704) (xy 300.704753 -274.999958) (xy 301.993566 -274.999958) (xy 301.997526 -274.950904)
			(xy 302.009303 -274.90312) (xy 302.028594 -274.857844) (xy 302.054897 -274.816248) (xy 302.087532 -274.779411)
			(xy 302.125653 -274.748286) (xy 302.168274 -274.723679) (xy 302.21429 -274.706227) (xy 302.262509 -274.696383)
			(xy 302.311684 -274.694402) (xy 302.360539 -274.700334) (xy 302.40781 -274.714026) (xy 302.452272 -274.735124)
			(xy 302.492775 -274.76308) (xy 302.528268 -274.797172) (xy 302.557833 -274.836516) (xy 302.580704 -274.880093)
			(xy 302.596288 -274.926774) (xy 302.604183 -274.975351) (xy 302.604673 -274.999704) (xy 303.89374 -274.999704)
			(xy 303.8977 -274.95065) (xy 303.909477 -274.902866) (xy 303.928768 -274.85759) (xy 303.955071 -274.815994)
			(xy 303.987706 -274.779157) (xy 304.025827 -274.748032) (xy 304.068448 -274.723425) (xy 304.114464 -274.705973)
			(xy 304.162683 -274.696129) (xy 304.211858 -274.694148) (xy 304.260713 -274.70008) (xy 304.307984 -274.713772)
			(xy 304.352446 -274.73487) (xy 304.392949 -274.762826) (xy 304.428442 -274.796918) (xy 304.458007 -274.836262)
			(xy 304.480878 -274.879839) (xy 304.496462 -274.92652) (xy 304.504357 -274.975097) (xy 304.504852 -274.999704)
			(xy 304.504847 -274.999958) (xy 305.79366 -274.999958) (xy 305.79762 -274.950904) (xy 305.809397 -274.90312)
			(xy 305.828688 -274.857844) (xy 305.854991 -274.816248) (xy 305.887626 -274.779411) (xy 305.925747 -274.748286)
			(xy 305.968368 -274.723679) (xy 306.014384 -274.706227) (xy 306.062603 -274.696383) (xy 306.111778 -274.694402)
			(xy 306.160633 -274.700334) (xy 306.207904 -274.714026) (xy 306.252366 -274.735124) (xy 306.292869 -274.76308)
			(xy 306.328362 -274.797172) (xy 306.357927 -274.836516) (xy 306.380798 -274.880093) (xy 306.396382 -274.926774)
			(xy 306.404277 -274.975351) (xy 306.404767 -274.999704) (xy 307.693834 -274.999704) (xy 307.697794 -274.95065)
			(xy 307.709571 -274.902866) (xy 307.728862 -274.85759) (xy 307.755165 -274.815994) (xy 307.7878 -274.779157)
			(xy 307.825921 -274.748032) (xy 307.868542 -274.723425) (xy 307.914558 -274.705973) (xy 307.962777 -274.696129)
			(xy 308.011952 -274.694148) (xy 308.060807 -274.70008) (xy 308.108078 -274.713772) (xy 308.15254 -274.73487)
			(xy 308.193043 -274.762826) (xy 308.228536 -274.796918) (xy 308.258101 -274.836262) (xy 308.280972 -274.879839)
			(xy 308.296556 -274.92652) (xy 308.304451 -274.975097) (xy 308.304946 -274.999704) (xy 308.304941 -274.999958)
			(xy 309.593754 -274.999958) (xy 309.597714 -274.950904) (xy 309.609491 -274.90312) (xy 309.628782 -274.857844)
			(xy 309.655085 -274.816248) (xy 309.68772 -274.779411) (xy 309.725841 -274.748286) (xy 309.768462 -274.723679)
			(xy 309.814478 -274.706227) (xy 309.862697 -274.696383) (xy 309.911872 -274.694402) (xy 309.960727 -274.700334)
			(xy 310.007998 -274.714026) (xy 310.05246 -274.735124) (xy 310.092963 -274.76308) (xy 310.128456 -274.797172)
			(xy 310.158021 -274.836516) (xy 310.180892 -274.880093) (xy 310.196476 -274.926774) (xy 310.204371 -274.975351)
			(xy 310.204866 -274.999958) (xy 311.493674 -274.999958) (xy 311.497634 -274.950904) (xy 311.509411 -274.90312)
			(xy 311.528702 -274.857844) (xy 311.555005 -274.816248) (xy 311.58764 -274.779411) (xy 311.625761 -274.748286)
			(xy 311.668382 -274.723679) (xy 311.714398 -274.706227) (xy 311.762617 -274.696383) (xy 311.811792 -274.694402)
			(xy 311.860647 -274.700334) (xy 311.907918 -274.714026) (xy 311.95238 -274.735124) (xy 311.992883 -274.76308)
			(xy 312.028376 -274.797172) (xy 312.057941 -274.836516) (xy 312.080812 -274.880093) (xy 312.096396 -274.926774)
			(xy 312.104291 -274.975351) (xy 312.104781 -274.999704) (xy 313.394102 -274.999704) (xy 313.398062 -274.95065)
			(xy 313.409839 -274.902866) (xy 313.42913 -274.85759) (xy 313.455433 -274.815994) (xy 313.488068 -274.779157)
			(xy 313.526189 -274.748032) (xy 313.56881 -274.723425) (xy 313.614826 -274.705973) (xy 313.663045 -274.696129)
			(xy 313.71222 -274.694148) (xy 313.761075 -274.70008) (xy 313.808346 -274.713772) (xy 313.852808 -274.73487)
			(xy 313.893311 -274.762826) (xy 313.928804 -274.796918) (xy 313.958369 -274.836262) (xy 313.98124 -274.879839)
			(xy 313.996824 -274.92652) (xy 314.004719 -274.975097) (xy 314.005214 -274.999704) (xy 314.344062 -274.999704)
			(xy 314.348022 -274.95065) (xy 314.359799 -274.902866) (xy 314.37909 -274.85759) (xy 314.405393 -274.815994)
			(xy 314.438028 -274.779157) (xy 314.476149 -274.748032) (xy 314.51877 -274.723425) (xy 314.564786 -274.705973)
			(xy 314.613005 -274.696129) (xy 314.66218 -274.694148) (xy 314.711035 -274.70008) (xy 314.758306 -274.713772)
			(xy 314.802768 -274.73487) (xy 314.843271 -274.762826) (xy 314.878764 -274.796918) (xy 314.908329 -274.836262)
			(xy 314.9312 -274.879839) (xy 314.946784 -274.92652) (xy 314.954679 -274.975097) (xy 314.955174 -274.999704)
			(xy 314.955169 -274.999958) (xy 393.394196 -274.999958) (xy 393.398156 -274.950904) (xy 393.409933 -274.90312)
			(xy 393.429224 -274.857844) (xy 393.455527 -274.816248) (xy 393.488162 -274.779411) (xy 393.526283 -274.748286)
			(xy 393.568904 -274.723679) (xy 393.61492 -274.706227) (xy 393.663139 -274.696383) (xy 393.712314 -274.694402)
			(xy 393.761169 -274.700334) (xy 393.80844 -274.714026) (xy 393.852902 -274.735124) (xy 393.893405 -274.76308)
			(xy 393.928898 -274.797172) (xy 393.958463 -274.836516) (xy 393.981334 -274.880093) (xy 393.996918 -274.926774)
			(xy 394.004813 -274.975351) (xy 394.005308 -274.999958) (xy 395.294116 -274.999958) (xy 395.298076 -274.950904)
			(xy 395.309853 -274.90312) (xy 395.329144 -274.857844) (xy 395.355447 -274.816248) (xy 395.388082 -274.779411)
			(xy 395.426203 -274.748286) (xy 395.468824 -274.723679) (xy 395.51484 -274.706227) (xy 395.563059 -274.696383)
			(xy 395.612234 -274.694402) (xy 395.661089 -274.700334) (xy 395.70836 -274.714026) (xy 395.752822 -274.735124)
			(xy 395.793325 -274.76308) (xy 395.828818 -274.797172) (xy 395.858383 -274.836516) (xy 395.881254 -274.880093)
			(xy 395.896838 -274.926774) (xy 395.904733 -274.975351) (xy 395.905228 -274.999958) (xy 397.194036 -274.999958)
			(xy 397.197996 -274.950904) (xy 397.209773 -274.90312) (xy 397.229064 -274.857844) (xy 397.255367 -274.816248)
			(xy 397.288002 -274.779411) (xy 397.326123 -274.748286) (xy 397.368744 -274.723679) (xy 397.41476 -274.706227)
			(xy 397.462979 -274.696383) (xy 397.512154 -274.694402) (xy 397.561009 -274.700334) (xy 397.60828 -274.714026)
			(xy 397.652742 -274.735124) (xy 397.693245 -274.76308) (xy 397.728738 -274.797172) (xy 397.758303 -274.836516)
			(xy 397.781174 -274.880093) (xy 397.796758 -274.926774) (xy 397.804653 -274.975351) (xy 397.805148 -274.999958)
			(xy 399.09421 -274.999958) (xy 399.09817 -274.950904) (xy 399.109947 -274.90312) (xy 399.129238 -274.857844)
			(xy 399.155541 -274.816248) (xy 399.188176 -274.779411) (xy 399.226297 -274.748286) (xy 399.268918 -274.723679)
			(xy 399.314934 -274.706227) (xy 399.363153 -274.696383) (xy 399.412328 -274.694402) (xy 399.461183 -274.700334)
			(xy 399.508454 -274.714026) (xy 399.552916 -274.735124) (xy 399.593419 -274.76308) (xy 399.628912 -274.797172)
			(xy 399.658477 -274.836516) (xy 399.681348 -274.880093) (xy 399.696932 -274.926774) (xy 399.704827 -274.975351)
			(xy 399.705322 -274.999958) (xy 400.99413 -274.999958) (xy 400.99809 -274.950904) (xy 401.009867 -274.90312)
			(xy 401.029158 -274.857844) (xy 401.055461 -274.816248) (xy 401.088096 -274.779411) (xy 401.126217 -274.748286)
			(xy 401.168838 -274.723679) (xy 401.214854 -274.706227) (xy 401.263073 -274.696383) (xy 401.312248 -274.694402)
			(xy 401.361103 -274.700334) (xy 401.408374 -274.714026) (xy 401.452836 -274.735124) (xy 401.493339 -274.76308)
			(xy 401.528832 -274.797172) (xy 401.558397 -274.836516) (xy 401.581268 -274.880093) (xy 401.596852 -274.926774)
			(xy 401.604747 -274.975351) (xy 401.605242 -274.999958) (xy 402.89405 -274.999958) (xy 402.89801 -274.950904)
			(xy 402.909787 -274.90312) (xy 402.929078 -274.857844) (xy 402.955381 -274.816248) (xy 402.988016 -274.779411)
			(xy 403.026137 -274.748286) (xy 403.068758 -274.723679) (xy 403.114774 -274.706227) (xy 403.162993 -274.696383)
			(xy 403.212168 -274.694402) (xy 403.261023 -274.700334) (xy 403.308294 -274.714026) (xy 403.352756 -274.735124)
			(xy 403.393259 -274.76308) (xy 403.428752 -274.797172) (xy 403.458317 -274.836516) (xy 403.481188 -274.880093)
			(xy 403.496772 -274.926774) (xy 403.504667 -274.975351) (xy 403.505162 -274.999958) (xy 404.794224 -274.999958)
			(xy 404.798184 -274.950904) (xy 404.809961 -274.90312) (xy 404.829252 -274.857844) (xy 404.855555 -274.816248)
			(xy 404.88819 -274.779411) (xy 404.926311 -274.748286) (xy 404.968932 -274.723679) (xy 405.014948 -274.706227)
			(xy 405.063167 -274.696383) (xy 405.112342 -274.694402) (xy 405.161197 -274.700334) (xy 405.208468 -274.714026)
			(xy 405.25293 -274.735124) (xy 405.293433 -274.76308) (xy 405.328926 -274.797172) (xy 405.358491 -274.836516)
			(xy 405.381362 -274.880093) (xy 405.396946 -274.926774) (xy 405.404841 -274.975351) (xy 405.405336 -274.999958)
			(xy 406.694144 -274.999958) (xy 406.698104 -274.950904) (xy 406.709881 -274.90312) (xy 406.729172 -274.857844)
			(xy 406.755475 -274.816248) (xy 406.78811 -274.779411) (xy 406.826231 -274.748286) (xy 406.868852 -274.723679)
			(xy 406.914868 -274.706227) (xy 406.963087 -274.696383) (xy 407.012262 -274.694402) (xy 407.061117 -274.700334)
			(xy 407.108388 -274.714026) (xy 407.15285 -274.735124) (xy 407.193353 -274.76308) (xy 407.228846 -274.797172)
			(xy 407.258411 -274.836516) (xy 407.281282 -274.880093) (xy 407.296866 -274.926774) (xy 407.304761 -274.975351)
			(xy 407.305251 -274.999704) (xy 408.59381 -274.999704) (xy 408.59777 -274.95065) (xy 408.609547 -274.902866)
			(xy 408.628838 -274.85759) (xy 408.655141 -274.815994) (xy 408.687776 -274.779157) (xy 408.725897 -274.748032)
			(xy 408.768518 -274.723425) (xy 408.814534 -274.705973) (xy 408.862753 -274.696129) (xy 408.911928 -274.694148)
			(xy 408.960783 -274.70008) (xy 409.008054 -274.713772) (xy 409.052516 -274.73487) (xy 409.093019 -274.762826)
			(xy 409.128512 -274.796918) (xy 409.158077 -274.836262) (xy 409.180948 -274.879839) (xy 409.196532 -274.92652)
			(xy 409.204427 -274.975097) (xy 409.204922 -274.999704) (xy 409.204917 -274.999958) (xy 410.49373 -274.999958)
			(xy 410.49769 -274.950904) (xy 410.509467 -274.90312) (xy 410.528758 -274.857844) (xy 410.555061 -274.816248)
			(xy 410.587696 -274.779411) (xy 410.625817 -274.748286) (xy 410.668438 -274.723679) (xy 410.714454 -274.706227)
			(xy 410.762673 -274.696383) (xy 410.811848 -274.694402) (xy 410.860703 -274.700334) (xy 410.907974 -274.714026)
			(xy 410.952436 -274.735124) (xy 410.992939 -274.76308) (xy 411.028432 -274.797172) (xy 411.057997 -274.836516)
			(xy 411.080868 -274.880093) (xy 411.096452 -274.926774) (xy 411.104347 -274.975351) (xy 411.104837 -274.999704)
			(xy 412.393904 -274.999704) (xy 412.397864 -274.95065) (xy 412.409641 -274.902866) (xy 412.428932 -274.85759)
			(xy 412.455235 -274.815994) (xy 412.48787 -274.779157) (xy 412.525991 -274.748032) (xy 412.568612 -274.723425)
			(xy 412.614628 -274.705973) (xy 412.662847 -274.696129) (xy 412.712022 -274.694148) (xy 412.760877 -274.70008)
			(xy 412.808148 -274.713772) (xy 412.85261 -274.73487) (xy 412.893113 -274.762826) (xy 412.928606 -274.796918)
			(xy 412.958171 -274.836262) (xy 412.981042 -274.879839) (xy 412.996626 -274.92652) (xy 413.004521 -274.975097)
			(xy 413.005016 -274.999704) (xy 413.005011 -274.999958) (xy 414.293824 -274.999958) (xy 414.297784 -274.950904)
			(xy 414.309561 -274.90312) (xy 414.328852 -274.857844) (xy 414.355155 -274.816248) (xy 414.38779 -274.779411)
			(xy 414.425911 -274.748286) (xy 414.468532 -274.723679) (xy 414.514548 -274.706227) (xy 414.562767 -274.696383)
			(xy 414.611942 -274.694402) (xy 414.660797 -274.700334) (xy 414.708068 -274.714026) (xy 414.75253 -274.735124)
			(xy 414.793033 -274.76308) (xy 414.828526 -274.797172) (xy 414.858091 -274.836516) (xy 414.880962 -274.880093)
			(xy 414.896546 -274.926774) (xy 414.904441 -274.975351) (xy 414.904931 -274.999704) (xy 416.193744 -274.999704)
			(xy 416.197704 -274.95065) (xy 416.209481 -274.902866) (xy 416.228772 -274.85759) (xy 416.255075 -274.815994)
			(xy 416.28771 -274.779157) (xy 416.325831 -274.748032) (xy 416.368452 -274.723425) (xy 416.414468 -274.705973)
			(xy 416.462687 -274.696129) (xy 416.511862 -274.694148) (xy 416.560717 -274.70008) (xy 416.607988 -274.713772)
			(xy 416.65245 -274.73487) (xy 416.692953 -274.762826) (xy 416.728446 -274.796918) (xy 416.758011 -274.836262)
			(xy 416.780882 -274.879839) (xy 416.796466 -274.92652) (xy 416.804361 -274.975097) (xy 416.804856 -274.999704)
			(xy 416.804851 -274.999958) (xy 418.093664 -274.999958) (xy 418.097624 -274.950904) (xy 418.109401 -274.90312)
			(xy 418.128692 -274.857844) (xy 418.154995 -274.816248) (xy 418.18763 -274.779411) (xy 418.225751 -274.748286)
			(xy 418.268372 -274.723679) (xy 418.314388 -274.706227) (xy 418.362607 -274.696383) (xy 418.411782 -274.694402)
			(xy 418.460637 -274.700334) (xy 418.507908 -274.714026) (xy 418.55237 -274.735124) (xy 418.592873 -274.76308)
			(xy 418.628366 -274.797172) (xy 418.657931 -274.836516) (xy 418.680802 -274.880093) (xy 418.696386 -274.926774)
			(xy 418.704281 -274.975351) (xy 418.704771 -274.999704) (xy 419.993838 -274.999704) (xy 419.997798 -274.95065)
			(xy 420.009575 -274.902866) (xy 420.028866 -274.85759) (xy 420.055169 -274.815994) (xy 420.087804 -274.779157)
			(xy 420.125925 -274.748032) (xy 420.168546 -274.723425) (xy 420.214562 -274.705973) (xy 420.262781 -274.696129)
			(xy 420.311956 -274.694148) (xy 420.360811 -274.70008) (xy 420.408082 -274.713772) (xy 420.452544 -274.73487)
			(xy 420.493047 -274.762826) (xy 420.52854 -274.796918) (xy 420.558105 -274.836262) (xy 420.580976 -274.879839)
			(xy 420.59656 -274.92652) (xy 420.604455 -274.975097) (xy 420.60495 -274.999704) (xy 420.604945 -274.999958)
			(xy 421.893758 -274.999958) (xy 421.897718 -274.950904) (xy 421.909495 -274.90312) (xy 421.928786 -274.857844)
			(xy 421.955089 -274.816248) (xy 421.987724 -274.779411) (xy 422.025845 -274.748286) (xy 422.068466 -274.723679)
			(xy 422.114482 -274.706227) (xy 422.162701 -274.696383) (xy 422.211876 -274.694402) (xy 422.260731 -274.700334)
			(xy 422.308002 -274.714026) (xy 422.352464 -274.735124) (xy 422.392967 -274.76308) (xy 422.42846 -274.797172)
			(xy 422.458025 -274.836516) (xy 422.480896 -274.880093) (xy 422.49648 -274.926774) (xy 422.504375 -274.975351)
			(xy 422.504865 -274.999704) (xy 423.793932 -274.999704) (xy 423.797892 -274.95065) (xy 423.809669 -274.902866)
			(xy 423.82896 -274.85759) (xy 423.855263 -274.815994) (xy 423.887898 -274.779157) (xy 423.926019 -274.748032)
			(xy 423.96864 -274.723425) (xy 424.014656 -274.705973) (xy 424.062875 -274.696129) (xy 424.11205 -274.694148)
			(xy 424.160905 -274.70008) (xy 424.208176 -274.713772) (xy 424.252638 -274.73487) (xy 424.293141 -274.762826)
			(xy 424.328634 -274.796918) (xy 424.358199 -274.836262) (xy 424.38107 -274.879839) (xy 424.396654 -274.92652)
			(xy 424.404549 -274.975097) (xy 424.405044 -274.999704) (xy 424.405039 -274.999958) (xy 425.693852 -274.999958)
			(xy 425.697812 -274.950904) (xy 425.709589 -274.90312) (xy 425.72888 -274.857844) (xy 425.755183 -274.816248)
			(xy 425.787818 -274.779411) (xy 425.825939 -274.748286) (xy 425.86856 -274.723679) (xy 425.914576 -274.706227)
			(xy 425.962795 -274.696383) (xy 426.01197 -274.694402) (xy 426.060825 -274.700334) (xy 426.108096 -274.714026)
			(xy 426.152558 -274.735124) (xy 426.193061 -274.76308) (xy 426.228554 -274.797172) (xy 426.258119 -274.836516)
			(xy 426.28099 -274.880093) (xy 426.296574 -274.926774) (xy 426.304469 -274.975351) (xy 426.304964 -274.999958)
			(xy 427.593772 -274.999958) (xy 427.597732 -274.950904) (xy 427.609509 -274.90312) (xy 427.6288 -274.857844)
			(xy 427.655103 -274.816248) (xy 427.687738 -274.779411) (xy 427.725859 -274.748286) (xy 427.76848 -274.723679)
			(xy 427.814496 -274.706227) (xy 427.862715 -274.696383) (xy 427.91189 -274.694402) (xy 427.960745 -274.700334)
			(xy 428.008016 -274.714026) (xy 428.052478 -274.735124) (xy 428.092981 -274.76308) (xy 428.128474 -274.797172)
			(xy 428.158039 -274.836516) (xy 428.18091 -274.880093) (xy 428.196494 -274.926774) (xy 428.204389 -274.975351)
			(xy 428.204879 -274.999704) (xy 429.4942 -274.999704) (xy 429.49816 -274.95065) (xy 429.509937 -274.902866)
			(xy 429.529228 -274.85759) (xy 429.555531 -274.815994) (xy 429.588166 -274.779157) (xy 429.626287 -274.748032)
			(xy 429.668908 -274.723425) (xy 429.714924 -274.705973) (xy 429.763143 -274.696129) (xy 429.812318 -274.694148)
			(xy 429.861173 -274.70008) (xy 429.908444 -274.713772) (xy 429.952906 -274.73487) (xy 429.993409 -274.762826)
			(xy 430.028902 -274.796918) (xy 430.058467 -274.836262) (xy 430.081338 -274.879839) (xy 430.096922 -274.92652)
			(xy 430.104817 -274.975097) (xy 430.105312 -274.999704) (xy 430.44416 -274.999704) (xy 430.44812 -274.95065)
			(xy 430.459897 -274.902866) (xy 430.479188 -274.85759) (xy 430.505491 -274.815994) (xy 430.538126 -274.779157)
			(xy 430.576247 -274.748032) (xy 430.618868 -274.723425) (xy 430.664884 -274.705973) (xy 430.713103 -274.696129)
			(xy 430.762278 -274.694148) (xy 430.811133 -274.70008) (xy 430.858404 -274.713772) (xy 430.902866 -274.73487)
			(xy 430.943369 -274.762826) (xy 430.978862 -274.796918) (xy 431.008427 -274.836262) (xy 431.031298 -274.879839)
			(xy 431.046882 -274.92652) (xy 431.054777 -274.975097) (xy 431.055272 -274.999704) (xy 431.054777 -275.024311)
			(xy 431.046882 -275.072888) (xy 431.031298 -275.119569) (xy 431.008427 -275.163146) (xy 430.978862 -275.20249)
			(xy 430.943369 -275.236582) (xy 430.902866 -275.264538) (xy 430.858404 -275.285636) (xy 430.811133 -275.299328)
			(xy 430.762278 -275.30526) (xy 430.713103 -275.303279) (xy 430.664884 -275.293435) (xy 430.618868 -275.275983)
			(xy 430.576247 -275.251376) (xy 430.538126 -275.220251) (xy 430.505491 -275.183414) (xy 430.479188 -275.141818)
			(xy 430.459897 -275.096542) (xy 430.44812 -275.048758) (xy 430.44416 -274.999704) (xy 430.105312 -274.999704)
			(xy 430.104817 -275.024311) (xy 430.096922 -275.072888) (xy 430.081338 -275.119569) (xy 430.058467 -275.163146)
			(xy 430.028902 -275.20249) (xy 429.993409 -275.236582) (xy 429.952906 -275.264538) (xy 429.908444 -275.285636)
			(xy 429.861173 -275.299328) (xy 429.812318 -275.30526) (xy 429.763143 -275.303279) (xy 429.714924 -275.293435)
			(xy 429.668908 -275.275983) (xy 429.626287 -275.251376) (xy 429.588166 -275.220251) (xy 429.555531 -275.183414)
			(xy 429.529228 -275.141818) (xy 429.509937 -275.096542) (xy 429.49816 -275.048758) (xy 429.4942 -274.999704)
			(xy 428.204879 -274.999704) (xy 428.204884 -274.999958) (xy 428.204389 -275.024565) (xy 428.196494 -275.073142)
			(xy 428.18091 -275.119823) (xy 428.158039 -275.1634) (xy 428.128474 -275.202744) (xy 428.092981 -275.236836)
			(xy 428.052478 -275.264792) (xy 428.008016 -275.28589) (xy 427.960745 -275.299582) (xy 427.91189 -275.305514)
			(xy 427.862715 -275.303533) (xy 427.814496 -275.293689) (xy 427.76848 -275.276237) (xy 427.725859 -275.25163)
			(xy 427.687738 -275.220505) (xy 427.655103 -275.183668) (xy 427.6288 -275.142072) (xy 427.609509 -275.096796)
			(xy 427.597732 -275.049012) (xy 427.593772 -274.999958) (xy 426.304964 -274.999958) (xy 426.304469 -275.024565)
			(xy 426.296574 -275.073142) (xy 426.28099 -275.119823) (xy 426.258119 -275.1634) (xy 426.228554 -275.202744)
			(xy 426.193061 -275.236836) (xy 426.152558 -275.264792) (xy 426.108096 -275.28589) (xy 426.060825 -275.299582)
			(xy 426.01197 -275.305514) (xy 425.962795 -275.303533) (xy 425.914576 -275.293689) (xy 425.86856 -275.276237)
			(xy 425.825939 -275.25163) (xy 425.787818 -275.220505) (xy 425.755183 -275.183668) (xy 425.72888 -275.142072)
			(xy 425.709589 -275.096796) (xy 425.697812 -275.049012) (xy 425.693852 -274.999958) (xy 424.405039 -274.999958)
			(xy 424.404549 -275.024311) (xy 424.396654 -275.072888) (xy 424.38107 -275.119569) (xy 424.358199 -275.163146)
			(xy 424.328634 -275.20249) (xy 424.293141 -275.236582) (xy 424.252638 -275.264538) (xy 424.208176 -275.285636)
			(xy 424.160905 -275.299328) (xy 424.11205 -275.30526) (xy 424.062875 -275.303279) (xy 424.014656 -275.293435)
			(xy 423.96864 -275.275983) (xy 423.926019 -275.251376) (xy 423.887898 -275.220251) (xy 423.855263 -275.183414)
			(xy 423.82896 -275.141818) (xy 423.809669 -275.096542) (xy 423.797892 -275.048758) (xy 423.793932 -274.999704)
			(xy 422.504865 -274.999704) (xy 422.50487 -274.999958) (xy 422.504375 -275.024565) (xy 422.49648 -275.073142)
			(xy 422.480896 -275.119823) (xy 422.458025 -275.1634) (xy 422.42846 -275.202744) (xy 422.392967 -275.236836)
			(xy 422.352464 -275.264792) (xy 422.308002 -275.28589) (xy 422.260731 -275.299582) (xy 422.211876 -275.305514)
			(xy 422.162701 -275.303533) (xy 422.114482 -275.293689) (xy 422.068466 -275.276237) (xy 422.025845 -275.25163)
			(xy 421.987724 -275.220505) (xy 421.955089 -275.183668) (xy 421.928786 -275.142072) (xy 421.909495 -275.096796)
			(xy 421.897718 -275.049012) (xy 421.893758 -274.999958) (xy 420.604945 -274.999958) (xy 420.604455 -275.024311)
			(xy 420.59656 -275.072888) (xy 420.580976 -275.119569) (xy 420.558105 -275.163146) (xy 420.52854 -275.20249)
			(xy 420.493047 -275.236582) (xy 420.452544 -275.264538) (xy 420.408082 -275.285636) (xy 420.360811 -275.299328)
			(xy 420.311956 -275.30526) (xy 420.262781 -275.303279) (xy 420.214562 -275.293435) (xy 420.168546 -275.275983)
			(xy 420.125925 -275.251376) (xy 420.087804 -275.220251) (xy 420.055169 -275.183414) (xy 420.028866 -275.141818)
			(xy 420.009575 -275.096542) (xy 419.997798 -275.048758) (xy 419.993838 -274.999704) (xy 418.704771 -274.999704)
			(xy 418.704776 -274.999958) (xy 418.704281 -275.024565) (xy 418.696386 -275.073142) (xy 418.680802 -275.119823)
			(xy 418.657931 -275.1634) (xy 418.628366 -275.202744) (xy 418.592873 -275.236836) (xy 418.55237 -275.264792)
			(xy 418.507908 -275.28589) (xy 418.460637 -275.299582) (xy 418.411782 -275.305514) (xy 418.362607 -275.303533)
			(xy 418.314388 -275.293689) (xy 418.268372 -275.276237) (xy 418.225751 -275.25163) (xy 418.18763 -275.220505)
			(xy 418.154995 -275.183668) (xy 418.128692 -275.142072) (xy 418.109401 -275.096796) (xy 418.097624 -275.049012)
			(xy 418.093664 -274.999958) (xy 416.804851 -274.999958) (xy 416.804361 -275.024311) (xy 416.796466 -275.072888)
			(xy 416.780882 -275.119569) (xy 416.758011 -275.163146) (xy 416.728446 -275.20249) (xy 416.692953 -275.236582)
			(xy 416.65245 -275.264538) (xy 416.607988 -275.285636) (xy 416.560717 -275.299328) (xy 416.511862 -275.30526)
			(xy 416.462687 -275.303279) (xy 416.414468 -275.293435) (xy 416.368452 -275.275983) (xy 416.325831 -275.251376)
			(xy 416.28771 -275.220251) (xy 416.255075 -275.183414) (xy 416.228772 -275.141818) (xy 416.209481 -275.096542)
			(xy 416.197704 -275.048758) (xy 416.193744 -274.999704) (xy 414.904931 -274.999704) (xy 414.904936 -274.999958)
			(xy 414.904441 -275.024565) (xy 414.896546 -275.073142) (xy 414.880962 -275.119823) (xy 414.858091 -275.1634)
			(xy 414.828526 -275.202744) (xy 414.793033 -275.236836) (xy 414.75253 -275.264792) (xy 414.708068 -275.28589)
			(xy 414.660797 -275.299582) (xy 414.611942 -275.305514) (xy 414.562767 -275.303533) (xy 414.514548 -275.293689)
			(xy 414.468532 -275.276237) (xy 414.425911 -275.25163) (xy 414.38779 -275.220505) (xy 414.355155 -275.183668)
			(xy 414.328852 -275.142072) (xy 414.309561 -275.096796) (xy 414.297784 -275.049012) (xy 414.293824 -274.999958)
			(xy 413.005011 -274.999958) (xy 413.004521 -275.024311) (xy 412.996626 -275.072888) (xy 412.981042 -275.119569)
			(xy 412.958171 -275.163146) (xy 412.928606 -275.20249) (xy 412.893113 -275.236582) (xy 412.85261 -275.264538)
			(xy 412.808148 -275.285636) (xy 412.760877 -275.299328) (xy 412.712022 -275.30526) (xy 412.662847 -275.303279)
			(xy 412.614628 -275.293435) (xy 412.568612 -275.275983) (xy 412.525991 -275.251376) (xy 412.48787 -275.220251)
			(xy 412.455235 -275.183414) (xy 412.428932 -275.141818) (xy 412.409641 -275.096542) (xy 412.397864 -275.048758)
			(xy 412.393904 -274.999704) (xy 411.104837 -274.999704) (xy 411.104842 -274.999958) (xy 411.104347 -275.024565)
			(xy 411.096452 -275.073142) (xy 411.080868 -275.119823) (xy 411.057997 -275.1634) (xy 411.028432 -275.202744)
			(xy 410.992939 -275.236836) (xy 410.952436 -275.264792) (xy 410.907974 -275.28589) (xy 410.860703 -275.299582)
			(xy 410.811848 -275.305514) (xy 410.762673 -275.303533) (xy 410.714454 -275.293689) (xy 410.668438 -275.276237)
			(xy 410.625817 -275.25163) (xy 410.587696 -275.220505) (xy 410.555061 -275.183668) (xy 410.528758 -275.142072)
			(xy 410.509467 -275.096796) (xy 410.49769 -275.049012) (xy 410.49373 -274.999958) (xy 409.204917 -274.999958)
			(xy 409.204427 -275.024311) (xy 409.196532 -275.072888) (xy 409.180948 -275.119569) (xy 409.158077 -275.163146)
			(xy 409.128512 -275.20249) (xy 409.093019 -275.236582) (xy 409.052516 -275.264538) (xy 409.008054 -275.285636)
			(xy 408.960783 -275.299328) (xy 408.911928 -275.30526) (xy 408.862753 -275.303279) (xy 408.814534 -275.293435)
			(xy 408.768518 -275.275983) (xy 408.725897 -275.251376) (xy 408.687776 -275.220251) (xy 408.655141 -275.183414)
			(xy 408.628838 -275.141818) (xy 408.609547 -275.096542) (xy 408.59777 -275.048758) (xy 408.59381 -274.999704)
			(xy 407.305251 -274.999704) (xy 407.305256 -274.999958) (xy 407.304761 -275.024565) (xy 407.296866 -275.073142)
			(xy 407.281282 -275.119823) (xy 407.258411 -275.1634) (xy 407.228846 -275.202744) (xy 407.193353 -275.236836)
			(xy 407.15285 -275.264792) (xy 407.108388 -275.28589) (xy 407.061117 -275.299582) (xy 407.012262 -275.305514)
			(xy 406.963087 -275.303533) (xy 406.914868 -275.293689) (xy 406.868852 -275.276237) (xy 406.826231 -275.25163)
			(xy 406.78811 -275.220505) (xy 406.755475 -275.183668) (xy 406.729172 -275.142072) (xy 406.709881 -275.096796)
			(xy 406.698104 -275.049012) (xy 406.694144 -274.999958) (xy 405.405336 -274.999958) (xy 405.404841 -275.024565)
			(xy 405.396946 -275.073142) (xy 405.381362 -275.119823) (xy 405.358491 -275.1634) (xy 405.328926 -275.202744)
			(xy 405.293433 -275.236836) (xy 405.25293 -275.264792) (xy 405.208468 -275.28589) (xy 405.161197 -275.299582)
			(xy 405.112342 -275.305514) (xy 405.063167 -275.303533) (xy 405.014948 -275.293689) (xy 404.968932 -275.276237)
			(xy 404.926311 -275.25163) (xy 404.88819 -275.220505) (xy 404.855555 -275.183668) (xy 404.829252 -275.142072)
			(xy 404.809961 -275.096796) (xy 404.798184 -275.049012) (xy 404.794224 -274.999958) (xy 403.505162 -274.999958)
			(xy 403.504667 -275.024565) (xy 403.496772 -275.073142) (xy 403.481188 -275.119823) (xy 403.458317 -275.1634)
			(xy 403.428752 -275.202744) (xy 403.393259 -275.236836) (xy 403.352756 -275.264792) (xy 403.308294 -275.28589)
			(xy 403.261023 -275.299582) (xy 403.212168 -275.305514) (xy 403.162993 -275.303533) (xy 403.114774 -275.293689)
			(xy 403.068758 -275.276237) (xy 403.026137 -275.25163) (xy 402.988016 -275.220505) (xy 402.955381 -275.183668)
			(xy 402.929078 -275.142072) (xy 402.909787 -275.096796) (xy 402.89801 -275.049012) (xy 402.89405 -274.999958)
			(xy 401.605242 -274.999958) (xy 401.604747 -275.024565) (xy 401.596852 -275.073142) (xy 401.581268 -275.119823)
			(xy 401.558397 -275.1634) (xy 401.528832 -275.202744) (xy 401.493339 -275.236836) (xy 401.452836 -275.264792)
			(xy 401.408374 -275.28589) (xy 401.361103 -275.299582) (xy 401.312248 -275.305514) (xy 401.263073 -275.303533)
			(xy 401.214854 -275.293689) (xy 401.168838 -275.276237) (xy 401.126217 -275.25163) (xy 401.088096 -275.220505)
			(xy 401.055461 -275.183668) (xy 401.029158 -275.142072) (xy 401.009867 -275.096796) (xy 400.99809 -275.049012)
			(xy 400.99413 -274.999958) (xy 399.705322 -274.999958) (xy 399.704827 -275.024565) (xy 399.696932 -275.073142)
			(xy 399.681348 -275.119823) (xy 399.658477 -275.1634) (xy 399.628912 -275.202744) (xy 399.593419 -275.236836)
			(xy 399.552916 -275.264792) (xy 399.508454 -275.28589) (xy 399.461183 -275.299582) (xy 399.412328 -275.305514)
			(xy 399.363153 -275.303533) (xy 399.314934 -275.293689) (xy 399.268918 -275.276237) (xy 399.226297 -275.25163)
			(xy 399.188176 -275.220505) (xy 399.155541 -275.183668) (xy 399.129238 -275.142072) (xy 399.109947 -275.096796)
			(xy 399.09817 -275.049012) (xy 399.09421 -274.999958) (xy 397.805148 -274.999958) (xy 397.804653 -275.024565)
			(xy 397.796758 -275.073142) (xy 397.781174 -275.119823) (xy 397.758303 -275.1634) (xy 397.728738 -275.202744)
			(xy 397.693245 -275.236836) (xy 397.652742 -275.264792) (xy 397.60828 -275.28589) (xy 397.561009 -275.299582)
			(xy 397.512154 -275.305514) (xy 397.462979 -275.303533) (xy 397.41476 -275.293689) (xy 397.368744 -275.276237)
			(xy 397.326123 -275.25163) (xy 397.288002 -275.220505) (xy 397.255367 -275.183668) (xy 397.229064 -275.142072)
			(xy 397.209773 -275.096796) (xy 397.197996 -275.049012) (xy 397.194036 -274.999958) (xy 395.905228 -274.999958)
			(xy 395.904733 -275.024565) (xy 395.896838 -275.073142) (xy 395.881254 -275.119823) (xy 395.858383 -275.1634)
			(xy 395.828818 -275.202744) (xy 395.793325 -275.236836) (xy 395.752822 -275.264792) (xy 395.70836 -275.28589)
			(xy 395.661089 -275.299582) (xy 395.612234 -275.305514) (xy 395.563059 -275.303533) (xy 395.51484 -275.293689)
			(xy 395.468824 -275.276237) (xy 395.426203 -275.25163) (xy 395.388082 -275.220505) (xy 395.355447 -275.183668)
			(xy 395.329144 -275.142072) (xy 395.309853 -275.096796) (xy 395.298076 -275.049012) (xy 395.294116 -274.999958)
			(xy 394.005308 -274.999958) (xy 394.004813 -275.024565) (xy 393.996918 -275.073142) (xy 393.981334 -275.119823)
			(xy 393.958463 -275.1634) (xy 393.928898 -275.202744) (xy 393.893405 -275.236836) (xy 393.852902 -275.264792)
			(xy 393.80844 -275.28589) (xy 393.761169 -275.299582) (xy 393.712314 -275.305514) (xy 393.663139 -275.303533)
			(xy 393.61492 -275.293689) (xy 393.568904 -275.276237) (xy 393.526283 -275.25163) (xy 393.488162 -275.220505)
			(xy 393.455527 -275.183668) (xy 393.429224 -275.142072) (xy 393.409933 -275.096796) (xy 393.398156 -275.049012)
			(xy 393.394196 -274.999958) (xy 314.955169 -274.999958) (xy 314.954679 -275.024311) (xy 314.946784 -275.072888)
			(xy 314.9312 -275.119569) (xy 314.908329 -275.163146) (xy 314.878764 -275.20249) (xy 314.843271 -275.236582)
			(xy 314.802768 -275.264538) (xy 314.758306 -275.285636) (xy 314.711035 -275.299328) (xy 314.66218 -275.30526)
			(xy 314.613005 -275.303279) (xy 314.564786 -275.293435) (xy 314.51877 -275.275983) (xy 314.476149 -275.251376)
			(xy 314.438028 -275.220251) (xy 314.405393 -275.183414) (xy 314.37909 -275.141818) (xy 314.359799 -275.096542)
			(xy 314.348022 -275.048758) (xy 314.344062 -274.999704) (xy 314.005214 -274.999704) (xy 314.004719 -275.024311)
			(xy 313.996824 -275.072888) (xy 313.98124 -275.119569) (xy 313.958369 -275.163146) (xy 313.928804 -275.20249)
			(xy 313.893311 -275.236582) (xy 313.852808 -275.264538) (xy 313.808346 -275.285636) (xy 313.761075 -275.299328)
			(xy 313.71222 -275.30526) (xy 313.663045 -275.303279) (xy 313.614826 -275.293435) (xy 313.56881 -275.275983)
			(xy 313.526189 -275.251376) (xy 313.488068 -275.220251) (xy 313.455433 -275.183414) (xy 313.42913 -275.141818)
			(xy 313.409839 -275.096542) (xy 313.398062 -275.048758) (xy 313.394102 -274.999704) (xy 312.104781 -274.999704)
			(xy 312.104786 -274.999958) (xy 312.104291 -275.024565) (xy 312.096396 -275.073142) (xy 312.080812 -275.119823)
			(xy 312.057941 -275.1634) (xy 312.028376 -275.202744) (xy 311.992883 -275.236836) (xy 311.95238 -275.264792)
			(xy 311.907918 -275.28589) (xy 311.860647 -275.299582) (xy 311.811792 -275.305514) (xy 311.762617 -275.303533)
			(xy 311.714398 -275.293689) (xy 311.668382 -275.276237) (xy 311.625761 -275.25163) (xy 311.58764 -275.220505)
			(xy 311.555005 -275.183668) (xy 311.528702 -275.142072) (xy 311.509411 -275.096796) (xy 311.497634 -275.049012)
			(xy 311.493674 -274.999958) (xy 310.204866 -274.999958) (xy 310.204371 -275.024565) (xy 310.196476 -275.073142)
			(xy 310.180892 -275.119823) (xy 310.158021 -275.1634) (xy 310.128456 -275.202744) (xy 310.092963 -275.236836)
			(xy 310.05246 -275.264792) (xy 310.007998 -275.28589) (xy 309.960727 -275.299582) (xy 309.911872 -275.305514)
			(xy 309.862697 -275.303533) (xy 309.814478 -275.293689) (xy 309.768462 -275.276237) (xy 309.725841 -275.25163)
			(xy 309.68772 -275.220505) (xy 309.655085 -275.183668) (xy 309.628782 -275.142072) (xy 309.609491 -275.096796)
			(xy 309.597714 -275.049012) (xy 309.593754 -274.999958) (xy 308.304941 -274.999958) (xy 308.304451 -275.024311)
			(xy 308.296556 -275.072888) (xy 308.280972 -275.119569) (xy 308.258101 -275.163146) (xy 308.228536 -275.20249)
			(xy 308.193043 -275.236582) (xy 308.15254 -275.264538) (xy 308.108078 -275.285636) (xy 308.060807 -275.299328)
			(xy 308.011952 -275.30526) (xy 307.962777 -275.303279) (xy 307.914558 -275.293435) (xy 307.868542 -275.275983)
			(xy 307.825921 -275.251376) (xy 307.7878 -275.220251) (xy 307.755165 -275.183414) (xy 307.728862 -275.141818)
			(xy 307.709571 -275.096542) (xy 307.697794 -275.048758) (xy 307.693834 -274.999704) (xy 306.404767 -274.999704)
			(xy 306.404772 -274.999958) (xy 306.404277 -275.024565) (xy 306.396382 -275.073142) (xy 306.380798 -275.119823)
			(xy 306.357927 -275.1634) (xy 306.328362 -275.202744) (xy 306.292869 -275.236836) (xy 306.252366 -275.264792)
			(xy 306.207904 -275.28589) (xy 306.160633 -275.299582) (xy 306.111778 -275.305514) (xy 306.062603 -275.303533)
			(xy 306.014384 -275.293689) (xy 305.968368 -275.276237) (xy 305.925747 -275.25163) (xy 305.887626 -275.220505)
			(xy 305.854991 -275.183668) (xy 305.828688 -275.142072) (xy 305.809397 -275.096796) (xy 305.79762 -275.049012)
			(xy 305.79366 -274.999958) (xy 304.504847 -274.999958) (xy 304.504357 -275.024311) (xy 304.496462 -275.072888)
			(xy 304.480878 -275.119569) (xy 304.458007 -275.163146) (xy 304.428442 -275.20249) (xy 304.392949 -275.236582)
			(xy 304.352446 -275.264538) (xy 304.307984 -275.285636) (xy 304.260713 -275.299328) (xy 304.211858 -275.30526)
			(xy 304.162683 -275.303279) (xy 304.114464 -275.293435) (xy 304.068448 -275.275983) (xy 304.025827 -275.251376)
			(xy 303.987706 -275.220251) (xy 303.955071 -275.183414) (xy 303.928768 -275.141818) (xy 303.909477 -275.096542)
			(xy 303.8977 -275.048758) (xy 303.89374 -274.999704) (xy 302.604673 -274.999704) (xy 302.604678 -274.999958)
			(xy 302.604183 -275.024565) (xy 302.596288 -275.073142) (xy 302.580704 -275.119823) (xy 302.557833 -275.1634)
			(xy 302.528268 -275.202744) (xy 302.492775 -275.236836) (xy 302.452272 -275.264792) (xy 302.40781 -275.28589)
			(xy 302.360539 -275.299582) (xy 302.311684 -275.305514) (xy 302.262509 -275.303533) (xy 302.21429 -275.293689)
			(xy 302.168274 -275.276237) (xy 302.125653 -275.25163) (xy 302.087532 -275.220505) (xy 302.054897 -275.183668)
			(xy 302.028594 -275.142072) (xy 302.009303 -275.096796) (xy 301.997526 -275.049012) (xy 301.993566 -274.999958)
			(xy 300.704753 -274.999958) (xy 300.704263 -275.024311) (xy 300.696368 -275.072888) (xy 300.680784 -275.119569)
			(xy 300.657913 -275.163146) (xy 300.628348 -275.20249) (xy 300.592855 -275.236582) (xy 300.552352 -275.264538)
			(xy 300.50789 -275.285636) (xy 300.460619 -275.299328) (xy 300.411764 -275.30526) (xy 300.362589 -275.303279)
			(xy 300.31437 -275.293435) (xy 300.268354 -275.275983) (xy 300.225733 -275.251376) (xy 300.187612 -275.220251)
			(xy 300.154977 -275.183414) (xy 300.128674 -275.141818) (xy 300.109383 -275.096542) (xy 300.097606 -275.048758)
			(xy 300.093646 -274.999704) (xy 298.804833 -274.999704) (xy 298.804838 -274.999958) (xy 298.804343 -275.024565)
			(xy 298.796448 -275.073142) (xy 298.780864 -275.119823) (xy 298.757993 -275.1634) (xy 298.728428 -275.202744)
			(xy 298.692935 -275.236836) (xy 298.652432 -275.264792) (xy 298.60797 -275.28589) (xy 298.560699 -275.299582)
			(xy 298.511844 -275.305514) (xy 298.462669 -275.303533) (xy 298.41445 -275.293689) (xy 298.368434 -275.276237)
			(xy 298.325813 -275.25163) (xy 298.287692 -275.220505) (xy 298.255057 -275.183668) (xy 298.228754 -275.142072)
			(xy 298.209463 -275.096796) (xy 298.197686 -275.049012) (xy 298.193726 -274.999958) (xy 296.904913 -274.999958)
			(xy 296.904423 -275.024311) (xy 296.896528 -275.072888) (xy 296.880944 -275.119569) (xy 296.858073 -275.163146)
			(xy 296.828508 -275.20249) (xy 296.793015 -275.236582) (xy 296.752512 -275.264538) (xy 296.70805 -275.285636)
			(xy 296.660779 -275.299328) (xy 296.611924 -275.30526) (xy 296.562749 -275.303279) (xy 296.51453 -275.293435)
			(xy 296.468514 -275.275983) (xy 296.425893 -275.251376) (xy 296.387772 -275.220251) (xy 296.355137 -275.183414)
			(xy 296.328834 -275.141818) (xy 296.309543 -275.096542) (xy 296.297766 -275.048758) (xy 296.293806 -274.999704)
			(xy 295.004739 -274.999704) (xy 295.004744 -274.999958) (xy 295.004249 -275.024565) (xy 294.996354 -275.073142)
			(xy 294.98077 -275.119823) (xy 294.957899 -275.1634) (xy 294.928334 -275.202744) (xy 294.892841 -275.236836)
			(xy 294.852338 -275.264792) (xy 294.807876 -275.28589) (xy 294.760605 -275.299582) (xy 294.71175 -275.305514)
			(xy 294.662575 -275.303533) (xy 294.614356 -275.293689) (xy 294.56834 -275.276237) (xy 294.525719 -275.25163)
			(xy 294.487598 -275.220505) (xy 294.454963 -275.183668) (xy 294.42866 -275.142072) (xy 294.409369 -275.096796)
			(xy 294.397592 -275.049012) (xy 294.393632 -274.999958) (xy 293.104819 -274.999958) (xy 293.104329 -275.024311)
			(xy 293.096434 -275.072888) (xy 293.08085 -275.119569) (xy 293.057979 -275.163146) (xy 293.028414 -275.20249)
			(xy 292.992921 -275.236582) (xy 292.952418 -275.264538) (xy 292.907956 -275.285636) (xy 292.860685 -275.299328)
			(xy 292.81183 -275.30526) (xy 292.762655 -275.303279) (xy 292.714436 -275.293435) (xy 292.66842 -275.275983)
			(xy 292.625799 -275.251376) (xy 292.587678 -275.220251) (xy 292.555043 -275.183414) (xy 292.52874 -275.141818)
			(xy 292.509449 -275.096542) (xy 292.497672 -275.048758) (xy 292.493712 -274.999704) (xy 291.205153 -274.999704)
			(xy 291.205158 -274.999958) (xy 291.204663 -275.024565) (xy 291.196768 -275.073142) (xy 291.181184 -275.119823)
			(xy 291.158313 -275.1634) (xy 291.128748 -275.202744) (xy 291.093255 -275.236836) (xy 291.052752 -275.264792)
			(xy 291.00829 -275.28589) (xy 290.961019 -275.299582) (xy 290.912164 -275.305514) (xy 290.862989 -275.303533)
			(xy 290.81477 -275.293689) (xy 290.768754 -275.276237) (xy 290.726133 -275.25163) (xy 290.688012 -275.220505)
			(xy 290.655377 -275.183668) (xy 290.629074 -275.142072) (xy 290.609783 -275.096796) (xy 290.598006 -275.049012)
			(xy 290.594046 -274.999958) (xy 289.305238 -274.999958) (xy 289.304743 -275.024565) (xy 289.296848 -275.073142)
			(xy 289.281264 -275.119823) (xy 289.258393 -275.1634) (xy 289.228828 -275.202744) (xy 289.193335 -275.236836)
			(xy 289.152832 -275.264792) (xy 289.10837 -275.28589) (xy 289.061099 -275.299582) (xy 289.012244 -275.305514)
			(xy 288.963069 -275.303533) (xy 288.91485 -275.293689) (xy 288.868834 -275.276237) (xy 288.826213 -275.25163)
			(xy 288.788092 -275.220505) (xy 288.755457 -275.183668) (xy 288.729154 -275.142072) (xy 288.709863 -275.096796)
			(xy 288.698086 -275.049012) (xy 288.694126 -274.999958) (xy 287.405064 -274.999958) (xy 287.404569 -275.024565)
			(xy 287.396674 -275.073142) (xy 287.38109 -275.119823) (xy 287.358219 -275.1634) (xy 287.328654 -275.202744)
			(xy 287.293161 -275.236836) (xy 287.252658 -275.264792) (xy 287.208196 -275.28589) (xy 287.160925 -275.299582)
			(xy 287.11207 -275.305514) (xy 287.062895 -275.303533) (xy 287.014676 -275.293689) (xy 286.96866 -275.276237)
			(xy 286.926039 -275.25163) (xy 286.887918 -275.220505) (xy 286.855283 -275.183668) (xy 286.82898 -275.142072)
			(xy 286.809689 -275.096796) (xy 286.797912 -275.049012) (xy 286.793952 -274.999958) (xy 285.505144 -274.999958)
			(xy 285.504649 -275.024565) (xy 285.496754 -275.073142) (xy 285.48117 -275.119823) (xy 285.458299 -275.1634)
			(xy 285.428734 -275.202744) (xy 285.393241 -275.236836) (xy 285.352738 -275.264792) (xy 285.308276 -275.28589)
			(xy 285.261005 -275.299582) (xy 285.21215 -275.305514) (xy 285.162975 -275.303533) (xy 285.114756 -275.293689)
			(xy 285.06874 -275.276237) (xy 285.026119 -275.25163) (xy 284.987998 -275.220505) (xy 284.955363 -275.183668)
			(xy 284.92906 -275.142072) (xy 284.909769 -275.096796) (xy 284.897992 -275.049012) (xy 284.894032 -274.999958)
			(xy 283.605224 -274.999958) (xy 283.604729 -275.024565) (xy 283.596834 -275.073142) (xy 283.58125 -275.119823)
			(xy 283.558379 -275.1634) (xy 283.528814 -275.202744) (xy 283.493321 -275.236836) (xy 283.452818 -275.264792)
			(xy 283.408356 -275.28589) (xy 283.361085 -275.299582) (xy 283.31223 -275.305514) (xy 283.263055 -275.303533)
			(xy 283.214836 -275.293689) (xy 283.16882 -275.276237) (xy 283.126199 -275.25163) (xy 283.088078 -275.220505)
			(xy 283.055443 -275.183668) (xy 283.02914 -275.142072) (xy 283.009849 -275.096796) (xy 282.998072 -275.049012)
			(xy 282.994112 -274.999958) (xy 281.70505 -274.999958) (xy 281.704555 -275.024565) (xy 281.69666 -275.073142)
			(xy 281.681076 -275.119823) (xy 281.658205 -275.1634) (xy 281.62864 -275.202744) (xy 281.593147 -275.236836)
			(xy 281.552644 -275.264792) (xy 281.508182 -275.28589) (xy 281.460911 -275.299582) (xy 281.412056 -275.305514)
			(xy 281.362881 -275.303533) (xy 281.314662 -275.293689) (xy 281.268646 -275.276237) (xy 281.226025 -275.25163)
			(xy 281.187904 -275.220505) (xy 281.155269 -275.183668) (xy 281.128966 -275.142072) (xy 281.109675 -275.096796)
			(xy 281.097898 -275.049012) (xy 281.093938 -274.999958) (xy 279.80513 -274.999958) (xy 279.804635 -275.024565)
			(xy 279.79674 -275.073142) (xy 279.781156 -275.119823) (xy 279.758285 -275.1634) (xy 279.72872 -275.202744)
			(xy 279.693227 -275.236836) (xy 279.652724 -275.264792) (xy 279.608262 -275.28589) (xy 279.560991 -275.299582)
			(xy 279.512136 -275.305514) (xy 279.462961 -275.303533) (xy 279.414742 -275.293689) (xy 279.368726 -275.276237)
			(xy 279.326105 -275.25163) (xy 279.287984 -275.220505) (xy 279.255349 -275.183668) (xy 279.229046 -275.142072)
			(xy 279.209755 -275.096796) (xy 279.197978 -275.049012) (xy 279.194018 -274.999958) (xy 277.90521 -274.999958)
			(xy 277.904715 -275.024565) (xy 277.89682 -275.073142) (xy 277.881236 -275.119823) (xy 277.858365 -275.1634)
			(xy 277.8288 -275.202744) (xy 277.793307 -275.236836) (xy 277.752804 -275.264792) (xy 277.708342 -275.28589)
			(xy 277.661071 -275.299582) (xy 277.612216 -275.305514) (xy 277.563041 -275.303533) (xy 277.514822 -275.293689)
			(xy 277.468806 -275.276237) (xy 277.426185 -275.25163) (xy 277.388064 -275.220505) (xy 277.355429 -275.183668)
			(xy 277.329126 -275.142072) (xy 277.309835 -275.096796) (xy 277.298058 -275.049012) (xy 277.294098 -274.999958)
			(xy 198.855325 -274.999958) (xy 198.854835 -275.024311) (xy 198.84694 -275.072888) (xy 198.831356 -275.119569)
			(xy 198.808485 -275.163146) (xy 198.77892 -275.20249) (xy 198.743427 -275.236582) (xy 198.702924 -275.264538)
			(xy 198.658462 -275.285636) (xy 198.611191 -275.299328) (xy 198.562336 -275.30526) (xy 198.513161 -275.303279)
			(xy 198.464942 -275.293435) (xy 198.418926 -275.275983) (xy 198.376305 -275.251376) (xy 198.338184 -275.220251)
			(xy 198.305549 -275.183414) (xy 198.279246 -275.141818) (xy 198.259955 -275.096542) (xy 198.248178 -275.048758)
			(xy 198.244218 -274.999704) (xy 197.90537 -274.999704) (xy 197.904875 -275.024311) (xy 197.89698 -275.072888)
			(xy 197.881396 -275.119569) (xy 197.858525 -275.163146) (xy 197.82896 -275.20249) (xy 197.793467 -275.236582)
			(xy 197.752964 -275.264538) (xy 197.708502 -275.285636) (xy 197.661231 -275.299328) (xy 197.612376 -275.30526)
			(xy 197.563201 -275.303279) (xy 197.514982 -275.293435) (xy 197.468966 -275.275983) (xy 197.426345 -275.251376)
			(xy 197.388224 -275.220251) (xy 197.355589 -275.183414) (xy 197.329286 -275.141818) (xy 197.309995 -275.096542)
			(xy 197.298218 -275.048758) (xy 197.294258 -274.999704) (xy 196.004937 -274.999704) (xy 196.004942 -274.999958)
			(xy 196.004447 -275.024565) (xy 195.996552 -275.073142) (xy 195.980968 -275.119823) (xy 195.958097 -275.1634)
			(xy 195.928532 -275.202744) (xy 195.893039 -275.236836) (xy 195.852536 -275.264792) (xy 195.808074 -275.28589)
			(xy 195.760803 -275.299582) (xy 195.711948 -275.305514) (xy 195.662773 -275.303533) (xy 195.614554 -275.293689)
			(xy 195.568538 -275.276237) (xy 195.525917 -275.25163) (xy 195.487796 -275.220505) (xy 195.455161 -275.183668)
			(xy 195.428858 -275.142072) (xy 195.409567 -275.096796) (xy 195.39779 -275.049012) (xy 195.39383 -274.999958)
			(xy 194.105022 -274.999958) (xy 194.104527 -275.024565) (xy 194.096632 -275.073142) (xy 194.081048 -275.119823)
			(xy 194.058177 -275.1634) (xy 194.028612 -275.202744) (xy 193.993119 -275.236836) (xy 193.952616 -275.264792)
			(xy 193.908154 -275.28589) (xy 193.860883 -275.299582) (xy 193.812028 -275.305514) (xy 193.762853 -275.303533)
			(xy 193.714634 -275.293689) (xy 193.668618 -275.276237) (xy 193.625997 -275.25163) (xy 193.587876 -275.220505)
			(xy 193.555241 -275.183668) (xy 193.528938 -275.142072) (xy 193.509647 -275.096796) (xy 193.49787 -275.049012)
			(xy 193.49391 -274.999958) (xy 192.205097 -274.999958) (xy 192.204607 -275.024311) (xy 192.196712 -275.072888)
			(xy 192.181128 -275.119569) (xy 192.158257 -275.163146) (xy 192.128692 -275.20249) (xy 192.093199 -275.236582)
			(xy 192.052696 -275.264538) (xy 192.008234 -275.285636) (xy 191.960963 -275.299328) (xy 191.912108 -275.30526)
			(xy 191.862933 -275.303279) (xy 191.814714 -275.293435) (xy 191.768698 -275.275983) (xy 191.726077 -275.251376)
			(xy 191.687956 -275.220251) (xy 191.655321 -275.183414) (xy 191.629018 -275.141818) (xy 191.609727 -275.096542)
			(xy 191.59795 -275.048758) (xy 191.59399 -274.999704) (xy 190.304923 -274.999704) (xy 190.304928 -274.999958)
			(xy 190.304433 -275.024565) (xy 190.296538 -275.073142) (xy 190.280954 -275.119823) (xy 190.258083 -275.1634)
			(xy 190.228518 -275.202744) (xy 190.193025 -275.236836) (xy 190.152522 -275.264792) (xy 190.10806 -275.28589)
			(xy 190.060789 -275.299582) (xy 190.011934 -275.305514) (xy 189.962759 -275.303533) (xy 189.91454 -275.293689)
			(xy 189.868524 -275.276237) (xy 189.825903 -275.25163) (xy 189.787782 -275.220505) (xy 189.755147 -275.183668)
			(xy 189.728844 -275.142072) (xy 189.709553 -275.096796) (xy 189.697776 -275.049012) (xy 189.693816 -274.999958)
			(xy 188.405003 -274.999958) (xy 188.404513 -275.024311) (xy 188.396618 -275.072888) (xy 188.381034 -275.119569)
			(xy 188.358163 -275.163146) (xy 188.328598 -275.20249) (xy 188.293105 -275.236582) (xy 188.252602 -275.264538)
			(xy 188.20814 -275.285636) (xy 188.160869 -275.299328) (xy 188.112014 -275.30526) (xy 188.062839 -275.303279)
			(xy 188.01462 -275.293435) (xy 187.968604 -275.275983) (xy 187.925983 -275.251376) (xy 187.887862 -275.220251)
			(xy 187.855227 -275.183414) (xy 187.828924 -275.141818) (xy 187.809633 -275.096542) (xy 187.797856 -275.048758)
			(xy 187.793896 -274.999704) (xy 186.504829 -274.999704) (xy 186.504834 -274.999958) (xy 186.504339 -275.024565)
			(xy 186.496444 -275.073142) (xy 186.48086 -275.119823) (xy 186.457989 -275.1634) (xy 186.428424 -275.202744)
			(xy 186.392931 -275.236836) (xy 186.352428 -275.264792) (xy 186.307966 -275.28589) (xy 186.260695 -275.299582)
			(xy 186.21184 -275.305514) (xy 186.162665 -275.303533) (xy 186.114446 -275.293689) (xy 186.06843 -275.276237)
			(xy 186.025809 -275.25163) (xy 185.987688 -275.220505) (xy 185.955053 -275.183668) (xy 185.92875 -275.142072)
			(xy 185.909459 -275.096796) (xy 185.897682 -275.049012) (xy 185.893722 -274.999958) (xy 184.604909 -274.999958)
			(xy 184.604419 -275.024311) (xy 184.596524 -275.072888) (xy 184.58094 -275.119569) (xy 184.558069 -275.163146)
			(xy 184.528504 -275.20249) (xy 184.493011 -275.236582) (xy 184.452508 -275.264538) (xy 184.408046 -275.285636)
			(xy 184.360775 -275.299328) (xy 184.31192 -275.30526) (xy 184.262745 -275.303279) (xy 184.214526 -275.293435)
			(xy 184.16851 -275.275983) (xy 184.125889 -275.251376) (xy 184.087768 -275.220251) (xy 184.055133 -275.183414)
			(xy 184.02883 -275.141818) (xy 184.009539 -275.096542) (xy 183.997762 -275.048758) (xy 183.993802 -274.999704)
			(xy 182.704989 -274.999704) (xy 182.704994 -274.999958) (xy 182.704499 -275.024565) (xy 182.696604 -275.073142)
			(xy 182.68102 -275.119823) (xy 182.658149 -275.1634) (xy 182.628584 -275.202744) (xy 182.593091 -275.236836)
			(xy 182.552588 -275.264792) (xy 182.508126 -275.28589) (xy 182.460855 -275.299582) (xy 182.412 -275.305514)
			(xy 182.362825 -275.303533) (xy 182.314606 -275.293689) (xy 182.26859 -275.276237) (xy 182.225969 -275.25163)
			(xy 182.187848 -275.220505) (xy 182.155213 -275.183668) (xy 182.12891 -275.142072) (xy 182.109619 -275.096796)
			(xy 182.097842 -275.049012) (xy 182.093882 -274.999958) (xy 180.805069 -274.999958) (xy 180.804579 -275.024311)
			(xy 180.796684 -275.072888) (xy 180.7811 -275.119569) (xy 180.758229 -275.163146) (xy 180.728664 -275.20249)
			(xy 180.693171 -275.236582) (xy 180.652668 -275.264538) (xy 180.608206 -275.285636) (xy 180.560935 -275.299328)
			(xy 180.51208 -275.30526) (xy 180.462905 -275.303279) (xy 180.414686 -275.293435) (xy 180.36867 -275.275983)
			(xy 180.326049 -275.251376) (xy 180.287928 -275.220251) (xy 180.255293 -275.183414) (xy 180.22899 -275.141818)
			(xy 180.209699 -275.096542) (xy 180.197922 -275.048758) (xy 180.193962 -274.999704) (xy 178.904895 -274.999704)
			(xy 178.9049 -274.999958) (xy 178.904405 -275.024565) (xy 178.89651 -275.073142) (xy 178.880926 -275.119823)
			(xy 178.858055 -275.1634) (xy 178.82849 -275.202744) (xy 178.792997 -275.236836) (xy 178.752494 -275.264792)
			(xy 178.708032 -275.28589) (xy 178.660761 -275.299582) (xy 178.611906 -275.305514) (xy 178.562731 -275.303533)
			(xy 178.514512 -275.293689) (xy 178.468496 -275.276237) (xy 178.425875 -275.25163) (xy 178.387754 -275.220505)
			(xy 178.355119 -275.183668) (xy 178.328816 -275.142072) (xy 178.309525 -275.096796) (xy 178.297748 -275.049012)
			(xy 178.293788 -274.999958) (xy 177.004975 -274.999958) (xy 177.004485 -275.024311) (xy 176.99659 -275.072888)
			(xy 176.981006 -275.119569) (xy 176.958135 -275.163146) (xy 176.92857 -275.20249) (xy 176.893077 -275.236582)
			(xy 176.852574 -275.264538) (xy 176.808112 -275.285636) (xy 176.760841 -275.299328) (xy 176.711986 -275.30526)
			(xy 176.662811 -275.303279) (xy 176.614592 -275.293435) (xy 176.568576 -275.275983) (xy 176.525955 -275.251376)
			(xy 176.487834 -275.220251) (xy 176.455199 -275.183414) (xy 176.428896 -275.141818) (xy 176.409605 -275.096542)
			(xy 176.397828 -275.048758) (xy 176.393868 -274.999704) (xy 175.105309 -274.999704) (xy 175.105314 -274.999958)
			(xy 175.104819 -275.024565) (xy 175.096924 -275.073142) (xy 175.08134 -275.119823) (xy 175.058469 -275.1634)
			(xy 175.028904 -275.202744) (xy 174.993411 -275.236836) (xy 174.952908 -275.264792) (xy 174.908446 -275.28589)
			(xy 174.861175 -275.299582) (xy 174.81232 -275.305514) (xy 174.763145 -275.303533) (xy 174.714926 -275.293689)
			(xy 174.66891 -275.276237) (xy 174.626289 -275.25163) (xy 174.588168 -275.220505) (xy 174.555533 -275.183668)
			(xy 174.52923 -275.142072) (xy 174.509939 -275.096796) (xy 174.498162 -275.049012) (xy 174.494202 -274.999958)
			(xy 173.205394 -274.999958) (xy 173.204899 -275.024565) (xy 173.197004 -275.073142) (xy 173.18142 -275.119823)
			(xy 173.158549 -275.1634) (xy 173.128984 -275.202744) (xy 173.093491 -275.236836) (xy 173.052988 -275.264792)
			(xy 173.008526 -275.28589) (xy 172.961255 -275.299582) (xy 172.9124 -275.305514) (xy 172.863225 -275.303533)
			(xy 172.815006 -275.293689) (xy 172.76899 -275.276237) (xy 172.726369 -275.25163) (xy 172.688248 -275.220505)
			(xy 172.655613 -275.183668) (xy 172.62931 -275.142072) (xy 172.610019 -275.096796) (xy 172.598242 -275.049012)
			(xy 172.594282 -274.999958) (xy 171.30522 -274.999958) (xy 171.304725 -275.024565) (xy 171.29683 -275.073142)
			(xy 171.281246 -275.119823) (xy 171.258375 -275.1634) (xy 171.22881 -275.202744) (xy 171.193317 -275.236836)
			(xy 171.152814 -275.264792) (xy 171.108352 -275.28589) (xy 171.061081 -275.299582) (xy 171.012226 -275.305514)
			(xy 170.963051 -275.303533) (xy 170.914832 -275.293689) (xy 170.868816 -275.276237) (xy 170.826195 -275.25163)
			(xy 170.788074 -275.220505) (xy 170.755439 -275.183668) (xy 170.729136 -275.142072) (xy 170.709845 -275.096796)
			(xy 170.698068 -275.049012) (xy 170.694108 -274.999958) (xy 169.4053 -274.999958) (xy 169.404805 -275.024565)
			(xy 169.39691 -275.073142) (xy 169.381326 -275.119823) (xy 169.358455 -275.1634) (xy 169.32889 -275.202744)
			(xy 169.293397 -275.236836) (xy 169.252894 -275.264792) (xy 169.208432 -275.28589) (xy 169.161161 -275.299582)
			(xy 169.112306 -275.305514) (xy 169.063131 -275.303533) (xy 169.014912 -275.293689) (xy 168.968896 -275.276237)
			(xy 168.926275 -275.25163) (xy 168.888154 -275.220505) (xy 168.855519 -275.183668) (xy 168.829216 -275.142072)
			(xy 168.809925 -275.096796) (xy 168.798148 -275.049012) (xy 168.794188 -274.999958) (xy 167.50538 -274.999958)
			(xy 167.504885 -275.024565) (xy 167.49699 -275.073142) (xy 167.481406 -275.119823) (xy 167.458535 -275.1634)
			(xy 167.42897 -275.202744) (xy 167.393477 -275.236836) (xy 167.352974 -275.264792) (xy 167.308512 -275.28589)
			(xy 167.261241 -275.299582) (xy 167.212386 -275.305514) (xy 167.163211 -275.303533) (xy 167.114992 -275.293689)
			(xy 167.068976 -275.276237) (xy 167.026355 -275.25163) (xy 166.988234 -275.220505) (xy 166.955599 -275.183668)
			(xy 166.929296 -275.142072) (xy 166.910005 -275.096796) (xy 166.898228 -275.049012) (xy 166.894268 -274.999958)
			(xy 165.605206 -274.999958) (xy 165.604711 -275.024565) (xy 165.596816 -275.073142) (xy 165.581232 -275.119823)
			(xy 165.558361 -275.1634) (xy 165.528796 -275.202744) (xy 165.493303 -275.236836) (xy 165.4528 -275.264792)
			(xy 165.408338 -275.28589) (xy 165.361067 -275.299582) (xy 165.312212 -275.305514) (xy 165.263037 -275.303533)
			(xy 165.214818 -275.293689) (xy 165.168802 -275.276237) (xy 165.126181 -275.25163) (xy 165.08806 -275.220505)
			(xy 165.055425 -275.183668) (xy 165.029122 -275.142072) (xy 165.009831 -275.096796) (xy 164.998054 -275.049012)
			(xy 164.994094 -274.999958) (xy 163.705286 -274.999958) (xy 163.704791 -275.024565) (xy 163.696896 -275.073142)
			(xy 163.681312 -275.119823) (xy 163.658441 -275.1634) (xy 163.628876 -275.202744) (xy 163.593383 -275.236836)
			(xy 163.55288 -275.264792) (xy 163.508418 -275.28589) (xy 163.461147 -275.299582) (xy 163.412292 -275.305514)
			(xy 163.363117 -275.303533) (xy 163.314898 -275.293689) (xy 163.268882 -275.276237) (xy 163.226261 -275.25163)
			(xy 163.18814 -275.220505) (xy 163.155505 -275.183668) (xy 163.129202 -275.142072) (xy 163.109911 -275.096796)
			(xy 163.098134 -275.049012) (xy 163.094174 -274.999958) (xy 161.805366 -274.999958) (xy 161.804871 -275.024565)
			(xy 161.796976 -275.073142) (xy 161.781392 -275.119823) (xy 161.758521 -275.1634) (xy 161.728956 -275.202744)
			(xy 161.693463 -275.236836) (xy 161.65296 -275.264792) (xy 161.608498 -275.28589) (xy 161.561227 -275.299582)
			(xy 161.512372 -275.305514) (xy 161.463197 -275.303533) (xy 161.414978 -275.293689) (xy 161.368962 -275.276237)
			(xy 161.326341 -275.25163) (xy 161.28822 -275.220505) (xy 161.255585 -275.183668) (xy 161.229282 -275.142072)
			(xy 161.209991 -275.096796) (xy 161.198214 -275.049012) (xy 161.194254 -274.999958) (xy 82.755227 -274.999958)
			(xy 82.754737 -275.024311) (xy 82.746842 -275.072888) (xy 82.731258 -275.119569) (xy 82.708387 -275.163146)
			(xy 82.678822 -275.20249) (xy 82.643329 -275.236582) (xy 82.602826 -275.264538) (xy 82.558364 -275.285636)
			(xy 82.511093 -275.299328) (xy 82.462238 -275.30526) (xy 82.413063 -275.303279) (xy 82.364844 -275.293435)
			(xy 82.318828 -275.275983) (xy 82.276207 -275.251376) (xy 82.238086 -275.220251) (xy 82.205451 -275.183414)
			(xy 82.179148 -275.141818) (xy 82.159857 -275.096542) (xy 82.14808 -275.048758) (xy 82.14412 -274.999704)
			(xy 81.805272 -274.999704) (xy 81.804777 -275.024311) (xy 81.796882 -275.072888) (xy 81.781298 -275.119569)
			(xy 81.758427 -275.163146) (xy 81.728862 -275.20249) (xy 81.693369 -275.236582) (xy 81.652866 -275.264538)
			(xy 81.608404 -275.285636) (xy 81.561133 -275.299328) (xy 81.512278 -275.30526) (xy 81.463103 -275.303279)
			(xy 81.414884 -275.293435) (xy 81.368868 -275.275983) (xy 81.326247 -275.251376) (xy 81.288126 -275.220251)
			(xy 81.255491 -275.183414) (xy 81.229188 -275.141818) (xy 81.209897 -275.096542) (xy 81.19812 -275.048758)
			(xy 81.19416 -274.999704) (xy 79.904839 -274.999704) (xy 79.904844 -274.999958) (xy 79.904349 -275.024565)
			(xy 79.896454 -275.073142) (xy 79.88087 -275.119823) (xy 79.857999 -275.1634) (xy 79.828434 -275.202744)
			(xy 79.792941 -275.236836) (xy 79.752438 -275.264792) (xy 79.707976 -275.28589) (xy 79.660705 -275.299582)
			(xy 79.61185 -275.305514) (xy 79.562675 -275.303533) (xy 79.514456 -275.293689) (xy 79.46844 -275.276237)
			(xy 79.425819 -275.25163) (xy 79.387698 -275.220505) (xy 79.355063 -275.183668) (xy 79.32876 -275.142072)
			(xy 79.309469 -275.096796) (xy 79.297692 -275.049012) (xy 79.293732 -274.999958) (xy 78.004924 -274.999958)
			(xy 78.004429 -275.024565) (xy 77.996534 -275.073142) (xy 77.98095 -275.119823) (xy 77.958079 -275.1634)
			(xy 77.928514 -275.202744) (xy 77.893021 -275.236836) (xy 77.852518 -275.264792) (xy 77.808056 -275.28589)
			(xy 77.760785 -275.299582) (xy 77.71193 -275.305514) (xy 77.662755 -275.303533) (xy 77.614536 -275.293689)
			(xy 77.56852 -275.276237) (xy 77.525899 -275.25163) (xy 77.487778 -275.220505) (xy 77.455143 -275.183668)
			(xy 77.42884 -275.142072) (xy 77.409549 -275.096796) (xy 77.397772 -275.049012) (xy 77.393812 -274.999958)
			(xy 76.104999 -274.999958) (xy 76.104509 -275.024311) (xy 76.096614 -275.072888) (xy 76.08103 -275.119569)
			(xy 76.058159 -275.163146) (xy 76.028594 -275.20249) (xy 75.993101 -275.236582) (xy 75.952598 -275.264538)
			(xy 75.908136 -275.285636) (xy 75.860865 -275.299328) (xy 75.81201 -275.30526) (xy 75.762835 -275.303279)
			(xy 75.714616 -275.293435) (xy 75.6686 -275.275983) (xy 75.625979 -275.251376) (xy 75.587858 -275.220251)
			(xy 75.555223 -275.183414) (xy 75.52892 -275.141818) (xy 75.509629 -275.096542) (xy 75.497852 -275.048758)
			(xy 75.493892 -274.999704) (xy 74.204825 -274.999704) (xy 74.20483 -274.999958) (xy 74.204335 -275.024565)
			(xy 74.19644 -275.073142) (xy 74.180856 -275.119823) (xy 74.157985 -275.1634) (xy 74.12842 -275.202744)
			(xy 74.092927 -275.236836) (xy 74.052424 -275.264792) (xy 74.007962 -275.28589) (xy 73.960691 -275.299582)
			(xy 73.911836 -275.305514) (xy 73.862661 -275.303533) (xy 73.814442 -275.293689) (xy 73.768426 -275.276237)
			(xy 73.725805 -275.25163) (xy 73.687684 -275.220505) (xy 73.655049 -275.183668) (xy 73.628746 -275.142072)
			(xy 73.609455 -275.096796) (xy 73.597678 -275.049012) (xy 73.593718 -274.999958) (xy 72.304905 -274.999958)
			(xy 72.304415 -275.024311) (xy 72.29652 -275.072888) (xy 72.280936 -275.119569) (xy 72.258065 -275.163146)
			(xy 72.2285 -275.20249) (xy 72.193007 -275.236582) (xy 72.152504 -275.264538) (xy 72.108042 -275.285636)
			(xy 72.060771 -275.299328) (xy 72.011916 -275.30526) (xy 71.962741 -275.303279) (xy 71.914522 -275.293435)
			(xy 71.868506 -275.275983) (xy 71.825885 -275.251376) (xy 71.787764 -275.220251) (xy 71.755129 -275.183414)
			(xy 71.728826 -275.141818) (xy 71.709535 -275.096542) (xy 71.697758 -275.048758) (xy 71.693798 -274.999704)
			(xy 70.404731 -274.999704) (xy 70.404736 -274.999958) (xy 70.404241 -275.024565) (xy 70.396346 -275.073142)
			(xy 70.380762 -275.119823) (xy 70.357891 -275.1634) (xy 70.328326 -275.202744) (xy 70.292833 -275.236836)
			(xy 70.25233 -275.264792) (xy 70.207868 -275.28589) (xy 70.160597 -275.299582) (xy 70.111742 -275.305514)
			(xy 70.062567 -275.303533) (xy 70.014348 -275.293689) (xy 69.968332 -275.276237) (xy 69.925711 -275.25163)
			(xy 69.88759 -275.220505) (xy 69.854955 -275.183668) (xy 69.828652 -275.142072) (xy 69.809361 -275.096796)
			(xy 69.797584 -275.049012) (xy 69.793624 -274.999958) (xy 68.504811 -274.999958) (xy 68.504321 -275.024311)
			(xy 68.496426 -275.072888) (xy 68.480842 -275.119569) (xy 68.457971 -275.163146) (xy 68.428406 -275.20249)
			(xy 68.392913 -275.236582) (xy 68.35241 -275.264538) (xy 68.307948 -275.285636) (xy 68.260677 -275.299328)
			(xy 68.211822 -275.30526) (xy 68.162647 -275.303279) (xy 68.114428 -275.293435) (xy 68.068412 -275.275983)
			(xy 68.025791 -275.251376) (xy 67.98767 -275.220251) (xy 67.955035 -275.183414) (xy 67.928732 -275.141818)
			(xy 67.909441 -275.096542) (xy 67.897664 -275.048758) (xy 67.893704 -274.999704) (xy 66.604891 -274.999704)
			(xy 66.604896 -274.999958) (xy 66.604401 -275.024565) (xy 66.596506 -275.073142) (xy 66.580922 -275.119823)
			(xy 66.558051 -275.1634) (xy 66.528486 -275.202744) (xy 66.492993 -275.236836) (xy 66.45249 -275.264792)
			(xy 66.408028 -275.28589) (xy 66.360757 -275.299582) (xy 66.311902 -275.305514) (xy 66.262727 -275.303533)
			(xy 66.214508 -275.293689) (xy 66.168492 -275.276237) (xy 66.125871 -275.25163) (xy 66.08775 -275.220505)
			(xy 66.055115 -275.183668) (xy 66.028812 -275.142072) (xy 66.009521 -275.096796) (xy 65.997744 -275.049012)
			(xy 65.993784 -274.999958) (xy 64.704971 -274.999958) (xy 64.704481 -275.024311) (xy 64.696586 -275.072888)
			(xy 64.681002 -275.119569) (xy 64.658131 -275.163146) (xy 64.628566 -275.20249) (xy 64.593073 -275.236582)
			(xy 64.55257 -275.264538) (xy 64.508108 -275.285636) (xy 64.460837 -275.299328) (xy 64.411982 -275.30526)
			(xy 64.362807 -275.303279) (xy 64.314588 -275.293435) (xy 64.268572 -275.275983) (xy 64.225951 -275.251376)
			(xy 64.18783 -275.220251) (xy 64.155195 -275.183414) (xy 64.128892 -275.141818) (xy 64.109601 -275.096542)
			(xy 64.097824 -275.048758) (xy 64.093864 -274.999704) (xy 62.804797 -274.999704) (xy 62.804802 -274.999958)
			(xy 62.804307 -275.024565) (xy 62.796412 -275.073142) (xy 62.780828 -275.119823) (xy 62.757957 -275.1634)
			(xy 62.728392 -275.202744) (xy 62.692899 -275.236836) (xy 62.652396 -275.264792) (xy 62.607934 -275.28589)
			(xy 62.560663 -275.299582) (xy 62.511808 -275.305514) (xy 62.462633 -275.303533) (xy 62.414414 -275.293689)
			(xy 62.368398 -275.276237) (xy 62.325777 -275.25163) (xy 62.287656 -275.220505) (xy 62.255021 -275.183668)
			(xy 62.228718 -275.142072) (xy 62.209427 -275.096796) (xy 62.19765 -275.049012) (xy 62.19369 -274.999958)
			(xy 60.904877 -274.999958) (xy 60.904387 -275.024311) (xy 60.896492 -275.072888) (xy 60.880908 -275.119569)
			(xy 60.858037 -275.163146) (xy 60.828472 -275.20249) (xy 60.792979 -275.236582) (xy 60.752476 -275.264538)
			(xy 60.708014 -275.285636) (xy 60.660743 -275.299328) (xy 60.611888 -275.30526) (xy 60.562713 -275.303279)
			(xy 60.514494 -275.293435) (xy 60.468478 -275.275983) (xy 60.425857 -275.251376) (xy 60.387736 -275.220251)
			(xy 60.355101 -275.183414) (xy 60.328798 -275.141818) (xy 60.309507 -275.096542) (xy 60.29773 -275.048758)
			(xy 60.29377 -274.999704) (xy 59.005211 -274.999704) (xy 59.005216 -274.999958) (xy 59.004721 -275.024565)
			(xy 58.996826 -275.073142) (xy 58.981242 -275.119823) (xy 58.958371 -275.1634) (xy 58.928806 -275.202744)
			(xy 58.893313 -275.236836) (xy 58.85281 -275.264792) (xy 58.808348 -275.28589) (xy 58.761077 -275.299582)
			(xy 58.712222 -275.305514) (xy 58.663047 -275.303533) (xy 58.614828 -275.293689) (xy 58.568812 -275.276237)
			(xy 58.526191 -275.25163) (xy 58.48807 -275.220505) (xy 58.455435 -275.183668) (xy 58.429132 -275.142072)
			(xy 58.409841 -275.096796) (xy 58.398064 -275.049012) (xy 58.394104 -274.999958) (xy 57.105296 -274.999958)
			(xy 57.104801 -275.024565) (xy 57.096906 -275.073142) (xy 57.081322 -275.119823) (xy 57.058451 -275.1634)
			(xy 57.028886 -275.202744) (xy 56.993393 -275.236836) (xy 56.95289 -275.264792) (xy 56.908428 -275.28589)
			(xy 56.861157 -275.299582) (xy 56.812302 -275.305514) (xy 56.763127 -275.303533) (xy 56.714908 -275.293689)
			(xy 56.668892 -275.276237) (xy 56.626271 -275.25163) (xy 56.58815 -275.220505) (xy 56.555515 -275.183668)
			(xy 56.529212 -275.142072) (xy 56.509921 -275.096796) (xy 56.498144 -275.049012) (xy 56.494184 -274.999958)
			(xy 55.205122 -274.999958) (xy 55.204627 -275.024565) (xy 55.196732 -275.073142) (xy 55.181148 -275.119823)
			(xy 55.158277 -275.1634) (xy 55.128712 -275.202744) (xy 55.093219 -275.236836) (xy 55.052716 -275.264792)
			(xy 55.008254 -275.28589) (xy 54.960983 -275.299582) (xy 54.912128 -275.305514) (xy 54.862953 -275.303533)
			(xy 54.814734 -275.293689) (xy 54.768718 -275.276237) (xy 54.726097 -275.25163) (xy 54.687976 -275.220505)
			(xy 54.655341 -275.183668) (xy 54.629038 -275.142072) (xy 54.609747 -275.096796) (xy 54.59797 -275.049012)
			(xy 54.59401 -274.999958) (xy 53.305202 -274.999958) (xy 53.304707 -275.024565) (xy 53.296812 -275.073142)
			(xy 53.281228 -275.119823) (xy 53.258357 -275.1634) (xy 53.228792 -275.202744) (xy 53.193299 -275.236836)
			(xy 53.152796 -275.264792) (xy 53.108334 -275.28589) (xy 53.061063 -275.299582) (xy 53.012208 -275.305514)
			(xy 52.963033 -275.303533) (xy 52.914814 -275.293689) (xy 52.868798 -275.276237) (xy 52.826177 -275.25163)
			(xy 52.788056 -275.220505) (xy 52.755421 -275.183668) (xy 52.729118 -275.142072) (xy 52.709827 -275.096796)
			(xy 52.69805 -275.049012) (xy 52.69409 -274.999958) (xy 51.405282 -274.999958) (xy 51.404787 -275.024565)
			(xy 51.396892 -275.073142) (xy 51.381308 -275.119823) (xy 51.358437 -275.1634) (xy 51.328872 -275.202744)
			(xy 51.293379 -275.236836) (xy 51.252876 -275.264792) (xy 51.208414 -275.28589) (xy 51.161143 -275.299582)
			(xy 51.112288 -275.305514) (xy 51.063113 -275.303533) (xy 51.014894 -275.293689) (xy 50.968878 -275.276237)
			(xy 50.926257 -275.25163) (xy 50.888136 -275.220505) (xy 50.855501 -275.183668) (xy 50.829198 -275.142072)
			(xy 50.809907 -275.096796) (xy 50.79813 -275.049012) (xy 50.79417 -274.999958) (xy 49.505108 -274.999958)
			(xy 49.504613 -275.024565) (xy 49.496718 -275.073142) (xy 49.481134 -275.119823) (xy 49.458263 -275.1634)
			(xy 49.428698 -275.202744) (xy 49.393205 -275.236836) (xy 49.352702 -275.264792) (xy 49.30824 -275.28589)
			(xy 49.260969 -275.299582) (xy 49.212114 -275.305514) (xy 49.162939 -275.303533) (xy 49.11472 -275.293689)
			(xy 49.068704 -275.276237) (xy 49.026083 -275.25163) (xy 48.987962 -275.220505) (xy 48.955327 -275.183668)
			(xy 48.929024 -275.142072) (xy 48.909733 -275.096796) (xy 48.897956 -275.049012) (xy 48.893996 -274.999958)
			(xy 47.605188 -274.999958) (xy 47.604693 -275.024565) (xy 47.596798 -275.073142) (xy 47.581214 -275.119823)
			(xy 47.558343 -275.1634) (xy 47.528778 -275.202744) (xy 47.493285 -275.236836) (xy 47.452782 -275.264792)
			(xy 47.40832 -275.28589) (xy 47.361049 -275.299582) (xy 47.312194 -275.305514) (xy 47.263019 -275.303533)
			(xy 47.2148 -275.293689) (xy 47.168784 -275.276237) (xy 47.126163 -275.25163) (xy 47.088042 -275.220505)
			(xy 47.055407 -275.183668) (xy 47.029104 -275.142072) (xy 47.009813 -275.096796) (xy 46.998036 -275.049012)
			(xy 46.994076 -274.999958) (xy 45.705268 -274.999958) (xy 45.704773 -275.024565) (xy 45.696878 -275.073142)
			(xy 45.681294 -275.119823) (xy 45.658423 -275.1634) (xy 45.628858 -275.202744) (xy 45.593365 -275.236836)
			(xy 45.552862 -275.264792) (xy 45.5084 -275.28589) (xy 45.461129 -275.299582) (xy 45.412274 -275.305514)
			(xy 45.363099 -275.303533) (xy 45.31488 -275.293689) (xy 45.268864 -275.276237) (xy 45.226243 -275.25163)
			(xy 45.188122 -275.220505) (xy 45.155487 -275.183668) (xy 45.129184 -275.142072) (xy 45.109893 -275.096796)
			(xy 45.098116 -275.049012) (xy 45.094156 -274.999958) (xy 0.509016 -274.999958) (xy 0.509016 -275.949918)
			(xy 45.094156 -275.949918) (xy 45.098116 -275.900864) (xy 45.109893 -275.85308) (xy 45.129184 -275.807804)
			(xy 45.155487 -275.766208) (xy 45.188122 -275.729371) (xy 45.226243 -275.698246) (xy 45.268864 -275.673639)
			(xy 45.31488 -275.656187) (xy 45.363099 -275.646343) (xy 45.412274 -275.644362) (xy 45.461129 -275.650294)
			(xy 45.5084 -275.663986) (xy 45.552862 -275.685084) (xy 45.593365 -275.71304) (xy 45.628858 -275.747132)
			(xy 45.658423 -275.786476) (xy 45.681294 -275.830053) (xy 45.696878 -275.876734) (xy 45.704773 -275.925311)
			(xy 45.705268 -275.949918) (xy 46.994076 -275.949918) (xy 46.998036 -275.900864) (xy 47.009813 -275.85308)
			(xy 47.029104 -275.807804) (xy 47.055407 -275.766208) (xy 47.088042 -275.729371) (xy 47.126163 -275.698246)
			(xy 47.168784 -275.673639) (xy 47.2148 -275.656187) (xy 47.263019 -275.646343) (xy 47.312194 -275.644362)
			(xy 47.361049 -275.650294) (xy 47.40832 -275.663986) (xy 47.452782 -275.685084) (xy 47.493285 -275.71304)
			(xy 47.528778 -275.747132) (xy 47.558343 -275.786476) (xy 47.581214 -275.830053) (xy 47.596798 -275.876734)
			(xy 47.604693 -275.925311) (xy 47.605188 -275.949918) (xy 48.893996 -275.949918) (xy 48.897956 -275.900864)
			(xy 48.909733 -275.85308) (xy 48.929024 -275.807804) (xy 48.955327 -275.766208) (xy 48.987962 -275.729371)
			(xy 49.026083 -275.698246) (xy 49.068704 -275.673639) (xy 49.11472 -275.656187) (xy 49.162939 -275.646343)
			(xy 49.212114 -275.644362) (xy 49.260969 -275.650294) (xy 49.30824 -275.663986) (xy 49.352702 -275.685084)
			(xy 49.393205 -275.71304) (xy 49.428698 -275.747132) (xy 49.458263 -275.786476) (xy 49.481134 -275.830053)
			(xy 49.496718 -275.876734) (xy 49.504613 -275.925311) (xy 49.505108 -275.949918) (xy 50.79417 -275.949918)
			(xy 50.79813 -275.900864) (xy 50.809907 -275.85308) (xy 50.829198 -275.807804) (xy 50.855501 -275.766208)
			(xy 50.888136 -275.729371) (xy 50.926257 -275.698246) (xy 50.968878 -275.673639) (xy 51.014894 -275.656187)
			(xy 51.063113 -275.646343) (xy 51.112288 -275.644362) (xy 51.161143 -275.650294) (xy 51.208414 -275.663986)
			(xy 51.252876 -275.685084) (xy 51.293379 -275.71304) (xy 51.328872 -275.747132) (xy 51.358437 -275.786476)
			(xy 51.381308 -275.830053) (xy 51.396892 -275.876734) (xy 51.404787 -275.925311) (xy 51.405282 -275.949918)
			(xy 52.69409 -275.949918) (xy 52.69805 -275.900864) (xy 52.709827 -275.85308) (xy 52.729118 -275.807804)
			(xy 52.755421 -275.766208) (xy 52.788056 -275.729371) (xy 52.826177 -275.698246) (xy 52.868798 -275.673639)
			(xy 52.914814 -275.656187) (xy 52.963033 -275.646343) (xy 53.012208 -275.644362) (xy 53.061063 -275.650294)
			(xy 53.108334 -275.663986) (xy 53.152796 -275.685084) (xy 53.193299 -275.71304) (xy 53.228792 -275.747132)
			(xy 53.258357 -275.786476) (xy 53.281228 -275.830053) (xy 53.296812 -275.876734) (xy 53.304707 -275.925311)
			(xy 53.305202 -275.949918) (xy 54.59401 -275.949918) (xy 54.59797 -275.900864) (xy 54.609747 -275.85308)
			(xy 54.629038 -275.807804) (xy 54.655341 -275.766208) (xy 54.687976 -275.729371) (xy 54.726097 -275.698246)
			(xy 54.768718 -275.673639) (xy 54.814734 -275.656187) (xy 54.862953 -275.646343) (xy 54.912128 -275.644362)
			(xy 54.960983 -275.650294) (xy 55.008254 -275.663986) (xy 55.052716 -275.685084) (xy 55.093219 -275.71304)
			(xy 55.128712 -275.747132) (xy 55.158277 -275.786476) (xy 55.181148 -275.830053) (xy 55.196732 -275.876734)
			(xy 55.204627 -275.925311) (xy 55.205122 -275.949918) (xy 56.494184 -275.949918) (xy 56.498144 -275.900864)
			(xy 56.509921 -275.85308) (xy 56.529212 -275.807804) (xy 56.555515 -275.766208) (xy 56.58815 -275.729371)
			(xy 56.626271 -275.698246) (xy 56.668892 -275.673639) (xy 56.714908 -275.656187) (xy 56.763127 -275.646343)
			(xy 56.812302 -275.644362) (xy 56.861157 -275.650294) (xy 56.908428 -275.663986) (xy 56.95289 -275.685084)
			(xy 56.993393 -275.71304) (xy 57.028886 -275.747132) (xy 57.058451 -275.786476) (xy 57.081322 -275.830053)
			(xy 57.096906 -275.876734) (xy 57.104801 -275.925311) (xy 57.105296 -275.949918) (xy 58.394104 -275.949918)
			(xy 58.398064 -275.900864) (xy 58.409841 -275.85308) (xy 58.429132 -275.807804) (xy 58.455435 -275.766208)
			(xy 58.48807 -275.729371) (xy 58.526191 -275.698246) (xy 58.568812 -275.673639) (xy 58.614828 -275.656187)
			(xy 58.663047 -275.646343) (xy 58.712222 -275.644362) (xy 58.761077 -275.650294) (xy 58.808348 -275.663986)
			(xy 58.85281 -275.685084) (xy 58.893313 -275.71304) (xy 58.928806 -275.747132) (xy 58.958371 -275.786476)
			(xy 58.981242 -275.830053) (xy 58.996826 -275.876734) (xy 59.004721 -275.925311) (xy 59.005211 -275.949664)
			(xy 60.29377 -275.949664) (xy 60.29773 -275.90061) (xy 60.309507 -275.852826) (xy 60.328798 -275.80755)
			(xy 60.355101 -275.765954) (xy 60.387736 -275.729117) (xy 60.425857 -275.697992) (xy 60.468478 -275.673385)
			(xy 60.514494 -275.655933) (xy 60.562713 -275.646089) (xy 60.611888 -275.644108) (xy 60.660743 -275.65004)
			(xy 60.708014 -275.663732) (xy 60.752476 -275.68483) (xy 60.792979 -275.712786) (xy 60.828472 -275.746878)
			(xy 60.858037 -275.786222) (xy 60.880908 -275.829799) (xy 60.896492 -275.87648) (xy 60.904387 -275.925057)
			(xy 60.904882 -275.949664) (xy 60.904877 -275.949918) (xy 62.19369 -275.949918) (xy 62.19765 -275.900864)
			(xy 62.209427 -275.85308) (xy 62.228718 -275.807804) (xy 62.255021 -275.766208) (xy 62.287656 -275.729371)
			(xy 62.325777 -275.698246) (xy 62.368398 -275.673639) (xy 62.414414 -275.656187) (xy 62.462633 -275.646343)
			(xy 62.511808 -275.644362) (xy 62.560663 -275.650294) (xy 62.607934 -275.663986) (xy 62.652396 -275.685084)
			(xy 62.692899 -275.71304) (xy 62.728392 -275.747132) (xy 62.757957 -275.786476) (xy 62.780828 -275.830053)
			(xy 62.796412 -275.876734) (xy 62.804307 -275.925311) (xy 62.804797 -275.949664) (xy 64.093864 -275.949664)
			(xy 64.097824 -275.90061) (xy 64.109601 -275.852826) (xy 64.128892 -275.80755) (xy 64.155195 -275.765954)
			(xy 64.18783 -275.729117) (xy 64.225951 -275.697992) (xy 64.268572 -275.673385) (xy 64.314588 -275.655933)
			(xy 64.362807 -275.646089) (xy 64.411982 -275.644108) (xy 64.460837 -275.65004) (xy 64.508108 -275.663732)
			(xy 64.55257 -275.68483) (xy 64.593073 -275.712786) (xy 64.628566 -275.746878) (xy 64.658131 -275.786222)
			(xy 64.681002 -275.829799) (xy 64.696586 -275.87648) (xy 64.704481 -275.925057) (xy 64.704976 -275.949664)
			(xy 64.704971 -275.949918) (xy 65.993784 -275.949918) (xy 65.997744 -275.900864) (xy 66.009521 -275.85308)
			(xy 66.028812 -275.807804) (xy 66.055115 -275.766208) (xy 66.08775 -275.729371) (xy 66.125871 -275.698246)
			(xy 66.168492 -275.673639) (xy 66.214508 -275.656187) (xy 66.262727 -275.646343) (xy 66.311902 -275.644362)
			(xy 66.360757 -275.650294) (xy 66.408028 -275.663986) (xy 66.45249 -275.685084) (xy 66.492993 -275.71304)
			(xy 66.528486 -275.747132) (xy 66.558051 -275.786476) (xy 66.580922 -275.830053) (xy 66.596506 -275.876734)
			(xy 66.604401 -275.925311) (xy 66.604891 -275.949664) (xy 67.893704 -275.949664) (xy 67.897664 -275.90061)
			(xy 67.909441 -275.852826) (xy 67.928732 -275.80755) (xy 67.955035 -275.765954) (xy 67.98767 -275.729117)
			(xy 68.025791 -275.697992) (xy 68.068412 -275.673385) (xy 68.114428 -275.655933) (xy 68.162647 -275.646089)
			(xy 68.211822 -275.644108) (xy 68.260677 -275.65004) (xy 68.307948 -275.663732) (xy 68.35241 -275.68483)
			(xy 68.392913 -275.712786) (xy 68.428406 -275.746878) (xy 68.457971 -275.786222) (xy 68.480842 -275.829799)
			(xy 68.496426 -275.87648) (xy 68.504321 -275.925057) (xy 68.504816 -275.949664) (xy 68.504811 -275.949918)
			(xy 69.793624 -275.949918) (xy 69.797584 -275.900864) (xy 69.809361 -275.85308) (xy 69.828652 -275.807804)
			(xy 69.854955 -275.766208) (xy 69.88759 -275.729371) (xy 69.925711 -275.698246) (xy 69.968332 -275.673639)
			(xy 70.014348 -275.656187) (xy 70.062567 -275.646343) (xy 70.111742 -275.644362) (xy 70.160597 -275.650294)
			(xy 70.207868 -275.663986) (xy 70.25233 -275.685084) (xy 70.292833 -275.71304) (xy 70.328326 -275.747132)
			(xy 70.357891 -275.786476) (xy 70.380762 -275.830053) (xy 70.396346 -275.876734) (xy 70.404241 -275.925311)
			(xy 70.404731 -275.949664) (xy 71.693798 -275.949664) (xy 71.697758 -275.90061) (xy 71.709535 -275.852826)
			(xy 71.728826 -275.80755) (xy 71.755129 -275.765954) (xy 71.787764 -275.729117) (xy 71.825885 -275.697992)
			(xy 71.868506 -275.673385) (xy 71.914522 -275.655933) (xy 71.962741 -275.646089) (xy 72.011916 -275.644108)
			(xy 72.060771 -275.65004) (xy 72.108042 -275.663732) (xy 72.152504 -275.68483) (xy 72.193007 -275.712786)
			(xy 72.2285 -275.746878) (xy 72.258065 -275.786222) (xy 72.280936 -275.829799) (xy 72.29652 -275.87648)
			(xy 72.304415 -275.925057) (xy 72.30491 -275.949664) (xy 72.304905 -275.949918) (xy 73.593718 -275.949918)
			(xy 73.597678 -275.900864) (xy 73.609455 -275.85308) (xy 73.628746 -275.807804) (xy 73.655049 -275.766208)
			(xy 73.687684 -275.729371) (xy 73.725805 -275.698246) (xy 73.768426 -275.673639) (xy 73.814442 -275.656187)
			(xy 73.862661 -275.646343) (xy 73.911836 -275.644362) (xy 73.960691 -275.650294) (xy 74.007962 -275.663986)
			(xy 74.052424 -275.685084) (xy 74.092927 -275.71304) (xy 74.12842 -275.747132) (xy 74.157985 -275.786476)
			(xy 74.180856 -275.830053) (xy 74.19644 -275.876734) (xy 74.204335 -275.925311) (xy 74.204825 -275.949664)
			(xy 75.493892 -275.949664) (xy 75.497852 -275.90061) (xy 75.509629 -275.852826) (xy 75.52892 -275.80755)
			(xy 75.555223 -275.765954) (xy 75.587858 -275.729117) (xy 75.625979 -275.697992) (xy 75.6686 -275.673385)
			(xy 75.714616 -275.655933) (xy 75.762835 -275.646089) (xy 75.81201 -275.644108) (xy 75.860865 -275.65004)
			(xy 75.908136 -275.663732) (xy 75.952598 -275.68483) (xy 75.993101 -275.712786) (xy 76.028594 -275.746878)
			(xy 76.058159 -275.786222) (xy 76.08103 -275.829799) (xy 76.096614 -275.87648) (xy 76.104509 -275.925057)
			(xy 76.105004 -275.949664) (xy 76.104999 -275.949918) (xy 77.393812 -275.949918) (xy 77.397772 -275.900864)
			(xy 77.409549 -275.85308) (xy 77.42884 -275.807804) (xy 77.455143 -275.766208) (xy 77.487778 -275.729371)
			(xy 77.525899 -275.698246) (xy 77.56852 -275.673639) (xy 77.614536 -275.656187) (xy 77.662755 -275.646343)
			(xy 77.71193 -275.644362) (xy 77.760785 -275.650294) (xy 77.808056 -275.663986) (xy 77.852518 -275.685084)
			(xy 77.893021 -275.71304) (xy 77.928514 -275.747132) (xy 77.958079 -275.786476) (xy 77.98095 -275.830053)
			(xy 77.996534 -275.876734) (xy 78.004429 -275.925311) (xy 78.004924 -275.949918) (xy 79.293732 -275.949918)
			(xy 79.297692 -275.900864) (xy 79.309469 -275.85308) (xy 79.32876 -275.807804) (xy 79.355063 -275.766208)
			(xy 79.387698 -275.729371) (xy 79.425819 -275.698246) (xy 79.46844 -275.673639) (xy 79.514456 -275.656187)
			(xy 79.562675 -275.646343) (xy 79.61185 -275.644362) (xy 79.660705 -275.650294) (xy 79.707976 -275.663986)
			(xy 79.752438 -275.685084) (xy 79.792941 -275.71304) (xy 79.828434 -275.747132) (xy 79.857999 -275.786476)
			(xy 79.88087 -275.830053) (xy 79.896454 -275.876734) (xy 79.904349 -275.925311) (xy 79.904844 -275.949918)
			(xy 161.194254 -275.949918) (xy 161.198214 -275.900864) (xy 161.209991 -275.85308) (xy 161.229282 -275.807804)
			(xy 161.255585 -275.766208) (xy 161.28822 -275.729371) (xy 161.326341 -275.698246) (xy 161.368962 -275.673639)
			(xy 161.414978 -275.656187) (xy 161.463197 -275.646343) (xy 161.512372 -275.644362) (xy 161.561227 -275.650294)
			(xy 161.608498 -275.663986) (xy 161.65296 -275.685084) (xy 161.693463 -275.71304) (xy 161.728956 -275.747132)
			(xy 161.758521 -275.786476) (xy 161.781392 -275.830053) (xy 161.796976 -275.876734) (xy 161.804871 -275.925311)
			(xy 161.805366 -275.949918) (xy 163.094174 -275.949918) (xy 163.098134 -275.900864) (xy 163.109911 -275.85308)
			(xy 163.129202 -275.807804) (xy 163.155505 -275.766208) (xy 163.18814 -275.729371) (xy 163.226261 -275.698246)
			(xy 163.268882 -275.673639) (xy 163.314898 -275.656187) (xy 163.363117 -275.646343) (xy 163.412292 -275.644362)
			(xy 163.461147 -275.650294) (xy 163.508418 -275.663986) (xy 163.55288 -275.685084) (xy 163.593383 -275.71304)
			(xy 163.628876 -275.747132) (xy 163.658441 -275.786476) (xy 163.681312 -275.830053) (xy 163.696896 -275.876734)
			(xy 163.704791 -275.925311) (xy 163.705286 -275.949918) (xy 164.994094 -275.949918) (xy 164.998054 -275.900864)
			(xy 165.009831 -275.85308) (xy 165.029122 -275.807804) (xy 165.055425 -275.766208) (xy 165.08806 -275.729371)
			(xy 165.126181 -275.698246) (xy 165.168802 -275.673639) (xy 165.214818 -275.656187) (xy 165.263037 -275.646343)
			(xy 165.312212 -275.644362) (xy 165.361067 -275.650294) (xy 165.408338 -275.663986) (xy 165.4528 -275.685084)
			(xy 165.493303 -275.71304) (xy 165.528796 -275.747132) (xy 165.558361 -275.786476) (xy 165.581232 -275.830053)
			(xy 165.596816 -275.876734) (xy 165.604711 -275.925311) (xy 165.605206 -275.949918) (xy 166.894268 -275.949918)
			(xy 166.898228 -275.900864) (xy 166.910005 -275.85308) (xy 166.929296 -275.807804) (xy 166.955599 -275.766208)
			(xy 166.988234 -275.729371) (xy 167.026355 -275.698246) (xy 167.068976 -275.673639) (xy 167.114992 -275.656187)
			(xy 167.163211 -275.646343) (xy 167.212386 -275.644362) (xy 167.261241 -275.650294) (xy 167.308512 -275.663986)
			(xy 167.352974 -275.685084) (xy 167.393477 -275.71304) (xy 167.42897 -275.747132) (xy 167.458535 -275.786476)
			(xy 167.481406 -275.830053) (xy 167.49699 -275.876734) (xy 167.504885 -275.925311) (xy 167.50538 -275.949918)
			(xy 168.794188 -275.949918) (xy 168.798148 -275.900864) (xy 168.809925 -275.85308) (xy 168.829216 -275.807804)
			(xy 168.855519 -275.766208) (xy 168.888154 -275.729371) (xy 168.926275 -275.698246) (xy 168.968896 -275.673639)
			(xy 169.014912 -275.656187) (xy 169.063131 -275.646343) (xy 169.112306 -275.644362) (xy 169.161161 -275.650294)
			(xy 169.208432 -275.663986) (xy 169.252894 -275.685084) (xy 169.293397 -275.71304) (xy 169.32889 -275.747132)
			(xy 169.358455 -275.786476) (xy 169.381326 -275.830053) (xy 169.39691 -275.876734) (xy 169.404805 -275.925311)
			(xy 169.4053 -275.949918) (xy 170.694108 -275.949918) (xy 170.698068 -275.900864) (xy 170.709845 -275.85308)
			(xy 170.729136 -275.807804) (xy 170.755439 -275.766208) (xy 170.788074 -275.729371) (xy 170.826195 -275.698246)
			(xy 170.868816 -275.673639) (xy 170.914832 -275.656187) (xy 170.963051 -275.646343) (xy 171.012226 -275.644362)
			(xy 171.061081 -275.650294) (xy 171.108352 -275.663986) (xy 171.152814 -275.685084) (xy 171.193317 -275.71304)
			(xy 171.22881 -275.747132) (xy 171.258375 -275.786476) (xy 171.281246 -275.830053) (xy 171.29683 -275.876734)
			(xy 171.304725 -275.925311) (xy 171.30522 -275.949918) (xy 172.594282 -275.949918) (xy 172.598242 -275.900864)
			(xy 172.610019 -275.85308) (xy 172.62931 -275.807804) (xy 172.655613 -275.766208) (xy 172.688248 -275.729371)
			(xy 172.726369 -275.698246) (xy 172.76899 -275.673639) (xy 172.815006 -275.656187) (xy 172.863225 -275.646343)
			(xy 172.9124 -275.644362) (xy 172.961255 -275.650294) (xy 173.008526 -275.663986) (xy 173.052988 -275.685084)
			(xy 173.093491 -275.71304) (xy 173.128984 -275.747132) (xy 173.158549 -275.786476) (xy 173.18142 -275.830053)
			(xy 173.197004 -275.876734) (xy 173.204899 -275.925311) (xy 173.205394 -275.949918) (xy 174.494202 -275.949918)
			(xy 174.498162 -275.900864) (xy 174.509939 -275.85308) (xy 174.52923 -275.807804) (xy 174.555533 -275.766208)
			(xy 174.588168 -275.729371) (xy 174.626289 -275.698246) (xy 174.66891 -275.673639) (xy 174.714926 -275.656187)
			(xy 174.763145 -275.646343) (xy 174.81232 -275.644362) (xy 174.861175 -275.650294) (xy 174.908446 -275.663986)
			(xy 174.952908 -275.685084) (xy 174.993411 -275.71304) (xy 175.028904 -275.747132) (xy 175.058469 -275.786476)
			(xy 175.08134 -275.830053) (xy 175.096924 -275.876734) (xy 175.104819 -275.925311) (xy 175.105309 -275.949664)
			(xy 176.393868 -275.949664) (xy 176.397828 -275.90061) (xy 176.409605 -275.852826) (xy 176.428896 -275.80755)
			(xy 176.455199 -275.765954) (xy 176.487834 -275.729117) (xy 176.525955 -275.697992) (xy 176.568576 -275.673385)
			(xy 176.614592 -275.655933) (xy 176.662811 -275.646089) (xy 176.711986 -275.644108) (xy 176.760841 -275.65004)
			(xy 176.808112 -275.663732) (xy 176.852574 -275.68483) (xy 176.893077 -275.712786) (xy 176.92857 -275.746878)
			(xy 176.958135 -275.786222) (xy 176.981006 -275.829799) (xy 176.99659 -275.87648) (xy 177.004485 -275.925057)
			(xy 177.00498 -275.949664) (xy 177.004975 -275.949918) (xy 178.293788 -275.949918) (xy 178.297748 -275.900864)
			(xy 178.309525 -275.85308) (xy 178.328816 -275.807804) (xy 178.355119 -275.766208) (xy 178.387754 -275.729371)
			(xy 178.425875 -275.698246) (xy 178.468496 -275.673639) (xy 178.514512 -275.656187) (xy 178.562731 -275.646343)
			(xy 178.611906 -275.644362) (xy 178.660761 -275.650294) (xy 178.708032 -275.663986) (xy 178.752494 -275.685084)
			(xy 178.792997 -275.71304) (xy 178.82849 -275.747132) (xy 178.858055 -275.786476) (xy 178.880926 -275.830053)
			(xy 178.89651 -275.876734) (xy 178.904405 -275.925311) (xy 178.904895 -275.949664) (xy 180.193962 -275.949664)
			(xy 180.197922 -275.90061) (xy 180.209699 -275.852826) (xy 180.22899 -275.80755) (xy 180.255293 -275.765954)
			(xy 180.287928 -275.729117) (xy 180.326049 -275.697992) (xy 180.36867 -275.673385) (xy 180.414686 -275.655933)
			(xy 180.462905 -275.646089) (xy 180.51208 -275.644108) (xy 180.560935 -275.65004) (xy 180.608206 -275.663732)
			(xy 180.652668 -275.68483) (xy 180.693171 -275.712786) (xy 180.728664 -275.746878) (xy 180.758229 -275.786222)
			(xy 180.7811 -275.829799) (xy 180.796684 -275.87648) (xy 180.804579 -275.925057) (xy 180.805074 -275.949664)
			(xy 180.805069 -275.949918) (xy 182.093882 -275.949918) (xy 182.097842 -275.900864) (xy 182.109619 -275.85308)
			(xy 182.12891 -275.807804) (xy 182.155213 -275.766208) (xy 182.187848 -275.729371) (xy 182.225969 -275.698246)
			(xy 182.26859 -275.673639) (xy 182.314606 -275.656187) (xy 182.362825 -275.646343) (xy 182.412 -275.644362)
			(xy 182.460855 -275.650294) (xy 182.508126 -275.663986) (xy 182.552588 -275.685084) (xy 182.593091 -275.71304)
			(xy 182.628584 -275.747132) (xy 182.658149 -275.786476) (xy 182.68102 -275.830053) (xy 182.696604 -275.876734)
			(xy 182.704499 -275.925311) (xy 182.704989 -275.949664) (xy 183.993802 -275.949664) (xy 183.997762 -275.90061)
			(xy 184.009539 -275.852826) (xy 184.02883 -275.80755) (xy 184.055133 -275.765954) (xy 184.087768 -275.729117)
			(xy 184.125889 -275.697992) (xy 184.16851 -275.673385) (xy 184.214526 -275.655933) (xy 184.262745 -275.646089)
			(xy 184.31192 -275.644108) (xy 184.360775 -275.65004) (xy 184.408046 -275.663732) (xy 184.452508 -275.68483)
			(xy 184.493011 -275.712786) (xy 184.528504 -275.746878) (xy 184.558069 -275.786222) (xy 184.58094 -275.829799)
			(xy 184.596524 -275.87648) (xy 184.604419 -275.925057) (xy 184.604914 -275.949664) (xy 184.604909 -275.949918)
			(xy 185.893722 -275.949918) (xy 185.897682 -275.900864) (xy 185.909459 -275.85308) (xy 185.92875 -275.807804)
			(xy 185.955053 -275.766208) (xy 185.987688 -275.729371) (xy 186.025809 -275.698246) (xy 186.06843 -275.673639)
			(xy 186.114446 -275.656187) (xy 186.162665 -275.646343) (xy 186.21184 -275.644362) (xy 186.260695 -275.650294)
			(xy 186.307966 -275.663986) (xy 186.352428 -275.685084) (xy 186.392931 -275.71304) (xy 186.428424 -275.747132)
			(xy 186.457989 -275.786476) (xy 186.48086 -275.830053) (xy 186.496444 -275.876734) (xy 186.504339 -275.925311)
			(xy 186.504829 -275.949664) (xy 187.793896 -275.949664) (xy 187.797856 -275.90061) (xy 187.809633 -275.852826)
			(xy 187.828924 -275.80755) (xy 187.855227 -275.765954) (xy 187.887862 -275.729117) (xy 187.925983 -275.697992)
			(xy 187.968604 -275.673385) (xy 188.01462 -275.655933) (xy 188.062839 -275.646089) (xy 188.112014 -275.644108)
			(xy 188.160869 -275.65004) (xy 188.20814 -275.663732) (xy 188.252602 -275.68483) (xy 188.293105 -275.712786)
			(xy 188.328598 -275.746878) (xy 188.358163 -275.786222) (xy 188.381034 -275.829799) (xy 188.396618 -275.87648)
			(xy 188.404513 -275.925057) (xy 188.405008 -275.949664) (xy 188.405003 -275.949918) (xy 189.693816 -275.949918)
			(xy 189.697776 -275.900864) (xy 189.709553 -275.85308) (xy 189.728844 -275.807804) (xy 189.755147 -275.766208)
			(xy 189.787782 -275.729371) (xy 189.825903 -275.698246) (xy 189.868524 -275.673639) (xy 189.91454 -275.656187)
			(xy 189.962759 -275.646343) (xy 190.011934 -275.644362) (xy 190.060789 -275.650294) (xy 190.10806 -275.663986)
			(xy 190.152522 -275.685084) (xy 190.193025 -275.71304) (xy 190.228518 -275.747132) (xy 190.258083 -275.786476)
			(xy 190.280954 -275.830053) (xy 190.296538 -275.876734) (xy 190.304433 -275.925311) (xy 190.304923 -275.949664)
			(xy 191.59399 -275.949664) (xy 191.59795 -275.90061) (xy 191.609727 -275.852826) (xy 191.629018 -275.80755)
			(xy 191.655321 -275.765954) (xy 191.687956 -275.729117) (xy 191.726077 -275.697992) (xy 191.768698 -275.673385)
			(xy 191.814714 -275.655933) (xy 191.862933 -275.646089) (xy 191.912108 -275.644108) (xy 191.960963 -275.65004)
			(xy 192.008234 -275.663732) (xy 192.052696 -275.68483) (xy 192.093199 -275.712786) (xy 192.128692 -275.746878)
			(xy 192.158257 -275.786222) (xy 192.181128 -275.829799) (xy 192.196712 -275.87648) (xy 192.204607 -275.925057)
			(xy 192.205102 -275.949664) (xy 192.205097 -275.949918) (xy 193.49391 -275.949918) (xy 193.49787 -275.900864)
			(xy 193.509647 -275.85308) (xy 193.528938 -275.807804) (xy 193.555241 -275.766208) (xy 193.587876 -275.729371)
			(xy 193.625997 -275.698246) (xy 193.668618 -275.673639) (xy 193.714634 -275.656187) (xy 193.762853 -275.646343)
			(xy 193.812028 -275.644362) (xy 193.860883 -275.650294) (xy 193.908154 -275.663986) (xy 193.952616 -275.685084)
			(xy 193.993119 -275.71304) (xy 194.028612 -275.747132) (xy 194.058177 -275.786476) (xy 194.081048 -275.830053)
			(xy 194.096632 -275.876734) (xy 194.104527 -275.925311) (xy 194.105022 -275.949918) (xy 195.39383 -275.949918)
			(xy 195.39779 -275.900864) (xy 195.409567 -275.85308) (xy 195.428858 -275.807804) (xy 195.455161 -275.766208)
			(xy 195.487796 -275.729371) (xy 195.525917 -275.698246) (xy 195.568538 -275.673639) (xy 195.614554 -275.656187)
			(xy 195.662773 -275.646343) (xy 195.711948 -275.644362) (xy 195.760803 -275.650294) (xy 195.808074 -275.663986)
			(xy 195.852536 -275.685084) (xy 195.893039 -275.71304) (xy 195.928532 -275.747132) (xy 195.958097 -275.786476)
			(xy 195.980968 -275.830053) (xy 195.996552 -275.876734) (xy 196.004447 -275.925311) (xy 196.004942 -275.949918)
			(xy 277.294098 -275.949918) (xy 277.298058 -275.900864) (xy 277.309835 -275.85308) (xy 277.329126 -275.807804)
			(xy 277.355429 -275.766208) (xy 277.388064 -275.729371) (xy 277.426185 -275.698246) (xy 277.468806 -275.673639)
			(xy 277.514822 -275.656187) (xy 277.563041 -275.646343) (xy 277.612216 -275.644362) (xy 277.661071 -275.650294)
			(xy 277.708342 -275.663986) (xy 277.752804 -275.685084) (xy 277.793307 -275.71304) (xy 277.8288 -275.747132)
			(xy 277.858365 -275.786476) (xy 277.881236 -275.830053) (xy 277.89682 -275.876734) (xy 277.904715 -275.925311)
			(xy 277.90521 -275.949918) (xy 279.194018 -275.949918) (xy 279.197978 -275.900864) (xy 279.209755 -275.85308)
			(xy 279.229046 -275.807804) (xy 279.255349 -275.766208) (xy 279.287984 -275.729371) (xy 279.326105 -275.698246)
			(xy 279.368726 -275.673639) (xy 279.414742 -275.656187) (xy 279.462961 -275.646343) (xy 279.512136 -275.644362)
			(xy 279.560991 -275.650294) (xy 279.608262 -275.663986) (xy 279.652724 -275.685084) (xy 279.693227 -275.71304)
			(xy 279.72872 -275.747132) (xy 279.758285 -275.786476) (xy 279.781156 -275.830053) (xy 279.79674 -275.876734)
			(xy 279.804635 -275.925311) (xy 279.80513 -275.949918) (xy 281.093938 -275.949918) (xy 281.097898 -275.900864)
			(xy 281.109675 -275.85308) (xy 281.128966 -275.807804) (xy 281.155269 -275.766208) (xy 281.187904 -275.729371)
			(xy 281.226025 -275.698246) (xy 281.268646 -275.673639) (xy 281.314662 -275.656187) (xy 281.362881 -275.646343)
			(xy 281.412056 -275.644362) (xy 281.460911 -275.650294) (xy 281.508182 -275.663986) (xy 281.552644 -275.685084)
			(xy 281.593147 -275.71304) (xy 281.62864 -275.747132) (xy 281.658205 -275.786476) (xy 281.681076 -275.830053)
			(xy 281.69666 -275.876734) (xy 281.704555 -275.925311) (xy 281.70505 -275.949918) (xy 282.994112 -275.949918)
			(xy 282.998072 -275.900864) (xy 283.009849 -275.85308) (xy 283.02914 -275.807804) (xy 283.055443 -275.766208)
			(xy 283.088078 -275.729371) (xy 283.126199 -275.698246) (xy 283.16882 -275.673639) (xy 283.214836 -275.656187)
			(xy 283.263055 -275.646343) (xy 283.31223 -275.644362) (xy 283.361085 -275.650294) (xy 283.408356 -275.663986)
			(xy 283.452818 -275.685084) (xy 283.493321 -275.71304) (xy 283.528814 -275.747132) (xy 283.558379 -275.786476)
			(xy 283.58125 -275.830053) (xy 283.596834 -275.876734) (xy 283.604729 -275.925311) (xy 283.605224 -275.949918)
			(xy 284.894032 -275.949918) (xy 284.897992 -275.900864) (xy 284.909769 -275.85308) (xy 284.92906 -275.807804)
			(xy 284.955363 -275.766208) (xy 284.987998 -275.729371) (xy 285.026119 -275.698246) (xy 285.06874 -275.673639)
			(xy 285.114756 -275.656187) (xy 285.162975 -275.646343) (xy 285.21215 -275.644362) (xy 285.261005 -275.650294)
			(xy 285.308276 -275.663986) (xy 285.352738 -275.685084) (xy 285.393241 -275.71304) (xy 285.428734 -275.747132)
			(xy 285.458299 -275.786476) (xy 285.48117 -275.830053) (xy 285.496754 -275.876734) (xy 285.504649 -275.925311)
			(xy 285.505144 -275.949918) (xy 286.793952 -275.949918) (xy 286.797912 -275.900864) (xy 286.809689 -275.85308)
			(xy 286.82898 -275.807804) (xy 286.855283 -275.766208) (xy 286.887918 -275.729371) (xy 286.926039 -275.698246)
			(xy 286.96866 -275.673639) (xy 287.014676 -275.656187) (xy 287.062895 -275.646343) (xy 287.11207 -275.644362)
			(xy 287.160925 -275.650294) (xy 287.208196 -275.663986) (xy 287.252658 -275.685084) (xy 287.293161 -275.71304)
			(xy 287.328654 -275.747132) (xy 287.358219 -275.786476) (xy 287.38109 -275.830053) (xy 287.396674 -275.876734)
			(xy 287.404569 -275.925311) (xy 287.405064 -275.949918) (xy 288.694126 -275.949918) (xy 288.698086 -275.900864)
			(xy 288.709863 -275.85308) (xy 288.729154 -275.807804) (xy 288.755457 -275.766208) (xy 288.788092 -275.729371)
			(xy 288.826213 -275.698246) (xy 288.868834 -275.673639) (xy 288.91485 -275.656187) (xy 288.963069 -275.646343)
			(xy 289.012244 -275.644362) (xy 289.061099 -275.650294) (xy 289.10837 -275.663986) (xy 289.152832 -275.685084)
			(xy 289.193335 -275.71304) (xy 289.228828 -275.747132) (xy 289.258393 -275.786476) (xy 289.281264 -275.830053)
			(xy 289.296848 -275.876734) (xy 289.304743 -275.925311) (xy 289.305238 -275.949918) (xy 290.594046 -275.949918)
			(xy 290.598006 -275.900864) (xy 290.609783 -275.85308) (xy 290.629074 -275.807804) (xy 290.655377 -275.766208)
			(xy 290.688012 -275.729371) (xy 290.726133 -275.698246) (xy 290.768754 -275.673639) (xy 290.81477 -275.656187)
			(xy 290.862989 -275.646343) (xy 290.912164 -275.644362) (xy 290.961019 -275.650294) (xy 291.00829 -275.663986)
			(xy 291.052752 -275.685084) (xy 291.093255 -275.71304) (xy 291.128748 -275.747132) (xy 291.158313 -275.786476)
			(xy 291.181184 -275.830053) (xy 291.196768 -275.876734) (xy 291.204663 -275.925311) (xy 291.205153 -275.949664)
			(xy 292.493712 -275.949664) (xy 292.497672 -275.90061) (xy 292.509449 -275.852826) (xy 292.52874 -275.80755)
			(xy 292.555043 -275.765954) (xy 292.587678 -275.729117) (xy 292.625799 -275.697992) (xy 292.66842 -275.673385)
			(xy 292.714436 -275.655933) (xy 292.762655 -275.646089) (xy 292.81183 -275.644108) (xy 292.860685 -275.65004)
			(xy 292.907956 -275.663732) (xy 292.952418 -275.68483) (xy 292.992921 -275.712786) (xy 293.028414 -275.746878)
			(xy 293.057979 -275.786222) (xy 293.08085 -275.829799) (xy 293.096434 -275.87648) (xy 293.104329 -275.925057)
			(xy 293.104824 -275.949664) (xy 293.104819 -275.949918) (xy 294.393632 -275.949918) (xy 294.397592 -275.900864)
			(xy 294.409369 -275.85308) (xy 294.42866 -275.807804) (xy 294.454963 -275.766208) (xy 294.487598 -275.729371)
			(xy 294.525719 -275.698246) (xy 294.56834 -275.673639) (xy 294.614356 -275.656187) (xy 294.662575 -275.646343)
			(xy 294.71175 -275.644362) (xy 294.760605 -275.650294) (xy 294.807876 -275.663986) (xy 294.852338 -275.685084)
			(xy 294.892841 -275.71304) (xy 294.928334 -275.747132) (xy 294.957899 -275.786476) (xy 294.98077 -275.830053)
			(xy 294.996354 -275.876734) (xy 295.004249 -275.925311) (xy 295.004739 -275.949664) (xy 296.293806 -275.949664)
			(xy 296.297766 -275.90061) (xy 296.309543 -275.852826) (xy 296.328834 -275.80755) (xy 296.355137 -275.765954)
			(xy 296.387772 -275.729117) (xy 296.425893 -275.697992) (xy 296.468514 -275.673385) (xy 296.51453 -275.655933)
			(xy 296.562749 -275.646089) (xy 296.611924 -275.644108) (xy 296.660779 -275.65004) (xy 296.70805 -275.663732)
			(xy 296.752512 -275.68483) (xy 296.793015 -275.712786) (xy 296.828508 -275.746878) (xy 296.858073 -275.786222)
			(xy 296.880944 -275.829799) (xy 296.896528 -275.87648) (xy 296.904423 -275.925057) (xy 296.904918 -275.949664)
			(xy 296.904913 -275.949918) (xy 298.193726 -275.949918) (xy 298.197686 -275.900864) (xy 298.209463 -275.85308)
			(xy 298.228754 -275.807804) (xy 298.255057 -275.766208) (xy 298.287692 -275.729371) (xy 298.325813 -275.698246)
			(xy 298.368434 -275.673639) (xy 298.41445 -275.656187) (xy 298.462669 -275.646343) (xy 298.511844 -275.644362)
			(xy 298.560699 -275.650294) (xy 298.60797 -275.663986) (xy 298.652432 -275.685084) (xy 298.692935 -275.71304)
			(xy 298.728428 -275.747132) (xy 298.757993 -275.786476) (xy 298.780864 -275.830053) (xy 298.796448 -275.876734)
			(xy 298.804343 -275.925311) (xy 298.804833 -275.949664) (xy 300.093646 -275.949664) (xy 300.097606 -275.90061)
			(xy 300.109383 -275.852826) (xy 300.128674 -275.80755) (xy 300.154977 -275.765954) (xy 300.187612 -275.729117)
			(xy 300.225733 -275.697992) (xy 300.268354 -275.673385) (xy 300.31437 -275.655933) (xy 300.362589 -275.646089)
			(xy 300.411764 -275.644108) (xy 300.460619 -275.65004) (xy 300.50789 -275.663732) (xy 300.552352 -275.68483)
			(xy 300.592855 -275.712786) (xy 300.628348 -275.746878) (xy 300.657913 -275.786222) (xy 300.680784 -275.829799)
			(xy 300.696368 -275.87648) (xy 300.704263 -275.925057) (xy 300.704758 -275.949664) (xy 300.704753 -275.949918)
			(xy 301.993566 -275.949918) (xy 301.997526 -275.900864) (xy 302.009303 -275.85308) (xy 302.028594 -275.807804)
			(xy 302.054897 -275.766208) (xy 302.087532 -275.729371) (xy 302.125653 -275.698246) (xy 302.168274 -275.673639)
			(xy 302.21429 -275.656187) (xy 302.262509 -275.646343) (xy 302.311684 -275.644362) (xy 302.360539 -275.650294)
			(xy 302.40781 -275.663986) (xy 302.452272 -275.685084) (xy 302.492775 -275.71304) (xy 302.528268 -275.747132)
			(xy 302.557833 -275.786476) (xy 302.580704 -275.830053) (xy 302.596288 -275.876734) (xy 302.604183 -275.925311)
			(xy 302.604673 -275.949664) (xy 303.89374 -275.949664) (xy 303.8977 -275.90061) (xy 303.909477 -275.852826)
			(xy 303.928768 -275.80755) (xy 303.955071 -275.765954) (xy 303.987706 -275.729117) (xy 304.025827 -275.697992)
			(xy 304.068448 -275.673385) (xy 304.114464 -275.655933) (xy 304.162683 -275.646089) (xy 304.211858 -275.644108)
			(xy 304.260713 -275.65004) (xy 304.307984 -275.663732) (xy 304.352446 -275.68483) (xy 304.392949 -275.712786)
			(xy 304.428442 -275.746878) (xy 304.458007 -275.786222) (xy 304.480878 -275.829799) (xy 304.496462 -275.87648)
			(xy 304.504357 -275.925057) (xy 304.504852 -275.949664) (xy 304.504847 -275.949918) (xy 305.79366 -275.949918)
			(xy 305.79762 -275.900864) (xy 305.809397 -275.85308) (xy 305.828688 -275.807804) (xy 305.854991 -275.766208)
			(xy 305.887626 -275.729371) (xy 305.925747 -275.698246) (xy 305.968368 -275.673639) (xy 306.014384 -275.656187)
			(xy 306.062603 -275.646343) (xy 306.111778 -275.644362) (xy 306.160633 -275.650294) (xy 306.207904 -275.663986)
			(xy 306.252366 -275.685084) (xy 306.292869 -275.71304) (xy 306.328362 -275.747132) (xy 306.357927 -275.786476)
			(xy 306.380798 -275.830053) (xy 306.396382 -275.876734) (xy 306.404277 -275.925311) (xy 306.404767 -275.949664)
			(xy 307.693834 -275.949664) (xy 307.697794 -275.90061) (xy 307.709571 -275.852826) (xy 307.728862 -275.80755)
			(xy 307.755165 -275.765954) (xy 307.7878 -275.729117) (xy 307.825921 -275.697992) (xy 307.868542 -275.673385)
			(xy 307.914558 -275.655933) (xy 307.962777 -275.646089) (xy 308.011952 -275.644108) (xy 308.060807 -275.65004)
			(xy 308.108078 -275.663732) (xy 308.15254 -275.68483) (xy 308.193043 -275.712786) (xy 308.228536 -275.746878)
			(xy 308.258101 -275.786222) (xy 308.280972 -275.829799) (xy 308.296556 -275.87648) (xy 308.304451 -275.925057)
			(xy 308.304946 -275.949664) (xy 308.304941 -275.949918) (xy 309.593754 -275.949918) (xy 309.597714 -275.900864)
			(xy 309.609491 -275.85308) (xy 309.628782 -275.807804) (xy 309.655085 -275.766208) (xy 309.68772 -275.729371)
			(xy 309.725841 -275.698246) (xy 309.768462 -275.673639) (xy 309.814478 -275.656187) (xy 309.862697 -275.646343)
			(xy 309.911872 -275.644362) (xy 309.960727 -275.650294) (xy 310.007998 -275.663986) (xy 310.05246 -275.685084)
			(xy 310.092963 -275.71304) (xy 310.128456 -275.747132) (xy 310.158021 -275.786476) (xy 310.180892 -275.830053)
			(xy 310.196476 -275.876734) (xy 310.204371 -275.925311) (xy 310.204866 -275.949918) (xy 311.493674 -275.949918)
			(xy 311.497634 -275.900864) (xy 311.509411 -275.85308) (xy 311.528702 -275.807804) (xy 311.555005 -275.766208)
			(xy 311.58764 -275.729371) (xy 311.625761 -275.698246) (xy 311.668382 -275.673639) (xy 311.714398 -275.656187)
			(xy 311.762617 -275.646343) (xy 311.811792 -275.644362) (xy 311.860647 -275.650294) (xy 311.907918 -275.663986)
			(xy 311.95238 -275.685084) (xy 311.992883 -275.71304) (xy 312.028376 -275.747132) (xy 312.057941 -275.786476)
			(xy 312.080812 -275.830053) (xy 312.096396 -275.876734) (xy 312.104291 -275.925311) (xy 312.104786 -275.949918)
			(xy 393.394196 -275.949918) (xy 393.398156 -275.900864) (xy 393.409933 -275.85308) (xy 393.429224 -275.807804)
			(xy 393.455527 -275.766208) (xy 393.488162 -275.729371) (xy 393.526283 -275.698246) (xy 393.568904 -275.673639)
			(xy 393.61492 -275.656187) (xy 393.663139 -275.646343) (xy 393.712314 -275.644362) (xy 393.761169 -275.650294)
			(xy 393.80844 -275.663986) (xy 393.852902 -275.685084) (xy 393.893405 -275.71304) (xy 393.928898 -275.747132)
			(xy 393.958463 -275.786476) (xy 393.981334 -275.830053) (xy 393.996918 -275.876734) (xy 394.004813 -275.925311)
			(xy 394.005308 -275.949918) (xy 395.294116 -275.949918) (xy 395.298076 -275.900864) (xy 395.309853 -275.85308)
			(xy 395.329144 -275.807804) (xy 395.355447 -275.766208) (xy 395.388082 -275.729371) (xy 395.426203 -275.698246)
			(xy 395.468824 -275.673639) (xy 395.51484 -275.656187) (xy 395.563059 -275.646343) (xy 395.612234 -275.644362)
			(xy 395.661089 -275.650294) (xy 395.70836 -275.663986) (xy 395.752822 -275.685084) (xy 395.793325 -275.71304)
			(xy 395.828818 -275.747132) (xy 395.858383 -275.786476) (xy 395.881254 -275.830053) (xy 395.896838 -275.876734)
			(xy 395.904733 -275.925311) (xy 395.905228 -275.949918) (xy 397.194036 -275.949918) (xy 397.197996 -275.900864)
			(xy 397.209773 -275.85308) (xy 397.229064 -275.807804) (xy 397.255367 -275.766208) (xy 397.288002 -275.729371)
			(xy 397.326123 -275.698246) (xy 397.368744 -275.673639) (xy 397.41476 -275.656187) (xy 397.462979 -275.646343)
			(xy 397.512154 -275.644362) (xy 397.561009 -275.650294) (xy 397.60828 -275.663986) (xy 397.652742 -275.685084)
			(xy 397.693245 -275.71304) (xy 397.728738 -275.747132) (xy 397.758303 -275.786476) (xy 397.781174 -275.830053)
			(xy 397.796758 -275.876734) (xy 397.804653 -275.925311) (xy 397.805148 -275.949918) (xy 399.09421 -275.949918)
			(xy 399.09817 -275.900864) (xy 399.109947 -275.85308) (xy 399.129238 -275.807804) (xy 399.155541 -275.766208)
			(xy 399.188176 -275.729371) (xy 399.226297 -275.698246) (xy 399.268918 -275.673639) (xy 399.314934 -275.656187)
			(xy 399.363153 -275.646343) (xy 399.412328 -275.644362) (xy 399.461183 -275.650294) (xy 399.508454 -275.663986)
			(xy 399.552916 -275.685084) (xy 399.593419 -275.71304) (xy 399.628912 -275.747132) (xy 399.658477 -275.786476)
			(xy 399.681348 -275.830053) (xy 399.696932 -275.876734) (xy 399.704827 -275.925311) (xy 399.705322 -275.949918)
			(xy 400.99413 -275.949918) (xy 400.99809 -275.900864) (xy 401.009867 -275.85308) (xy 401.029158 -275.807804)
			(xy 401.055461 -275.766208) (xy 401.088096 -275.729371) (xy 401.126217 -275.698246) (xy 401.168838 -275.673639)
			(xy 401.214854 -275.656187) (xy 401.263073 -275.646343) (xy 401.312248 -275.644362) (xy 401.361103 -275.650294)
			(xy 401.408374 -275.663986) (xy 401.452836 -275.685084) (xy 401.493339 -275.71304) (xy 401.528832 -275.747132)
			(xy 401.558397 -275.786476) (xy 401.581268 -275.830053) (xy 401.596852 -275.876734) (xy 401.604747 -275.925311)
			(xy 401.605242 -275.949918) (xy 402.89405 -275.949918) (xy 402.89801 -275.900864) (xy 402.909787 -275.85308)
			(xy 402.929078 -275.807804) (xy 402.955381 -275.766208) (xy 402.988016 -275.729371) (xy 403.026137 -275.698246)
			(xy 403.068758 -275.673639) (xy 403.114774 -275.656187) (xy 403.162993 -275.646343) (xy 403.212168 -275.644362)
			(xy 403.261023 -275.650294) (xy 403.308294 -275.663986) (xy 403.352756 -275.685084) (xy 403.393259 -275.71304)
			(xy 403.428752 -275.747132) (xy 403.458317 -275.786476) (xy 403.481188 -275.830053) (xy 403.496772 -275.876734)
			(xy 403.504667 -275.925311) (xy 403.505162 -275.949918) (xy 404.794224 -275.949918) (xy 404.798184 -275.900864)
			(xy 404.809961 -275.85308) (xy 404.829252 -275.807804) (xy 404.855555 -275.766208) (xy 404.88819 -275.729371)
			(xy 404.926311 -275.698246) (xy 404.968932 -275.673639) (xy 405.014948 -275.656187) (xy 405.063167 -275.646343)
			(xy 405.112342 -275.644362) (xy 405.161197 -275.650294) (xy 405.208468 -275.663986) (xy 405.25293 -275.685084)
			(xy 405.293433 -275.71304) (xy 405.328926 -275.747132) (xy 405.358491 -275.786476) (xy 405.381362 -275.830053)
			(xy 405.396946 -275.876734) (xy 405.404841 -275.925311) (xy 405.405336 -275.949918) (xy 406.694144 -275.949918)
			(xy 406.698104 -275.900864) (xy 406.709881 -275.85308) (xy 406.729172 -275.807804) (xy 406.755475 -275.766208)
			(xy 406.78811 -275.729371) (xy 406.826231 -275.698246) (xy 406.868852 -275.673639) (xy 406.914868 -275.656187)
			(xy 406.963087 -275.646343) (xy 407.012262 -275.644362) (xy 407.061117 -275.650294) (xy 407.108388 -275.663986)
			(xy 407.15285 -275.685084) (xy 407.193353 -275.71304) (xy 407.228846 -275.747132) (xy 407.258411 -275.786476)
			(xy 407.281282 -275.830053) (xy 407.296866 -275.876734) (xy 407.304761 -275.925311) (xy 407.305251 -275.949664)
			(xy 408.59381 -275.949664) (xy 408.59777 -275.90061) (xy 408.609547 -275.852826) (xy 408.628838 -275.80755)
			(xy 408.655141 -275.765954) (xy 408.687776 -275.729117) (xy 408.725897 -275.697992) (xy 408.768518 -275.673385)
			(xy 408.814534 -275.655933) (xy 408.862753 -275.646089) (xy 408.911928 -275.644108) (xy 408.960783 -275.65004)
			(xy 409.008054 -275.663732) (xy 409.052516 -275.68483) (xy 409.093019 -275.712786) (xy 409.128512 -275.746878)
			(xy 409.158077 -275.786222) (xy 409.180948 -275.829799) (xy 409.196532 -275.87648) (xy 409.204427 -275.925057)
			(xy 409.204922 -275.949664) (xy 409.204917 -275.949918) (xy 410.49373 -275.949918) (xy 410.49769 -275.900864)
			(xy 410.509467 -275.85308) (xy 410.528758 -275.807804) (xy 410.555061 -275.766208) (xy 410.587696 -275.729371)
			(xy 410.625817 -275.698246) (xy 410.668438 -275.673639) (xy 410.714454 -275.656187) (xy 410.762673 -275.646343)
			(xy 410.811848 -275.644362) (xy 410.860703 -275.650294) (xy 410.907974 -275.663986) (xy 410.952436 -275.685084)
			(xy 410.992939 -275.71304) (xy 411.028432 -275.747132) (xy 411.057997 -275.786476) (xy 411.080868 -275.830053)
			(xy 411.096452 -275.876734) (xy 411.104347 -275.925311) (xy 411.104837 -275.949664) (xy 412.393904 -275.949664)
			(xy 412.397864 -275.90061) (xy 412.409641 -275.852826) (xy 412.428932 -275.80755) (xy 412.455235 -275.765954)
			(xy 412.48787 -275.729117) (xy 412.525991 -275.697992) (xy 412.568612 -275.673385) (xy 412.614628 -275.655933)
			(xy 412.662847 -275.646089) (xy 412.712022 -275.644108) (xy 412.760877 -275.65004) (xy 412.808148 -275.663732)
			(xy 412.85261 -275.68483) (xy 412.893113 -275.712786) (xy 412.928606 -275.746878) (xy 412.958171 -275.786222)
			(xy 412.981042 -275.829799) (xy 412.996626 -275.87648) (xy 413.004521 -275.925057) (xy 413.005016 -275.949664)
			(xy 413.005011 -275.949918) (xy 414.293824 -275.949918) (xy 414.297784 -275.900864) (xy 414.309561 -275.85308)
			(xy 414.328852 -275.807804) (xy 414.355155 -275.766208) (xy 414.38779 -275.729371) (xy 414.425911 -275.698246)
			(xy 414.468532 -275.673639) (xy 414.514548 -275.656187) (xy 414.562767 -275.646343) (xy 414.611942 -275.644362)
			(xy 414.660797 -275.650294) (xy 414.708068 -275.663986) (xy 414.75253 -275.685084) (xy 414.793033 -275.71304)
			(xy 414.828526 -275.747132) (xy 414.858091 -275.786476) (xy 414.880962 -275.830053) (xy 414.896546 -275.876734)
			(xy 414.904441 -275.925311) (xy 414.904931 -275.949664) (xy 416.193744 -275.949664) (xy 416.197704 -275.90061)
			(xy 416.209481 -275.852826) (xy 416.228772 -275.80755) (xy 416.255075 -275.765954) (xy 416.28771 -275.729117)
			(xy 416.325831 -275.697992) (xy 416.368452 -275.673385) (xy 416.414468 -275.655933) (xy 416.462687 -275.646089)
			(xy 416.511862 -275.644108) (xy 416.560717 -275.65004) (xy 416.607988 -275.663732) (xy 416.65245 -275.68483)
			(xy 416.692953 -275.712786) (xy 416.728446 -275.746878) (xy 416.758011 -275.786222) (xy 416.780882 -275.829799)
			(xy 416.796466 -275.87648) (xy 416.804361 -275.925057) (xy 416.804856 -275.949664) (xy 416.804851 -275.949918)
			(xy 418.093664 -275.949918) (xy 418.097624 -275.900864) (xy 418.109401 -275.85308) (xy 418.128692 -275.807804)
			(xy 418.154995 -275.766208) (xy 418.18763 -275.729371) (xy 418.225751 -275.698246) (xy 418.268372 -275.673639)
			(xy 418.314388 -275.656187) (xy 418.362607 -275.646343) (xy 418.411782 -275.644362) (xy 418.460637 -275.650294)
			(xy 418.507908 -275.663986) (xy 418.55237 -275.685084) (xy 418.592873 -275.71304) (xy 418.628366 -275.747132)
			(xy 418.657931 -275.786476) (xy 418.680802 -275.830053) (xy 418.696386 -275.876734) (xy 418.704281 -275.925311)
			(xy 418.704771 -275.949664) (xy 419.993838 -275.949664) (xy 419.997798 -275.90061) (xy 420.009575 -275.852826)
			(xy 420.028866 -275.80755) (xy 420.055169 -275.765954) (xy 420.087804 -275.729117) (xy 420.125925 -275.697992)
			(xy 420.168546 -275.673385) (xy 420.214562 -275.655933) (xy 420.262781 -275.646089) (xy 420.311956 -275.644108)
			(xy 420.360811 -275.65004) (xy 420.408082 -275.663732) (xy 420.452544 -275.68483) (xy 420.493047 -275.712786)
			(xy 420.52854 -275.746878) (xy 420.558105 -275.786222) (xy 420.580976 -275.829799) (xy 420.59656 -275.87648)
			(xy 420.604455 -275.925057) (xy 420.60495 -275.949664) (xy 420.604945 -275.949918) (xy 421.893758 -275.949918)
			(xy 421.897718 -275.900864) (xy 421.909495 -275.85308) (xy 421.928786 -275.807804) (xy 421.955089 -275.766208)
			(xy 421.987724 -275.729371) (xy 422.025845 -275.698246) (xy 422.068466 -275.673639) (xy 422.114482 -275.656187)
			(xy 422.162701 -275.646343) (xy 422.211876 -275.644362) (xy 422.260731 -275.650294) (xy 422.308002 -275.663986)
			(xy 422.352464 -275.685084) (xy 422.392967 -275.71304) (xy 422.42846 -275.747132) (xy 422.458025 -275.786476)
			(xy 422.480896 -275.830053) (xy 422.49648 -275.876734) (xy 422.504375 -275.925311) (xy 422.504865 -275.949664)
			(xy 423.793932 -275.949664) (xy 423.797892 -275.90061) (xy 423.809669 -275.852826) (xy 423.82896 -275.80755)
			(xy 423.855263 -275.765954) (xy 423.887898 -275.729117) (xy 423.926019 -275.697992) (xy 423.96864 -275.673385)
			(xy 424.014656 -275.655933) (xy 424.062875 -275.646089) (xy 424.11205 -275.644108) (xy 424.160905 -275.65004)
			(xy 424.208176 -275.663732) (xy 424.252638 -275.68483) (xy 424.293141 -275.712786) (xy 424.328634 -275.746878)
			(xy 424.358199 -275.786222) (xy 424.38107 -275.829799) (xy 424.396654 -275.87648) (xy 424.404549 -275.925057)
			(xy 424.405044 -275.949664) (xy 424.405039 -275.949918) (xy 425.693852 -275.949918) (xy 425.697812 -275.900864)
			(xy 425.709589 -275.85308) (xy 425.72888 -275.807804) (xy 425.755183 -275.766208) (xy 425.787818 -275.729371)
			(xy 425.825939 -275.698246) (xy 425.86856 -275.673639) (xy 425.914576 -275.656187) (xy 425.962795 -275.646343)
			(xy 426.01197 -275.644362) (xy 426.060825 -275.650294) (xy 426.108096 -275.663986) (xy 426.152558 -275.685084)
			(xy 426.193061 -275.71304) (xy 426.228554 -275.747132) (xy 426.258119 -275.786476) (xy 426.28099 -275.830053)
			(xy 426.296574 -275.876734) (xy 426.304469 -275.925311) (xy 426.304964 -275.949918) (xy 427.593772 -275.949918)
			(xy 427.597732 -275.900864) (xy 427.609509 -275.85308) (xy 427.6288 -275.807804) (xy 427.655103 -275.766208)
			(xy 427.687738 -275.729371) (xy 427.725859 -275.698246) (xy 427.76848 -275.673639) (xy 427.814496 -275.656187)
			(xy 427.862715 -275.646343) (xy 427.91189 -275.644362) (xy 427.960745 -275.650294) (xy 428.008016 -275.663986)
			(xy 428.052478 -275.685084) (xy 428.092981 -275.71304) (xy 428.128474 -275.747132) (xy 428.158039 -275.786476)
			(xy 428.18091 -275.830053) (xy 428.196494 -275.876734) (xy 428.204389 -275.925311) (xy 428.204884 -275.949918)
			(xy 428.204389 -275.974525) (xy 428.196494 -276.023102) (xy 428.18091 -276.069783) (xy 428.158039 -276.11336)
			(xy 428.128474 -276.152704) (xy 428.092981 -276.186796) (xy 428.052478 -276.214752) (xy 428.008016 -276.23585)
			(xy 427.960745 -276.249542) (xy 427.91189 -276.255474) (xy 427.862715 -276.253493) (xy 427.814496 -276.243649)
			(xy 427.76848 -276.226197) (xy 427.725859 -276.20159) (xy 427.687738 -276.170465) (xy 427.655103 -276.133628)
			(xy 427.6288 -276.092032) (xy 427.609509 -276.046756) (xy 427.597732 -275.998972) (xy 427.593772 -275.949918)
			(xy 426.304964 -275.949918) (xy 426.304469 -275.974525) (xy 426.296574 -276.023102) (xy 426.28099 -276.069783)
			(xy 426.258119 -276.11336) (xy 426.228554 -276.152704) (xy 426.193061 -276.186796) (xy 426.152558 -276.214752)
			(xy 426.108096 -276.23585) (xy 426.060825 -276.249542) (xy 426.01197 -276.255474) (xy 425.962795 -276.253493)
			(xy 425.914576 -276.243649) (xy 425.86856 -276.226197) (xy 425.825939 -276.20159) (xy 425.787818 -276.170465)
			(xy 425.755183 -276.133628) (xy 425.72888 -276.092032) (xy 425.709589 -276.046756) (xy 425.697812 -275.998972)
			(xy 425.693852 -275.949918) (xy 424.405039 -275.949918) (xy 424.404549 -275.974271) (xy 424.396654 -276.022848)
			(xy 424.38107 -276.069529) (xy 424.358199 -276.113106) (xy 424.328634 -276.15245) (xy 424.293141 -276.186542)
			(xy 424.252638 -276.214498) (xy 424.208176 -276.235596) (xy 424.160905 -276.249288) (xy 424.11205 -276.25522)
			(xy 424.062875 -276.253239) (xy 424.014656 -276.243395) (xy 423.96864 -276.225943) (xy 423.926019 -276.201336)
			(xy 423.887898 -276.170211) (xy 423.855263 -276.133374) (xy 423.82896 -276.091778) (xy 423.809669 -276.046502)
			(xy 423.797892 -275.998718) (xy 423.793932 -275.949664) (xy 422.504865 -275.949664) (xy 422.50487 -275.949918)
			(xy 422.504375 -275.974525) (xy 422.49648 -276.023102) (xy 422.480896 -276.069783) (xy 422.458025 -276.11336)
			(xy 422.42846 -276.152704) (xy 422.392967 -276.186796) (xy 422.352464 -276.214752) (xy 422.308002 -276.23585)
			(xy 422.260731 -276.249542) (xy 422.211876 -276.255474) (xy 422.162701 -276.253493) (xy 422.114482 -276.243649)
			(xy 422.068466 -276.226197) (xy 422.025845 -276.20159) (xy 421.987724 -276.170465) (xy 421.955089 -276.133628)
			(xy 421.928786 -276.092032) (xy 421.909495 -276.046756) (xy 421.897718 -275.998972) (xy 421.893758 -275.949918)
			(xy 420.604945 -275.949918) (xy 420.604455 -275.974271) (xy 420.59656 -276.022848) (xy 420.580976 -276.069529)
			(xy 420.558105 -276.113106) (xy 420.52854 -276.15245) (xy 420.493047 -276.186542) (xy 420.452544 -276.214498)
			(xy 420.408082 -276.235596) (xy 420.360811 -276.249288) (xy 420.311956 -276.25522) (xy 420.262781 -276.253239)
			(xy 420.214562 -276.243395) (xy 420.168546 -276.225943) (xy 420.125925 -276.201336) (xy 420.087804 -276.170211)
			(xy 420.055169 -276.133374) (xy 420.028866 -276.091778) (xy 420.009575 -276.046502) (xy 419.997798 -275.998718)
			(xy 419.993838 -275.949664) (xy 418.704771 -275.949664) (xy 418.704776 -275.949918) (xy 418.704281 -275.974525)
			(xy 418.696386 -276.023102) (xy 418.680802 -276.069783) (xy 418.657931 -276.11336) (xy 418.628366 -276.152704)
			(xy 418.592873 -276.186796) (xy 418.55237 -276.214752) (xy 418.507908 -276.23585) (xy 418.460637 -276.249542)
			(xy 418.411782 -276.255474) (xy 418.362607 -276.253493) (xy 418.314388 -276.243649) (xy 418.268372 -276.226197)
			(xy 418.225751 -276.20159) (xy 418.18763 -276.170465) (xy 418.154995 -276.133628) (xy 418.128692 -276.092032)
			(xy 418.109401 -276.046756) (xy 418.097624 -275.998972) (xy 418.093664 -275.949918) (xy 416.804851 -275.949918)
			(xy 416.804361 -275.974271) (xy 416.796466 -276.022848) (xy 416.780882 -276.069529) (xy 416.758011 -276.113106)
			(xy 416.728446 -276.15245) (xy 416.692953 -276.186542) (xy 416.65245 -276.214498) (xy 416.607988 -276.235596)
			(xy 416.560717 -276.249288) (xy 416.511862 -276.25522) (xy 416.462687 -276.253239) (xy 416.414468 -276.243395)
			(xy 416.368452 -276.225943) (xy 416.325831 -276.201336) (xy 416.28771 -276.170211) (xy 416.255075 -276.133374)
			(xy 416.228772 -276.091778) (xy 416.209481 -276.046502) (xy 416.197704 -275.998718) (xy 416.193744 -275.949664)
			(xy 414.904931 -275.949664) (xy 414.904936 -275.949918) (xy 414.904441 -275.974525) (xy 414.896546 -276.023102)
			(xy 414.880962 -276.069783) (xy 414.858091 -276.11336) (xy 414.828526 -276.152704) (xy 414.793033 -276.186796)
			(xy 414.75253 -276.214752) (xy 414.708068 -276.23585) (xy 414.660797 -276.249542) (xy 414.611942 -276.255474)
			(xy 414.562767 -276.253493) (xy 414.514548 -276.243649) (xy 414.468532 -276.226197) (xy 414.425911 -276.20159)
			(xy 414.38779 -276.170465) (xy 414.355155 -276.133628) (xy 414.328852 -276.092032) (xy 414.309561 -276.046756)
			(xy 414.297784 -275.998972) (xy 414.293824 -275.949918) (xy 413.005011 -275.949918) (xy 413.004521 -275.974271)
			(xy 412.996626 -276.022848) (xy 412.981042 -276.069529) (xy 412.958171 -276.113106) (xy 412.928606 -276.15245)
			(xy 412.893113 -276.186542) (xy 412.85261 -276.214498) (xy 412.808148 -276.235596) (xy 412.760877 -276.249288)
			(xy 412.712022 -276.25522) (xy 412.662847 -276.253239) (xy 412.614628 -276.243395) (xy 412.568612 -276.225943)
			(xy 412.525991 -276.201336) (xy 412.48787 -276.170211) (xy 412.455235 -276.133374) (xy 412.428932 -276.091778)
			(xy 412.409641 -276.046502) (xy 412.397864 -275.998718) (xy 412.393904 -275.949664) (xy 411.104837 -275.949664)
			(xy 411.104842 -275.949918) (xy 411.104347 -275.974525) (xy 411.096452 -276.023102) (xy 411.080868 -276.069783)
			(xy 411.057997 -276.11336) (xy 411.028432 -276.152704) (xy 410.992939 -276.186796) (xy 410.952436 -276.214752)
			(xy 410.907974 -276.23585) (xy 410.860703 -276.249542) (xy 410.811848 -276.255474) (xy 410.762673 -276.253493)
			(xy 410.714454 -276.243649) (xy 410.668438 -276.226197) (xy 410.625817 -276.20159) (xy 410.587696 -276.170465)
			(xy 410.555061 -276.133628) (xy 410.528758 -276.092032) (xy 410.509467 -276.046756) (xy 410.49769 -275.998972)
			(xy 410.49373 -275.949918) (xy 409.204917 -275.949918) (xy 409.204427 -275.974271) (xy 409.196532 -276.022848)
			(xy 409.180948 -276.069529) (xy 409.158077 -276.113106) (xy 409.128512 -276.15245) (xy 409.093019 -276.186542)
			(xy 409.052516 -276.214498) (xy 409.008054 -276.235596) (xy 408.960783 -276.249288) (xy 408.911928 -276.25522)
			(xy 408.862753 -276.253239) (xy 408.814534 -276.243395) (xy 408.768518 -276.225943) (xy 408.725897 -276.201336)
			(xy 408.687776 -276.170211) (xy 408.655141 -276.133374) (xy 408.628838 -276.091778) (xy 408.609547 -276.046502)
			(xy 408.59777 -275.998718) (xy 408.59381 -275.949664) (xy 407.305251 -275.949664) (xy 407.305256 -275.949918)
			(xy 407.304761 -275.974525) (xy 407.296866 -276.023102) (xy 407.281282 -276.069783) (xy 407.258411 -276.11336)
			(xy 407.228846 -276.152704) (xy 407.193353 -276.186796) (xy 407.15285 -276.214752) (xy 407.108388 -276.23585)
			(xy 407.061117 -276.249542) (xy 407.012262 -276.255474) (xy 406.963087 -276.253493) (xy 406.914868 -276.243649)
			(xy 406.868852 -276.226197) (xy 406.826231 -276.20159) (xy 406.78811 -276.170465) (xy 406.755475 -276.133628)
			(xy 406.729172 -276.092032) (xy 406.709881 -276.046756) (xy 406.698104 -275.998972) (xy 406.694144 -275.949918)
			(xy 405.405336 -275.949918) (xy 405.404841 -275.974525) (xy 405.396946 -276.023102) (xy 405.381362 -276.069783)
			(xy 405.358491 -276.11336) (xy 405.328926 -276.152704) (xy 405.293433 -276.186796) (xy 405.25293 -276.214752)
			(xy 405.208468 -276.23585) (xy 405.161197 -276.249542) (xy 405.112342 -276.255474) (xy 405.063167 -276.253493)
			(xy 405.014948 -276.243649) (xy 404.968932 -276.226197) (xy 404.926311 -276.20159) (xy 404.88819 -276.170465)
			(xy 404.855555 -276.133628) (xy 404.829252 -276.092032) (xy 404.809961 -276.046756) (xy 404.798184 -275.998972)
			(xy 404.794224 -275.949918) (xy 403.505162 -275.949918) (xy 403.504667 -275.974525) (xy 403.496772 -276.023102)
			(xy 403.481188 -276.069783) (xy 403.458317 -276.11336) (xy 403.428752 -276.152704) (xy 403.393259 -276.186796)
			(xy 403.352756 -276.214752) (xy 403.308294 -276.23585) (xy 403.261023 -276.249542) (xy 403.212168 -276.255474)
			(xy 403.162993 -276.253493) (xy 403.114774 -276.243649) (xy 403.068758 -276.226197) (xy 403.026137 -276.20159)
			(xy 402.988016 -276.170465) (xy 402.955381 -276.133628) (xy 402.929078 -276.092032) (xy 402.909787 -276.046756)
			(xy 402.89801 -275.998972) (xy 402.89405 -275.949918) (xy 401.605242 -275.949918) (xy 401.604747 -275.974525)
			(xy 401.596852 -276.023102) (xy 401.581268 -276.069783) (xy 401.558397 -276.11336) (xy 401.528832 -276.152704)
			(xy 401.493339 -276.186796) (xy 401.452836 -276.214752) (xy 401.408374 -276.23585) (xy 401.361103 -276.249542)
			(xy 401.312248 -276.255474) (xy 401.263073 -276.253493) (xy 401.214854 -276.243649) (xy 401.168838 -276.226197)
			(xy 401.126217 -276.20159) (xy 401.088096 -276.170465) (xy 401.055461 -276.133628) (xy 401.029158 -276.092032)
			(xy 401.009867 -276.046756) (xy 400.99809 -275.998972) (xy 400.99413 -275.949918) (xy 399.705322 -275.949918)
			(xy 399.704827 -275.974525) (xy 399.696932 -276.023102) (xy 399.681348 -276.069783) (xy 399.658477 -276.11336)
			(xy 399.628912 -276.152704) (xy 399.593419 -276.186796) (xy 399.552916 -276.214752) (xy 399.508454 -276.23585)
			(xy 399.461183 -276.249542) (xy 399.412328 -276.255474) (xy 399.363153 -276.253493) (xy 399.314934 -276.243649)
			(xy 399.268918 -276.226197) (xy 399.226297 -276.20159) (xy 399.188176 -276.170465) (xy 399.155541 -276.133628)
			(xy 399.129238 -276.092032) (xy 399.109947 -276.046756) (xy 399.09817 -275.998972) (xy 399.09421 -275.949918)
			(xy 397.805148 -275.949918) (xy 397.804653 -275.974525) (xy 397.796758 -276.023102) (xy 397.781174 -276.069783)
			(xy 397.758303 -276.11336) (xy 397.728738 -276.152704) (xy 397.693245 -276.186796) (xy 397.652742 -276.214752)
			(xy 397.60828 -276.23585) (xy 397.561009 -276.249542) (xy 397.512154 -276.255474) (xy 397.462979 -276.253493)
			(xy 397.41476 -276.243649) (xy 397.368744 -276.226197) (xy 397.326123 -276.20159) (xy 397.288002 -276.170465)
			(xy 397.255367 -276.133628) (xy 397.229064 -276.092032) (xy 397.209773 -276.046756) (xy 397.197996 -275.998972)
			(xy 397.194036 -275.949918) (xy 395.905228 -275.949918) (xy 395.904733 -275.974525) (xy 395.896838 -276.023102)
			(xy 395.881254 -276.069783) (xy 395.858383 -276.11336) (xy 395.828818 -276.152704) (xy 395.793325 -276.186796)
			(xy 395.752822 -276.214752) (xy 395.70836 -276.23585) (xy 395.661089 -276.249542) (xy 395.612234 -276.255474)
			(xy 395.563059 -276.253493) (xy 395.51484 -276.243649) (xy 395.468824 -276.226197) (xy 395.426203 -276.20159)
			(xy 395.388082 -276.170465) (xy 395.355447 -276.133628) (xy 395.329144 -276.092032) (xy 395.309853 -276.046756)
			(xy 395.298076 -275.998972) (xy 395.294116 -275.949918) (xy 394.005308 -275.949918) (xy 394.004813 -275.974525)
			(xy 393.996918 -276.023102) (xy 393.981334 -276.069783) (xy 393.958463 -276.11336) (xy 393.928898 -276.152704)
			(xy 393.893405 -276.186796) (xy 393.852902 -276.214752) (xy 393.80844 -276.23585) (xy 393.761169 -276.249542)
			(xy 393.712314 -276.255474) (xy 393.663139 -276.253493) (xy 393.61492 -276.243649) (xy 393.568904 -276.226197)
			(xy 393.526283 -276.20159) (xy 393.488162 -276.170465) (xy 393.455527 -276.133628) (xy 393.429224 -276.092032)
			(xy 393.409933 -276.046756) (xy 393.398156 -275.998972) (xy 393.394196 -275.949918) (xy 312.104786 -275.949918)
			(xy 312.104291 -275.974525) (xy 312.096396 -276.023102) (xy 312.080812 -276.069783) (xy 312.057941 -276.11336)
			(xy 312.028376 -276.152704) (xy 311.992883 -276.186796) (xy 311.95238 -276.214752) (xy 311.907918 -276.23585)
			(xy 311.860647 -276.249542) (xy 311.811792 -276.255474) (xy 311.762617 -276.253493) (xy 311.714398 -276.243649)
			(xy 311.668382 -276.226197) (xy 311.625761 -276.20159) (xy 311.58764 -276.170465) (xy 311.555005 -276.133628)
			(xy 311.528702 -276.092032) (xy 311.509411 -276.046756) (xy 311.497634 -275.998972) (xy 311.493674 -275.949918)
			(xy 310.204866 -275.949918) (xy 310.204371 -275.974525) (xy 310.196476 -276.023102) (xy 310.180892 -276.069783)
			(xy 310.158021 -276.11336) (xy 310.128456 -276.152704) (xy 310.092963 -276.186796) (xy 310.05246 -276.214752)
			(xy 310.007998 -276.23585) (xy 309.960727 -276.249542) (xy 309.911872 -276.255474) (xy 309.862697 -276.253493)
			(xy 309.814478 -276.243649) (xy 309.768462 -276.226197) (xy 309.725841 -276.20159) (xy 309.68772 -276.170465)
			(xy 309.655085 -276.133628) (xy 309.628782 -276.092032) (xy 309.609491 -276.046756) (xy 309.597714 -275.998972)
			(xy 309.593754 -275.949918) (xy 308.304941 -275.949918) (xy 308.304451 -275.974271) (xy 308.296556 -276.022848)
			(xy 308.280972 -276.069529) (xy 308.258101 -276.113106) (xy 308.228536 -276.15245) (xy 308.193043 -276.186542)
			(xy 308.15254 -276.214498) (xy 308.108078 -276.235596) (xy 308.060807 -276.249288) (xy 308.011952 -276.25522)
			(xy 307.962777 -276.253239) (xy 307.914558 -276.243395) (xy 307.868542 -276.225943) (xy 307.825921 -276.201336)
			(xy 307.7878 -276.170211) (xy 307.755165 -276.133374) (xy 307.728862 -276.091778) (xy 307.709571 -276.046502)
			(xy 307.697794 -275.998718) (xy 307.693834 -275.949664) (xy 306.404767 -275.949664) (xy 306.404772 -275.949918)
			(xy 306.404277 -275.974525) (xy 306.396382 -276.023102) (xy 306.380798 -276.069783) (xy 306.357927 -276.11336)
			(xy 306.328362 -276.152704) (xy 306.292869 -276.186796) (xy 306.252366 -276.214752) (xy 306.207904 -276.23585)
			(xy 306.160633 -276.249542) (xy 306.111778 -276.255474) (xy 306.062603 -276.253493) (xy 306.014384 -276.243649)
			(xy 305.968368 -276.226197) (xy 305.925747 -276.20159) (xy 305.887626 -276.170465) (xy 305.854991 -276.133628)
			(xy 305.828688 -276.092032) (xy 305.809397 -276.046756) (xy 305.79762 -275.998972) (xy 305.79366 -275.949918)
			(xy 304.504847 -275.949918) (xy 304.504357 -275.974271) (xy 304.496462 -276.022848) (xy 304.480878 -276.069529)
			(xy 304.458007 -276.113106) (xy 304.428442 -276.15245) (xy 304.392949 -276.186542) (xy 304.352446 -276.214498)
			(xy 304.307984 -276.235596) (xy 304.260713 -276.249288) (xy 304.211858 -276.25522) (xy 304.162683 -276.253239)
			(xy 304.114464 -276.243395) (xy 304.068448 -276.225943) (xy 304.025827 -276.201336) (xy 303.987706 -276.170211)
			(xy 303.955071 -276.133374) (xy 303.928768 -276.091778) (xy 303.909477 -276.046502) (xy 303.8977 -275.998718)
			(xy 303.89374 -275.949664) (xy 302.604673 -275.949664) (xy 302.604678 -275.949918) (xy 302.604183 -275.974525)
			(xy 302.596288 -276.023102) (xy 302.580704 -276.069783) (xy 302.557833 -276.11336) (xy 302.528268 -276.152704)
			(xy 302.492775 -276.186796) (xy 302.452272 -276.214752) (xy 302.40781 -276.23585) (xy 302.360539 -276.249542)
			(xy 302.311684 -276.255474) (xy 302.262509 -276.253493) (xy 302.21429 -276.243649) (xy 302.168274 -276.226197)
			(xy 302.125653 -276.20159) (xy 302.087532 -276.170465) (xy 302.054897 -276.133628) (xy 302.028594 -276.092032)
			(xy 302.009303 -276.046756) (xy 301.997526 -275.998972) (xy 301.993566 -275.949918) (xy 300.704753 -275.949918)
			(xy 300.704263 -275.974271) (xy 300.696368 -276.022848) (xy 300.680784 -276.069529) (xy 300.657913 -276.113106)
			(xy 300.628348 -276.15245) (xy 300.592855 -276.186542) (xy 300.552352 -276.214498) (xy 300.50789 -276.235596)
			(xy 300.460619 -276.249288) (xy 300.411764 -276.25522) (xy 300.362589 -276.253239) (xy 300.31437 -276.243395)
			(xy 300.268354 -276.225943) (xy 300.225733 -276.201336) (xy 300.187612 -276.170211) (xy 300.154977 -276.133374)
			(xy 300.128674 -276.091778) (xy 300.109383 -276.046502) (xy 300.097606 -275.998718) (xy 300.093646 -275.949664)
			(xy 298.804833 -275.949664) (xy 298.804838 -275.949918) (xy 298.804343 -275.974525) (xy 298.796448 -276.023102)
			(xy 298.780864 -276.069783) (xy 298.757993 -276.11336) (xy 298.728428 -276.152704) (xy 298.692935 -276.186796)
			(xy 298.652432 -276.214752) (xy 298.60797 -276.23585) (xy 298.560699 -276.249542) (xy 298.511844 -276.255474)
			(xy 298.462669 -276.253493) (xy 298.41445 -276.243649) (xy 298.368434 -276.226197) (xy 298.325813 -276.20159)
			(xy 298.287692 -276.170465) (xy 298.255057 -276.133628) (xy 298.228754 -276.092032) (xy 298.209463 -276.046756)
			(xy 298.197686 -275.998972) (xy 298.193726 -275.949918) (xy 296.904913 -275.949918) (xy 296.904423 -275.974271)
			(xy 296.896528 -276.022848) (xy 296.880944 -276.069529) (xy 296.858073 -276.113106) (xy 296.828508 -276.15245)
			(xy 296.793015 -276.186542) (xy 296.752512 -276.214498) (xy 296.70805 -276.235596) (xy 296.660779 -276.249288)
			(xy 296.611924 -276.25522) (xy 296.562749 -276.253239) (xy 296.51453 -276.243395) (xy 296.468514 -276.225943)
			(xy 296.425893 -276.201336) (xy 296.387772 -276.170211) (xy 296.355137 -276.133374) (xy 296.328834 -276.091778)
			(xy 296.309543 -276.046502) (xy 296.297766 -275.998718) (xy 296.293806 -275.949664) (xy 295.004739 -275.949664)
			(xy 295.004744 -275.949918) (xy 295.004249 -275.974525) (xy 294.996354 -276.023102) (xy 294.98077 -276.069783)
			(xy 294.957899 -276.11336) (xy 294.928334 -276.152704) (xy 294.892841 -276.186796) (xy 294.852338 -276.214752)
			(xy 294.807876 -276.23585) (xy 294.760605 -276.249542) (xy 294.71175 -276.255474) (xy 294.662575 -276.253493)
			(xy 294.614356 -276.243649) (xy 294.56834 -276.226197) (xy 294.525719 -276.20159) (xy 294.487598 -276.170465)
			(xy 294.454963 -276.133628) (xy 294.42866 -276.092032) (xy 294.409369 -276.046756) (xy 294.397592 -275.998972)
			(xy 294.393632 -275.949918) (xy 293.104819 -275.949918) (xy 293.104329 -275.974271) (xy 293.096434 -276.022848)
			(xy 293.08085 -276.069529) (xy 293.057979 -276.113106) (xy 293.028414 -276.15245) (xy 292.992921 -276.186542)
			(xy 292.952418 -276.214498) (xy 292.907956 -276.235596) (xy 292.860685 -276.249288) (xy 292.81183 -276.25522)
			(xy 292.762655 -276.253239) (xy 292.714436 -276.243395) (xy 292.66842 -276.225943) (xy 292.625799 -276.201336)
			(xy 292.587678 -276.170211) (xy 292.555043 -276.133374) (xy 292.52874 -276.091778) (xy 292.509449 -276.046502)
			(xy 292.497672 -275.998718) (xy 292.493712 -275.949664) (xy 291.205153 -275.949664) (xy 291.205158 -275.949918)
			(xy 291.204663 -275.974525) (xy 291.196768 -276.023102) (xy 291.181184 -276.069783) (xy 291.158313 -276.11336)
			(xy 291.128748 -276.152704) (xy 291.093255 -276.186796) (xy 291.052752 -276.214752) (xy 291.00829 -276.23585)
			(xy 290.961019 -276.249542) (xy 290.912164 -276.255474) (xy 290.862989 -276.253493) (xy 290.81477 -276.243649)
			(xy 290.768754 -276.226197) (xy 290.726133 -276.20159) (xy 290.688012 -276.170465) (xy 290.655377 -276.133628)
			(xy 290.629074 -276.092032) (xy 290.609783 -276.046756) (xy 290.598006 -275.998972) (xy 290.594046 -275.949918)
			(xy 289.305238 -275.949918) (xy 289.304743 -275.974525) (xy 289.296848 -276.023102) (xy 289.281264 -276.069783)
			(xy 289.258393 -276.11336) (xy 289.228828 -276.152704) (xy 289.193335 -276.186796) (xy 289.152832 -276.214752)
			(xy 289.10837 -276.23585) (xy 289.061099 -276.249542) (xy 289.012244 -276.255474) (xy 288.963069 -276.253493)
			(xy 288.91485 -276.243649) (xy 288.868834 -276.226197) (xy 288.826213 -276.20159) (xy 288.788092 -276.170465)
			(xy 288.755457 -276.133628) (xy 288.729154 -276.092032) (xy 288.709863 -276.046756) (xy 288.698086 -275.998972)
			(xy 288.694126 -275.949918) (xy 287.405064 -275.949918) (xy 287.404569 -275.974525) (xy 287.396674 -276.023102)
			(xy 287.38109 -276.069783) (xy 287.358219 -276.11336) (xy 287.328654 -276.152704) (xy 287.293161 -276.186796)
			(xy 287.252658 -276.214752) (xy 287.208196 -276.23585) (xy 287.160925 -276.249542) (xy 287.11207 -276.255474)
			(xy 287.062895 -276.253493) (xy 287.014676 -276.243649) (xy 286.96866 -276.226197) (xy 286.926039 -276.20159)
			(xy 286.887918 -276.170465) (xy 286.855283 -276.133628) (xy 286.82898 -276.092032) (xy 286.809689 -276.046756)
			(xy 286.797912 -275.998972) (xy 286.793952 -275.949918) (xy 285.505144 -275.949918) (xy 285.504649 -275.974525)
			(xy 285.496754 -276.023102) (xy 285.48117 -276.069783) (xy 285.458299 -276.11336) (xy 285.428734 -276.152704)
			(xy 285.393241 -276.186796) (xy 285.352738 -276.214752) (xy 285.308276 -276.23585) (xy 285.261005 -276.249542)
			(xy 285.21215 -276.255474) (xy 285.162975 -276.253493) (xy 285.114756 -276.243649) (xy 285.06874 -276.226197)
			(xy 285.026119 -276.20159) (xy 284.987998 -276.170465) (xy 284.955363 -276.133628) (xy 284.92906 -276.092032)
			(xy 284.909769 -276.046756) (xy 284.897992 -275.998972) (xy 284.894032 -275.949918) (xy 283.605224 -275.949918)
			(xy 283.604729 -275.974525) (xy 283.596834 -276.023102) (xy 283.58125 -276.069783) (xy 283.558379 -276.11336)
			(xy 283.528814 -276.152704) (xy 283.493321 -276.186796) (xy 283.452818 -276.214752) (xy 283.408356 -276.23585)
			(xy 283.361085 -276.249542) (xy 283.31223 -276.255474) (xy 283.263055 -276.253493) (xy 283.214836 -276.243649)
			(xy 283.16882 -276.226197) (xy 283.126199 -276.20159) (xy 283.088078 -276.170465) (xy 283.055443 -276.133628)
			(xy 283.02914 -276.092032) (xy 283.009849 -276.046756) (xy 282.998072 -275.998972) (xy 282.994112 -275.949918)
			(xy 281.70505 -275.949918) (xy 281.704555 -275.974525) (xy 281.69666 -276.023102) (xy 281.681076 -276.069783)
			(xy 281.658205 -276.11336) (xy 281.62864 -276.152704) (xy 281.593147 -276.186796) (xy 281.552644 -276.214752)
			(xy 281.508182 -276.23585) (xy 281.460911 -276.249542) (xy 281.412056 -276.255474) (xy 281.362881 -276.253493)
			(xy 281.314662 -276.243649) (xy 281.268646 -276.226197) (xy 281.226025 -276.20159) (xy 281.187904 -276.170465)
			(xy 281.155269 -276.133628) (xy 281.128966 -276.092032) (xy 281.109675 -276.046756) (xy 281.097898 -275.998972)
			(xy 281.093938 -275.949918) (xy 279.80513 -275.949918) (xy 279.804635 -275.974525) (xy 279.79674 -276.023102)
			(xy 279.781156 -276.069783) (xy 279.758285 -276.11336) (xy 279.72872 -276.152704) (xy 279.693227 -276.186796)
			(xy 279.652724 -276.214752) (xy 279.608262 -276.23585) (xy 279.560991 -276.249542) (xy 279.512136 -276.255474)
			(xy 279.462961 -276.253493) (xy 279.414742 -276.243649) (xy 279.368726 -276.226197) (xy 279.326105 -276.20159)
			(xy 279.287984 -276.170465) (xy 279.255349 -276.133628) (xy 279.229046 -276.092032) (xy 279.209755 -276.046756)
			(xy 279.197978 -275.998972) (xy 279.194018 -275.949918) (xy 277.90521 -275.949918) (xy 277.904715 -275.974525)
			(xy 277.89682 -276.023102) (xy 277.881236 -276.069783) (xy 277.858365 -276.11336) (xy 277.8288 -276.152704)
			(xy 277.793307 -276.186796) (xy 277.752804 -276.214752) (xy 277.708342 -276.23585) (xy 277.661071 -276.249542)
			(xy 277.612216 -276.255474) (xy 277.563041 -276.253493) (xy 277.514822 -276.243649) (xy 277.468806 -276.226197)
			(xy 277.426185 -276.20159) (xy 277.388064 -276.170465) (xy 277.355429 -276.133628) (xy 277.329126 -276.092032)
			(xy 277.309835 -276.046756) (xy 277.298058 -275.998972) (xy 277.294098 -275.949918) (xy 196.004942 -275.949918)
			(xy 196.004447 -275.974525) (xy 195.996552 -276.023102) (xy 195.980968 -276.069783) (xy 195.958097 -276.11336)
			(xy 195.928532 -276.152704) (xy 195.893039 -276.186796) (xy 195.852536 -276.214752) (xy 195.808074 -276.23585)
			(xy 195.760803 -276.249542) (xy 195.711948 -276.255474) (xy 195.662773 -276.253493) (xy 195.614554 -276.243649)
			(xy 195.568538 -276.226197) (xy 195.525917 -276.20159) (xy 195.487796 -276.170465) (xy 195.455161 -276.133628)
			(xy 195.428858 -276.092032) (xy 195.409567 -276.046756) (xy 195.39779 -275.998972) (xy 195.39383 -275.949918)
			(xy 194.105022 -275.949918) (xy 194.104527 -275.974525) (xy 194.096632 -276.023102) (xy 194.081048 -276.069783)
			(xy 194.058177 -276.11336) (xy 194.028612 -276.152704) (xy 193.993119 -276.186796) (xy 193.952616 -276.214752)
			(xy 193.908154 -276.23585) (xy 193.860883 -276.249542) (xy 193.812028 -276.255474) (xy 193.762853 -276.253493)
			(xy 193.714634 -276.243649) (xy 193.668618 -276.226197) (xy 193.625997 -276.20159) (xy 193.587876 -276.170465)
			(xy 193.555241 -276.133628) (xy 193.528938 -276.092032) (xy 193.509647 -276.046756) (xy 193.49787 -275.998972)
			(xy 193.49391 -275.949918) (xy 192.205097 -275.949918) (xy 192.204607 -275.974271) (xy 192.196712 -276.022848)
			(xy 192.181128 -276.069529) (xy 192.158257 -276.113106) (xy 192.128692 -276.15245) (xy 192.093199 -276.186542)
			(xy 192.052696 -276.214498) (xy 192.008234 -276.235596) (xy 191.960963 -276.249288) (xy 191.912108 -276.25522)
			(xy 191.862933 -276.253239) (xy 191.814714 -276.243395) (xy 191.768698 -276.225943) (xy 191.726077 -276.201336)
			(xy 191.687956 -276.170211) (xy 191.655321 -276.133374) (xy 191.629018 -276.091778) (xy 191.609727 -276.046502)
			(xy 191.59795 -275.998718) (xy 191.59399 -275.949664) (xy 190.304923 -275.949664) (xy 190.304928 -275.949918)
			(xy 190.304433 -275.974525) (xy 190.296538 -276.023102) (xy 190.280954 -276.069783) (xy 190.258083 -276.11336)
			(xy 190.228518 -276.152704) (xy 190.193025 -276.186796) (xy 190.152522 -276.214752) (xy 190.10806 -276.23585)
			(xy 190.060789 -276.249542) (xy 190.011934 -276.255474) (xy 189.962759 -276.253493) (xy 189.91454 -276.243649)
			(xy 189.868524 -276.226197) (xy 189.825903 -276.20159) (xy 189.787782 -276.170465) (xy 189.755147 -276.133628)
			(xy 189.728844 -276.092032) (xy 189.709553 -276.046756) (xy 189.697776 -275.998972) (xy 189.693816 -275.949918)
			(xy 188.405003 -275.949918) (xy 188.404513 -275.974271) (xy 188.396618 -276.022848) (xy 188.381034 -276.069529)
			(xy 188.358163 -276.113106) (xy 188.328598 -276.15245) (xy 188.293105 -276.186542) (xy 188.252602 -276.214498)
			(xy 188.20814 -276.235596) (xy 188.160869 -276.249288) (xy 188.112014 -276.25522) (xy 188.062839 -276.253239)
			(xy 188.01462 -276.243395) (xy 187.968604 -276.225943) (xy 187.925983 -276.201336) (xy 187.887862 -276.170211)
			(xy 187.855227 -276.133374) (xy 187.828924 -276.091778) (xy 187.809633 -276.046502) (xy 187.797856 -275.998718)
			(xy 187.793896 -275.949664) (xy 186.504829 -275.949664) (xy 186.504834 -275.949918) (xy 186.504339 -275.974525)
			(xy 186.496444 -276.023102) (xy 186.48086 -276.069783) (xy 186.457989 -276.11336) (xy 186.428424 -276.152704)
			(xy 186.392931 -276.186796) (xy 186.352428 -276.214752) (xy 186.307966 -276.23585) (xy 186.260695 -276.249542)
			(xy 186.21184 -276.255474) (xy 186.162665 -276.253493) (xy 186.114446 -276.243649) (xy 186.06843 -276.226197)
			(xy 186.025809 -276.20159) (xy 185.987688 -276.170465) (xy 185.955053 -276.133628) (xy 185.92875 -276.092032)
			(xy 185.909459 -276.046756) (xy 185.897682 -275.998972) (xy 185.893722 -275.949918) (xy 184.604909 -275.949918)
			(xy 184.604419 -275.974271) (xy 184.596524 -276.022848) (xy 184.58094 -276.069529) (xy 184.558069 -276.113106)
			(xy 184.528504 -276.15245) (xy 184.493011 -276.186542) (xy 184.452508 -276.214498) (xy 184.408046 -276.235596)
			(xy 184.360775 -276.249288) (xy 184.31192 -276.25522) (xy 184.262745 -276.253239) (xy 184.214526 -276.243395)
			(xy 184.16851 -276.225943) (xy 184.125889 -276.201336) (xy 184.087768 -276.170211) (xy 184.055133 -276.133374)
			(xy 184.02883 -276.091778) (xy 184.009539 -276.046502) (xy 183.997762 -275.998718) (xy 183.993802 -275.949664)
			(xy 182.704989 -275.949664) (xy 182.704994 -275.949918) (xy 182.704499 -275.974525) (xy 182.696604 -276.023102)
			(xy 182.68102 -276.069783) (xy 182.658149 -276.11336) (xy 182.628584 -276.152704) (xy 182.593091 -276.186796)
			(xy 182.552588 -276.214752) (xy 182.508126 -276.23585) (xy 182.460855 -276.249542) (xy 182.412 -276.255474)
			(xy 182.362825 -276.253493) (xy 182.314606 -276.243649) (xy 182.26859 -276.226197) (xy 182.225969 -276.20159)
			(xy 182.187848 -276.170465) (xy 182.155213 -276.133628) (xy 182.12891 -276.092032) (xy 182.109619 -276.046756)
			(xy 182.097842 -275.998972) (xy 182.093882 -275.949918) (xy 180.805069 -275.949918) (xy 180.804579 -275.974271)
			(xy 180.796684 -276.022848) (xy 180.7811 -276.069529) (xy 180.758229 -276.113106) (xy 180.728664 -276.15245)
			(xy 180.693171 -276.186542) (xy 180.652668 -276.214498) (xy 180.608206 -276.235596) (xy 180.560935 -276.249288)
			(xy 180.51208 -276.25522) (xy 180.462905 -276.253239) (xy 180.414686 -276.243395) (xy 180.36867 -276.225943)
			(xy 180.326049 -276.201336) (xy 180.287928 -276.170211) (xy 180.255293 -276.133374) (xy 180.22899 -276.091778)
			(xy 180.209699 -276.046502) (xy 180.197922 -275.998718) (xy 180.193962 -275.949664) (xy 178.904895 -275.949664)
			(xy 178.9049 -275.949918) (xy 178.904405 -275.974525) (xy 178.89651 -276.023102) (xy 178.880926 -276.069783)
			(xy 178.858055 -276.11336) (xy 178.82849 -276.152704) (xy 178.792997 -276.186796) (xy 178.752494 -276.214752)
			(xy 178.708032 -276.23585) (xy 178.660761 -276.249542) (xy 178.611906 -276.255474) (xy 178.562731 -276.253493)
			(xy 178.514512 -276.243649) (xy 178.468496 -276.226197) (xy 178.425875 -276.20159) (xy 178.387754 -276.170465)
			(xy 178.355119 -276.133628) (xy 178.328816 -276.092032) (xy 178.309525 -276.046756) (xy 178.297748 -275.998972)
			(xy 178.293788 -275.949918) (xy 177.004975 -275.949918) (xy 177.004485 -275.974271) (xy 176.99659 -276.022848)
			(xy 176.981006 -276.069529) (xy 176.958135 -276.113106) (xy 176.92857 -276.15245) (xy 176.893077 -276.186542)
			(xy 176.852574 -276.214498) (xy 176.808112 -276.235596) (xy 176.760841 -276.249288) (xy 176.711986 -276.25522)
			(xy 176.662811 -276.253239) (xy 176.614592 -276.243395) (xy 176.568576 -276.225943) (xy 176.525955 -276.201336)
			(xy 176.487834 -276.170211) (xy 176.455199 -276.133374) (xy 176.428896 -276.091778) (xy 176.409605 -276.046502)
			(xy 176.397828 -275.998718) (xy 176.393868 -275.949664) (xy 175.105309 -275.949664) (xy 175.105314 -275.949918)
			(xy 175.104819 -275.974525) (xy 175.096924 -276.023102) (xy 175.08134 -276.069783) (xy 175.058469 -276.11336)
			(xy 175.028904 -276.152704) (xy 174.993411 -276.186796) (xy 174.952908 -276.214752) (xy 174.908446 -276.23585)
			(xy 174.861175 -276.249542) (xy 174.81232 -276.255474) (xy 174.763145 -276.253493) (xy 174.714926 -276.243649)
			(xy 174.66891 -276.226197) (xy 174.626289 -276.20159) (xy 174.588168 -276.170465) (xy 174.555533 -276.133628)
			(xy 174.52923 -276.092032) (xy 174.509939 -276.046756) (xy 174.498162 -275.998972) (xy 174.494202 -275.949918)
			(xy 173.205394 -275.949918) (xy 173.204899 -275.974525) (xy 173.197004 -276.023102) (xy 173.18142 -276.069783)
			(xy 173.158549 -276.11336) (xy 173.128984 -276.152704) (xy 173.093491 -276.186796) (xy 173.052988 -276.214752)
			(xy 173.008526 -276.23585) (xy 172.961255 -276.249542) (xy 172.9124 -276.255474) (xy 172.863225 -276.253493)
			(xy 172.815006 -276.243649) (xy 172.76899 -276.226197) (xy 172.726369 -276.20159) (xy 172.688248 -276.170465)
			(xy 172.655613 -276.133628) (xy 172.62931 -276.092032) (xy 172.610019 -276.046756) (xy 172.598242 -275.998972)
			(xy 172.594282 -275.949918) (xy 171.30522 -275.949918) (xy 171.304725 -275.974525) (xy 171.29683 -276.023102)
			(xy 171.281246 -276.069783) (xy 171.258375 -276.11336) (xy 171.22881 -276.152704) (xy 171.193317 -276.186796)
			(xy 171.152814 -276.214752) (xy 171.108352 -276.23585) (xy 171.061081 -276.249542) (xy 171.012226 -276.255474)
			(xy 170.963051 -276.253493) (xy 170.914832 -276.243649) (xy 170.868816 -276.226197) (xy 170.826195 -276.20159)
			(xy 170.788074 -276.170465) (xy 170.755439 -276.133628) (xy 170.729136 -276.092032) (xy 170.709845 -276.046756)
			(xy 170.698068 -275.998972) (xy 170.694108 -275.949918) (xy 169.4053 -275.949918) (xy 169.404805 -275.974525)
			(xy 169.39691 -276.023102) (xy 169.381326 -276.069783) (xy 169.358455 -276.11336) (xy 169.32889 -276.152704)
			(xy 169.293397 -276.186796) (xy 169.252894 -276.214752) (xy 169.208432 -276.23585) (xy 169.161161 -276.249542)
			(xy 169.112306 -276.255474) (xy 169.063131 -276.253493) (xy 169.014912 -276.243649) (xy 168.968896 -276.226197)
			(xy 168.926275 -276.20159) (xy 168.888154 -276.170465) (xy 168.855519 -276.133628) (xy 168.829216 -276.092032)
			(xy 168.809925 -276.046756) (xy 168.798148 -275.998972) (xy 168.794188 -275.949918) (xy 167.50538 -275.949918)
			(xy 167.504885 -275.974525) (xy 167.49699 -276.023102) (xy 167.481406 -276.069783) (xy 167.458535 -276.11336)
			(xy 167.42897 -276.152704) (xy 167.393477 -276.186796) (xy 167.352974 -276.214752) (xy 167.308512 -276.23585)
			(xy 167.261241 -276.249542) (xy 167.212386 -276.255474) (xy 167.163211 -276.253493) (xy 167.114992 -276.243649)
			(xy 167.068976 -276.226197) (xy 167.026355 -276.20159) (xy 166.988234 -276.170465) (xy 166.955599 -276.133628)
			(xy 166.929296 -276.092032) (xy 166.910005 -276.046756) (xy 166.898228 -275.998972) (xy 166.894268 -275.949918)
			(xy 165.605206 -275.949918) (xy 165.604711 -275.974525) (xy 165.596816 -276.023102) (xy 165.581232 -276.069783)
			(xy 165.558361 -276.11336) (xy 165.528796 -276.152704) (xy 165.493303 -276.186796) (xy 165.4528 -276.214752)
			(xy 165.408338 -276.23585) (xy 165.361067 -276.249542) (xy 165.312212 -276.255474) (xy 165.263037 -276.253493)
			(xy 165.214818 -276.243649) (xy 165.168802 -276.226197) (xy 165.126181 -276.20159) (xy 165.08806 -276.170465)
			(xy 165.055425 -276.133628) (xy 165.029122 -276.092032) (xy 165.009831 -276.046756) (xy 164.998054 -275.998972)
			(xy 164.994094 -275.949918) (xy 163.705286 -275.949918) (xy 163.704791 -275.974525) (xy 163.696896 -276.023102)
			(xy 163.681312 -276.069783) (xy 163.658441 -276.11336) (xy 163.628876 -276.152704) (xy 163.593383 -276.186796)
			(xy 163.55288 -276.214752) (xy 163.508418 -276.23585) (xy 163.461147 -276.249542) (xy 163.412292 -276.255474)
			(xy 163.363117 -276.253493) (xy 163.314898 -276.243649) (xy 163.268882 -276.226197) (xy 163.226261 -276.20159)
			(xy 163.18814 -276.170465) (xy 163.155505 -276.133628) (xy 163.129202 -276.092032) (xy 163.109911 -276.046756)
			(xy 163.098134 -275.998972) (xy 163.094174 -275.949918) (xy 161.805366 -275.949918) (xy 161.804871 -275.974525)
			(xy 161.796976 -276.023102) (xy 161.781392 -276.069783) (xy 161.758521 -276.11336) (xy 161.728956 -276.152704)
			(xy 161.693463 -276.186796) (xy 161.65296 -276.214752) (xy 161.608498 -276.23585) (xy 161.561227 -276.249542)
			(xy 161.512372 -276.255474) (xy 161.463197 -276.253493) (xy 161.414978 -276.243649) (xy 161.368962 -276.226197)
			(xy 161.326341 -276.20159) (xy 161.28822 -276.170465) (xy 161.255585 -276.133628) (xy 161.229282 -276.092032)
			(xy 161.209991 -276.046756) (xy 161.198214 -275.998972) (xy 161.194254 -275.949918) (xy 79.904844 -275.949918)
			(xy 79.904349 -275.974525) (xy 79.896454 -276.023102) (xy 79.88087 -276.069783) (xy 79.857999 -276.11336)
			(xy 79.828434 -276.152704) (xy 79.792941 -276.186796) (xy 79.752438 -276.214752) (xy 79.707976 -276.23585)
			(xy 79.660705 -276.249542) (xy 79.61185 -276.255474) (xy 79.562675 -276.253493) (xy 79.514456 -276.243649)
			(xy 79.46844 -276.226197) (xy 79.425819 -276.20159) (xy 79.387698 -276.170465) (xy 79.355063 -276.133628)
			(xy 79.32876 -276.092032) (xy 79.309469 -276.046756) (xy 79.297692 -275.998972) (xy 79.293732 -275.949918)
			(xy 78.004924 -275.949918) (xy 78.004429 -275.974525) (xy 77.996534 -276.023102) (xy 77.98095 -276.069783)
			(xy 77.958079 -276.11336) (xy 77.928514 -276.152704) (xy 77.893021 -276.186796) (xy 77.852518 -276.214752)
			(xy 77.808056 -276.23585) (xy 77.760785 -276.249542) (xy 77.71193 -276.255474) (xy 77.662755 -276.253493)
			(xy 77.614536 -276.243649) (xy 77.56852 -276.226197) (xy 77.525899 -276.20159) (xy 77.487778 -276.170465)
			(xy 77.455143 -276.133628) (xy 77.42884 -276.092032) (xy 77.409549 -276.046756) (xy 77.397772 -275.998972)
			(xy 77.393812 -275.949918) (xy 76.104999 -275.949918) (xy 76.104509 -275.974271) (xy 76.096614 -276.022848)
			(xy 76.08103 -276.069529) (xy 76.058159 -276.113106) (xy 76.028594 -276.15245) (xy 75.993101 -276.186542)
			(xy 75.952598 -276.214498) (xy 75.908136 -276.235596) (xy 75.860865 -276.249288) (xy 75.81201 -276.25522)
			(xy 75.762835 -276.253239) (xy 75.714616 -276.243395) (xy 75.6686 -276.225943) (xy 75.625979 -276.201336)
			(xy 75.587858 -276.170211) (xy 75.555223 -276.133374) (xy 75.52892 -276.091778) (xy 75.509629 -276.046502)
			(xy 75.497852 -275.998718) (xy 75.493892 -275.949664) (xy 74.204825 -275.949664) (xy 74.20483 -275.949918)
			(xy 74.204335 -275.974525) (xy 74.19644 -276.023102) (xy 74.180856 -276.069783) (xy 74.157985 -276.11336)
			(xy 74.12842 -276.152704) (xy 74.092927 -276.186796) (xy 74.052424 -276.214752) (xy 74.007962 -276.23585)
			(xy 73.960691 -276.249542) (xy 73.911836 -276.255474) (xy 73.862661 -276.253493) (xy 73.814442 -276.243649)
			(xy 73.768426 -276.226197) (xy 73.725805 -276.20159) (xy 73.687684 -276.170465) (xy 73.655049 -276.133628)
			(xy 73.628746 -276.092032) (xy 73.609455 -276.046756) (xy 73.597678 -275.998972) (xy 73.593718 -275.949918)
			(xy 72.304905 -275.949918) (xy 72.304415 -275.974271) (xy 72.29652 -276.022848) (xy 72.280936 -276.069529)
			(xy 72.258065 -276.113106) (xy 72.2285 -276.15245) (xy 72.193007 -276.186542) (xy 72.152504 -276.214498)
			(xy 72.108042 -276.235596) (xy 72.060771 -276.249288) (xy 72.011916 -276.25522) (xy 71.962741 -276.253239)
			(xy 71.914522 -276.243395) (xy 71.868506 -276.225943) (xy 71.825885 -276.201336) (xy 71.787764 -276.170211)
			(xy 71.755129 -276.133374) (xy 71.728826 -276.091778) (xy 71.709535 -276.046502) (xy 71.697758 -275.998718)
			(xy 71.693798 -275.949664) (xy 70.404731 -275.949664) (xy 70.404736 -275.949918) (xy 70.404241 -275.974525)
			(xy 70.396346 -276.023102) (xy 70.380762 -276.069783) (xy 70.357891 -276.11336) (xy 70.328326 -276.152704)
			(xy 70.292833 -276.186796) (xy 70.25233 -276.214752) (xy 70.207868 -276.23585) (xy 70.160597 -276.249542)
			(xy 70.111742 -276.255474) (xy 70.062567 -276.253493) (xy 70.014348 -276.243649) (xy 69.968332 -276.226197)
			(xy 69.925711 -276.20159) (xy 69.88759 -276.170465) (xy 69.854955 -276.133628) (xy 69.828652 -276.092032)
			(xy 69.809361 -276.046756) (xy 69.797584 -275.998972) (xy 69.793624 -275.949918) (xy 68.504811 -275.949918)
			(xy 68.504321 -275.974271) (xy 68.496426 -276.022848) (xy 68.480842 -276.069529) (xy 68.457971 -276.113106)
			(xy 68.428406 -276.15245) (xy 68.392913 -276.186542) (xy 68.35241 -276.214498) (xy 68.307948 -276.235596)
			(xy 68.260677 -276.249288) (xy 68.211822 -276.25522) (xy 68.162647 -276.253239) (xy 68.114428 -276.243395)
			(xy 68.068412 -276.225943) (xy 68.025791 -276.201336) (xy 67.98767 -276.170211) (xy 67.955035 -276.133374)
			(xy 67.928732 -276.091778) (xy 67.909441 -276.046502) (xy 67.897664 -275.998718) (xy 67.893704 -275.949664)
			(xy 66.604891 -275.949664) (xy 66.604896 -275.949918) (xy 66.604401 -275.974525) (xy 66.596506 -276.023102)
			(xy 66.580922 -276.069783) (xy 66.558051 -276.11336) (xy 66.528486 -276.152704) (xy 66.492993 -276.186796)
			(xy 66.45249 -276.214752) (xy 66.408028 -276.23585) (xy 66.360757 -276.249542) (xy 66.311902 -276.255474)
			(xy 66.262727 -276.253493) (xy 66.214508 -276.243649) (xy 66.168492 -276.226197) (xy 66.125871 -276.20159)
			(xy 66.08775 -276.170465) (xy 66.055115 -276.133628) (xy 66.028812 -276.092032) (xy 66.009521 -276.046756)
			(xy 65.997744 -275.998972) (xy 65.993784 -275.949918) (xy 64.704971 -275.949918) (xy 64.704481 -275.974271)
			(xy 64.696586 -276.022848) (xy 64.681002 -276.069529) (xy 64.658131 -276.113106) (xy 64.628566 -276.15245)
			(xy 64.593073 -276.186542) (xy 64.55257 -276.214498) (xy 64.508108 -276.235596) (xy 64.460837 -276.249288)
			(xy 64.411982 -276.25522) (xy 64.362807 -276.253239) (xy 64.314588 -276.243395) (xy 64.268572 -276.225943)
			(xy 64.225951 -276.201336) (xy 64.18783 -276.170211) (xy 64.155195 -276.133374) (xy 64.128892 -276.091778)
			(xy 64.109601 -276.046502) (xy 64.097824 -275.998718) (xy 64.093864 -275.949664) (xy 62.804797 -275.949664)
			(xy 62.804802 -275.949918) (xy 62.804307 -275.974525) (xy 62.796412 -276.023102) (xy 62.780828 -276.069783)
			(xy 62.757957 -276.11336) (xy 62.728392 -276.152704) (xy 62.692899 -276.186796) (xy 62.652396 -276.214752)
			(xy 62.607934 -276.23585) (xy 62.560663 -276.249542) (xy 62.511808 -276.255474) (xy 62.462633 -276.253493)
			(xy 62.414414 -276.243649) (xy 62.368398 -276.226197) (xy 62.325777 -276.20159) (xy 62.287656 -276.170465)
			(xy 62.255021 -276.133628) (xy 62.228718 -276.092032) (xy 62.209427 -276.046756) (xy 62.19765 -275.998972)
			(xy 62.19369 -275.949918) (xy 60.904877 -275.949918) (xy 60.904387 -275.974271) (xy 60.896492 -276.022848)
			(xy 60.880908 -276.069529) (xy 60.858037 -276.113106) (xy 60.828472 -276.15245) (xy 60.792979 -276.186542)
			(xy 60.752476 -276.214498) (xy 60.708014 -276.235596) (xy 60.660743 -276.249288) (xy 60.611888 -276.25522)
			(xy 60.562713 -276.253239) (xy 60.514494 -276.243395) (xy 60.468478 -276.225943) (xy 60.425857 -276.201336)
			(xy 60.387736 -276.170211) (xy 60.355101 -276.133374) (xy 60.328798 -276.091778) (xy 60.309507 -276.046502)
			(xy 60.29773 -275.998718) (xy 60.29377 -275.949664) (xy 59.005211 -275.949664) (xy 59.005216 -275.949918)
			(xy 59.004721 -275.974525) (xy 58.996826 -276.023102) (xy 58.981242 -276.069783) (xy 58.958371 -276.11336)
			(xy 58.928806 -276.152704) (xy 58.893313 -276.186796) (xy 58.85281 -276.214752) (xy 58.808348 -276.23585)
			(xy 58.761077 -276.249542) (xy 58.712222 -276.255474) (xy 58.663047 -276.253493) (xy 58.614828 -276.243649)
			(xy 58.568812 -276.226197) (xy 58.526191 -276.20159) (xy 58.48807 -276.170465) (xy 58.455435 -276.133628)
			(xy 58.429132 -276.092032) (xy 58.409841 -276.046756) (xy 58.398064 -275.998972) (xy 58.394104 -275.949918)
			(xy 57.105296 -275.949918) (xy 57.104801 -275.974525) (xy 57.096906 -276.023102) (xy 57.081322 -276.069783)
			(xy 57.058451 -276.11336) (xy 57.028886 -276.152704) (xy 56.993393 -276.186796) (xy 56.95289 -276.214752)
			(xy 56.908428 -276.23585) (xy 56.861157 -276.249542) (xy 56.812302 -276.255474) (xy 56.763127 -276.253493)
			(xy 56.714908 -276.243649) (xy 56.668892 -276.226197) (xy 56.626271 -276.20159) (xy 56.58815 -276.170465)
			(xy 56.555515 -276.133628) (xy 56.529212 -276.092032) (xy 56.509921 -276.046756) (xy 56.498144 -275.998972)
			(xy 56.494184 -275.949918) (xy 55.205122 -275.949918) (xy 55.204627 -275.974525) (xy 55.196732 -276.023102)
			(xy 55.181148 -276.069783) (xy 55.158277 -276.11336) (xy 55.128712 -276.152704) (xy 55.093219 -276.186796)
			(xy 55.052716 -276.214752) (xy 55.008254 -276.23585) (xy 54.960983 -276.249542) (xy 54.912128 -276.255474)
			(xy 54.862953 -276.253493) (xy 54.814734 -276.243649) (xy 54.768718 -276.226197) (xy 54.726097 -276.20159)
			(xy 54.687976 -276.170465) (xy 54.655341 -276.133628) (xy 54.629038 -276.092032) (xy 54.609747 -276.046756)
			(xy 54.59797 -275.998972) (xy 54.59401 -275.949918) (xy 53.305202 -275.949918) (xy 53.304707 -275.974525)
			(xy 53.296812 -276.023102) (xy 53.281228 -276.069783) (xy 53.258357 -276.11336) (xy 53.228792 -276.152704)
			(xy 53.193299 -276.186796) (xy 53.152796 -276.214752) (xy 53.108334 -276.23585) (xy 53.061063 -276.249542)
			(xy 53.012208 -276.255474) (xy 52.963033 -276.253493) (xy 52.914814 -276.243649) (xy 52.868798 -276.226197)
			(xy 52.826177 -276.20159) (xy 52.788056 -276.170465) (xy 52.755421 -276.133628) (xy 52.729118 -276.092032)
			(xy 52.709827 -276.046756) (xy 52.69805 -275.998972) (xy 52.69409 -275.949918) (xy 51.405282 -275.949918)
			(xy 51.404787 -275.974525) (xy 51.396892 -276.023102) (xy 51.381308 -276.069783) (xy 51.358437 -276.11336)
			(xy 51.328872 -276.152704) (xy 51.293379 -276.186796) (xy 51.252876 -276.214752) (xy 51.208414 -276.23585)
			(xy 51.161143 -276.249542) (xy 51.112288 -276.255474) (xy 51.063113 -276.253493) (xy 51.014894 -276.243649)
			(xy 50.968878 -276.226197) (xy 50.926257 -276.20159) (xy 50.888136 -276.170465) (xy 50.855501 -276.133628)
			(xy 50.829198 -276.092032) (xy 50.809907 -276.046756) (xy 50.79813 -275.998972) (xy 50.79417 -275.949918)
			(xy 49.505108 -275.949918) (xy 49.504613 -275.974525) (xy 49.496718 -276.023102) (xy 49.481134 -276.069783)
			(xy 49.458263 -276.11336) (xy 49.428698 -276.152704) (xy 49.393205 -276.186796) (xy 49.352702 -276.214752)
			(xy 49.30824 -276.23585) (xy 49.260969 -276.249542) (xy 49.212114 -276.255474) (xy 49.162939 -276.253493)
			(xy 49.11472 -276.243649) (xy 49.068704 -276.226197) (xy 49.026083 -276.20159) (xy 48.987962 -276.170465)
			(xy 48.955327 -276.133628) (xy 48.929024 -276.092032) (xy 48.909733 -276.046756) (xy 48.897956 -275.998972)
			(xy 48.893996 -275.949918) (xy 47.605188 -275.949918) (xy 47.604693 -275.974525) (xy 47.596798 -276.023102)
			(xy 47.581214 -276.069783) (xy 47.558343 -276.11336) (xy 47.528778 -276.152704) (xy 47.493285 -276.186796)
			(xy 47.452782 -276.214752) (xy 47.40832 -276.23585) (xy 47.361049 -276.249542) (xy 47.312194 -276.255474)
			(xy 47.263019 -276.253493) (xy 47.2148 -276.243649) (xy 47.168784 -276.226197) (xy 47.126163 -276.20159)
			(xy 47.088042 -276.170465) (xy 47.055407 -276.133628) (xy 47.029104 -276.092032) (xy 47.009813 -276.046756)
			(xy 46.998036 -275.998972) (xy 46.994076 -275.949918) (xy 45.705268 -275.949918) (xy 45.704773 -275.974525)
			(xy 45.696878 -276.023102) (xy 45.681294 -276.069783) (xy 45.658423 -276.11336) (xy 45.628858 -276.152704)
			(xy 45.593365 -276.186796) (xy 45.552862 -276.214752) (xy 45.5084 -276.23585) (xy 45.461129 -276.249542)
			(xy 45.412274 -276.255474) (xy 45.363099 -276.253493) (xy 45.31488 -276.243649) (xy 45.268864 -276.226197)
			(xy 45.226243 -276.20159) (xy 45.188122 -276.170465) (xy 45.155487 -276.133628) (xy 45.129184 -276.092032)
			(xy 45.109893 -276.046756) (xy 45.098116 -275.998972) (xy 45.094156 -275.949918) (xy 0.509016 -275.949918)
			(xy 0.509016 -276.899878) (xy 81.19416 -276.899878) (xy 81.19812 -276.850824) (xy 81.209897 -276.80304)
			(xy 81.229188 -276.757764) (xy 81.255491 -276.716168) (xy 81.288126 -276.679331) (xy 81.326247 -276.648206)
			(xy 81.368868 -276.623599) (xy 81.414884 -276.606147) (xy 81.463103 -276.596303) (xy 81.512278 -276.594322)
			(xy 81.561133 -276.600254) (xy 81.608404 -276.613946) (xy 81.652866 -276.635044) (xy 81.693369 -276.663)
			(xy 81.728862 -276.697092) (xy 81.758427 -276.736436) (xy 81.781298 -276.780013) (xy 81.796882 -276.826694)
			(xy 81.804777 -276.875271) (xy 81.805272 -276.899878) (xy 82.14412 -276.899878) (xy 82.14808 -276.850824)
			(xy 82.159857 -276.80304) (xy 82.179148 -276.757764) (xy 82.205451 -276.716168) (xy 82.238086 -276.679331)
			(xy 82.276207 -276.648206) (xy 82.318828 -276.623599) (xy 82.364844 -276.606147) (xy 82.413063 -276.596303)
			(xy 82.462238 -276.594322) (xy 82.511093 -276.600254) (xy 82.558364 -276.613946) (xy 82.602826 -276.635044)
			(xy 82.643329 -276.663) (xy 82.678822 -276.697092) (xy 82.708387 -276.736436) (xy 82.731258 -276.780013)
			(xy 82.746842 -276.826694) (xy 82.754737 -276.875271) (xy 82.755232 -276.899878) (xy 197.294258 -276.899878)
			(xy 197.298218 -276.850824) (xy 197.309995 -276.80304) (xy 197.329286 -276.757764) (xy 197.355589 -276.716168)
			(xy 197.388224 -276.679331) (xy 197.426345 -276.648206) (xy 197.468966 -276.623599) (xy 197.514982 -276.606147)
			(xy 197.563201 -276.596303) (xy 197.612376 -276.594322) (xy 197.661231 -276.600254) (xy 197.708502 -276.613946)
			(xy 197.752964 -276.635044) (xy 197.793467 -276.663) (xy 197.82896 -276.697092) (xy 197.858525 -276.736436)
			(xy 197.881396 -276.780013) (xy 197.89698 -276.826694) (xy 197.904875 -276.875271) (xy 197.90537 -276.899878)
			(xy 198.244218 -276.899878) (xy 198.248178 -276.850824) (xy 198.259955 -276.80304) (xy 198.279246 -276.757764)
			(xy 198.305549 -276.716168) (xy 198.338184 -276.679331) (xy 198.376305 -276.648206) (xy 198.418926 -276.623599)
			(xy 198.464942 -276.606147) (xy 198.513161 -276.596303) (xy 198.562336 -276.594322) (xy 198.611191 -276.600254)
			(xy 198.658462 -276.613946) (xy 198.702924 -276.635044) (xy 198.743427 -276.663) (xy 198.77892 -276.697092)
			(xy 198.808485 -276.736436) (xy 198.831356 -276.780013) (xy 198.84694 -276.826694) (xy 198.854835 -276.875271)
			(xy 198.85533 -276.899878) (xy 313.394102 -276.899878) (xy 313.398062 -276.850824) (xy 313.409839 -276.80304)
			(xy 313.42913 -276.757764) (xy 313.455433 -276.716168) (xy 313.488068 -276.679331) (xy 313.526189 -276.648206)
			(xy 313.56881 -276.623599) (xy 313.614826 -276.606147) (xy 313.663045 -276.596303) (xy 313.71222 -276.594322)
			(xy 313.761075 -276.600254) (xy 313.808346 -276.613946) (xy 313.852808 -276.635044) (xy 313.893311 -276.663)
			(xy 313.928804 -276.697092) (xy 313.958369 -276.736436) (xy 313.98124 -276.780013) (xy 313.996824 -276.826694)
			(xy 314.004719 -276.875271) (xy 314.005214 -276.899878) (xy 314.344062 -276.899878) (xy 314.348022 -276.850824)
			(xy 314.359799 -276.80304) (xy 314.37909 -276.757764) (xy 314.405393 -276.716168) (xy 314.438028 -276.679331)
			(xy 314.476149 -276.648206) (xy 314.51877 -276.623599) (xy 314.564786 -276.606147) (xy 314.613005 -276.596303)
			(xy 314.66218 -276.594322) (xy 314.711035 -276.600254) (xy 314.758306 -276.613946) (xy 314.802768 -276.635044)
			(xy 314.843271 -276.663) (xy 314.878764 -276.697092) (xy 314.908329 -276.736436) (xy 314.9312 -276.780013)
			(xy 314.946784 -276.826694) (xy 314.954679 -276.875271) (xy 314.955174 -276.899878) (xy 429.4942 -276.899878)
			(xy 429.49816 -276.850824) (xy 429.509937 -276.80304) (xy 429.529228 -276.757764) (xy 429.555531 -276.716168)
			(xy 429.588166 -276.679331) (xy 429.626287 -276.648206) (xy 429.668908 -276.623599) (xy 429.714924 -276.606147)
			(xy 429.763143 -276.596303) (xy 429.812318 -276.594322) (xy 429.861173 -276.600254) (xy 429.908444 -276.613946)
			(xy 429.952906 -276.635044) (xy 429.993409 -276.663) (xy 430.028902 -276.697092) (xy 430.058467 -276.736436)
			(xy 430.081338 -276.780013) (xy 430.096922 -276.826694) (xy 430.104817 -276.875271) (xy 430.105312 -276.899878)
			(xy 430.44416 -276.899878) (xy 430.44812 -276.850824) (xy 430.459897 -276.80304) (xy 430.479188 -276.757764)
			(xy 430.505491 -276.716168) (xy 430.538126 -276.679331) (xy 430.576247 -276.648206) (xy 430.618868 -276.623599)
			(xy 430.664884 -276.606147) (xy 430.713103 -276.596303) (xy 430.762278 -276.594322) (xy 430.811133 -276.600254)
			(xy 430.858404 -276.613946) (xy 430.902866 -276.635044) (xy 430.943369 -276.663) (xy 430.978862 -276.697092)
			(xy 431.008427 -276.736436) (xy 431.031298 -276.780013) (xy 431.046882 -276.826694) (xy 431.054777 -276.875271)
			(xy 431.055272 -276.899878) (xy 431.054777 -276.924485) (xy 431.046882 -276.973062) (xy 431.031298 -277.019743)
			(xy 431.008427 -277.06332) (xy 430.978862 -277.102664) (xy 430.943369 -277.136756) (xy 430.902866 -277.164712)
			(xy 430.858404 -277.18581) (xy 430.811133 -277.199502) (xy 430.762278 -277.205434) (xy 430.713103 -277.203453)
			(xy 430.664884 -277.193609) (xy 430.618868 -277.176157) (xy 430.576247 -277.15155) (xy 430.538126 -277.120425)
			(xy 430.505491 -277.083588) (xy 430.479188 -277.041992) (xy 430.459897 -276.996716) (xy 430.44812 -276.948932)
			(xy 430.44416 -276.899878) (xy 430.105312 -276.899878) (xy 430.104817 -276.924485) (xy 430.096922 -276.973062)
			(xy 430.081338 -277.019743) (xy 430.058467 -277.06332) (xy 430.028902 -277.102664) (xy 429.993409 -277.136756)
			(xy 429.952906 -277.164712) (xy 429.908444 -277.18581) (xy 429.861173 -277.199502) (xy 429.812318 -277.205434)
			(xy 429.763143 -277.203453) (xy 429.714924 -277.193609) (xy 429.668908 -277.176157) (xy 429.626287 -277.15155)
			(xy 429.588166 -277.120425) (xy 429.555531 -277.083588) (xy 429.529228 -277.041992) (xy 429.509937 -276.996716)
			(xy 429.49816 -276.948932) (xy 429.4942 -276.899878) (xy 314.955174 -276.899878) (xy 314.954679 -276.924485)
			(xy 314.946784 -276.973062) (xy 314.9312 -277.019743) (xy 314.908329 -277.06332) (xy 314.878764 -277.102664)
			(xy 314.843271 -277.136756) (xy 314.802768 -277.164712) (xy 314.758306 -277.18581) (xy 314.711035 -277.199502)
			(xy 314.66218 -277.205434) (xy 314.613005 -277.203453) (xy 314.564786 -277.193609) (xy 314.51877 -277.176157)
			(xy 314.476149 -277.15155) (xy 314.438028 -277.120425) (xy 314.405393 -277.083588) (xy 314.37909 -277.041992)
			(xy 314.359799 -276.996716) (xy 314.348022 -276.948932) (xy 314.344062 -276.899878) (xy 314.005214 -276.899878)
			(xy 314.004719 -276.924485) (xy 313.996824 -276.973062) (xy 313.98124 -277.019743) (xy 313.958369 -277.06332)
			(xy 313.928804 -277.102664) (xy 313.893311 -277.136756) (xy 313.852808 -277.164712) (xy 313.808346 -277.18581)
			(xy 313.761075 -277.199502) (xy 313.71222 -277.205434) (xy 313.663045 -277.203453) (xy 313.614826 -277.193609)
			(xy 313.56881 -277.176157) (xy 313.526189 -277.15155) (xy 313.488068 -277.120425) (xy 313.455433 -277.083588)
			(xy 313.42913 -277.041992) (xy 313.409839 -276.996716) (xy 313.398062 -276.948932) (xy 313.394102 -276.899878)
			(xy 198.85533 -276.899878) (xy 198.854835 -276.924485) (xy 198.84694 -276.973062) (xy 198.831356 -277.019743)
			(xy 198.808485 -277.06332) (xy 198.77892 -277.102664) (xy 198.743427 -277.136756) (xy 198.702924 -277.164712)
			(xy 198.658462 -277.18581) (xy 198.611191 -277.199502) (xy 198.562336 -277.205434) (xy 198.513161 -277.203453)
			(xy 198.464942 -277.193609) (xy 198.418926 -277.176157) (xy 198.376305 -277.15155) (xy 198.338184 -277.120425)
			(xy 198.305549 -277.083588) (xy 198.279246 -277.041992) (xy 198.259955 -276.996716) (xy 198.248178 -276.948932)
			(xy 198.244218 -276.899878) (xy 197.90537 -276.899878) (xy 197.904875 -276.924485) (xy 197.89698 -276.973062)
			(xy 197.881396 -277.019743) (xy 197.858525 -277.06332) (xy 197.82896 -277.102664) (xy 197.793467 -277.136756)
			(xy 197.752964 -277.164712) (xy 197.708502 -277.18581) (xy 197.661231 -277.199502) (xy 197.612376 -277.205434)
			(xy 197.563201 -277.203453) (xy 197.514982 -277.193609) (xy 197.468966 -277.176157) (xy 197.426345 -277.15155)
			(xy 197.388224 -277.120425) (xy 197.355589 -277.083588) (xy 197.329286 -277.041992) (xy 197.309995 -276.996716)
			(xy 197.298218 -276.948932) (xy 197.294258 -276.899878) (xy 82.755232 -276.899878) (xy 82.754737 -276.924485)
			(xy 82.746842 -276.973062) (xy 82.731258 -277.019743) (xy 82.708387 -277.06332) (xy 82.678822 -277.102664)
			(xy 82.643329 -277.136756) (xy 82.602826 -277.164712) (xy 82.558364 -277.18581) (xy 82.511093 -277.199502)
			(xy 82.462238 -277.205434) (xy 82.413063 -277.203453) (xy 82.364844 -277.193609) (xy 82.318828 -277.176157)
			(xy 82.276207 -277.15155) (xy 82.238086 -277.120425) (xy 82.205451 -277.083588) (xy 82.179148 -277.041992)
			(xy 82.159857 -276.996716) (xy 82.14808 -276.948932) (xy 82.14412 -276.899878) (xy 81.805272 -276.899878)
			(xy 81.804777 -276.924485) (xy 81.796882 -276.973062) (xy 81.781298 -277.019743) (xy 81.758427 -277.06332)
			(xy 81.728862 -277.102664) (xy 81.693369 -277.136756) (xy 81.652866 -277.164712) (xy 81.608404 -277.18581)
			(xy 81.561133 -277.199502) (xy 81.512278 -277.205434) (xy 81.463103 -277.203453) (xy 81.414884 -277.193609)
			(xy 81.368868 -277.176157) (xy 81.326247 -277.15155) (xy 81.288126 -277.120425) (xy 81.255491 -277.083588)
			(xy 81.229188 -277.041992) (xy 81.209897 -276.996716) (xy 81.19812 -276.948932) (xy 81.19416 -276.899878)
			(xy 0.509016 -276.899878) (xy 0.509016 -277.849838) (xy 44.143942 -277.849838) (xy 44.147902 -277.800784)
			(xy 44.159679 -277.753) (xy 44.17897 -277.707724) (xy 44.205273 -277.666128) (xy 44.237908 -277.629291)
			(xy 44.276029 -277.598166) (xy 44.31865 -277.573559) (xy 44.364666 -277.556107) (xy 44.412885 -277.546263)
			(xy 44.46206 -277.544282) (xy 44.510915 -277.550214) (xy 44.558186 -277.563906) (xy 44.602648 -277.585004)
			(xy 44.643151 -277.61296) (xy 44.678644 -277.647052) (xy 44.708209 -277.686396) (xy 44.73108 -277.729973)
			(xy 44.746664 -277.776654) (xy 44.754559 -277.825231) (xy 44.755054 -277.849838) (xy 46.044116 -277.849838)
			(xy 46.048076 -277.800784) (xy 46.059853 -277.753) (xy 46.079144 -277.707724) (xy 46.105447 -277.666128)
			(xy 46.138082 -277.629291) (xy 46.176203 -277.598166) (xy 46.218824 -277.573559) (xy 46.26484 -277.556107)
			(xy 46.313059 -277.546263) (xy 46.362234 -277.544282) (xy 46.411089 -277.550214) (xy 46.45836 -277.563906)
			(xy 46.502822 -277.585004) (xy 46.543325 -277.61296) (xy 46.578818 -277.647052) (xy 46.608383 -277.686396)
			(xy 46.631254 -277.729973) (xy 46.646838 -277.776654) (xy 46.654733 -277.825231) (xy 46.655228 -277.849838)
			(xy 47.944036 -277.849838) (xy 47.947996 -277.800784) (xy 47.959773 -277.753) (xy 47.979064 -277.707724)
			(xy 48.005367 -277.666128) (xy 48.038002 -277.629291) (xy 48.076123 -277.598166) (xy 48.118744 -277.573559)
			(xy 48.16476 -277.556107) (xy 48.212979 -277.546263) (xy 48.262154 -277.544282) (xy 48.311009 -277.550214)
			(xy 48.35828 -277.563906) (xy 48.402742 -277.585004) (xy 48.443245 -277.61296) (xy 48.478738 -277.647052)
			(xy 48.508303 -277.686396) (xy 48.531174 -277.729973) (xy 48.546758 -277.776654) (xy 48.554653 -277.825231)
			(xy 48.555148 -277.849838) (xy 49.843956 -277.849838) (xy 49.847916 -277.800784) (xy 49.859693 -277.753)
			(xy 49.878984 -277.707724) (xy 49.905287 -277.666128) (xy 49.937922 -277.629291) (xy 49.976043 -277.598166)
			(xy 50.018664 -277.573559) (xy 50.06468 -277.556107) (xy 50.112899 -277.546263) (xy 50.162074 -277.544282)
			(xy 50.210929 -277.550214) (xy 50.2582 -277.563906) (xy 50.302662 -277.585004) (xy 50.343165 -277.61296)
			(xy 50.378658 -277.647052) (xy 50.408223 -277.686396) (xy 50.431094 -277.729973) (xy 50.446678 -277.776654)
			(xy 50.454573 -277.825231) (xy 50.455068 -277.849838) (xy 51.74413 -277.849838) (xy 51.74809 -277.800784)
			(xy 51.759867 -277.753) (xy 51.779158 -277.707724) (xy 51.805461 -277.666128) (xy 51.838096 -277.629291)
			(xy 51.876217 -277.598166) (xy 51.918838 -277.573559) (xy 51.964854 -277.556107) (xy 52.013073 -277.546263)
			(xy 52.062248 -277.544282) (xy 52.111103 -277.550214) (xy 52.158374 -277.563906) (xy 52.202836 -277.585004)
			(xy 52.243339 -277.61296) (xy 52.278832 -277.647052) (xy 52.308397 -277.686396) (xy 52.331268 -277.729973)
			(xy 52.346852 -277.776654) (xy 52.354747 -277.825231) (xy 52.355242 -277.849838) (xy 53.64405 -277.849838)
			(xy 53.64801 -277.800784) (xy 53.659787 -277.753) (xy 53.679078 -277.707724) (xy 53.705381 -277.666128)
			(xy 53.738016 -277.629291) (xy 53.776137 -277.598166) (xy 53.818758 -277.573559) (xy 53.864774 -277.556107)
			(xy 53.912993 -277.546263) (xy 53.962168 -277.544282) (xy 54.011023 -277.550214) (xy 54.058294 -277.563906)
			(xy 54.102756 -277.585004) (xy 54.143259 -277.61296) (xy 54.178752 -277.647052) (xy 54.208317 -277.686396)
			(xy 54.231188 -277.729973) (xy 54.246772 -277.776654) (xy 54.254667 -277.825231) (xy 54.255162 -277.849838)
			(xy 55.54397 -277.849838) (xy 55.54793 -277.800784) (xy 55.559707 -277.753) (xy 55.578998 -277.707724)
			(xy 55.605301 -277.666128) (xy 55.637936 -277.629291) (xy 55.676057 -277.598166) (xy 55.718678 -277.573559)
			(xy 55.764694 -277.556107) (xy 55.812913 -277.546263) (xy 55.862088 -277.544282) (xy 55.910943 -277.550214)
			(xy 55.958214 -277.563906) (xy 56.002676 -277.585004) (xy 56.043179 -277.61296) (xy 56.078672 -277.647052)
			(xy 56.108237 -277.686396) (xy 56.131108 -277.729973) (xy 56.146692 -277.776654) (xy 56.154587 -277.825231)
			(xy 56.155082 -277.849838) (xy 57.444144 -277.849838) (xy 57.448104 -277.800784) (xy 57.459881 -277.753)
			(xy 57.479172 -277.707724) (xy 57.505475 -277.666128) (xy 57.53811 -277.629291) (xy 57.576231 -277.598166)
			(xy 57.618852 -277.573559) (xy 57.664868 -277.556107) (xy 57.713087 -277.546263) (xy 57.762262 -277.544282)
			(xy 57.811117 -277.550214) (xy 57.858388 -277.563906) (xy 57.90285 -277.585004) (xy 57.943353 -277.61296)
			(xy 57.978846 -277.647052) (xy 58.008411 -277.686396) (xy 58.031282 -277.729973) (xy 58.046866 -277.776654)
			(xy 58.054761 -277.825231) (xy 58.055256 -277.849838) (xy 59.34381 -277.849838) (xy 59.34777 -277.800784)
			(xy 59.359547 -277.753) (xy 59.378838 -277.707724) (xy 59.405141 -277.666128) (xy 59.437776 -277.629291)
			(xy 59.475897 -277.598166) (xy 59.518518 -277.573559) (xy 59.564534 -277.556107) (xy 59.612753 -277.546263)
			(xy 59.661928 -277.544282) (xy 59.710783 -277.550214) (xy 59.758054 -277.563906) (xy 59.802516 -277.585004)
			(xy 59.843019 -277.61296) (xy 59.878512 -277.647052) (xy 59.908077 -277.686396) (xy 59.930948 -277.729973)
			(xy 59.946532 -277.776654) (xy 59.954427 -277.825231) (xy 59.954922 -277.849838) (xy 61.24373 -277.849838)
			(xy 61.24769 -277.800784) (xy 61.259467 -277.753) (xy 61.278758 -277.707724) (xy 61.305061 -277.666128)
			(xy 61.337696 -277.629291) (xy 61.375817 -277.598166) (xy 61.418438 -277.573559) (xy 61.464454 -277.556107)
			(xy 61.512673 -277.546263) (xy 61.561848 -277.544282) (xy 61.610703 -277.550214) (xy 61.657974 -277.563906)
			(xy 61.702436 -277.585004) (xy 61.742939 -277.61296) (xy 61.778432 -277.647052) (xy 61.807997 -277.686396)
			(xy 61.830868 -277.729973) (xy 61.846452 -277.776654) (xy 61.854347 -277.825231) (xy 61.854842 -277.849838)
			(xy 63.143904 -277.849838) (xy 63.147864 -277.800784) (xy 63.159641 -277.753) (xy 63.178932 -277.707724)
			(xy 63.205235 -277.666128) (xy 63.23787 -277.629291) (xy 63.275991 -277.598166) (xy 63.318612 -277.573559)
			(xy 63.364628 -277.556107) (xy 63.412847 -277.546263) (xy 63.462022 -277.544282) (xy 63.510877 -277.550214)
			(xy 63.558148 -277.563906) (xy 63.60261 -277.585004) (xy 63.643113 -277.61296) (xy 63.678606 -277.647052)
			(xy 63.708171 -277.686396) (xy 63.731042 -277.729973) (xy 63.746626 -277.776654) (xy 63.754521 -277.825231)
			(xy 63.755016 -277.849838) (xy 65.043824 -277.849838) (xy 65.047784 -277.800784) (xy 65.059561 -277.753)
			(xy 65.078852 -277.707724) (xy 65.105155 -277.666128) (xy 65.13779 -277.629291) (xy 65.175911 -277.598166)
			(xy 65.218532 -277.573559) (xy 65.264548 -277.556107) (xy 65.312767 -277.546263) (xy 65.361942 -277.544282)
			(xy 65.410797 -277.550214) (xy 65.458068 -277.563906) (xy 65.50253 -277.585004) (xy 65.543033 -277.61296)
			(xy 65.578526 -277.647052) (xy 65.608091 -277.686396) (xy 65.630962 -277.729973) (xy 65.646546 -277.776654)
			(xy 65.654441 -277.825231) (xy 65.654936 -277.849838) (xy 66.943744 -277.849838) (xy 66.947704 -277.800784)
			(xy 66.959481 -277.753) (xy 66.978772 -277.707724) (xy 67.005075 -277.666128) (xy 67.03771 -277.629291)
			(xy 67.075831 -277.598166) (xy 67.118452 -277.573559) (xy 67.164468 -277.556107) (xy 67.212687 -277.546263)
			(xy 67.261862 -277.544282) (xy 67.310717 -277.550214) (xy 67.357988 -277.563906) (xy 67.40245 -277.585004)
			(xy 67.442953 -277.61296) (xy 67.478446 -277.647052) (xy 67.508011 -277.686396) (xy 67.530882 -277.729973)
			(xy 67.546466 -277.776654) (xy 67.554361 -277.825231) (xy 67.554856 -277.849838) (xy 68.843918 -277.849838)
			(xy 68.847878 -277.800784) (xy 68.859655 -277.753) (xy 68.878946 -277.707724) (xy 68.905249 -277.666128)
			(xy 68.937884 -277.629291) (xy 68.976005 -277.598166) (xy 69.018626 -277.573559) (xy 69.064642 -277.556107)
			(xy 69.112861 -277.546263) (xy 69.162036 -277.544282) (xy 69.210891 -277.550214) (xy 69.258162 -277.563906)
			(xy 69.302624 -277.585004) (xy 69.343127 -277.61296) (xy 69.37862 -277.647052) (xy 69.408185 -277.686396)
			(xy 69.431056 -277.729973) (xy 69.44664 -277.776654) (xy 69.454535 -277.825231) (xy 69.45503 -277.849838)
			(xy 70.743838 -277.849838) (xy 70.747798 -277.800784) (xy 70.759575 -277.753) (xy 70.778866 -277.707724)
			(xy 70.805169 -277.666128) (xy 70.837804 -277.629291) (xy 70.875925 -277.598166) (xy 70.918546 -277.573559)
			(xy 70.964562 -277.556107) (xy 71.012781 -277.546263) (xy 71.061956 -277.544282) (xy 71.110811 -277.550214)
			(xy 71.158082 -277.563906) (xy 71.202544 -277.585004) (xy 71.243047 -277.61296) (xy 71.27854 -277.647052)
			(xy 71.308105 -277.686396) (xy 71.330976 -277.729973) (xy 71.34656 -277.776654) (xy 71.354455 -277.825231)
			(xy 71.35495 -277.849838) (xy 72.643758 -277.849838) (xy 72.647718 -277.800784) (xy 72.659495 -277.753)
			(xy 72.678786 -277.707724) (xy 72.705089 -277.666128) (xy 72.737724 -277.629291) (xy 72.775845 -277.598166)
			(xy 72.818466 -277.573559) (xy 72.864482 -277.556107) (xy 72.912701 -277.546263) (xy 72.961876 -277.544282)
			(xy 73.010731 -277.550214) (xy 73.058002 -277.563906) (xy 73.102464 -277.585004) (xy 73.142967 -277.61296)
			(xy 73.17846 -277.647052) (xy 73.208025 -277.686396) (xy 73.230896 -277.729973) (xy 73.24648 -277.776654)
			(xy 73.254375 -277.825231) (xy 73.25487 -277.849838) (xy 74.543932 -277.849838) (xy 74.547892 -277.800784)
			(xy 74.559669 -277.753) (xy 74.57896 -277.707724) (xy 74.605263 -277.666128) (xy 74.637898 -277.629291)
			(xy 74.676019 -277.598166) (xy 74.71864 -277.573559) (xy 74.764656 -277.556107) (xy 74.812875 -277.546263)
			(xy 74.86205 -277.544282) (xy 74.910905 -277.550214) (xy 74.958176 -277.563906) (xy 75.002638 -277.585004)
			(xy 75.043141 -277.61296) (xy 75.078634 -277.647052) (xy 75.108199 -277.686396) (xy 75.13107 -277.729973)
			(xy 75.146654 -277.776654) (xy 75.154549 -277.825231) (xy 75.155044 -277.849838) (xy 76.443852 -277.849838)
			(xy 76.447812 -277.800784) (xy 76.459589 -277.753) (xy 76.47888 -277.707724) (xy 76.505183 -277.666128)
			(xy 76.537818 -277.629291) (xy 76.575939 -277.598166) (xy 76.61856 -277.573559) (xy 76.664576 -277.556107)
			(xy 76.712795 -277.546263) (xy 76.76197 -277.544282) (xy 76.810825 -277.550214) (xy 76.858096 -277.563906)
			(xy 76.902558 -277.585004) (xy 76.943061 -277.61296) (xy 76.978554 -277.647052) (xy 77.008119 -277.686396)
			(xy 77.03099 -277.729973) (xy 77.046574 -277.776654) (xy 77.054469 -277.825231) (xy 77.054964 -277.849838)
			(xy 78.343772 -277.849838) (xy 78.347732 -277.800784) (xy 78.359509 -277.753) (xy 78.3788 -277.707724)
			(xy 78.405103 -277.666128) (xy 78.437738 -277.629291) (xy 78.475859 -277.598166) (xy 78.51848 -277.573559)
			(xy 78.564496 -277.556107) (xy 78.612715 -277.546263) (xy 78.66189 -277.544282) (xy 78.710745 -277.550214)
			(xy 78.758016 -277.563906) (xy 78.802478 -277.585004) (xy 78.842981 -277.61296) (xy 78.878474 -277.647052)
			(xy 78.908039 -277.686396) (xy 78.93091 -277.729973) (xy 78.946494 -277.776654) (xy 78.954389 -277.825231)
			(xy 78.954884 -277.849838) (xy 80.243946 -277.849838) (xy 80.247906 -277.800784) (xy 80.259683 -277.753)
			(xy 80.278974 -277.707724) (xy 80.305277 -277.666128) (xy 80.337912 -277.629291) (xy 80.376033 -277.598166)
			(xy 80.418654 -277.573559) (xy 80.46467 -277.556107) (xy 80.512889 -277.546263) (xy 80.562064 -277.544282)
			(xy 80.610919 -277.550214) (xy 80.65819 -277.563906) (xy 80.702652 -277.585004) (xy 80.743155 -277.61296)
			(xy 80.778648 -277.647052) (xy 80.808213 -277.686396) (xy 80.831084 -277.729973) (xy 80.846668 -277.776654)
			(xy 80.854563 -277.825231) (xy 80.855058 -277.849838) (xy 160.24404 -277.849838) (xy 160.248 -277.800784)
			(xy 160.259777 -277.753) (xy 160.279068 -277.707724) (xy 160.305371 -277.666128) (xy 160.338006 -277.629291)
			(xy 160.376127 -277.598166) (xy 160.418748 -277.573559) (xy 160.464764 -277.556107) (xy 160.512983 -277.546263)
			(xy 160.562158 -277.544282) (xy 160.611013 -277.550214) (xy 160.658284 -277.563906) (xy 160.702746 -277.585004)
			(xy 160.743249 -277.61296) (xy 160.778742 -277.647052) (xy 160.808307 -277.686396) (xy 160.831178 -277.729973)
			(xy 160.846762 -277.776654) (xy 160.854657 -277.825231) (xy 160.855152 -277.849838) (xy 162.144214 -277.849838)
			(xy 162.148174 -277.800784) (xy 162.159951 -277.753) (xy 162.179242 -277.707724) (xy 162.205545 -277.666128)
			(xy 162.23818 -277.629291) (xy 162.276301 -277.598166) (xy 162.318922 -277.573559) (xy 162.364938 -277.556107)
			(xy 162.413157 -277.546263) (xy 162.462332 -277.544282) (xy 162.511187 -277.550214) (xy 162.558458 -277.563906)
			(xy 162.60292 -277.585004) (xy 162.643423 -277.61296) (xy 162.678916 -277.647052) (xy 162.708481 -277.686396)
			(xy 162.731352 -277.729973) (xy 162.746936 -277.776654) (xy 162.754831 -277.825231) (xy 162.755326 -277.849838)
			(xy 164.044134 -277.849838) (xy 164.048094 -277.800784) (xy 164.059871 -277.753) (xy 164.079162 -277.707724)
			(xy 164.105465 -277.666128) (xy 164.1381 -277.629291) (xy 164.176221 -277.598166) (xy 164.218842 -277.573559)
			(xy 164.264858 -277.556107) (xy 164.313077 -277.546263) (xy 164.362252 -277.544282) (xy 164.411107 -277.550214)
			(xy 164.458378 -277.563906) (xy 164.50284 -277.585004) (xy 164.543343 -277.61296) (xy 164.578836 -277.647052)
			(xy 164.608401 -277.686396) (xy 164.631272 -277.729973) (xy 164.646856 -277.776654) (xy 164.654751 -277.825231)
			(xy 164.655246 -277.849838) (xy 165.944054 -277.849838) (xy 165.948014 -277.800784) (xy 165.959791 -277.753)
			(xy 165.979082 -277.707724) (xy 166.005385 -277.666128) (xy 166.03802 -277.629291) (xy 166.076141 -277.598166)
			(xy 166.118762 -277.573559) (xy 166.164778 -277.556107) (xy 166.212997 -277.546263) (xy 166.262172 -277.544282)
			(xy 166.311027 -277.550214) (xy 166.358298 -277.563906) (xy 166.40276 -277.585004) (xy 166.443263 -277.61296)
			(xy 166.478756 -277.647052) (xy 166.508321 -277.686396) (xy 166.531192 -277.729973) (xy 166.546776 -277.776654)
			(xy 166.554671 -277.825231) (xy 166.555166 -277.849838) (xy 167.844228 -277.849838) (xy 167.848188 -277.800784)
			(xy 167.859965 -277.753) (xy 167.879256 -277.707724) (xy 167.905559 -277.666128) (xy 167.938194 -277.629291)
			(xy 167.976315 -277.598166) (xy 168.018936 -277.573559) (xy 168.064952 -277.556107) (xy 168.113171 -277.546263)
			(xy 168.162346 -277.544282) (xy 168.211201 -277.550214) (xy 168.258472 -277.563906) (xy 168.302934 -277.585004)
			(xy 168.343437 -277.61296) (xy 168.37893 -277.647052) (xy 168.408495 -277.686396) (xy 168.431366 -277.729973)
			(xy 168.44695 -277.776654) (xy 168.454845 -277.825231) (xy 168.45534 -277.849838) (xy 169.744148 -277.849838)
			(xy 169.748108 -277.800784) (xy 169.759885 -277.753) (xy 169.779176 -277.707724) (xy 169.805479 -277.666128)
			(xy 169.838114 -277.629291) (xy 169.876235 -277.598166) (xy 169.918856 -277.573559) (xy 169.964872 -277.556107)
			(xy 170.013091 -277.546263) (xy 170.062266 -277.544282) (xy 170.111121 -277.550214) (xy 170.158392 -277.563906)
			(xy 170.202854 -277.585004) (xy 170.243357 -277.61296) (xy 170.27885 -277.647052) (xy 170.308415 -277.686396)
			(xy 170.331286 -277.729973) (xy 170.34687 -277.776654) (xy 170.354765 -277.825231) (xy 170.35526 -277.849838)
			(xy 171.644068 -277.849838) (xy 171.648028 -277.800784) (xy 171.659805 -277.753) (xy 171.679096 -277.707724)
			(xy 171.705399 -277.666128) (xy 171.738034 -277.629291) (xy 171.776155 -277.598166) (xy 171.818776 -277.573559)
			(xy 171.864792 -277.556107) (xy 171.913011 -277.546263) (xy 171.962186 -277.544282) (xy 172.011041 -277.550214)
			(xy 172.058312 -277.563906) (xy 172.102774 -277.585004) (xy 172.143277 -277.61296) (xy 172.17877 -277.647052)
			(xy 172.208335 -277.686396) (xy 172.231206 -277.729973) (xy 172.24679 -277.776654) (xy 172.254685 -277.825231)
			(xy 172.25518 -277.849838) (xy 173.544242 -277.849838) (xy 173.548202 -277.800784) (xy 173.559979 -277.753)
			(xy 173.57927 -277.707724) (xy 173.605573 -277.666128) (xy 173.638208 -277.629291) (xy 173.676329 -277.598166)
			(xy 173.71895 -277.573559) (xy 173.764966 -277.556107) (xy 173.813185 -277.546263) (xy 173.86236 -277.544282)
			(xy 173.911215 -277.550214) (xy 173.958486 -277.563906) (xy 174.002948 -277.585004) (xy 174.043451 -277.61296)
			(xy 174.078944 -277.647052) (xy 174.108509 -277.686396) (xy 174.13138 -277.729973) (xy 174.146964 -277.776654)
			(xy 174.154859 -277.825231) (xy 174.155354 -277.849838) (xy 175.443908 -277.849838) (xy 175.447868 -277.800784)
			(xy 175.459645 -277.753) (xy 175.478936 -277.707724) (xy 175.505239 -277.666128) (xy 175.537874 -277.629291)
			(xy 175.575995 -277.598166) (xy 175.618616 -277.573559) (xy 175.664632 -277.556107) (xy 175.712851 -277.546263)
			(xy 175.762026 -277.544282) (xy 175.810881 -277.550214) (xy 175.858152 -277.563906) (xy 175.902614 -277.585004)
			(xy 175.943117 -277.61296) (xy 175.97861 -277.647052) (xy 176.008175 -277.686396) (xy 176.031046 -277.729973)
			(xy 176.04663 -277.776654) (xy 176.054525 -277.825231) (xy 176.05502 -277.849838) (xy 177.343828 -277.849838)
			(xy 177.347788 -277.800784) (xy 177.359565 -277.753) (xy 177.378856 -277.707724) (xy 177.405159 -277.666128)
			(xy 177.437794 -277.629291) (xy 177.475915 -277.598166) (xy 177.518536 -277.573559) (xy 177.564552 -277.556107)
			(xy 177.612771 -277.546263) (xy 177.661946 -277.544282) (xy 177.710801 -277.550214) (xy 177.758072 -277.563906)
			(xy 177.802534 -277.585004) (xy 177.843037 -277.61296) (xy 177.87853 -277.647052) (xy 177.908095 -277.686396)
			(xy 177.930966 -277.729973) (xy 177.94655 -277.776654) (xy 177.954445 -277.825231) (xy 177.95494 -277.849838)
			(xy 179.244002 -277.849838) (xy 179.247962 -277.800784) (xy 179.259739 -277.753) (xy 179.27903 -277.707724)
			(xy 179.305333 -277.666128) (xy 179.337968 -277.629291) (xy 179.376089 -277.598166) (xy 179.41871 -277.573559)
			(xy 179.464726 -277.556107) (xy 179.512945 -277.546263) (xy 179.56212 -277.544282) (xy 179.610975 -277.550214)
			(xy 179.658246 -277.563906) (xy 179.702708 -277.585004) (xy 179.743211 -277.61296) (xy 179.778704 -277.647052)
			(xy 179.808269 -277.686396) (xy 179.83114 -277.729973) (xy 179.846724 -277.776654) (xy 179.854619 -277.825231)
			(xy 179.855114 -277.849838) (xy 181.143922 -277.849838) (xy 181.147882 -277.800784) (xy 181.159659 -277.753)
			(xy 181.17895 -277.707724) (xy 181.205253 -277.666128) (xy 181.237888 -277.629291) (xy 181.276009 -277.598166)
			(xy 181.31863 -277.573559) (xy 181.364646 -277.556107) (xy 181.412865 -277.546263) (xy 181.46204 -277.544282)
			(xy 181.510895 -277.550214) (xy 181.558166 -277.563906) (xy 181.602628 -277.585004) (xy 181.643131 -277.61296)
			(xy 181.678624 -277.647052) (xy 181.708189 -277.686396) (xy 181.73106 -277.729973) (xy 181.746644 -277.776654)
			(xy 181.754539 -277.825231) (xy 181.755034 -277.849838) (xy 183.043842 -277.849838) (xy 183.047802 -277.800784)
			(xy 183.059579 -277.753) (xy 183.07887 -277.707724) (xy 183.105173 -277.666128) (xy 183.137808 -277.629291)
			(xy 183.175929 -277.598166) (xy 183.21855 -277.573559) (xy 183.264566 -277.556107) (xy 183.312785 -277.546263)
			(xy 183.36196 -277.544282) (xy 183.410815 -277.550214) (xy 183.458086 -277.563906) (xy 183.502548 -277.585004)
			(xy 183.543051 -277.61296) (xy 183.578544 -277.647052) (xy 183.608109 -277.686396) (xy 183.63098 -277.729973)
			(xy 183.646564 -277.776654) (xy 183.654459 -277.825231) (xy 183.654954 -277.849838) (xy 184.944016 -277.849838)
			(xy 184.947976 -277.800784) (xy 184.959753 -277.753) (xy 184.979044 -277.707724) (xy 185.005347 -277.666128)
			(xy 185.037982 -277.629291) (xy 185.076103 -277.598166) (xy 185.118724 -277.573559) (xy 185.16474 -277.556107)
			(xy 185.212959 -277.546263) (xy 185.262134 -277.544282) (xy 185.310989 -277.550214) (xy 185.35826 -277.563906)
			(xy 185.402722 -277.585004) (xy 185.443225 -277.61296) (xy 185.478718 -277.647052) (xy 185.508283 -277.686396)
			(xy 185.531154 -277.729973) (xy 185.546738 -277.776654) (xy 185.554633 -277.825231) (xy 185.555128 -277.849838)
			(xy 186.843936 -277.849838) (xy 186.847896 -277.800784) (xy 186.859673 -277.753) (xy 186.878964 -277.707724)
			(xy 186.905267 -277.666128) (xy 186.937902 -277.629291) (xy 186.976023 -277.598166) (xy 187.018644 -277.573559)
			(xy 187.06466 -277.556107) (xy 187.112879 -277.546263) (xy 187.162054 -277.544282) (xy 187.210909 -277.550214)
			(xy 187.25818 -277.563906) (xy 187.302642 -277.585004) (xy 187.343145 -277.61296) (xy 187.378638 -277.647052)
			(xy 187.408203 -277.686396) (xy 187.431074 -277.729973) (xy 187.446658 -277.776654) (xy 187.454553 -277.825231)
			(xy 187.455048 -277.849838) (xy 188.743856 -277.849838) (xy 188.747816 -277.800784) (xy 188.759593 -277.753)
			(xy 188.778884 -277.707724) (xy 188.805187 -277.666128) (xy 188.837822 -277.629291) (xy 188.875943 -277.598166)
			(xy 188.918564 -277.573559) (xy 188.96458 -277.556107) (xy 189.012799 -277.546263) (xy 189.061974 -277.544282)
			(xy 189.110829 -277.550214) (xy 189.1581 -277.563906) (xy 189.202562 -277.585004) (xy 189.243065 -277.61296)
			(xy 189.278558 -277.647052) (xy 189.308123 -277.686396) (xy 189.330994 -277.729973) (xy 189.346578 -277.776654)
			(xy 189.354473 -277.825231) (xy 189.354968 -277.849838) (xy 190.64403 -277.849838) (xy 190.64799 -277.800784)
			(xy 190.659767 -277.753) (xy 190.679058 -277.707724) (xy 190.705361 -277.666128) (xy 190.737996 -277.629291)
			(xy 190.776117 -277.598166) (xy 190.818738 -277.573559) (xy 190.864754 -277.556107) (xy 190.912973 -277.546263)
			(xy 190.962148 -277.544282) (xy 191.011003 -277.550214) (xy 191.058274 -277.563906) (xy 191.102736 -277.585004)
			(xy 191.143239 -277.61296) (xy 191.178732 -277.647052) (xy 191.208297 -277.686396) (xy 191.231168 -277.729973)
			(xy 191.246752 -277.776654) (xy 191.254647 -277.825231) (xy 191.255142 -277.849838) (xy 192.54395 -277.849838)
			(xy 192.54791 -277.800784) (xy 192.559687 -277.753) (xy 192.578978 -277.707724) (xy 192.605281 -277.666128)
			(xy 192.637916 -277.629291) (xy 192.676037 -277.598166) (xy 192.718658 -277.573559) (xy 192.764674 -277.556107)
			(xy 192.812893 -277.546263) (xy 192.862068 -277.544282) (xy 192.910923 -277.550214) (xy 192.958194 -277.563906)
			(xy 193.002656 -277.585004) (xy 193.043159 -277.61296) (xy 193.078652 -277.647052) (xy 193.108217 -277.686396)
			(xy 193.131088 -277.729973) (xy 193.146672 -277.776654) (xy 193.154567 -277.825231) (xy 193.155062 -277.849838)
			(xy 194.44387 -277.849838) (xy 194.44783 -277.800784) (xy 194.459607 -277.753) (xy 194.478898 -277.707724)
			(xy 194.505201 -277.666128) (xy 194.537836 -277.629291) (xy 194.575957 -277.598166) (xy 194.618578 -277.573559)
			(xy 194.664594 -277.556107) (xy 194.712813 -277.546263) (xy 194.761988 -277.544282) (xy 194.810843 -277.550214)
			(xy 194.858114 -277.563906) (xy 194.902576 -277.585004) (xy 194.943079 -277.61296) (xy 194.978572 -277.647052)
			(xy 195.008137 -277.686396) (xy 195.031008 -277.729973) (xy 195.046592 -277.776654) (xy 195.054487 -277.825231)
			(xy 195.054982 -277.849838) (xy 196.344044 -277.849838) (xy 196.348004 -277.800784) (xy 196.359781 -277.753)
			(xy 196.379072 -277.707724) (xy 196.405375 -277.666128) (xy 196.43801 -277.629291) (xy 196.476131 -277.598166)
			(xy 196.518752 -277.573559) (xy 196.564768 -277.556107) (xy 196.612987 -277.546263) (xy 196.662162 -277.544282)
			(xy 196.711017 -277.550214) (xy 196.758288 -277.563906) (xy 196.80275 -277.585004) (xy 196.843253 -277.61296)
			(xy 196.878746 -277.647052) (xy 196.908311 -277.686396) (xy 196.931182 -277.729973) (xy 196.946766 -277.776654)
			(xy 196.954661 -277.825231) (xy 196.955156 -277.849838) (xy 276.343884 -277.849838) (xy 276.347844 -277.800784)
			(xy 276.359621 -277.753) (xy 276.378912 -277.707724) (xy 276.405215 -277.666128) (xy 276.43785 -277.629291)
			(xy 276.475971 -277.598166) (xy 276.518592 -277.573559) (xy 276.564608 -277.556107) (xy 276.612827 -277.546263)
			(xy 276.662002 -277.544282) (xy 276.710857 -277.550214) (xy 276.758128 -277.563906) (xy 276.80259 -277.585004)
			(xy 276.843093 -277.61296) (xy 276.878586 -277.647052) (xy 276.908151 -277.686396) (xy 276.931022 -277.729973)
			(xy 276.946606 -277.776654) (xy 276.954501 -277.825231) (xy 276.954996 -277.849838) (xy 278.244058 -277.849838)
			(xy 278.248018 -277.800784) (xy 278.259795 -277.753) (xy 278.279086 -277.707724) (xy 278.305389 -277.666128)
			(xy 278.338024 -277.629291) (xy 278.376145 -277.598166) (xy 278.418766 -277.573559) (xy 278.464782 -277.556107)
			(xy 278.513001 -277.546263) (xy 278.562176 -277.544282) (xy 278.611031 -277.550214) (xy 278.658302 -277.563906)
			(xy 278.702764 -277.585004) (xy 278.743267 -277.61296) (xy 278.77876 -277.647052) (xy 278.808325 -277.686396)
			(xy 278.831196 -277.729973) (xy 278.84678 -277.776654) (xy 278.854675 -277.825231) (xy 278.85517 -277.849838)
			(xy 280.143978 -277.849838) (xy 280.147938 -277.800784) (xy 280.159715 -277.753) (xy 280.179006 -277.707724)
			(xy 280.205309 -277.666128) (xy 280.237944 -277.629291) (xy 280.276065 -277.598166) (xy 280.318686 -277.573559)
			(xy 280.364702 -277.556107) (xy 280.412921 -277.546263) (xy 280.462096 -277.544282) (xy 280.510951 -277.550214)
			(xy 280.558222 -277.563906) (xy 280.602684 -277.585004) (xy 280.643187 -277.61296) (xy 280.67868 -277.647052)
			(xy 280.708245 -277.686396) (xy 280.731116 -277.729973) (xy 280.7467 -277.776654) (xy 280.754595 -277.825231)
			(xy 280.75509 -277.849838) (xy 282.043898 -277.849838) (xy 282.047858 -277.800784) (xy 282.059635 -277.753)
			(xy 282.078926 -277.707724) (xy 282.105229 -277.666128) (xy 282.137864 -277.629291) (xy 282.175985 -277.598166)
			(xy 282.218606 -277.573559) (xy 282.264622 -277.556107) (xy 282.312841 -277.546263) (xy 282.362016 -277.544282)
			(xy 282.410871 -277.550214) (xy 282.458142 -277.563906) (xy 282.502604 -277.585004) (xy 282.543107 -277.61296)
			(xy 282.5786 -277.647052) (xy 282.608165 -277.686396) (xy 282.631036 -277.729973) (xy 282.64662 -277.776654)
			(xy 282.654515 -277.825231) (xy 282.65501 -277.849838) (xy 283.944072 -277.849838) (xy 283.948032 -277.800784)
			(xy 283.959809 -277.753) (xy 283.9791 -277.707724) (xy 284.005403 -277.666128) (xy 284.038038 -277.629291)
			(xy 284.076159 -277.598166) (xy 284.11878 -277.573559) (xy 284.164796 -277.556107) (xy 284.213015 -277.546263)
			(xy 284.26219 -277.544282) (xy 284.311045 -277.550214) (xy 284.358316 -277.563906) (xy 284.402778 -277.585004)
			(xy 284.443281 -277.61296) (xy 284.478774 -277.647052) (xy 284.508339 -277.686396) (xy 284.53121 -277.729973)
			(xy 284.546794 -277.776654) (xy 284.554689 -277.825231) (xy 284.555184 -277.849838) (xy 285.843992 -277.849838)
			(xy 285.847952 -277.800784) (xy 285.859729 -277.753) (xy 285.87902 -277.707724) (xy 285.905323 -277.666128)
			(xy 285.937958 -277.629291) (xy 285.976079 -277.598166) (xy 286.0187 -277.573559) (xy 286.064716 -277.556107)
			(xy 286.112935 -277.546263) (xy 286.16211 -277.544282) (xy 286.210965 -277.550214) (xy 286.258236 -277.563906)
			(xy 286.302698 -277.585004) (xy 286.343201 -277.61296) (xy 286.378694 -277.647052) (xy 286.408259 -277.686396)
			(xy 286.43113 -277.729973) (xy 286.446714 -277.776654) (xy 286.454609 -277.825231) (xy 286.455104 -277.849838)
			(xy 287.743912 -277.849838) (xy 287.747872 -277.800784) (xy 287.759649 -277.753) (xy 287.77894 -277.707724)
			(xy 287.805243 -277.666128) (xy 287.837878 -277.629291) (xy 287.875999 -277.598166) (xy 287.91862 -277.573559)
			(xy 287.964636 -277.556107) (xy 288.012855 -277.546263) (xy 288.06203 -277.544282) (xy 288.110885 -277.550214)
			(xy 288.158156 -277.563906) (xy 288.202618 -277.585004) (xy 288.243121 -277.61296) (xy 288.278614 -277.647052)
			(xy 288.308179 -277.686396) (xy 288.33105 -277.729973) (xy 288.346634 -277.776654) (xy 288.354529 -277.825231)
			(xy 288.355024 -277.849838) (xy 289.644086 -277.849838) (xy 289.648046 -277.800784) (xy 289.659823 -277.753)
			(xy 289.679114 -277.707724) (xy 289.705417 -277.666128) (xy 289.738052 -277.629291) (xy 289.776173 -277.598166)
			(xy 289.818794 -277.573559) (xy 289.86481 -277.556107) (xy 289.913029 -277.546263) (xy 289.962204 -277.544282)
			(xy 290.011059 -277.550214) (xy 290.05833 -277.563906) (xy 290.102792 -277.585004) (xy 290.143295 -277.61296)
			(xy 290.178788 -277.647052) (xy 290.208353 -277.686396) (xy 290.231224 -277.729973) (xy 290.246808 -277.776654)
			(xy 290.254703 -277.825231) (xy 290.255198 -277.849838) (xy 291.543752 -277.849838) (xy 291.547712 -277.800784)
			(xy 291.559489 -277.753) (xy 291.57878 -277.707724) (xy 291.605083 -277.666128) (xy 291.637718 -277.629291)
			(xy 291.675839 -277.598166) (xy 291.71846 -277.573559) (xy 291.764476 -277.556107) (xy 291.812695 -277.546263)
			(xy 291.86187 -277.544282) (xy 291.910725 -277.550214) (xy 291.957996 -277.563906) (xy 292.002458 -277.585004)
			(xy 292.042961 -277.61296) (xy 292.078454 -277.647052) (xy 292.108019 -277.686396) (xy 292.13089 -277.729973)
			(xy 292.146474 -277.776654) (xy 292.154369 -277.825231) (xy 292.154864 -277.849838) (xy 293.443672 -277.849838)
			(xy 293.447632 -277.800784) (xy 293.459409 -277.753) (xy 293.4787 -277.707724) (xy 293.505003 -277.666128)
			(xy 293.537638 -277.629291) (xy 293.575759 -277.598166) (xy 293.61838 -277.573559) (xy 293.664396 -277.556107)
			(xy 293.712615 -277.546263) (xy 293.76179 -277.544282) (xy 293.810645 -277.550214) (xy 293.857916 -277.563906)
			(xy 293.902378 -277.585004) (xy 293.942881 -277.61296) (xy 293.978374 -277.647052) (xy 294.007939 -277.686396)
			(xy 294.03081 -277.729973) (xy 294.046394 -277.776654) (xy 294.054289 -277.825231) (xy 294.054784 -277.849838)
			(xy 295.343846 -277.849838) (xy 295.347806 -277.800784) (xy 295.359583 -277.753) (xy 295.378874 -277.707724)
			(xy 295.405177 -277.666128) (xy 295.437812 -277.629291) (xy 295.475933 -277.598166) (xy 295.518554 -277.573559)
			(xy 295.56457 -277.556107) (xy 295.612789 -277.546263) (xy 295.661964 -277.544282) (xy 295.710819 -277.550214)
			(xy 295.75809 -277.563906) (xy 295.802552 -277.585004) (xy 295.843055 -277.61296) (xy 295.878548 -277.647052)
			(xy 295.908113 -277.686396) (xy 295.930984 -277.729973) (xy 295.946568 -277.776654) (xy 295.954463 -277.825231)
			(xy 295.954958 -277.849838) (xy 297.243766 -277.849838) (xy 297.247726 -277.800784) (xy 297.259503 -277.753)
			(xy 297.278794 -277.707724) (xy 297.305097 -277.666128) (xy 297.337732 -277.629291) (xy 297.375853 -277.598166)
			(xy 297.418474 -277.573559) (xy 297.46449 -277.556107) (xy 297.512709 -277.546263) (xy 297.561884 -277.544282)
			(xy 297.610739 -277.550214) (xy 297.65801 -277.563906) (xy 297.702472 -277.585004) (xy 297.742975 -277.61296)
			(xy 297.778468 -277.647052) (xy 297.808033 -277.686396) (xy 297.830904 -277.729973) (xy 297.846488 -277.776654)
			(xy 297.854383 -277.825231) (xy 297.854878 -277.849838) (xy 299.143686 -277.849838) (xy 299.147646 -277.800784)
			(xy 299.159423 -277.753) (xy 299.178714 -277.707724) (xy 299.205017 -277.666128) (xy 299.237652 -277.629291)
			(xy 299.275773 -277.598166) (xy 299.318394 -277.573559) (xy 299.36441 -277.556107) (xy 299.412629 -277.546263)
			(xy 299.461804 -277.544282) (xy 299.510659 -277.550214) (xy 299.55793 -277.563906) (xy 299.602392 -277.585004)
			(xy 299.642895 -277.61296) (xy 299.678388 -277.647052) (xy 299.707953 -277.686396) (xy 299.730824 -277.729973)
			(xy 299.746408 -277.776654) (xy 299.754303 -277.825231) (xy 299.754798 -277.849838) (xy 301.04386 -277.849838)
			(xy 301.04782 -277.800784) (xy 301.059597 -277.753) (xy 301.078888 -277.707724) (xy 301.105191 -277.666128)
			(xy 301.137826 -277.629291) (xy 301.175947 -277.598166) (xy 301.218568 -277.573559) (xy 301.264584 -277.556107)
			(xy 301.312803 -277.546263) (xy 301.361978 -277.544282) (xy 301.410833 -277.550214) (xy 301.458104 -277.563906)
			(xy 301.502566 -277.585004) (xy 301.543069 -277.61296) (xy 301.578562 -277.647052) (xy 301.608127 -277.686396)
			(xy 301.630998 -277.729973) (xy 301.646582 -277.776654) (xy 301.654477 -277.825231) (xy 301.654972 -277.849838)
			(xy 302.94378 -277.849838) (xy 302.94774 -277.800784) (xy 302.959517 -277.753) (xy 302.978808 -277.707724)
			(xy 303.005111 -277.666128) (xy 303.037746 -277.629291) (xy 303.075867 -277.598166) (xy 303.118488 -277.573559)
			(xy 303.164504 -277.556107) (xy 303.212723 -277.546263) (xy 303.261898 -277.544282) (xy 303.310753 -277.550214)
			(xy 303.358024 -277.563906) (xy 303.402486 -277.585004) (xy 303.442989 -277.61296) (xy 303.478482 -277.647052)
			(xy 303.508047 -277.686396) (xy 303.530918 -277.729973) (xy 303.546502 -277.776654) (xy 303.554397 -277.825231)
			(xy 303.554892 -277.849838) (xy 304.8437 -277.849838) (xy 304.84766 -277.800784) (xy 304.859437 -277.753)
			(xy 304.878728 -277.707724) (xy 304.905031 -277.666128) (xy 304.937666 -277.629291) (xy 304.975787 -277.598166)
			(xy 305.018408 -277.573559) (xy 305.064424 -277.556107) (xy 305.112643 -277.546263) (xy 305.161818 -277.544282)
			(xy 305.210673 -277.550214) (xy 305.257944 -277.563906) (xy 305.302406 -277.585004) (xy 305.342909 -277.61296)
			(xy 305.378402 -277.647052) (xy 305.407967 -277.686396) (xy 305.430838 -277.729973) (xy 305.446422 -277.776654)
			(xy 305.454317 -277.825231) (xy 305.454812 -277.849838) (xy 306.743874 -277.849838) (xy 306.747834 -277.800784)
			(xy 306.759611 -277.753) (xy 306.778902 -277.707724) (xy 306.805205 -277.666128) (xy 306.83784 -277.629291)
			(xy 306.875961 -277.598166) (xy 306.918582 -277.573559) (xy 306.964598 -277.556107) (xy 307.012817 -277.546263)
			(xy 307.061992 -277.544282) (xy 307.110847 -277.550214) (xy 307.158118 -277.563906) (xy 307.20258 -277.585004)
			(xy 307.243083 -277.61296) (xy 307.278576 -277.647052) (xy 307.308141 -277.686396) (xy 307.331012 -277.729973)
			(xy 307.346596 -277.776654) (xy 307.354491 -277.825231) (xy 307.354986 -277.849838) (xy 308.643794 -277.849838)
			(xy 308.647754 -277.800784) (xy 308.659531 -277.753) (xy 308.678822 -277.707724) (xy 308.705125 -277.666128)
			(xy 308.73776 -277.629291) (xy 308.775881 -277.598166) (xy 308.818502 -277.573559) (xy 308.864518 -277.556107)
			(xy 308.912737 -277.546263) (xy 308.961912 -277.544282) (xy 309.010767 -277.550214) (xy 309.058038 -277.563906)
			(xy 309.1025 -277.585004) (xy 309.143003 -277.61296) (xy 309.178496 -277.647052) (xy 309.208061 -277.686396)
			(xy 309.230932 -277.729973) (xy 309.246516 -277.776654) (xy 309.254411 -277.825231) (xy 309.254906 -277.849838)
			(xy 310.543714 -277.849838) (xy 310.547674 -277.800784) (xy 310.559451 -277.753) (xy 310.578742 -277.707724)
			(xy 310.605045 -277.666128) (xy 310.63768 -277.629291) (xy 310.675801 -277.598166) (xy 310.718422 -277.573559)
			(xy 310.764438 -277.556107) (xy 310.812657 -277.546263) (xy 310.861832 -277.544282) (xy 310.910687 -277.550214)
			(xy 310.957958 -277.563906) (xy 311.00242 -277.585004) (xy 311.042923 -277.61296) (xy 311.078416 -277.647052)
			(xy 311.107981 -277.686396) (xy 311.130852 -277.729973) (xy 311.146436 -277.776654) (xy 311.154331 -277.825231)
			(xy 311.154826 -277.849838) (xy 312.443888 -277.849838) (xy 312.447848 -277.800784) (xy 312.459625 -277.753)
			(xy 312.478916 -277.707724) (xy 312.505219 -277.666128) (xy 312.537854 -277.629291) (xy 312.575975 -277.598166)
			(xy 312.618596 -277.573559) (xy 312.664612 -277.556107) (xy 312.712831 -277.546263) (xy 312.762006 -277.544282)
			(xy 312.810861 -277.550214) (xy 312.858132 -277.563906) (xy 312.902594 -277.585004) (xy 312.943097 -277.61296)
			(xy 312.97859 -277.647052) (xy 313.008155 -277.686396) (xy 313.031026 -277.729973) (xy 313.04661 -277.776654)
			(xy 313.054505 -277.825231) (xy 313.055 -277.849838) (xy 392.443982 -277.849838) (xy 392.447942 -277.800784)
			(xy 392.459719 -277.753) (xy 392.47901 -277.707724) (xy 392.505313 -277.666128) (xy 392.537948 -277.629291)
			(xy 392.576069 -277.598166) (xy 392.61869 -277.573559) (xy 392.664706 -277.556107) (xy 392.712925 -277.546263)
			(xy 392.7621 -277.544282) (xy 392.810955 -277.550214) (xy 392.858226 -277.563906) (xy 392.902688 -277.585004)
			(xy 392.943191 -277.61296) (xy 392.978684 -277.647052) (xy 393.008249 -277.686396) (xy 393.03112 -277.729973)
			(xy 393.046704 -277.776654) (xy 393.054599 -277.825231) (xy 393.055094 -277.849838) (xy 394.344156 -277.849838)
			(xy 394.348116 -277.800784) (xy 394.359893 -277.753) (xy 394.379184 -277.707724) (xy 394.405487 -277.666128)
			(xy 394.438122 -277.629291) (xy 394.476243 -277.598166) (xy 394.518864 -277.573559) (xy 394.56488 -277.556107)
			(xy 394.613099 -277.546263) (xy 394.662274 -277.544282) (xy 394.711129 -277.550214) (xy 394.7584 -277.563906)
			(xy 394.802862 -277.585004) (xy 394.843365 -277.61296) (xy 394.878858 -277.647052) (xy 394.908423 -277.686396)
			(xy 394.931294 -277.729973) (xy 394.946878 -277.776654) (xy 394.954773 -277.825231) (xy 394.955268 -277.849838)
			(xy 396.244076 -277.849838) (xy 396.248036 -277.800784) (xy 396.259813 -277.753) (xy 396.279104 -277.707724)
			(xy 396.305407 -277.666128) (xy 396.338042 -277.629291) (xy 396.376163 -277.598166) (xy 396.418784 -277.573559)
			(xy 396.4648 -277.556107) (xy 396.513019 -277.546263) (xy 396.562194 -277.544282) (xy 396.611049 -277.550214)
			(xy 396.65832 -277.563906) (xy 396.702782 -277.585004) (xy 396.743285 -277.61296) (xy 396.778778 -277.647052)
			(xy 396.808343 -277.686396) (xy 396.831214 -277.729973) (xy 396.846798 -277.776654) (xy 396.854693 -277.825231)
			(xy 396.855188 -277.849838) (xy 398.143996 -277.849838) (xy 398.147956 -277.800784) (xy 398.159733 -277.753)
			(xy 398.179024 -277.707724) (xy 398.205327 -277.666128) (xy 398.237962 -277.629291) (xy 398.276083 -277.598166)
			(xy 398.318704 -277.573559) (xy 398.36472 -277.556107) (xy 398.412939 -277.546263) (xy 398.462114 -277.544282)
			(xy 398.510969 -277.550214) (xy 398.55824 -277.563906) (xy 398.602702 -277.585004) (xy 398.643205 -277.61296)
			(xy 398.678698 -277.647052) (xy 398.708263 -277.686396) (xy 398.731134 -277.729973) (xy 398.746718 -277.776654)
			(xy 398.754613 -277.825231) (xy 398.755108 -277.849838) (xy 400.04417 -277.849838) (xy 400.04813 -277.800784)
			(xy 400.059907 -277.753) (xy 400.079198 -277.707724) (xy 400.105501 -277.666128) (xy 400.138136 -277.629291)
			(xy 400.176257 -277.598166) (xy 400.218878 -277.573559) (xy 400.264894 -277.556107) (xy 400.313113 -277.546263)
			(xy 400.362288 -277.544282) (xy 400.411143 -277.550214) (xy 400.458414 -277.563906) (xy 400.502876 -277.585004)
			(xy 400.543379 -277.61296) (xy 400.578872 -277.647052) (xy 400.608437 -277.686396) (xy 400.631308 -277.729973)
			(xy 400.646892 -277.776654) (xy 400.654787 -277.825231) (xy 400.655282 -277.849838) (xy 401.94409 -277.849838)
			(xy 401.94805 -277.800784) (xy 401.959827 -277.753) (xy 401.979118 -277.707724) (xy 402.005421 -277.666128)
			(xy 402.038056 -277.629291) (xy 402.076177 -277.598166) (xy 402.118798 -277.573559) (xy 402.164814 -277.556107)
			(xy 402.213033 -277.546263) (xy 402.262208 -277.544282) (xy 402.311063 -277.550214) (xy 402.358334 -277.563906)
			(xy 402.402796 -277.585004) (xy 402.443299 -277.61296) (xy 402.478792 -277.647052) (xy 402.508357 -277.686396)
			(xy 402.531228 -277.729973) (xy 402.546812 -277.776654) (xy 402.554707 -277.825231) (xy 402.555202 -277.849838)
			(xy 403.84401 -277.849838) (xy 403.84797 -277.800784) (xy 403.859747 -277.753) (xy 403.879038 -277.707724)
			(xy 403.905341 -277.666128) (xy 403.937976 -277.629291) (xy 403.976097 -277.598166) (xy 404.018718 -277.573559)
			(xy 404.064734 -277.556107) (xy 404.112953 -277.546263) (xy 404.162128 -277.544282) (xy 404.210983 -277.550214)
			(xy 404.258254 -277.563906) (xy 404.302716 -277.585004) (xy 404.343219 -277.61296) (xy 404.378712 -277.647052)
			(xy 404.408277 -277.686396) (xy 404.431148 -277.729973) (xy 404.446732 -277.776654) (xy 404.454627 -277.825231)
			(xy 404.455122 -277.849838) (xy 405.744184 -277.849838) (xy 405.748144 -277.800784) (xy 405.759921 -277.753)
			(xy 405.779212 -277.707724) (xy 405.805515 -277.666128) (xy 405.83815 -277.629291) (xy 405.876271 -277.598166)
			(xy 405.918892 -277.573559) (xy 405.964908 -277.556107) (xy 406.013127 -277.546263) (xy 406.062302 -277.544282)
			(xy 406.111157 -277.550214) (xy 406.158428 -277.563906) (xy 406.20289 -277.585004) (xy 406.243393 -277.61296)
			(xy 406.278886 -277.647052) (xy 406.308451 -277.686396) (xy 406.331322 -277.729973) (xy 406.346906 -277.776654)
			(xy 406.354801 -277.825231) (xy 406.355296 -277.849838) (xy 407.64385 -277.849838) (xy 407.64781 -277.800784)
			(xy 407.659587 -277.753) (xy 407.678878 -277.707724) (xy 407.705181 -277.666128) (xy 407.737816 -277.629291)
			(xy 407.775937 -277.598166) (xy 407.818558 -277.573559) (xy 407.864574 -277.556107) (xy 407.912793 -277.546263)
			(xy 407.961968 -277.544282) (xy 408.010823 -277.550214) (xy 408.058094 -277.563906) (xy 408.102556 -277.585004)
			(xy 408.143059 -277.61296) (xy 408.178552 -277.647052) (xy 408.208117 -277.686396) (xy 408.230988 -277.729973)
			(xy 408.246572 -277.776654) (xy 408.254467 -277.825231) (xy 408.254962 -277.849838) (xy 409.54377 -277.849838)
			(xy 409.54773 -277.800784) (xy 409.559507 -277.753) (xy 409.578798 -277.707724) (xy 409.605101 -277.666128)
			(xy 409.637736 -277.629291) (xy 409.675857 -277.598166) (xy 409.718478 -277.573559) (xy 409.764494 -277.556107)
			(xy 409.812713 -277.546263) (xy 409.861888 -277.544282) (xy 409.910743 -277.550214) (xy 409.958014 -277.563906)
			(xy 410.002476 -277.585004) (xy 410.042979 -277.61296) (xy 410.078472 -277.647052) (xy 410.108037 -277.686396)
			(xy 410.130908 -277.729973) (xy 410.146492 -277.776654) (xy 410.154387 -277.825231) (xy 410.154882 -277.849838)
			(xy 411.443944 -277.849838) (xy 411.447904 -277.800784) (xy 411.459681 -277.753) (xy 411.478972 -277.707724)
			(xy 411.505275 -277.666128) (xy 411.53791 -277.629291) (xy 411.576031 -277.598166) (xy 411.618652 -277.573559)
			(xy 411.664668 -277.556107) (xy 411.712887 -277.546263) (xy 411.762062 -277.544282) (xy 411.810917 -277.550214)
			(xy 411.858188 -277.563906) (xy 411.90265 -277.585004) (xy 411.943153 -277.61296) (xy 411.978646 -277.647052)
			(xy 412.008211 -277.686396) (xy 412.031082 -277.729973) (xy 412.046666 -277.776654) (xy 412.054561 -277.825231)
			(xy 412.055056 -277.849838) (xy 413.343864 -277.849838) (xy 413.347824 -277.800784) (xy 413.359601 -277.753)
			(xy 413.378892 -277.707724) (xy 413.405195 -277.666128) (xy 413.43783 -277.629291) (xy 413.475951 -277.598166)
			(xy 413.518572 -277.573559) (xy 413.564588 -277.556107) (xy 413.612807 -277.546263) (xy 413.661982 -277.544282)
			(xy 413.710837 -277.550214) (xy 413.758108 -277.563906) (xy 413.80257 -277.585004) (xy 413.843073 -277.61296)
			(xy 413.878566 -277.647052) (xy 413.908131 -277.686396) (xy 413.931002 -277.729973) (xy 413.946586 -277.776654)
			(xy 413.954481 -277.825231) (xy 413.954976 -277.849838) (xy 415.243784 -277.849838) (xy 415.247744 -277.800784)
			(xy 415.259521 -277.753) (xy 415.278812 -277.707724) (xy 415.305115 -277.666128) (xy 415.33775 -277.629291)
			(xy 415.375871 -277.598166) (xy 415.418492 -277.573559) (xy 415.464508 -277.556107) (xy 415.512727 -277.546263)
			(xy 415.561902 -277.544282) (xy 415.610757 -277.550214) (xy 415.658028 -277.563906) (xy 415.70249 -277.585004)
			(xy 415.742993 -277.61296) (xy 415.778486 -277.647052) (xy 415.808051 -277.686396) (xy 415.830922 -277.729973)
			(xy 415.846506 -277.776654) (xy 415.854401 -277.825231) (xy 415.854896 -277.849838) (xy 417.143958 -277.849838)
			(xy 417.147918 -277.800784) (xy 417.159695 -277.753) (xy 417.178986 -277.707724) (xy 417.205289 -277.666128)
			(xy 417.237924 -277.629291) (xy 417.276045 -277.598166) (xy 417.318666 -277.573559) (xy 417.364682 -277.556107)
			(xy 417.412901 -277.546263) (xy 417.462076 -277.544282) (xy 417.510931 -277.550214) (xy 417.558202 -277.563906)
			(xy 417.602664 -277.585004) (xy 417.643167 -277.61296) (xy 417.67866 -277.647052) (xy 417.708225 -277.686396)
			(xy 417.731096 -277.729973) (xy 417.74668 -277.776654) (xy 417.754575 -277.825231) (xy 417.75507 -277.849838)
			(xy 419.043878 -277.849838) (xy 419.047838 -277.800784) (xy 419.059615 -277.753) (xy 419.078906 -277.707724)
			(xy 419.105209 -277.666128) (xy 419.137844 -277.629291) (xy 419.175965 -277.598166) (xy 419.218586 -277.573559)
			(xy 419.264602 -277.556107) (xy 419.312821 -277.546263) (xy 419.361996 -277.544282) (xy 419.410851 -277.550214)
			(xy 419.458122 -277.563906) (xy 419.502584 -277.585004) (xy 419.543087 -277.61296) (xy 419.57858 -277.647052)
			(xy 419.608145 -277.686396) (xy 419.631016 -277.729973) (xy 419.6466 -277.776654) (xy 419.654495 -277.825231)
			(xy 419.65499 -277.849838) (xy 420.943798 -277.849838) (xy 420.947758 -277.800784) (xy 420.959535 -277.753)
			(xy 420.978826 -277.707724) (xy 421.005129 -277.666128) (xy 421.037764 -277.629291) (xy 421.075885 -277.598166)
			(xy 421.118506 -277.573559) (xy 421.164522 -277.556107) (xy 421.212741 -277.546263) (xy 421.261916 -277.544282)
			(xy 421.310771 -277.550214) (xy 421.358042 -277.563906) (xy 421.402504 -277.585004) (xy 421.443007 -277.61296)
			(xy 421.4785 -277.647052) (xy 421.508065 -277.686396) (xy 421.530936 -277.729973) (xy 421.54652 -277.776654)
			(xy 421.554415 -277.825231) (xy 421.55491 -277.849838) (xy 422.843972 -277.849838) (xy 422.847932 -277.800784)
			(xy 422.859709 -277.753) (xy 422.879 -277.707724) (xy 422.905303 -277.666128) (xy 422.937938 -277.629291)
			(xy 422.976059 -277.598166) (xy 423.01868 -277.573559) (xy 423.064696 -277.556107) (xy 423.112915 -277.546263)
			(xy 423.16209 -277.544282) (xy 423.210945 -277.550214) (xy 423.258216 -277.563906) (xy 423.302678 -277.585004)
			(xy 423.343181 -277.61296) (xy 423.378674 -277.647052) (xy 423.408239 -277.686396) (xy 423.43111 -277.729973)
			(xy 423.446694 -277.776654) (xy 423.454589 -277.825231) (xy 423.455084 -277.849838) (xy 424.743892 -277.849838)
			(xy 424.747852 -277.800784) (xy 424.759629 -277.753) (xy 424.77892 -277.707724) (xy 424.805223 -277.666128)
			(xy 424.837858 -277.629291) (xy 424.875979 -277.598166) (xy 424.9186 -277.573559) (xy 424.964616 -277.556107)
			(xy 425.012835 -277.546263) (xy 425.06201 -277.544282) (xy 425.110865 -277.550214) (xy 425.158136 -277.563906)
			(xy 425.202598 -277.585004) (xy 425.243101 -277.61296) (xy 425.278594 -277.647052) (xy 425.308159 -277.686396)
			(xy 425.33103 -277.729973) (xy 425.346614 -277.776654) (xy 425.354509 -277.825231) (xy 425.355004 -277.849838)
			(xy 426.643812 -277.849838) (xy 426.647772 -277.800784) (xy 426.659549 -277.753) (xy 426.67884 -277.707724)
			(xy 426.705143 -277.666128) (xy 426.737778 -277.629291) (xy 426.775899 -277.598166) (xy 426.81852 -277.573559)
			(xy 426.864536 -277.556107) (xy 426.912755 -277.546263) (xy 426.96193 -277.544282) (xy 427.010785 -277.550214)
			(xy 427.058056 -277.563906) (xy 427.102518 -277.585004) (xy 427.143021 -277.61296) (xy 427.178514 -277.647052)
			(xy 427.208079 -277.686396) (xy 427.23095 -277.729973) (xy 427.246534 -277.776654) (xy 427.254429 -277.825231)
			(xy 427.254924 -277.849838) (xy 428.543986 -277.849838) (xy 428.547946 -277.800784) (xy 428.559723 -277.753)
			(xy 428.579014 -277.707724) (xy 428.605317 -277.666128) (xy 428.637952 -277.629291) (xy 428.676073 -277.598166)
			(xy 428.718694 -277.573559) (xy 428.76471 -277.556107) (xy 428.812929 -277.546263) (xy 428.862104 -277.544282)
			(xy 428.910959 -277.550214) (xy 428.95823 -277.563906) (xy 429.002692 -277.585004) (xy 429.043195 -277.61296)
			(xy 429.078688 -277.647052) (xy 429.108253 -277.686396) (xy 429.131124 -277.729973) (xy 429.146708 -277.776654)
			(xy 429.154603 -277.825231) (xy 429.155098 -277.849838) (xy 429.154603 -277.874445) (xy 429.146708 -277.923022)
			(xy 429.131124 -277.969703) (xy 429.108253 -278.01328) (xy 429.078688 -278.052624) (xy 429.043195 -278.086716)
			(xy 429.002692 -278.114672) (xy 428.95823 -278.13577) (xy 428.910959 -278.149462) (xy 428.862104 -278.155394)
			(xy 428.812929 -278.153413) (xy 428.76471 -278.143569) (xy 428.718694 -278.126117) (xy 428.676073 -278.10151)
			(xy 428.637952 -278.070385) (xy 428.605317 -278.033548) (xy 428.579014 -277.991952) (xy 428.559723 -277.946676)
			(xy 428.547946 -277.898892) (xy 428.543986 -277.849838) (xy 427.254924 -277.849838) (xy 427.254429 -277.874445)
			(xy 427.246534 -277.923022) (xy 427.23095 -277.969703) (xy 427.208079 -278.01328) (xy 427.178514 -278.052624)
			(xy 427.143021 -278.086716) (xy 427.102518 -278.114672) (xy 427.058056 -278.13577) (xy 427.010785 -278.149462)
			(xy 426.96193 -278.155394) (xy 426.912755 -278.153413) (xy 426.864536 -278.143569) (xy 426.81852 -278.126117)
			(xy 426.775899 -278.10151) (xy 426.737778 -278.070385) (xy 426.705143 -278.033548) (xy 426.67884 -277.991952)
			(xy 426.659549 -277.946676) (xy 426.647772 -277.898892) (xy 426.643812 -277.849838) (xy 425.355004 -277.849838)
			(xy 425.354509 -277.874445) (xy 425.346614 -277.923022) (xy 425.33103 -277.969703) (xy 425.308159 -278.01328)
			(xy 425.278594 -278.052624) (xy 425.243101 -278.086716) (xy 425.202598 -278.114672) (xy 425.158136 -278.13577)
			(xy 425.110865 -278.149462) (xy 425.06201 -278.155394) (xy 425.012835 -278.153413) (xy 424.964616 -278.143569)
			(xy 424.9186 -278.126117) (xy 424.875979 -278.10151) (xy 424.837858 -278.070385) (xy 424.805223 -278.033548)
			(xy 424.77892 -277.991952) (xy 424.759629 -277.946676) (xy 424.747852 -277.898892) (xy 424.743892 -277.849838)
			(xy 423.455084 -277.849838) (xy 423.454589 -277.874445) (xy 423.446694 -277.923022) (xy 423.43111 -277.969703)
			(xy 423.408239 -278.01328) (xy 423.378674 -278.052624) (xy 423.343181 -278.086716) (xy 423.302678 -278.114672)
			(xy 423.258216 -278.13577) (xy 423.210945 -278.149462) (xy 423.16209 -278.155394) (xy 423.112915 -278.153413)
			(xy 423.064696 -278.143569) (xy 423.01868 -278.126117) (xy 422.976059 -278.10151) (xy 422.937938 -278.070385)
			(xy 422.905303 -278.033548) (xy 422.879 -277.991952) (xy 422.859709 -277.946676) (xy 422.847932 -277.898892)
			(xy 422.843972 -277.849838) (xy 421.55491 -277.849838) (xy 421.554415 -277.874445) (xy 421.54652 -277.923022)
			(xy 421.530936 -277.969703) (xy 421.508065 -278.01328) (xy 421.4785 -278.052624) (xy 421.443007 -278.086716)
			(xy 421.402504 -278.114672) (xy 421.358042 -278.13577) (xy 421.310771 -278.149462) (xy 421.261916 -278.155394)
			(xy 421.212741 -278.153413) (xy 421.164522 -278.143569) (xy 421.118506 -278.126117) (xy 421.075885 -278.10151)
			(xy 421.037764 -278.070385) (xy 421.005129 -278.033548) (xy 420.978826 -277.991952) (xy 420.959535 -277.946676)
			(xy 420.947758 -277.898892) (xy 420.943798 -277.849838) (xy 419.65499 -277.849838) (xy 419.654495 -277.874445)
			(xy 419.6466 -277.923022) (xy 419.631016 -277.969703) (xy 419.608145 -278.01328) (xy 419.57858 -278.052624)
			(xy 419.543087 -278.086716) (xy 419.502584 -278.114672) (xy 419.458122 -278.13577) (xy 419.410851 -278.149462)
			(xy 419.361996 -278.155394) (xy 419.312821 -278.153413) (xy 419.264602 -278.143569) (xy 419.218586 -278.126117)
			(xy 419.175965 -278.10151) (xy 419.137844 -278.070385) (xy 419.105209 -278.033548) (xy 419.078906 -277.991952)
			(xy 419.059615 -277.946676) (xy 419.047838 -277.898892) (xy 419.043878 -277.849838) (xy 417.75507 -277.849838)
			(xy 417.754575 -277.874445) (xy 417.74668 -277.923022) (xy 417.731096 -277.969703) (xy 417.708225 -278.01328)
			(xy 417.67866 -278.052624) (xy 417.643167 -278.086716) (xy 417.602664 -278.114672) (xy 417.558202 -278.13577)
			(xy 417.510931 -278.149462) (xy 417.462076 -278.155394) (xy 417.412901 -278.153413) (xy 417.364682 -278.143569)
			(xy 417.318666 -278.126117) (xy 417.276045 -278.10151) (xy 417.237924 -278.070385) (xy 417.205289 -278.033548)
			(xy 417.178986 -277.991952) (xy 417.159695 -277.946676) (xy 417.147918 -277.898892) (xy 417.143958 -277.849838)
			(xy 415.854896 -277.849838) (xy 415.854401 -277.874445) (xy 415.846506 -277.923022) (xy 415.830922 -277.969703)
			(xy 415.808051 -278.01328) (xy 415.778486 -278.052624) (xy 415.742993 -278.086716) (xy 415.70249 -278.114672)
			(xy 415.658028 -278.13577) (xy 415.610757 -278.149462) (xy 415.561902 -278.155394) (xy 415.512727 -278.153413)
			(xy 415.464508 -278.143569) (xy 415.418492 -278.126117) (xy 415.375871 -278.10151) (xy 415.33775 -278.070385)
			(xy 415.305115 -278.033548) (xy 415.278812 -277.991952) (xy 415.259521 -277.946676) (xy 415.247744 -277.898892)
			(xy 415.243784 -277.849838) (xy 413.954976 -277.849838) (xy 413.954481 -277.874445) (xy 413.946586 -277.923022)
			(xy 413.931002 -277.969703) (xy 413.908131 -278.01328) (xy 413.878566 -278.052624) (xy 413.843073 -278.086716)
			(xy 413.80257 -278.114672) (xy 413.758108 -278.13577) (xy 413.710837 -278.149462) (xy 413.661982 -278.155394)
			(xy 413.612807 -278.153413) (xy 413.564588 -278.143569) (xy 413.518572 -278.126117) (xy 413.475951 -278.10151)
			(xy 413.43783 -278.070385) (xy 413.405195 -278.033548) (xy 413.378892 -277.991952) (xy 413.359601 -277.946676)
			(xy 413.347824 -277.898892) (xy 413.343864 -277.849838) (xy 412.055056 -277.849838) (xy 412.054561 -277.874445)
			(xy 412.046666 -277.923022) (xy 412.031082 -277.969703) (xy 412.008211 -278.01328) (xy 411.978646 -278.052624)
			(xy 411.943153 -278.086716) (xy 411.90265 -278.114672) (xy 411.858188 -278.13577) (xy 411.810917 -278.149462)
			(xy 411.762062 -278.155394) (xy 411.712887 -278.153413) (xy 411.664668 -278.143569) (xy 411.618652 -278.126117)
			(xy 411.576031 -278.10151) (xy 411.53791 -278.070385) (xy 411.505275 -278.033548) (xy 411.478972 -277.991952)
			(xy 411.459681 -277.946676) (xy 411.447904 -277.898892) (xy 411.443944 -277.849838) (xy 410.154882 -277.849838)
			(xy 410.154387 -277.874445) (xy 410.146492 -277.923022) (xy 410.130908 -277.969703) (xy 410.108037 -278.01328)
			(xy 410.078472 -278.052624) (xy 410.042979 -278.086716) (xy 410.002476 -278.114672) (xy 409.958014 -278.13577)
			(xy 409.910743 -278.149462) (xy 409.861888 -278.155394) (xy 409.812713 -278.153413) (xy 409.764494 -278.143569)
			(xy 409.718478 -278.126117) (xy 409.675857 -278.10151) (xy 409.637736 -278.070385) (xy 409.605101 -278.033548)
			(xy 409.578798 -277.991952) (xy 409.559507 -277.946676) (xy 409.54773 -277.898892) (xy 409.54377 -277.849838)
			(xy 408.254962 -277.849838) (xy 408.254467 -277.874445) (xy 408.246572 -277.923022) (xy 408.230988 -277.969703)
			(xy 408.208117 -278.01328) (xy 408.178552 -278.052624) (xy 408.143059 -278.086716) (xy 408.102556 -278.114672)
			(xy 408.058094 -278.13577) (xy 408.010823 -278.149462) (xy 407.961968 -278.155394) (xy 407.912793 -278.153413)
			(xy 407.864574 -278.143569) (xy 407.818558 -278.126117) (xy 407.775937 -278.10151) (xy 407.737816 -278.070385)
			(xy 407.705181 -278.033548) (xy 407.678878 -277.991952) (xy 407.659587 -277.946676) (xy 407.64781 -277.898892)
			(xy 407.64385 -277.849838) (xy 406.355296 -277.849838) (xy 406.354801 -277.874445) (xy 406.346906 -277.923022)
			(xy 406.331322 -277.969703) (xy 406.308451 -278.01328) (xy 406.278886 -278.052624) (xy 406.243393 -278.086716)
			(xy 406.20289 -278.114672) (xy 406.158428 -278.13577) (xy 406.111157 -278.149462) (xy 406.062302 -278.155394)
			(xy 406.013127 -278.153413) (xy 405.964908 -278.143569) (xy 405.918892 -278.126117) (xy 405.876271 -278.10151)
			(xy 405.83815 -278.070385) (xy 405.805515 -278.033548) (xy 405.779212 -277.991952) (xy 405.759921 -277.946676)
			(xy 405.748144 -277.898892) (xy 405.744184 -277.849838) (xy 404.455122 -277.849838) (xy 404.454627 -277.874445)
			(xy 404.446732 -277.923022) (xy 404.431148 -277.969703) (xy 404.408277 -278.01328) (xy 404.378712 -278.052624)
			(xy 404.343219 -278.086716) (xy 404.302716 -278.114672) (xy 404.258254 -278.13577) (xy 404.210983 -278.149462)
			(xy 404.162128 -278.155394) (xy 404.112953 -278.153413) (xy 404.064734 -278.143569) (xy 404.018718 -278.126117)
			(xy 403.976097 -278.10151) (xy 403.937976 -278.070385) (xy 403.905341 -278.033548) (xy 403.879038 -277.991952)
			(xy 403.859747 -277.946676) (xy 403.84797 -277.898892) (xy 403.84401 -277.849838) (xy 402.555202 -277.849838)
			(xy 402.554707 -277.874445) (xy 402.546812 -277.923022) (xy 402.531228 -277.969703) (xy 402.508357 -278.01328)
			(xy 402.478792 -278.052624) (xy 402.443299 -278.086716) (xy 402.402796 -278.114672) (xy 402.358334 -278.13577)
			(xy 402.311063 -278.149462) (xy 402.262208 -278.155394) (xy 402.213033 -278.153413) (xy 402.164814 -278.143569)
			(xy 402.118798 -278.126117) (xy 402.076177 -278.10151) (xy 402.038056 -278.070385) (xy 402.005421 -278.033548)
			(xy 401.979118 -277.991952) (xy 401.959827 -277.946676) (xy 401.94805 -277.898892) (xy 401.94409 -277.849838)
			(xy 400.655282 -277.849838) (xy 400.654787 -277.874445) (xy 400.646892 -277.923022) (xy 400.631308 -277.969703)
			(xy 400.608437 -278.01328) (xy 400.578872 -278.052624) (xy 400.543379 -278.086716) (xy 400.502876 -278.114672)
			(xy 400.458414 -278.13577) (xy 400.411143 -278.149462) (xy 400.362288 -278.155394) (xy 400.313113 -278.153413)
			(xy 400.264894 -278.143569) (xy 400.218878 -278.126117) (xy 400.176257 -278.10151) (xy 400.138136 -278.070385)
			(xy 400.105501 -278.033548) (xy 400.079198 -277.991952) (xy 400.059907 -277.946676) (xy 400.04813 -277.898892)
			(xy 400.04417 -277.849838) (xy 398.755108 -277.849838) (xy 398.754613 -277.874445) (xy 398.746718 -277.923022)
			(xy 398.731134 -277.969703) (xy 398.708263 -278.01328) (xy 398.678698 -278.052624) (xy 398.643205 -278.086716)
			(xy 398.602702 -278.114672) (xy 398.55824 -278.13577) (xy 398.510969 -278.149462) (xy 398.462114 -278.155394)
			(xy 398.412939 -278.153413) (xy 398.36472 -278.143569) (xy 398.318704 -278.126117) (xy 398.276083 -278.10151)
			(xy 398.237962 -278.070385) (xy 398.205327 -278.033548) (xy 398.179024 -277.991952) (xy 398.159733 -277.946676)
			(xy 398.147956 -277.898892) (xy 398.143996 -277.849838) (xy 396.855188 -277.849838) (xy 396.854693 -277.874445)
			(xy 396.846798 -277.923022) (xy 396.831214 -277.969703) (xy 396.808343 -278.01328) (xy 396.778778 -278.052624)
			(xy 396.743285 -278.086716) (xy 396.702782 -278.114672) (xy 396.65832 -278.13577) (xy 396.611049 -278.149462)
			(xy 396.562194 -278.155394) (xy 396.513019 -278.153413) (xy 396.4648 -278.143569) (xy 396.418784 -278.126117)
			(xy 396.376163 -278.10151) (xy 396.338042 -278.070385) (xy 396.305407 -278.033548) (xy 396.279104 -277.991952)
			(xy 396.259813 -277.946676) (xy 396.248036 -277.898892) (xy 396.244076 -277.849838) (xy 394.955268 -277.849838)
			(xy 394.954773 -277.874445) (xy 394.946878 -277.923022) (xy 394.931294 -277.969703) (xy 394.908423 -278.01328)
			(xy 394.878858 -278.052624) (xy 394.843365 -278.086716) (xy 394.802862 -278.114672) (xy 394.7584 -278.13577)
			(xy 394.711129 -278.149462) (xy 394.662274 -278.155394) (xy 394.613099 -278.153413) (xy 394.56488 -278.143569)
			(xy 394.518864 -278.126117) (xy 394.476243 -278.10151) (xy 394.438122 -278.070385) (xy 394.405487 -278.033548)
			(xy 394.379184 -277.991952) (xy 394.359893 -277.946676) (xy 394.348116 -277.898892) (xy 394.344156 -277.849838)
			(xy 393.055094 -277.849838) (xy 393.054599 -277.874445) (xy 393.046704 -277.923022) (xy 393.03112 -277.969703)
			(xy 393.008249 -278.01328) (xy 392.978684 -278.052624) (xy 392.943191 -278.086716) (xy 392.902688 -278.114672)
			(xy 392.858226 -278.13577) (xy 392.810955 -278.149462) (xy 392.7621 -278.155394) (xy 392.712925 -278.153413)
			(xy 392.664706 -278.143569) (xy 392.61869 -278.126117) (xy 392.576069 -278.10151) (xy 392.537948 -278.070385)
			(xy 392.505313 -278.033548) (xy 392.47901 -277.991952) (xy 392.459719 -277.946676) (xy 392.447942 -277.898892)
			(xy 392.443982 -277.849838) (xy 313.055 -277.849838) (xy 313.054505 -277.874445) (xy 313.04661 -277.923022)
			(xy 313.031026 -277.969703) (xy 313.008155 -278.01328) (xy 312.97859 -278.052624) (xy 312.943097 -278.086716)
			(xy 312.902594 -278.114672) (xy 312.858132 -278.13577) (xy 312.810861 -278.149462) (xy 312.762006 -278.155394)
			(xy 312.712831 -278.153413) (xy 312.664612 -278.143569) (xy 312.618596 -278.126117) (xy 312.575975 -278.10151)
			(xy 312.537854 -278.070385) (xy 312.505219 -278.033548) (xy 312.478916 -277.991952) (xy 312.459625 -277.946676)
			(xy 312.447848 -277.898892) (xy 312.443888 -277.849838) (xy 311.154826 -277.849838) (xy 311.154331 -277.874445)
			(xy 311.146436 -277.923022) (xy 311.130852 -277.969703) (xy 311.107981 -278.01328) (xy 311.078416 -278.052624)
			(xy 311.042923 -278.086716) (xy 311.00242 -278.114672) (xy 310.957958 -278.13577) (xy 310.910687 -278.149462)
			(xy 310.861832 -278.155394) (xy 310.812657 -278.153413) (xy 310.764438 -278.143569) (xy 310.718422 -278.126117)
			(xy 310.675801 -278.10151) (xy 310.63768 -278.070385) (xy 310.605045 -278.033548) (xy 310.578742 -277.991952)
			(xy 310.559451 -277.946676) (xy 310.547674 -277.898892) (xy 310.543714 -277.849838) (xy 309.254906 -277.849838)
			(xy 309.254411 -277.874445) (xy 309.246516 -277.923022) (xy 309.230932 -277.969703) (xy 309.208061 -278.01328)
			(xy 309.178496 -278.052624) (xy 309.143003 -278.086716) (xy 309.1025 -278.114672) (xy 309.058038 -278.13577)
			(xy 309.010767 -278.149462) (xy 308.961912 -278.155394) (xy 308.912737 -278.153413) (xy 308.864518 -278.143569)
			(xy 308.818502 -278.126117) (xy 308.775881 -278.10151) (xy 308.73776 -278.070385) (xy 308.705125 -278.033548)
			(xy 308.678822 -277.991952) (xy 308.659531 -277.946676) (xy 308.647754 -277.898892) (xy 308.643794 -277.849838)
			(xy 307.354986 -277.849838) (xy 307.354491 -277.874445) (xy 307.346596 -277.923022) (xy 307.331012 -277.969703)
			(xy 307.308141 -278.01328) (xy 307.278576 -278.052624) (xy 307.243083 -278.086716) (xy 307.20258 -278.114672)
			(xy 307.158118 -278.13577) (xy 307.110847 -278.149462) (xy 307.061992 -278.155394) (xy 307.012817 -278.153413)
			(xy 306.964598 -278.143569) (xy 306.918582 -278.126117) (xy 306.875961 -278.10151) (xy 306.83784 -278.070385)
			(xy 306.805205 -278.033548) (xy 306.778902 -277.991952) (xy 306.759611 -277.946676) (xy 306.747834 -277.898892)
			(xy 306.743874 -277.849838) (xy 305.454812 -277.849838) (xy 305.454317 -277.874445) (xy 305.446422 -277.923022)
			(xy 305.430838 -277.969703) (xy 305.407967 -278.01328) (xy 305.378402 -278.052624) (xy 305.342909 -278.086716)
			(xy 305.302406 -278.114672) (xy 305.257944 -278.13577) (xy 305.210673 -278.149462) (xy 305.161818 -278.155394)
			(xy 305.112643 -278.153413) (xy 305.064424 -278.143569) (xy 305.018408 -278.126117) (xy 304.975787 -278.10151)
			(xy 304.937666 -278.070385) (xy 304.905031 -278.033548) (xy 304.878728 -277.991952) (xy 304.859437 -277.946676)
			(xy 304.84766 -277.898892) (xy 304.8437 -277.849838) (xy 303.554892 -277.849838) (xy 303.554397 -277.874445)
			(xy 303.546502 -277.923022) (xy 303.530918 -277.969703) (xy 303.508047 -278.01328) (xy 303.478482 -278.052624)
			(xy 303.442989 -278.086716) (xy 303.402486 -278.114672) (xy 303.358024 -278.13577) (xy 303.310753 -278.149462)
			(xy 303.261898 -278.155394) (xy 303.212723 -278.153413) (xy 303.164504 -278.143569) (xy 303.118488 -278.126117)
			(xy 303.075867 -278.10151) (xy 303.037746 -278.070385) (xy 303.005111 -278.033548) (xy 302.978808 -277.991952)
			(xy 302.959517 -277.946676) (xy 302.94774 -277.898892) (xy 302.94378 -277.849838) (xy 301.654972 -277.849838)
			(xy 301.654477 -277.874445) (xy 301.646582 -277.923022) (xy 301.630998 -277.969703) (xy 301.608127 -278.01328)
			(xy 301.578562 -278.052624) (xy 301.543069 -278.086716) (xy 301.502566 -278.114672) (xy 301.458104 -278.13577)
			(xy 301.410833 -278.149462) (xy 301.361978 -278.155394) (xy 301.312803 -278.153413) (xy 301.264584 -278.143569)
			(xy 301.218568 -278.126117) (xy 301.175947 -278.10151) (xy 301.137826 -278.070385) (xy 301.105191 -278.033548)
			(xy 301.078888 -277.991952) (xy 301.059597 -277.946676) (xy 301.04782 -277.898892) (xy 301.04386 -277.849838)
			(xy 299.754798 -277.849838) (xy 299.754303 -277.874445) (xy 299.746408 -277.923022) (xy 299.730824 -277.969703)
			(xy 299.707953 -278.01328) (xy 299.678388 -278.052624) (xy 299.642895 -278.086716) (xy 299.602392 -278.114672)
			(xy 299.55793 -278.13577) (xy 299.510659 -278.149462) (xy 299.461804 -278.155394) (xy 299.412629 -278.153413)
			(xy 299.36441 -278.143569) (xy 299.318394 -278.126117) (xy 299.275773 -278.10151) (xy 299.237652 -278.070385)
			(xy 299.205017 -278.033548) (xy 299.178714 -277.991952) (xy 299.159423 -277.946676) (xy 299.147646 -277.898892)
			(xy 299.143686 -277.849838) (xy 297.854878 -277.849838) (xy 297.854383 -277.874445) (xy 297.846488 -277.923022)
			(xy 297.830904 -277.969703) (xy 297.808033 -278.01328) (xy 297.778468 -278.052624) (xy 297.742975 -278.086716)
			(xy 297.702472 -278.114672) (xy 297.65801 -278.13577) (xy 297.610739 -278.149462) (xy 297.561884 -278.155394)
			(xy 297.512709 -278.153413) (xy 297.46449 -278.143569) (xy 297.418474 -278.126117) (xy 297.375853 -278.10151)
			(xy 297.337732 -278.070385) (xy 297.305097 -278.033548) (xy 297.278794 -277.991952) (xy 297.259503 -277.946676)
			(xy 297.247726 -277.898892) (xy 297.243766 -277.849838) (xy 295.954958 -277.849838) (xy 295.954463 -277.874445)
			(xy 295.946568 -277.923022) (xy 295.930984 -277.969703) (xy 295.908113 -278.01328) (xy 295.878548 -278.052624)
			(xy 295.843055 -278.086716) (xy 295.802552 -278.114672) (xy 295.75809 -278.13577) (xy 295.710819 -278.149462)
			(xy 295.661964 -278.155394) (xy 295.612789 -278.153413) (xy 295.56457 -278.143569) (xy 295.518554 -278.126117)
			(xy 295.475933 -278.10151) (xy 295.437812 -278.070385) (xy 295.405177 -278.033548) (xy 295.378874 -277.991952)
			(xy 295.359583 -277.946676) (xy 295.347806 -277.898892) (xy 295.343846 -277.849838) (xy 294.054784 -277.849838)
			(xy 294.054289 -277.874445) (xy 294.046394 -277.923022) (xy 294.03081 -277.969703) (xy 294.007939 -278.01328)
			(xy 293.978374 -278.052624) (xy 293.942881 -278.086716) (xy 293.902378 -278.114672) (xy 293.857916 -278.13577)
			(xy 293.810645 -278.149462) (xy 293.76179 -278.155394) (xy 293.712615 -278.153413) (xy 293.664396 -278.143569)
			(xy 293.61838 -278.126117) (xy 293.575759 -278.10151) (xy 293.537638 -278.070385) (xy 293.505003 -278.033548)
			(xy 293.4787 -277.991952) (xy 293.459409 -277.946676) (xy 293.447632 -277.898892) (xy 293.443672 -277.849838)
			(xy 292.154864 -277.849838) (xy 292.154369 -277.874445) (xy 292.146474 -277.923022) (xy 292.13089 -277.969703)
			(xy 292.108019 -278.01328) (xy 292.078454 -278.052624) (xy 292.042961 -278.086716) (xy 292.002458 -278.114672)
			(xy 291.957996 -278.13577) (xy 291.910725 -278.149462) (xy 291.86187 -278.155394) (xy 291.812695 -278.153413)
			(xy 291.764476 -278.143569) (xy 291.71846 -278.126117) (xy 291.675839 -278.10151) (xy 291.637718 -278.070385)
			(xy 291.605083 -278.033548) (xy 291.57878 -277.991952) (xy 291.559489 -277.946676) (xy 291.547712 -277.898892)
			(xy 291.543752 -277.849838) (xy 290.255198 -277.849838) (xy 290.254703 -277.874445) (xy 290.246808 -277.923022)
			(xy 290.231224 -277.969703) (xy 290.208353 -278.01328) (xy 290.178788 -278.052624) (xy 290.143295 -278.086716)
			(xy 290.102792 -278.114672) (xy 290.05833 -278.13577) (xy 290.011059 -278.149462) (xy 289.962204 -278.155394)
			(xy 289.913029 -278.153413) (xy 289.86481 -278.143569) (xy 289.818794 -278.126117) (xy 289.776173 -278.10151)
			(xy 289.738052 -278.070385) (xy 289.705417 -278.033548) (xy 289.679114 -277.991952) (xy 289.659823 -277.946676)
			(xy 289.648046 -277.898892) (xy 289.644086 -277.849838) (xy 288.355024 -277.849838) (xy 288.354529 -277.874445)
			(xy 288.346634 -277.923022) (xy 288.33105 -277.969703) (xy 288.308179 -278.01328) (xy 288.278614 -278.052624)
			(xy 288.243121 -278.086716) (xy 288.202618 -278.114672) (xy 288.158156 -278.13577) (xy 288.110885 -278.149462)
			(xy 288.06203 -278.155394) (xy 288.012855 -278.153413) (xy 287.964636 -278.143569) (xy 287.91862 -278.126117)
			(xy 287.875999 -278.10151) (xy 287.837878 -278.070385) (xy 287.805243 -278.033548) (xy 287.77894 -277.991952)
			(xy 287.759649 -277.946676) (xy 287.747872 -277.898892) (xy 287.743912 -277.849838) (xy 286.455104 -277.849838)
			(xy 286.454609 -277.874445) (xy 286.446714 -277.923022) (xy 286.43113 -277.969703) (xy 286.408259 -278.01328)
			(xy 286.378694 -278.052624) (xy 286.343201 -278.086716) (xy 286.302698 -278.114672) (xy 286.258236 -278.13577)
			(xy 286.210965 -278.149462) (xy 286.16211 -278.155394) (xy 286.112935 -278.153413) (xy 286.064716 -278.143569)
			(xy 286.0187 -278.126117) (xy 285.976079 -278.10151) (xy 285.937958 -278.070385) (xy 285.905323 -278.033548)
			(xy 285.87902 -277.991952) (xy 285.859729 -277.946676) (xy 285.847952 -277.898892) (xy 285.843992 -277.849838)
			(xy 284.555184 -277.849838) (xy 284.554689 -277.874445) (xy 284.546794 -277.923022) (xy 284.53121 -277.969703)
			(xy 284.508339 -278.01328) (xy 284.478774 -278.052624) (xy 284.443281 -278.086716) (xy 284.402778 -278.114672)
			(xy 284.358316 -278.13577) (xy 284.311045 -278.149462) (xy 284.26219 -278.155394) (xy 284.213015 -278.153413)
			(xy 284.164796 -278.143569) (xy 284.11878 -278.126117) (xy 284.076159 -278.10151) (xy 284.038038 -278.070385)
			(xy 284.005403 -278.033548) (xy 283.9791 -277.991952) (xy 283.959809 -277.946676) (xy 283.948032 -277.898892)
			(xy 283.944072 -277.849838) (xy 282.65501 -277.849838) (xy 282.654515 -277.874445) (xy 282.64662 -277.923022)
			(xy 282.631036 -277.969703) (xy 282.608165 -278.01328) (xy 282.5786 -278.052624) (xy 282.543107 -278.086716)
			(xy 282.502604 -278.114672) (xy 282.458142 -278.13577) (xy 282.410871 -278.149462) (xy 282.362016 -278.155394)
			(xy 282.312841 -278.153413) (xy 282.264622 -278.143569) (xy 282.218606 -278.126117) (xy 282.175985 -278.10151)
			(xy 282.137864 -278.070385) (xy 282.105229 -278.033548) (xy 282.078926 -277.991952) (xy 282.059635 -277.946676)
			(xy 282.047858 -277.898892) (xy 282.043898 -277.849838) (xy 280.75509 -277.849838) (xy 280.754595 -277.874445)
			(xy 280.7467 -277.923022) (xy 280.731116 -277.969703) (xy 280.708245 -278.01328) (xy 280.67868 -278.052624)
			(xy 280.643187 -278.086716) (xy 280.602684 -278.114672) (xy 280.558222 -278.13577) (xy 280.510951 -278.149462)
			(xy 280.462096 -278.155394) (xy 280.412921 -278.153413) (xy 280.364702 -278.143569) (xy 280.318686 -278.126117)
			(xy 280.276065 -278.10151) (xy 280.237944 -278.070385) (xy 280.205309 -278.033548) (xy 280.179006 -277.991952)
			(xy 280.159715 -277.946676) (xy 280.147938 -277.898892) (xy 280.143978 -277.849838) (xy 278.85517 -277.849838)
			(xy 278.854675 -277.874445) (xy 278.84678 -277.923022) (xy 278.831196 -277.969703) (xy 278.808325 -278.01328)
			(xy 278.77876 -278.052624) (xy 278.743267 -278.086716) (xy 278.702764 -278.114672) (xy 278.658302 -278.13577)
			(xy 278.611031 -278.149462) (xy 278.562176 -278.155394) (xy 278.513001 -278.153413) (xy 278.464782 -278.143569)
			(xy 278.418766 -278.126117) (xy 278.376145 -278.10151) (xy 278.338024 -278.070385) (xy 278.305389 -278.033548)
			(xy 278.279086 -277.991952) (xy 278.259795 -277.946676) (xy 278.248018 -277.898892) (xy 278.244058 -277.849838)
			(xy 276.954996 -277.849838) (xy 276.954501 -277.874445) (xy 276.946606 -277.923022) (xy 276.931022 -277.969703)
			(xy 276.908151 -278.01328) (xy 276.878586 -278.052624) (xy 276.843093 -278.086716) (xy 276.80259 -278.114672)
			(xy 276.758128 -278.13577) (xy 276.710857 -278.149462) (xy 276.662002 -278.155394) (xy 276.612827 -278.153413)
			(xy 276.564608 -278.143569) (xy 276.518592 -278.126117) (xy 276.475971 -278.10151) (xy 276.43785 -278.070385)
			(xy 276.405215 -278.033548) (xy 276.378912 -277.991952) (xy 276.359621 -277.946676) (xy 276.347844 -277.898892)
			(xy 276.343884 -277.849838) (xy 196.955156 -277.849838) (xy 196.954661 -277.874445) (xy 196.946766 -277.923022)
			(xy 196.931182 -277.969703) (xy 196.908311 -278.01328) (xy 196.878746 -278.052624) (xy 196.843253 -278.086716)
			(xy 196.80275 -278.114672) (xy 196.758288 -278.13577) (xy 196.711017 -278.149462) (xy 196.662162 -278.155394)
			(xy 196.612987 -278.153413) (xy 196.564768 -278.143569) (xy 196.518752 -278.126117) (xy 196.476131 -278.10151)
			(xy 196.43801 -278.070385) (xy 196.405375 -278.033548) (xy 196.379072 -277.991952) (xy 196.359781 -277.946676)
			(xy 196.348004 -277.898892) (xy 196.344044 -277.849838) (xy 195.054982 -277.849838) (xy 195.054487 -277.874445)
			(xy 195.046592 -277.923022) (xy 195.031008 -277.969703) (xy 195.008137 -278.01328) (xy 194.978572 -278.052624)
			(xy 194.943079 -278.086716) (xy 194.902576 -278.114672) (xy 194.858114 -278.13577) (xy 194.810843 -278.149462)
			(xy 194.761988 -278.155394) (xy 194.712813 -278.153413) (xy 194.664594 -278.143569) (xy 194.618578 -278.126117)
			(xy 194.575957 -278.10151) (xy 194.537836 -278.070385) (xy 194.505201 -278.033548) (xy 194.478898 -277.991952)
			(xy 194.459607 -277.946676) (xy 194.44783 -277.898892) (xy 194.44387 -277.849838) (xy 193.155062 -277.849838)
			(xy 193.154567 -277.874445) (xy 193.146672 -277.923022) (xy 193.131088 -277.969703) (xy 193.108217 -278.01328)
			(xy 193.078652 -278.052624) (xy 193.043159 -278.086716) (xy 193.002656 -278.114672) (xy 192.958194 -278.13577)
			(xy 192.910923 -278.149462) (xy 192.862068 -278.155394) (xy 192.812893 -278.153413) (xy 192.764674 -278.143569)
			(xy 192.718658 -278.126117) (xy 192.676037 -278.10151) (xy 192.637916 -278.070385) (xy 192.605281 -278.033548)
			(xy 192.578978 -277.991952) (xy 192.559687 -277.946676) (xy 192.54791 -277.898892) (xy 192.54395 -277.849838)
			(xy 191.255142 -277.849838) (xy 191.254647 -277.874445) (xy 191.246752 -277.923022) (xy 191.231168 -277.969703)
			(xy 191.208297 -278.01328) (xy 191.178732 -278.052624) (xy 191.143239 -278.086716) (xy 191.102736 -278.114672)
			(xy 191.058274 -278.13577) (xy 191.011003 -278.149462) (xy 190.962148 -278.155394) (xy 190.912973 -278.153413)
			(xy 190.864754 -278.143569) (xy 190.818738 -278.126117) (xy 190.776117 -278.10151) (xy 190.737996 -278.070385)
			(xy 190.705361 -278.033548) (xy 190.679058 -277.991952) (xy 190.659767 -277.946676) (xy 190.64799 -277.898892)
			(xy 190.64403 -277.849838) (xy 189.354968 -277.849838) (xy 189.354473 -277.874445) (xy 189.346578 -277.923022)
			(xy 189.330994 -277.969703) (xy 189.308123 -278.01328) (xy 189.278558 -278.052624) (xy 189.243065 -278.086716)
			(xy 189.202562 -278.114672) (xy 189.1581 -278.13577) (xy 189.110829 -278.149462) (xy 189.061974 -278.155394)
			(xy 189.012799 -278.153413) (xy 188.96458 -278.143569) (xy 188.918564 -278.126117) (xy 188.875943 -278.10151)
			(xy 188.837822 -278.070385) (xy 188.805187 -278.033548) (xy 188.778884 -277.991952) (xy 188.759593 -277.946676)
			(xy 188.747816 -277.898892) (xy 188.743856 -277.849838) (xy 187.455048 -277.849838) (xy 187.454553 -277.874445)
			(xy 187.446658 -277.923022) (xy 187.431074 -277.969703) (xy 187.408203 -278.01328) (xy 187.378638 -278.052624)
			(xy 187.343145 -278.086716) (xy 187.302642 -278.114672) (xy 187.25818 -278.13577) (xy 187.210909 -278.149462)
			(xy 187.162054 -278.155394) (xy 187.112879 -278.153413) (xy 187.06466 -278.143569) (xy 187.018644 -278.126117)
			(xy 186.976023 -278.10151) (xy 186.937902 -278.070385) (xy 186.905267 -278.033548) (xy 186.878964 -277.991952)
			(xy 186.859673 -277.946676) (xy 186.847896 -277.898892) (xy 186.843936 -277.849838) (xy 185.555128 -277.849838)
			(xy 185.554633 -277.874445) (xy 185.546738 -277.923022) (xy 185.531154 -277.969703) (xy 185.508283 -278.01328)
			(xy 185.478718 -278.052624) (xy 185.443225 -278.086716) (xy 185.402722 -278.114672) (xy 185.35826 -278.13577)
			(xy 185.310989 -278.149462) (xy 185.262134 -278.155394) (xy 185.212959 -278.153413) (xy 185.16474 -278.143569)
			(xy 185.118724 -278.126117) (xy 185.076103 -278.10151) (xy 185.037982 -278.070385) (xy 185.005347 -278.033548)
			(xy 184.979044 -277.991952) (xy 184.959753 -277.946676) (xy 184.947976 -277.898892) (xy 184.944016 -277.849838)
			(xy 183.654954 -277.849838) (xy 183.654459 -277.874445) (xy 183.646564 -277.923022) (xy 183.63098 -277.969703)
			(xy 183.608109 -278.01328) (xy 183.578544 -278.052624) (xy 183.543051 -278.086716) (xy 183.502548 -278.114672)
			(xy 183.458086 -278.13577) (xy 183.410815 -278.149462) (xy 183.36196 -278.155394) (xy 183.312785 -278.153413)
			(xy 183.264566 -278.143569) (xy 183.21855 -278.126117) (xy 183.175929 -278.10151) (xy 183.137808 -278.070385)
			(xy 183.105173 -278.033548) (xy 183.07887 -277.991952) (xy 183.059579 -277.946676) (xy 183.047802 -277.898892)
			(xy 183.043842 -277.849838) (xy 181.755034 -277.849838) (xy 181.754539 -277.874445) (xy 181.746644 -277.923022)
			(xy 181.73106 -277.969703) (xy 181.708189 -278.01328) (xy 181.678624 -278.052624) (xy 181.643131 -278.086716)
			(xy 181.602628 -278.114672) (xy 181.558166 -278.13577) (xy 181.510895 -278.149462) (xy 181.46204 -278.155394)
			(xy 181.412865 -278.153413) (xy 181.364646 -278.143569) (xy 181.31863 -278.126117) (xy 181.276009 -278.10151)
			(xy 181.237888 -278.070385) (xy 181.205253 -278.033548) (xy 181.17895 -277.991952) (xy 181.159659 -277.946676)
			(xy 181.147882 -277.898892) (xy 181.143922 -277.849838) (xy 179.855114 -277.849838) (xy 179.854619 -277.874445)
			(xy 179.846724 -277.923022) (xy 179.83114 -277.969703) (xy 179.808269 -278.01328) (xy 179.778704 -278.052624)
			(xy 179.743211 -278.086716) (xy 179.702708 -278.114672) (xy 179.658246 -278.13577) (xy 179.610975 -278.149462)
			(xy 179.56212 -278.155394) (xy 179.512945 -278.153413) (xy 179.464726 -278.143569) (xy 179.41871 -278.126117)
			(xy 179.376089 -278.10151) (xy 179.337968 -278.070385) (xy 179.305333 -278.033548) (xy 179.27903 -277.991952)
			(xy 179.259739 -277.946676) (xy 179.247962 -277.898892) (xy 179.244002 -277.849838) (xy 177.95494 -277.849838)
			(xy 177.954445 -277.874445) (xy 177.94655 -277.923022) (xy 177.930966 -277.969703) (xy 177.908095 -278.01328)
			(xy 177.87853 -278.052624) (xy 177.843037 -278.086716) (xy 177.802534 -278.114672) (xy 177.758072 -278.13577)
			(xy 177.710801 -278.149462) (xy 177.661946 -278.155394) (xy 177.612771 -278.153413) (xy 177.564552 -278.143569)
			(xy 177.518536 -278.126117) (xy 177.475915 -278.10151) (xy 177.437794 -278.070385) (xy 177.405159 -278.033548)
			(xy 177.378856 -277.991952) (xy 177.359565 -277.946676) (xy 177.347788 -277.898892) (xy 177.343828 -277.849838)
			(xy 176.05502 -277.849838) (xy 176.054525 -277.874445) (xy 176.04663 -277.923022) (xy 176.031046 -277.969703)
			(xy 176.008175 -278.01328) (xy 175.97861 -278.052624) (xy 175.943117 -278.086716) (xy 175.902614 -278.114672)
			(xy 175.858152 -278.13577) (xy 175.810881 -278.149462) (xy 175.762026 -278.155394) (xy 175.712851 -278.153413)
			(xy 175.664632 -278.143569) (xy 175.618616 -278.126117) (xy 175.575995 -278.10151) (xy 175.537874 -278.070385)
			(xy 175.505239 -278.033548) (xy 175.478936 -277.991952) (xy 175.459645 -277.946676) (xy 175.447868 -277.898892)
			(xy 175.443908 -277.849838) (xy 174.155354 -277.849838) (xy 174.154859 -277.874445) (xy 174.146964 -277.923022)
			(xy 174.13138 -277.969703) (xy 174.108509 -278.01328) (xy 174.078944 -278.052624) (xy 174.043451 -278.086716)
			(xy 174.002948 -278.114672) (xy 173.958486 -278.13577) (xy 173.911215 -278.149462) (xy 173.86236 -278.155394)
			(xy 173.813185 -278.153413) (xy 173.764966 -278.143569) (xy 173.71895 -278.126117) (xy 173.676329 -278.10151)
			(xy 173.638208 -278.070385) (xy 173.605573 -278.033548) (xy 173.57927 -277.991952) (xy 173.559979 -277.946676)
			(xy 173.548202 -277.898892) (xy 173.544242 -277.849838) (xy 172.25518 -277.849838) (xy 172.254685 -277.874445)
			(xy 172.24679 -277.923022) (xy 172.231206 -277.969703) (xy 172.208335 -278.01328) (xy 172.17877 -278.052624)
			(xy 172.143277 -278.086716) (xy 172.102774 -278.114672) (xy 172.058312 -278.13577) (xy 172.011041 -278.149462)
			(xy 171.962186 -278.155394) (xy 171.913011 -278.153413) (xy 171.864792 -278.143569) (xy 171.818776 -278.126117)
			(xy 171.776155 -278.10151) (xy 171.738034 -278.070385) (xy 171.705399 -278.033548) (xy 171.679096 -277.991952)
			(xy 171.659805 -277.946676) (xy 171.648028 -277.898892) (xy 171.644068 -277.849838) (xy 170.35526 -277.849838)
			(xy 170.354765 -277.874445) (xy 170.34687 -277.923022) (xy 170.331286 -277.969703) (xy 170.308415 -278.01328)
			(xy 170.27885 -278.052624) (xy 170.243357 -278.086716) (xy 170.202854 -278.114672) (xy 170.158392 -278.13577)
			(xy 170.111121 -278.149462) (xy 170.062266 -278.155394) (xy 170.013091 -278.153413) (xy 169.964872 -278.143569)
			(xy 169.918856 -278.126117) (xy 169.876235 -278.10151) (xy 169.838114 -278.070385) (xy 169.805479 -278.033548)
			(xy 169.779176 -277.991952) (xy 169.759885 -277.946676) (xy 169.748108 -277.898892) (xy 169.744148 -277.849838)
			(xy 168.45534 -277.849838) (xy 168.454845 -277.874445) (xy 168.44695 -277.923022) (xy 168.431366 -277.969703)
			(xy 168.408495 -278.01328) (xy 168.37893 -278.052624) (xy 168.343437 -278.086716) (xy 168.302934 -278.114672)
			(xy 168.258472 -278.13577) (xy 168.211201 -278.149462) (xy 168.162346 -278.155394) (xy 168.113171 -278.153413)
			(xy 168.064952 -278.143569) (xy 168.018936 -278.126117) (xy 167.976315 -278.10151) (xy 167.938194 -278.070385)
			(xy 167.905559 -278.033548) (xy 167.879256 -277.991952) (xy 167.859965 -277.946676) (xy 167.848188 -277.898892)
			(xy 167.844228 -277.849838) (xy 166.555166 -277.849838) (xy 166.554671 -277.874445) (xy 166.546776 -277.923022)
			(xy 166.531192 -277.969703) (xy 166.508321 -278.01328) (xy 166.478756 -278.052624) (xy 166.443263 -278.086716)
			(xy 166.40276 -278.114672) (xy 166.358298 -278.13577) (xy 166.311027 -278.149462) (xy 166.262172 -278.155394)
			(xy 166.212997 -278.153413) (xy 166.164778 -278.143569) (xy 166.118762 -278.126117) (xy 166.076141 -278.10151)
			(xy 166.03802 -278.070385) (xy 166.005385 -278.033548) (xy 165.979082 -277.991952) (xy 165.959791 -277.946676)
			(xy 165.948014 -277.898892) (xy 165.944054 -277.849838) (xy 164.655246 -277.849838) (xy 164.654751 -277.874445)
			(xy 164.646856 -277.923022) (xy 164.631272 -277.969703) (xy 164.608401 -278.01328) (xy 164.578836 -278.052624)
			(xy 164.543343 -278.086716) (xy 164.50284 -278.114672) (xy 164.458378 -278.13577) (xy 164.411107 -278.149462)
			(xy 164.362252 -278.155394) (xy 164.313077 -278.153413) (xy 164.264858 -278.143569) (xy 164.218842 -278.126117)
			(xy 164.176221 -278.10151) (xy 164.1381 -278.070385) (xy 164.105465 -278.033548) (xy 164.079162 -277.991952)
			(xy 164.059871 -277.946676) (xy 164.048094 -277.898892) (xy 164.044134 -277.849838) (xy 162.755326 -277.849838)
			(xy 162.754831 -277.874445) (xy 162.746936 -277.923022) (xy 162.731352 -277.969703) (xy 162.708481 -278.01328)
			(xy 162.678916 -278.052624) (xy 162.643423 -278.086716) (xy 162.60292 -278.114672) (xy 162.558458 -278.13577)
			(xy 162.511187 -278.149462) (xy 162.462332 -278.155394) (xy 162.413157 -278.153413) (xy 162.364938 -278.143569)
			(xy 162.318922 -278.126117) (xy 162.276301 -278.10151) (xy 162.23818 -278.070385) (xy 162.205545 -278.033548)
			(xy 162.179242 -277.991952) (xy 162.159951 -277.946676) (xy 162.148174 -277.898892) (xy 162.144214 -277.849838)
			(xy 160.855152 -277.849838) (xy 160.854657 -277.874445) (xy 160.846762 -277.923022) (xy 160.831178 -277.969703)
			(xy 160.808307 -278.01328) (xy 160.778742 -278.052624) (xy 160.743249 -278.086716) (xy 160.702746 -278.114672)
			(xy 160.658284 -278.13577) (xy 160.611013 -278.149462) (xy 160.562158 -278.155394) (xy 160.512983 -278.153413)
			(xy 160.464764 -278.143569) (xy 160.418748 -278.126117) (xy 160.376127 -278.10151) (xy 160.338006 -278.070385)
			(xy 160.305371 -278.033548) (xy 160.279068 -277.991952) (xy 160.259777 -277.946676) (xy 160.248 -277.898892)
			(xy 160.24404 -277.849838) (xy 80.855058 -277.849838) (xy 80.854563 -277.874445) (xy 80.846668 -277.923022)
			(xy 80.831084 -277.969703) (xy 80.808213 -278.01328) (xy 80.778648 -278.052624) (xy 80.743155 -278.086716)
			(xy 80.702652 -278.114672) (xy 80.65819 -278.13577) (xy 80.610919 -278.149462) (xy 80.562064 -278.155394)
			(xy 80.512889 -278.153413) (xy 80.46467 -278.143569) (xy 80.418654 -278.126117) (xy 80.376033 -278.10151)
			(xy 80.337912 -278.070385) (xy 80.305277 -278.033548) (xy 80.278974 -277.991952) (xy 80.259683 -277.946676)
			(xy 80.247906 -277.898892) (xy 80.243946 -277.849838) (xy 78.954884 -277.849838) (xy 78.954389 -277.874445)
			(xy 78.946494 -277.923022) (xy 78.93091 -277.969703) (xy 78.908039 -278.01328) (xy 78.878474 -278.052624)
			(xy 78.842981 -278.086716) (xy 78.802478 -278.114672) (xy 78.758016 -278.13577) (xy 78.710745 -278.149462)
			(xy 78.66189 -278.155394) (xy 78.612715 -278.153413) (xy 78.564496 -278.143569) (xy 78.51848 -278.126117)
			(xy 78.475859 -278.10151) (xy 78.437738 -278.070385) (xy 78.405103 -278.033548) (xy 78.3788 -277.991952)
			(xy 78.359509 -277.946676) (xy 78.347732 -277.898892) (xy 78.343772 -277.849838) (xy 77.054964 -277.849838)
			(xy 77.054469 -277.874445) (xy 77.046574 -277.923022) (xy 77.03099 -277.969703) (xy 77.008119 -278.01328)
			(xy 76.978554 -278.052624) (xy 76.943061 -278.086716) (xy 76.902558 -278.114672) (xy 76.858096 -278.13577)
			(xy 76.810825 -278.149462) (xy 76.76197 -278.155394) (xy 76.712795 -278.153413) (xy 76.664576 -278.143569)
			(xy 76.61856 -278.126117) (xy 76.575939 -278.10151) (xy 76.537818 -278.070385) (xy 76.505183 -278.033548)
			(xy 76.47888 -277.991952) (xy 76.459589 -277.946676) (xy 76.447812 -277.898892) (xy 76.443852 -277.849838)
			(xy 75.155044 -277.849838) (xy 75.154549 -277.874445) (xy 75.146654 -277.923022) (xy 75.13107 -277.969703)
			(xy 75.108199 -278.01328) (xy 75.078634 -278.052624) (xy 75.043141 -278.086716) (xy 75.002638 -278.114672)
			(xy 74.958176 -278.13577) (xy 74.910905 -278.149462) (xy 74.86205 -278.155394) (xy 74.812875 -278.153413)
			(xy 74.764656 -278.143569) (xy 74.71864 -278.126117) (xy 74.676019 -278.10151) (xy 74.637898 -278.070385)
			(xy 74.605263 -278.033548) (xy 74.57896 -277.991952) (xy 74.559669 -277.946676) (xy 74.547892 -277.898892)
			(xy 74.543932 -277.849838) (xy 73.25487 -277.849838) (xy 73.254375 -277.874445) (xy 73.24648 -277.923022)
			(xy 73.230896 -277.969703) (xy 73.208025 -278.01328) (xy 73.17846 -278.052624) (xy 73.142967 -278.086716)
			(xy 73.102464 -278.114672) (xy 73.058002 -278.13577) (xy 73.010731 -278.149462) (xy 72.961876 -278.155394)
			(xy 72.912701 -278.153413) (xy 72.864482 -278.143569) (xy 72.818466 -278.126117) (xy 72.775845 -278.10151)
			(xy 72.737724 -278.070385) (xy 72.705089 -278.033548) (xy 72.678786 -277.991952) (xy 72.659495 -277.946676)
			(xy 72.647718 -277.898892) (xy 72.643758 -277.849838) (xy 71.35495 -277.849838) (xy 71.354455 -277.874445)
			(xy 71.34656 -277.923022) (xy 71.330976 -277.969703) (xy 71.308105 -278.01328) (xy 71.27854 -278.052624)
			(xy 71.243047 -278.086716) (xy 71.202544 -278.114672) (xy 71.158082 -278.13577) (xy 71.110811 -278.149462)
			(xy 71.061956 -278.155394) (xy 71.012781 -278.153413) (xy 70.964562 -278.143569) (xy 70.918546 -278.126117)
			(xy 70.875925 -278.10151) (xy 70.837804 -278.070385) (xy 70.805169 -278.033548) (xy 70.778866 -277.991952)
			(xy 70.759575 -277.946676) (xy 70.747798 -277.898892) (xy 70.743838 -277.849838) (xy 69.45503 -277.849838)
			(xy 69.454535 -277.874445) (xy 69.44664 -277.923022) (xy 69.431056 -277.969703) (xy 69.408185 -278.01328)
			(xy 69.37862 -278.052624) (xy 69.343127 -278.086716) (xy 69.302624 -278.114672) (xy 69.258162 -278.13577)
			(xy 69.210891 -278.149462) (xy 69.162036 -278.155394) (xy 69.112861 -278.153413) (xy 69.064642 -278.143569)
			(xy 69.018626 -278.126117) (xy 68.976005 -278.10151) (xy 68.937884 -278.070385) (xy 68.905249 -278.033548)
			(xy 68.878946 -277.991952) (xy 68.859655 -277.946676) (xy 68.847878 -277.898892) (xy 68.843918 -277.849838)
			(xy 67.554856 -277.849838) (xy 67.554361 -277.874445) (xy 67.546466 -277.923022) (xy 67.530882 -277.969703)
			(xy 67.508011 -278.01328) (xy 67.478446 -278.052624) (xy 67.442953 -278.086716) (xy 67.40245 -278.114672)
			(xy 67.357988 -278.13577) (xy 67.310717 -278.149462) (xy 67.261862 -278.155394) (xy 67.212687 -278.153413)
			(xy 67.164468 -278.143569) (xy 67.118452 -278.126117) (xy 67.075831 -278.10151) (xy 67.03771 -278.070385)
			(xy 67.005075 -278.033548) (xy 66.978772 -277.991952) (xy 66.959481 -277.946676) (xy 66.947704 -277.898892)
			(xy 66.943744 -277.849838) (xy 65.654936 -277.849838) (xy 65.654441 -277.874445) (xy 65.646546 -277.923022)
			(xy 65.630962 -277.969703) (xy 65.608091 -278.01328) (xy 65.578526 -278.052624) (xy 65.543033 -278.086716)
			(xy 65.50253 -278.114672) (xy 65.458068 -278.13577) (xy 65.410797 -278.149462) (xy 65.361942 -278.155394)
			(xy 65.312767 -278.153413) (xy 65.264548 -278.143569) (xy 65.218532 -278.126117) (xy 65.175911 -278.10151)
			(xy 65.13779 -278.070385) (xy 65.105155 -278.033548) (xy 65.078852 -277.991952) (xy 65.059561 -277.946676)
			(xy 65.047784 -277.898892) (xy 65.043824 -277.849838) (xy 63.755016 -277.849838) (xy 63.754521 -277.874445)
			(xy 63.746626 -277.923022) (xy 63.731042 -277.969703) (xy 63.708171 -278.01328) (xy 63.678606 -278.052624)
			(xy 63.643113 -278.086716) (xy 63.60261 -278.114672) (xy 63.558148 -278.13577) (xy 63.510877 -278.149462)
			(xy 63.462022 -278.155394) (xy 63.412847 -278.153413) (xy 63.364628 -278.143569) (xy 63.318612 -278.126117)
			(xy 63.275991 -278.10151) (xy 63.23787 -278.070385) (xy 63.205235 -278.033548) (xy 63.178932 -277.991952)
			(xy 63.159641 -277.946676) (xy 63.147864 -277.898892) (xy 63.143904 -277.849838) (xy 61.854842 -277.849838)
			(xy 61.854347 -277.874445) (xy 61.846452 -277.923022) (xy 61.830868 -277.969703) (xy 61.807997 -278.01328)
			(xy 61.778432 -278.052624) (xy 61.742939 -278.086716) (xy 61.702436 -278.114672) (xy 61.657974 -278.13577)
			(xy 61.610703 -278.149462) (xy 61.561848 -278.155394) (xy 61.512673 -278.153413) (xy 61.464454 -278.143569)
			(xy 61.418438 -278.126117) (xy 61.375817 -278.10151) (xy 61.337696 -278.070385) (xy 61.305061 -278.033548)
			(xy 61.278758 -277.991952) (xy 61.259467 -277.946676) (xy 61.24769 -277.898892) (xy 61.24373 -277.849838)
			(xy 59.954922 -277.849838) (xy 59.954427 -277.874445) (xy 59.946532 -277.923022) (xy 59.930948 -277.969703)
			(xy 59.908077 -278.01328) (xy 59.878512 -278.052624) (xy 59.843019 -278.086716) (xy 59.802516 -278.114672)
			(xy 59.758054 -278.13577) (xy 59.710783 -278.149462) (xy 59.661928 -278.155394) (xy 59.612753 -278.153413)
			(xy 59.564534 -278.143569) (xy 59.518518 -278.126117) (xy 59.475897 -278.10151) (xy 59.437776 -278.070385)
			(xy 59.405141 -278.033548) (xy 59.378838 -277.991952) (xy 59.359547 -277.946676) (xy 59.34777 -277.898892)
			(xy 59.34381 -277.849838) (xy 58.055256 -277.849838) (xy 58.054761 -277.874445) (xy 58.046866 -277.923022)
			(xy 58.031282 -277.969703) (xy 58.008411 -278.01328) (xy 57.978846 -278.052624) (xy 57.943353 -278.086716)
			(xy 57.90285 -278.114672) (xy 57.858388 -278.13577) (xy 57.811117 -278.149462) (xy 57.762262 -278.155394)
			(xy 57.713087 -278.153413) (xy 57.664868 -278.143569) (xy 57.618852 -278.126117) (xy 57.576231 -278.10151)
			(xy 57.53811 -278.070385) (xy 57.505475 -278.033548) (xy 57.479172 -277.991952) (xy 57.459881 -277.946676)
			(xy 57.448104 -277.898892) (xy 57.444144 -277.849838) (xy 56.155082 -277.849838) (xy 56.154587 -277.874445)
			(xy 56.146692 -277.923022) (xy 56.131108 -277.969703) (xy 56.108237 -278.01328) (xy 56.078672 -278.052624)
			(xy 56.043179 -278.086716) (xy 56.002676 -278.114672) (xy 55.958214 -278.13577) (xy 55.910943 -278.149462)
			(xy 55.862088 -278.155394) (xy 55.812913 -278.153413) (xy 55.764694 -278.143569) (xy 55.718678 -278.126117)
			(xy 55.676057 -278.10151) (xy 55.637936 -278.070385) (xy 55.605301 -278.033548) (xy 55.578998 -277.991952)
			(xy 55.559707 -277.946676) (xy 55.54793 -277.898892) (xy 55.54397 -277.849838) (xy 54.255162 -277.849838)
			(xy 54.254667 -277.874445) (xy 54.246772 -277.923022) (xy 54.231188 -277.969703) (xy 54.208317 -278.01328)
			(xy 54.178752 -278.052624) (xy 54.143259 -278.086716) (xy 54.102756 -278.114672) (xy 54.058294 -278.13577)
			(xy 54.011023 -278.149462) (xy 53.962168 -278.155394) (xy 53.912993 -278.153413) (xy 53.864774 -278.143569)
			(xy 53.818758 -278.126117) (xy 53.776137 -278.10151) (xy 53.738016 -278.070385) (xy 53.705381 -278.033548)
			(xy 53.679078 -277.991952) (xy 53.659787 -277.946676) (xy 53.64801 -277.898892) (xy 53.64405 -277.849838)
			(xy 52.355242 -277.849838) (xy 52.354747 -277.874445) (xy 52.346852 -277.923022) (xy 52.331268 -277.969703)
			(xy 52.308397 -278.01328) (xy 52.278832 -278.052624) (xy 52.243339 -278.086716) (xy 52.202836 -278.114672)
			(xy 52.158374 -278.13577) (xy 52.111103 -278.149462) (xy 52.062248 -278.155394) (xy 52.013073 -278.153413)
			(xy 51.964854 -278.143569) (xy 51.918838 -278.126117) (xy 51.876217 -278.10151) (xy 51.838096 -278.070385)
			(xy 51.805461 -278.033548) (xy 51.779158 -277.991952) (xy 51.759867 -277.946676) (xy 51.74809 -277.898892)
			(xy 51.74413 -277.849838) (xy 50.455068 -277.849838) (xy 50.454573 -277.874445) (xy 50.446678 -277.923022)
			(xy 50.431094 -277.969703) (xy 50.408223 -278.01328) (xy 50.378658 -278.052624) (xy 50.343165 -278.086716)
			(xy 50.302662 -278.114672) (xy 50.2582 -278.13577) (xy 50.210929 -278.149462) (xy 50.162074 -278.155394)
			(xy 50.112899 -278.153413) (xy 50.06468 -278.143569) (xy 50.018664 -278.126117) (xy 49.976043 -278.10151)
			(xy 49.937922 -278.070385) (xy 49.905287 -278.033548) (xy 49.878984 -277.991952) (xy 49.859693 -277.946676)
			(xy 49.847916 -277.898892) (xy 49.843956 -277.849838) (xy 48.555148 -277.849838) (xy 48.554653 -277.874445)
			(xy 48.546758 -277.923022) (xy 48.531174 -277.969703) (xy 48.508303 -278.01328) (xy 48.478738 -278.052624)
			(xy 48.443245 -278.086716) (xy 48.402742 -278.114672) (xy 48.35828 -278.13577) (xy 48.311009 -278.149462)
			(xy 48.262154 -278.155394) (xy 48.212979 -278.153413) (xy 48.16476 -278.143569) (xy 48.118744 -278.126117)
			(xy 48.076123 -278.10151) (xy 48.038002 -278.070385) (xy 48.005367 -278.033548) (xy 47.979064 -277.991952)
			(xy 47.959773 -277.946676) (xy 47.947996 -277.898892) (xy 47.944036 -277.849838) (xy 46.655228 -277.849838)
			(xy 46.654733 -277.874445) (xy 46.646838 -277.923022) (xy 46.631254 -277.969703) (xy 46.608383 -278.01328)
			(xy 46.578818 -278.052624) (xy 46.543325 -278.086716) (xy 46.502822 -278.114672) (xy 46.45836 -278.13577)
			(xy 46.411089 -278.149462) (xy 46.362234 -278.155394) (xy 46.313059 -278.153413) (xy 46.26484 -278.143569)
			(xy 46.218824 -278.126117) (xy 46.176203 -278.10151) (xy 46.138082 -278.070385) (xy 46.105447 -278.033548)
			(xy 46.079144 -277.991952) (xy 46.059853 -277.946676) (xy 46.048076 -277.898892) (xy 46.044116 -277.849838)
			(xy 44.755054 -277.849838) (xy 44.754559 -277.874445) (xy 44.746664 -277.923022) (xy 44.73108 -277.969703)
			(xy 44.708209 -278.01328) (xy 44.678644 -278.052624) (xy 44.643151 -278.086716) (xy 44.602648 -278.114672)
			(xy 44.558186 -278.13577) (xy 44.510915 -278.149462) (xy 44.46206 -278.155394) (xy 44.412885 -278.153413)
			(xy 44.364666 -278.143569) (xy 44.31865 -278.126117) (xy 44.276029 -278.10151) (xy 44.237908 -278.070385)
			(xy 44.205273 -278.033548) (xy 44.17897 -277.991952) (xy 44.159679 -277.946676) (xy 44.147902 -277.898892)
			(xy 44.143942 -277.849838) (xy 0.509016 -277.849838) (xy 0.509016 -278.799798) (xy 44.143942 -278.799798)
			(xy 44.147902 -278.750744) (xy 44.159679 -278.70296) (xy 44.17897 -278.657684) (xy 44.205273 -278.616088)
			(xy 44.237908 -278.579251) (xy 44.276029 -278.548126) (xy 44.31865 -278.523519) (xy 44.364666 -278.506067)
			(xy 44.412885 -278.496223) (xy 44.46206 -278.494242) (xy 44.510915 -278.500174) (xy 44.558186 -278.513866)
			(xy 44.602648 -278.534964) (xy 44.643151 -278.56292) (xy 44.678644 -278.597012) (xy 44.708209 -278.636356)
			(xy 44.73108 -278.679933) (xy 44.746664 -278.726614) (xy 44.754559 -278.775191) (xy 44.755054 -278.799798)
			(xy 46.044116 -278.799798) (xy 46.048076 -278.750744) (xy 46.059853 -278.70296) (xy 46.079144 -278.657684)
			(xy 46.105447 -278.616088) (xy 46.138082 -278.579251) (xy 46.176203 -278.548126) (xy 46.218824 -278.523519)
			(xy 46.26484 -278.506067) (xy 46.313059 -278.496223) (xy 46.362234 -278.494242) (xy 46.411089 -278.500174)
			(xy 46.45836 -278.513866) (xy 46.502822 -278.534964) (xy 46.543325 -278.56292) (xy 46.578818 -278.597012)
			(xy 46.608383 -278.636356) (xy 46.631254 -278.679933) (xy 46.646838 -278.726614) (xy 46.654733 -278.775191)
			(xy 46.655228 -278.799798) (xy 47.944036 -278.799798) (xy 47.947996 -278.750744) (xy 47.959773 -278.70296)
			(xy 47.979064 -278.657684) (xy 48.005367 -278.616088) (xy 48.038002 -278.579251) (xy 48.076123 -278.548126)
			(xy 48.118744 -278.523519) (xy 48.16476 -278.506067) (xy 48.212979 -278.496223) (xy 48.262154 -278.494242)
			(xy 48.311009 -278.500174) (xy 48.35828 -278.513866) (xy 48.402742 -278.534964) (xy 48.443245 -278.56292)
			(xy 48.478738 -278.597012) (xy 48.508303 -278.636356) (xy 48.531174 -278.679933) (xy 48.546758 -278.726614)
			(xy 48.554653 -278.775191) (xy 48.555148 -278.799798) (xy 49.843956 -278.799798) (xy 49.847916 -278.750744)
			(xy 49.859693 -278.70296) (xy 49.878984 -278.657684) (xy 49.905287 -278.616088) (xy 49.937922 -278.579251)
			(xy 49.976043 -278.548126) (xy 50.018664 -278.523519) (xy 50.06468 -278.506067) (xy 50.112899 -278.496223)
			(xy 50.162074 -278.494242) (xy 50.210929 -278.500174) (xy 50.2582 -278.513866) (xy 50.302662 -278.534964)
			(xy 50.343165 -278.56292) (xy 50.378658 -278.597012) (xy 50.408223 -278.636356) (xy 50.431094 -278.679933)
			(xy 50.446678 -278.726614) (xy 50.454573 -278.775191) (xy 50.455068 -278.799798) (xy 51.74413 -278.799798)
			(xy 51.74809 -278.750744) (xy 51.759867 -278.70296) (xy 51.779158 -278.657684) (xy 51.805461 -278.616088)
			(xy 51.838096 -278.579251) (xy 51.876217 -278.548126) (xy 51.918838 -278.523519) (xy 51.964854 -278.506067)
			(xy 52.013073 -278.496223) (xy 52.062248 -278.494242) (xy 52.111103 -278.500174) (xy 52.158374 -278.513866)
			(xy 52.202836 -278.534964) (xy 52.243339 -278.56292) (xy 52.278832 -278.597012) (xy 52.308397 -278.636356)
			(xy 52.331268 -278.679933) (xy 52.346852 -278.726614) (xy 52.354747 -278.775191) (xy 52.355242 -278.799798)
			(xy 53.64405 -278.799798) (xy 53.64801 -278.750744) (xy 53.659787 -278.70296) (xy 53.679078 -278.657684)
			(xy 53.705381 -278.616088) (xy 53.738016 -278.579251) (xy 53.776137 -278.548126) (xy 53.818758 -278.523519)
			(xy 53.864774 -278.506067) (xy 53.912993 -278.496223) (xy 53.962168 -278.494242) (xy 54.011023 -278.500174)
			(xy 54.058294 -278.513866) (xy 54.102756 -278.534964) (xy 54.143259 -278.56292) (xy 54.178752 -278.597012)
			(xy 54.208317 -278.636356) (xy 54.231188 -278.679933) (xy 54.246772 -278.726614) (xy 54.254667 -278.775191)
			(xy 54.255162 -278.799798) (xy 55.54397 -278.799798) (xy 55.54793 -278.750744) (xy 55.559707 -278.70296)
			(xy 55.578998 -278.657684) (xy 55.605301 -278.616088) (xy 55.637936 -278.579251) (xy 55.676057 -278.548126)
			(xy 55.718678 -278.523519) (xy 55.764694 -278.506067) (xy 55.812913 -278.496223) (xy 55.862088 -278.494242)
			(xy 55.910943 -278.500174) (xy 55.958214 -278.513866) (xy 56.002676 -278.534964) (xy 56.043179 -278.56292)
			(xy 56.078672 -278.597012) (xy 56.108237 -278.636356) (xy 56.131108 -278.679933) (xy 56.146692 -278.726614)
			(xy 56.154587 -278.775191) (xy 56.155082 -278.799798) (xy 57.444144 -278.799798) (xy 57.448104 -278.750744)
			(xy 57.459881 -278.70296) (xy 57.479172 -278.657684) (xy 57.505475 -278.616088) (xy 57.53811 -278.579251)
			(xy 57.576231 -278.548126) (xy 57.618852 -278.523519) (xy 57.664868 -278.506067) (xy 57.713087 -278.496223)
			(xy 57.762262 -278.494242) (xy 57.811117 -278.500174) (xy 57.858388 -278.513866) (xy 57.90285 -278.534964)
			(xy 57.943353 -278.56292) (xy 57.978846 -278.597012) (xy 58.008411 -278.636356) (xy 58.031282 -278.679933)
			(xy 58.046866 -278.726614) (xy 58.054761 -278.775191) (xy 58.055256 -278.799798) (xy 59.34381 -278.799798)
			(xy 59.34777 -278.750744) (xy 59.359547 -278.70296) (xy 59.378838 -278.657684) (xy 59.405141 -278.616088)
			(xy 59.437776 -278.579251) (xy 59.475897 -278.548126) (xy 59.518518 -278.523519) (xy 59.564534 -278.506067)
			(xy 59.612753 -278.496223) (xy 59.661928 -278.494242) (xy 59.710783 -278.500174) (xy 59.758054 -278.513866)
			(xy 59.802516 -278.534964) (xy 59.843019 -278.56292) (xy 59.878512 -278.597012) (xy 59.908077 -278.636356)
			(xy 59.930948 -278.679933) (xy 59.946532 -278.726614) (xy 59.954427 -278.775191) (xy 59.954922 -278.799798)
			(xy 61.24373 -278.799798) (xy 61.24769 -278.750744) (xy 61.259467 -278.70296) (xy 61.278758 -278.657684)
			(xy 61.305061 -278.616088) (xy 61.337696 -278.579251) (xy 61.375817 -278.548126) (xy 61.418438 -278.523519)
			(xy 61.464454 -278.506067) (xy 61.512673 -278.496223) (xy 61.561848 -278.494242) (xy 61.610703 -278.500174)
			(xy 61.657974 -278.513866) (xy 61.702436 -278.534964) (xy 61.742939 -278.56292) (xy 61.778432 -278.597012)
			(xy 61.807997 -278.636356) (xy 61.830868 -278.679933) (xy 61.846452 -278.726614) (xy 61.854347 -278.775191)
			(xy 61.854842 -278.799798) (xy 63.143904 -278.799798) (xy 63.147864 -278.750744) (xy 63.159641 -278.70296)
			(xy 63.178932 -278.657684) (xy 63.205235 -278.616088) (xy 63.23787 -278.579251) (xy 63.275991 -278.548126)
			(xy 63.318612 -278.523519) (xy 63.364628 -278.506067) (xy 63.412847 -278.496223) (xy 63.462022 -278.494242)
			(xy 63.510877 -278.500174) (xy 63.558148 -278.513866) (xy 63.60261 -278.534964) (xy 63.643113 -278.56292)
			(xy 63.678606 -278.597012) (xy 63.708171 -278.636356) (xy 63.731042 -278.679933) (xy 63.746626 -278.726614)
			(xy 63.754521 -278.775191) (xy 63.755016 -278.799798) (xy 65.043824 -278.799798) (xy 65.047784 -278.750744)
			(xy 65.059561 -278.70296) (xy 65.078852 -278.657684) (xy 65.105155 -278.616088) (xy 65.13779 -278.579251)
			(xy 65.175911 -278.548126) (xy 65.218532 -278.523519) (xy 65.264548 -278.506067) (xy 65.312767 -278.496223)
			(xy 65.361942 -278.494242) (xy 65.410797 -278.500174) (xy 65.458068 -278.513866) (xy 65.50253 -278.534964)
			(xy 65.543033 -278.56292) (xy 65.578526 -278.597012) (xy 65.608091 -278.636356) (xy 65.630962 -278.679933)
			(xy 65.646546 -278.726614) (xy 65.654441 -278.775191) (xy 65.654936 -278.799798) (xy 66.943744 -278.799798)
			(xy 66.947704 -278.750744) (xy 66.959481 -278.70296) (xy 66.978772 -278.657684) (xy 67.005075 -278.616088)
			(xy 67.03771 -278.579251) (xy 67.075831 -278.548126) (xy 67.118452 -278.523519) (xy 67.164468 -278.506067)
			(xy 67.212687 -278.496223) (xy 67.261862 -278.494242) (xy 67.310717 -278.500174) (xy 67.357988 -278.513866)
			(xy 67.40245 -278.534964) (xy 67.442953 -278.56292) (xy 67.478446 -278.597012) (xy 67.508011 -278.636356)
			(xy 67.530882 -278.679933) (xy 67.546466 -278.726614) (xy 67.554361 -278.775191) (xy 67.554856 -278.799798)
			(xy 68.843918 -278.799798) (xy 68.847878 -278.750744) (xy 68.859655 -278.70296) (xy 68.878946 -278.657684)
			(xy 68.905249 -278.616088) (xy 68.937884 -278.579251) (xy 68.976005 -278.548126) (xy 69.018626 -278.523519)
			(xy 69.064642 -278.506067) (xy 69.112861 -278.496223) (xy 69.162036 -278.494242) (xy 69.210891 -278.500174)
			(xy 69.258162 -278.513866) (xy 69.302624 -278.534964) (xy 69.343127 -278.56292) (xy 69.37862 -278.597012)
			(xy 69.408185 -278.636356) (xy 69.431056 -278.679933) (xy 69.44664 -278.726614) (xy 69.454535 -278.775191)
			(xy 69.45503 -278.799798) (xy 70.743838 -278.799798) (xy 70.747798 -278.750744) (xy 70.759575 -278.70296)
			(xy 70.778866 -278.657684) (xy 70.805169 -278.616088) (xy 70.837804 -278.579251) (xy 70.875925 -278.548126)
			(xy 70.918546 -278.523519) (xy 70.964562 -278.506067) (xy 71.012781 -278.496223) (xy 71.061956 -278.494242)
			(xy 71.110811 -278.500174) (xy 71.158082 -278.513866) (xy 71.202544 -278.534964) (xy 71.243047 -278.56292)
			(xy 71.27854 -278.597012) (xy 71.308105 -278.636356) (xy 71.330976 -278.679933) (xy 71.34656 -278.726614)
			(xy 71.354455 -278.775191) (xy 71.35495 -278.799798) (xy 72.643758 -278.799798) (xy 72.647718 -278.750744)
			(xy 72.659495 -278.70296) (xy 72.678786 -278.657684) (xy 72.705089 -278.616088) (xy 72.737724 -278.579251)
			(xy 72.775845 -278.548126) (xy 72.818466 -278.523519) (xy 72.864482 -278.506067) (xy 72.912701 -278.496223)
			(xy 72.961876 -278.494242) (xy 73.010731 -278.500174) (xy 73.058002 -278.513866) (xy 73.102464 -278.534964)
			(xy 73.142967 -278.56292) (xy 73.17846 -278.597012) (xy 73.208025 -278.636356) (xy 73.230896 -278.679933)
			(xy 73.24648 -278.726614) (xy 73.254375 -278.775191) (xy 73.25487 -278.799798) (xy 74.543932 -278.799798)
			(xy 74.547892 -278.750744) (xy 74.559669 -278.70296) (xy 74.57896 -278.657684) (xy 74.605263 -278.616088)
			(xy 74.637898 -278.579251) (xy 74.676019 -278.548126) (xy 74.71864 -278.523519) (xy 74.764656 -278.506067)
			(xy 74.812875 -278.496223) (xy 74.86205 -278.494242) (xy 74.910905 -278.500174) (xy 74.958176 -278.513866)
			(xy 75.002638 -278.534964) (xy 75.043141 -278.56292) (xy 75.078634 -278.597012) (xy 75.108199 -278.636356)
			(xy 75.13107 -278.679933) (xy 75.146654 -278.726614) (xy 75.154549 -278.775191) (xy 75.155044 -278.799798)
			(xy 76.443852 -278.799798) (xy 76.447812 -278.750744) (xy 76.459589 -278.70296) (xy 76.47888 -278.657684)
			(xy 76.505183 -278.616088) (xy 76.537818 -278.579251) (xy 76.575939 -278.548126) (xy 76.61856 -278.523519)
			(xy 76.664576 -278.506067) (xy 76.712795 -278.496223) (xy 76.76197 -278.494242) (xy 76.810825 -278.500174)
			(xy 76.858096 -278.513866) (xy 76.902558 -278.534964) (xy 76.943061 -278.56292) (xy 76.978554 -278.597012)
			(xy 77.008119 -278.636356) (xy 77.03099 -278.679933) (xy 77.046574 -278.726614) (xy 77.054469 -278.775191)
			(xy 77.054964 -278.799798) (xy 78.343772 -278.799798) (xy 78.347732 -278.750744) (xy 78.359509 -278.70296)
			(xy 78.3788 -278.657684) (xy 78.405103 -278.616088) (xy 78.437738 -278.579251) (xy 78.475859 -278.548126)
			(xy 78.51848 -278.523519) (xy 78.564496 -278.506067) (xy 78.612715 -278.496223) (xy 78.66189 -278.494242)
			(xy 78.710745 -278.500174) (xy 78.758016 -278.513866) (xy 78.802478 -278.534964) (xy 78.842981 -278.56292)
			(xy 78.878474 -278.597012) (xy 78.908039 -278.636356) (xy 78.93091 -278.679933) (xy 78.946494 -278.726614)
			(xy 78.954389 -278.775191) (xy 78.954884 -278.799798) (xy 80.243946 -278.799798) (xy 80.247906 -278.750744)
			(xy 80.259683 -278.70296) (xy 80.278974 -278.657684) (xy 80.305277 -278.616088) (xy 80.337912 -278.579251)
			(xy 80.376033 -278.548126) (xy 80.418654 -278.523519) (xy 80.46467 -278.506067) (xy 80.512889 -278.496223)
			(xy 80.562064 -278.494242) (xy 80.610919 -278.500174) (xy 80.65819 -278.513866) (xy 80.702652 -278.534964)
			(xy 80.743155 -278.56292) (xy 80.778648 -278.597012) (xy 80.808213 -278.636356) (xy 80.831084 -278.679933)
			(xy 80.846668 -278.726614) (xy 80.854563 -278.775191) (xy 80.855058 -278.799798) (xy 160.24404 -278.799798)
			(xy 160.248 -278.750744) (xy 160.259777 -278.70296) (xy 160.279068 -278.657684) (xy 160.305371 -278.616088)
			(xy 160.338006 -278.579251) (xy 160.376127 -278.548126) (xy 160.418748 -278.523519) (xy 160.464764 -278.506067)
			(xy 160.512983 -278.496223) (xy 160.562158 -278.494242) (xy 160.611013 -278.500174) (xy 160.658284 -278.513866)
			(xy 160.702746 -278.534964) (xy 160.743249 -278.56292) (xy 160.778742 -278.597012) (xy 160.808307 -278.636356)
			(xy 160.831178 -278.679933) (xy 160.846762 -278.726614) (xy 160.854657 -278.775191) (xy 160.855152 -278.799798)
			(xy 162.144214 -278.799798) (xy 162.148174 -278.750744) (xy 162.159951 -278.70296) (xy 162.179242 -278.657684)
			(xy 162.205545 -278.616088) (xy 162.23818 -278.579251) (xy 162.276301 -278.548126) (xy 162.318922 -278.523519)
			(xy 162.364938 -278.506067) (xy 162.413157 -278.496223) (xy 162.462332 -278.494242) (xy 162.511187 -278.500174)
			(xy 162.558458 -278.513866) (xy 162.60292 -278.534964) (xy 162.643423 -278.56292) (xy 162.678916 -278.597012)
			(xy 162.708481 -278.636356) (xy 162.731352 -278.679933) (xy 162.746936 -278.726614) (xy 162.754831 -278.775191)
			(xy 162.755326 -278.799798) (xy 164.044134 -278.799798) (xy 164.048094 -278.750744) (xy 164.059871 -278.70296)
			(xy 164.079162 -278.657684) (xy 164.105465 -278.616088) (xy 164.1381 -278.579251) (xy 164.176221 -278.548126)
			(xy 164.218842 -278.523519) (xy 164.264858 -278.506067) (xy 164.313077 -278.496223) (xy 164.362252 -278.494242)
			(xy 164.411107 -278.500174) (xy 164.458378 -278.513866) (xy 164.50284 -278.534964) (xy 164.543343 -278.56292)
			(xy 164.578836 -278.597012) (xy 164.608401 -278.636356) (xy 164.631272 -278.679933) (xy 164.646856 -278.726614)
			(xy 164.654751 -278.775191) (xy 164.655246 -278.799798) (xy 165.944054 -278.799798) (xy 165.948014 -278.750744)
			(xy 165.959791 -278.70296) (xy 165.979082 -278.657684) (xy 166.005385 -278.616088) (xy 166.03802 -278.579251)
			(xy 166.076141 -278.548126) (xy 166.118762 -278.523519) (xy 166.164778 -278.506067) (xy 166.212997 -278.496223)
			(xy 166.262172 -278.494242) (xy 166.311027 -278.500174) (xy 166.358298 -278.513866) (xy 166.40276 -278.534964)
			(xy 166.443263 -278.56292) (xy 166.478756 -278.597012) (xy 166.508321 -278.636356) (xy 166.531192 -278.679933)
			(xy 166.546776 -278.726614) (xy 166.554671 -278.775191) (xy 166.555166 -278.799798) (xy 167.844228 -278.799798)
			(xy 167.848188 -278.750744) (xy 167.859965 -278.70296) (xy 167.879256 -278.657684) (xy 167.905559 -278.616088)
			(xy 167.938194 -278.579251) (xy 167.976315 -278.548126) (xy 168.018936 -278.523519) (xy 168.064952 -278.506067)
			(xy 168.113171 -278.496223) (xy 168.162346 -278.494242) (xy 168.211201 -278.500174) (xy 168.258472 -278.513866)
			(xy 168.302934 -278.534964) (xy 168.343437 -278.56292) (xy 168.37893 -278.597012) (xy 168.408495 -278.636356)
			(xy 168.431366 -278.679933) (xy 168.44695 -278.726614) (xy 168.454845 -278.775191) (xy 168.45534 -278.799798)
			(xy 169.744148 -278.799798) (xy 169.748108 -278.750744) (xy 169.759885 -278.70296) (xy 169.779176 -278.657684)
			(xy 169.805479 -278.616088) (xy 169.838114 -278.579251) (xy 169.876235 -278.548126) (xy 169.918856 -278.523519)
			(xy 169.964872 -278.506067) (xy 170.013091 -278.496223) (xy 170.062266 -278.494242) (xy 170.111121 -278.500174)
			(xy 170.158392 -278.513866) (xy 170.202854 -278.534964) (xy 170.243357 -278.56292) (xy 170.27885 -278.597012)
			(xy 170.308415 -278.636356) (xy 170.331286 -278.679933) (xy 170.34687 -278.726614) (xy 170.354765 -278.775191)
			(xy 170.35526 -278.799798) (xy 171.644068 -278.799798) (xy 171.648028 -278.750744) (xy 171.659805 -278.70296)
			(xy 171.679096 -278.657684) (xy 171.705399 -278.616088) (xy 171.738034 -278.579251) (xy 171.776155 -278.548126)
			(xy 171.818776 -278.523519) (xy 171.864792 -278.506067) (xy 171.913011 -278.496223) (xy 171.962186 -278.494242)
			(xy 172.011041 -278.500174) (xy 172.058312 -278.513866) (xy 172.102774 -278.534964) (xy 172.143277 -278.56292)
			(xy 172.17877 -278.597012) (xy 172.208335 -278.636356) (xy 172.231206 -278.679933) (xy 172.24679 -278.726614)
			(xy 172.254685 -278.775191) (xy 172.25518 -278.799798) (xy 173.544242 -278.799798) (xy 173.548202 -278.750744)
			(xy 173.559979 -278.70296) (xy 173.57927 -278.657684) (xy 173.605573 -278.616088) (xy 173.638208 -278.579251)
			(xy 173.676329 -278.548126) (xy 173.71895 -278.523519) (xy 173.764966 -278.506067) (xy 173.813185 -278.496223)
			(xy 173.86236 -278.494242) (xy 173.911215 -278.500174) (xy 173.958486 -278.513866) (xy 174.002948 -278.534964)
			(xy 174.043451 -278.56292) (xy 174.078944 -278.597012) (xy 174.108509 -278.636356) (xy 174.13138 -278.679933)
			(xy 174.146964 -278.726614) (xy 174.154859 -278.775191) (xy 174.155354 -278.799798) (xy 175.443908 -278.799798)
			(xy 175.447868 -278.750744) (xy 175.459645 -278.70296) (xy 175.478936 -278.657684) (xy 175.505239 -278.616088)
			(xy 175.537874 -278.579251) (xy 175.575995 -278.548126) (xy 175.618616 -278.523519) (xy 175.664632 -278.506067)
			(xy 175.712851 -278.496223) (xy 175.762026 -278.494242) (xy 175.810881 -278.500174) (xy 175.858152 -278.513866)
			(xy 175.902614 -278.534964) (xy 175.943117 -278.56292) (xy 175.97861 -278.597012) (xy 176.008175 -278.636356)
			(xy 176.031046 -278.679933) (xy 176.04663 -278.726614) (xy 176.054525 -278.775191) (xy 176.05502 -278.799798)
			(xy 177.343828 -278.799798) (xy 177.347788 -278.750744) (xy 177.359565 -278.70296) (xy 177.378856 -278.657684)
			(xy 177.405159 -278.616088) (xy 177.437794 -278.579251) (xy 177.475915 -278.548126) (xy 177.518536 -278.523519)
			(xy 177.564552 -278.506067) (xy 177.612771 -278.496223) (xy 177.661946 -278.494242) (xy 177.710801 -278.500174)
			(xy 177.758072 -278.513866) (xy 177.802534 -278.534964) (xy 177.843037 -278.56292) (xy 177.87853 -278.597012)
			(xy 177.908095 -278.636356) (xy 177.930966 -278.679933) (xy 177.94655 -278.726614) (xy 177.954445 -278.775191)
			(xy 177.95494 -278.799798) (xy 179.244002 -278.799798) (xy 179.247962 -278.750744) (xy 179.259739 -278.70296)
			(xy 179.27903 -278.657684) (xy 179.305333 -278.616088) (xy 179.337968 -278.579251) (xy 179.376089 -278.548126)
			(xy 179.41871 -278.523519) (xy 179.464726 -278.506067) (xy 179.512945 -278.496223) (xy 179.56212 -278.494242)
			(xy 179.610975 -278.500174) (xy 179.658246 -278.513866) (xy 179.702708 -278.534964) (xy 179.743211 -278.56292)
			(xy 179.778704 -278.597012) (xy 179.808269 -278.636356) (xy 179.83114 -278.679933) (xy 179.846724 -278.726614)
			(xy 179.854619 -278.775191) (xy 179.855114 -278.799798) (xy 181.143922 -278.799798) (xy 181.147882 -278.750744)
			(xy 181.159659 -278.70296) (xy 181.17895 -278.657684) (xy 181.205253 -278.616088) (xy 181.237888 -278.579251)
			(xy 181.276009 -278.548126) (xy 181.31863 -278.523519) (xy 181.364646 -278.506067) (xy 181.412865 -278.496223)
			(xy 181.46204 -278.494242) (xy 181.510895 -278.500174) (xy 181.558166 -278.513866) (xy 181.602628 -278.534964)
			(xy 181.643131 -278.56292) (xy 181.678624 -278.597012) (xy 181.708189 -278.636356) (xy 181.73106 -278.679933)
			(xy 181.746644 -278.726614) (xy 181.754539 -278.775191) (xy 181.755034 -278.799798) (xy 183.043842 -278.799798)
			(xy 183.047802 -278.750744) (xy 183.059579 -278.70296) (xy 183.07887 -278.657684) (xy 183.105173 -278.616088)
			(xy 183.137808 -278.579251) (xy 183.175929 -278.548126) (xy 183.21855 -278.523519) (xy 183.264566 -278.506067)
			(xy 183.312785 -278.496223) (xy 183.36196 -278.494242) (xy 183.410815 -278.500174) (xy 183.458086 -278.513866)
			(xy 183.502548 -278.534964) (xy 183.543051 -278.56292) (xy 183.578544 -278.597012) (xy 183.608109 -278.636356)
			(xy 183.63098 -278.679933) (xy 183.646564 -278.726614) (xy 183.654459 -278.775191) (xy 183.654954 -278.799798)
			(xy 184.944016 -278.799798) (xy 184.947976 -278.750744) (xy 184.959753 -278.70296) (xy 184.979044 -278.657684)
			(xy 185.005347 -278.616088) (xy 185.037982 -278.579251) (xy 185.076103 -278.548126) (xy 185.118724 -278.523519)
			(xy 185.16474 -278.506067) (xy 185.212959 -278.496223) (xy 185.262134 -278.494242) (xy 185.310989 -278.500174)
			(xy 185.35826 -278.513866) (xy 185.402722 -278.534964) (xy 185.443225 -278.56292) (xy 185.478718 -278.597012)
			(xy 185.508283 -278.636356) (xy 185.531154 -278.679933) (xy 185.546738 -278.726614) (xy 185.554633 -278.775191)
			(xy 185.555128 -278.799798) (xy 186.843936 -278.799798) (xy 186.847896 -278.750744) (xy 186.859673 -278.70296)
			(xy 186.878964 -278.657684) (xy 186.905267 -278.616088) (xy 186.937902 -278.579251) (xy 186.976023 -278.548126)
			(xy 187.018644 -278.523519) (xy 187.06466 -278.506067) (xy 187.112879 -278.496223) (xy 187.162054 -278.494242)
			(xy 187.210909 -278.500174) (xy 187.25818 -278.513866) (xy 187.302642 -278.534964) (xy 187.343145 -278.56292)
			(xy 187.378638 -278.597012) (xy 187.408203 -278.636356) (xy 187.431074 -278.679933) (xy 187.446658 -278.726614)
			(xy 187.454553 -278.775191) (xy 187.455048 -278.799798) (xy 188.743856 -278.799798) (xy 188.747816 -278.750744)
			(xy 188.759593 -278.70296) (xy 188.778884 -278.657684) (xy 188.805187 -278.616088) (xy 188.837822 -278.579251)
			(xy 188.875943 -278.548126) (xy 188.918564 -278.523519) (xy 188.96458 -278.506067) (xy 189.012799 -278.496223)
			(xy 189.061974 -278.494242) (xy 189.110829 -278.500174) (xy 189.1581 -278.513866) (xy 189.202562 -278.534964)
			(xy 189.243065 -278.56292) (xy 189.278558 -278.597012) (xy 189.308123 -278.636356) (xy 189.330994 -278.679933)
			(xy 189.346578 -278.726614) (xy 189.354473 -278.775191) (xy 189.354968 -278.799798) (xy 190.64403 -278.799798)
			(xy 190.64799 -278.750744) (xy 190.659767 -278.70296) (xy 190.679058 -278.657684) (xy 190.705361 -278.616088)
			(xy 190.737996 -278.579251) (xy 190.776117 -278.548126) (xy 190.818738 -278.523519) (xy 190.864754 -278.506067)
			(xy 190.912973 -278.496223) (xy 190.962148 -278.494242) (xy 191.011003 -278.500174) (xy 191.058274 -278.513866)
			(xy 191.102736 -278.534964) (xy 191.143239 -278.56292) (xy 191.178732 -278.597012) (xy 191.208297 -278.636356)
			(xy 191.231168 -278.679933) (xy 191.246752 -278.726614) (xy 191.254647 -278.775191) (xy 191.255142 -278.799798)
			(xy 192.54395 -278.799798) (xy 192.54791 -278.750744) (xy 192.559687 -278.70296) (xy 192.578978 -278.657684)
			(xy 192.605281 -278.616088) (xy 192.637916 -278.579251) (xy 192.676037 -278.548126) (xy 192.718658 -278.523519)
			(xy 192.764674 -278.506067) (xy 192.812893 -278.496223) (xy 192.862068 -278.494242) (xy 192.910923 -278.500174)
			(xy 192.958194 -278.513866) (xy 193.002656 -278.534964) (xy 193.043159 -278.56292) (xy 193.078652 -278.597012)
			(xy 193.108217 -278.636356) (xy 193.131088 -278.679933) (xy 193.146672 -278.726614) (xy 193.154567 -278.775191)
			(xy 193.155062 -278.799798) (xy 194.44387 -278.799798) (xy 194.44783 -278.750744) (xy 194.459607 -278.70296)
			(xy 194.478898 -278.657684) (xy 194.505201 -278.616088) (xy 194.537836 -278.579251) (xy 194.575957 -278.548126)
			(xy 194.618578 -278.523519) (xy 194.664594 -278.506067) (xy 194.712813 -278.496223) (xy 194.761988 -278.494242)
			(xy 194.810843 -278.500174) (xy 194.858114 -278.513866) (xy 194.902576 -278.534964) (xy 194.943079 -278.56292)
			(xy 194.978572 -278.597012) (xy 195.008137 -278.636356) (xy 195.031008 -278.679933) (xy 195.046592 -278.726614)
			(xy 195.054487 -278.775191) (xy 195.054982 -278.799798) (xy 196.344044 -278.799798) (xy 196.348004 -278.750744)
			(xy 196.359781 -278.70296) (xy 196.379072 -278.657684) (xy 196.405375 -278.616088) (xy 196.43801 -278.579251)
			(xy 196.476131 -278.548126) (xy 196.518752 -278.523519) (xy 196.564768 -278.506067) (xy 196.612987 -278.496223)
			(xy 196.662162 -278.494242) (xy 196.711017 -278.500174) (xy 196.758288 -278.513866) (xy 196.80275 -278.534964)
			(xy 196.843253 -278.56292) (xy 196.878746 -278.597012) (xy 196.908311 -278.636356) (xy 196.931182 -278.679933)
			(xy 196.946766 -278.726614) (xy 196.954661 -278.775191) (xy 196.955156 -278.799798) (xy 276.343884 -278.799798)
			(xy 276.347844 -278.750744) (xy 276.359621 -278.70296) (xy 276.378912 -278.657684) (xy 276.405215 -278.616088)
			(xy 276.43785 -278.579251) (xy 276.475971 -278.548126) (xy 276.518592 -278.523519) (xy 276.564608 -278.506067)
			(xy 276.612827 -278.496223) (xy 276.662002 -278.494242) (xy 276.710857 -278.500174) (xy 276.758128 -278.513866)
			(xy 276.80259 -278.534964) (xy 276.843093 -278.56292) (xy 276.878586 -278.597012) (xy 276.908151 -278.636356)
			(xy 276.931022 -278.679933) (xy 276.946606 -278.726614) (xy 276.954501 -278.775191) (xy 276.954996 -278.799798)
			(xy 278.244058 -278.799798) (xy 278.248018 -278.750744) (xy 278.259795 -278.70296) (xy 278.279086 -278.657684)
			(xy 278.305389 -278.616088) (xy 278.338024 -278.579251) (xy 278.376145 -278.548126) (xy 278.418766 -278.523519)
			(xy 278.464782 -278.506067) (xy 278.513001 -278.496223) (xy 278.562176 -278.494242) (xy 278.611031 -278.500174)
			(xy 278.658302 -278.513866) (xy 278.702764 -278.534964) (xy 278.743267 -278.56292) (xy 278.77876 -278.597012)
			(xy 278.808325 -278.636356) (xy 278.831196 -278.679933) (xy 278.84678 -278.726614) (xy 278.854675 -278.775191)
			(xy 278.85517 -278.799798) (xy 280.143978 -278.799798) (xy 280.147938 -278.750744) (xy 280.159715 -278.70296)
			(xy 280.179006 -278.657684) (xy 280.205309 -278.616088) (xy 280.237944 -278.579251) (xy 280.276065 -278.548126)
			(xy 280.318686 -278.523519) (xy 280.364702 -278.506067) (xy 280.412921 -278.496223) (xy 280.462096 -278.494242)
			(xy 280.510951 -278.500174) (xy 280.558222 -278.513866) (xy 280.602684 -278.534964) (xy 280.643187 -278.56292)
			(xy 280.67868 -278.597012) (xy 280.708245 -278.636356) (xy 280.731116 -278.679933) (xy 280.7467 -278.726614)
			(xy 280.754595 -278.775191) (xy 280.75509 -278.799798) (xy 282.043898 -278.799798) (xy 282.047858 -278.750744)
			(xy 282.059635 -278.70296) (xy 282.078926 -278.657684) (xy 282.105229 -278.616088) (xy 282.137864 -278.579251)
			(xy 282.175985 -278.548126) (xy 282.218606 -278.523519) (xy 282.264622 -278.506067) (xy 282.312841 -278.496223)
			(xy 282.362016 -278.494242) (xy 282.410871 -278.500174) (xy 282.458142 -278.513866) (xy 282.502604 -278.534964)
			(xy 282.543107 -278.56292) (xy 282.5786 -278.597012) (xy 282.608165 -278.636356) (xy 282.631036 -278.679933)
			(xy 282.64662 -278.726614) (xy 282.654515 -278.775191) (xy 282.65501 -278.799798) (xy 283.944072 -278.799798)
			(xy 283.948032 -278.750744) (xy 283.959809 -278.70296) (xy 283.9791 -278.657684) (xy 284.005403 -278.616088)
			(xy 284.038038 -278.579251) (xy 284.076159 -278.548126) (xy 284.11878 -278.523519) (xy 284.164796 -278.506067)
			(xy 284.213015 -278.496223) (xy 284.26219 -278.494242) (xy 284.311045 -278.500174) (xy 284.358316 -278.513866)
			(xy 284.402778 -278.534964) (xy 284.443281 -278.56292) (xy 284.478774 -278.597012) (xy 284.508339 -278.636356)
			(xy 284.53121 -278.679933) (xy 284.546794 -278.726614) (xy 284.554689 -278.775191) (xy 284.555184 -278.799798)
			(xy 285.843992 -278.799798) (xy 285.847952 -278.750744) (xy 285.859729 -278.70296) (xy 285.87902 -278.657684)
			(xy 285.905323 -278.616088) (xy 285.937958 -278.579251) (xy 285.976079 -278.548126) (xy 286.0187 -278.523519)
			(xy 286.064716 -278.506067) (xy 286.112935 -278.496223) (xy 286.16211 -278.494242) (xy 286.210965 -278.500174)
			(xy 286.258236 -278.513866) (xy 286.302698 -278.534964) (xy 286.343201 -278.56292) (xy 286.378694 -278.597012)
			(xy 286.408259 -278.636356) (xy 286.43113 -278.679933) (xy 286.446714 -278.726614) (xy 286.454609 -278.775191)
			(xy 286.455104 -278.799798) (xy 287.743912 -278.799798) (xy 287.747872 -278.750744) (xy 287.759649 -278.70296)
			(xy 287.77894 -278.657684) (xy 287.805243 -278.616088) (xy 287.837878 -278.579251) (xy 287.875999 -278.548126)
			(xy 287.91862 -278.523519) (xy 287.964636 -278.506067) (xy 288.012855 -278.496223) (xy 288.06203 -278.494242)
			(xy 288.110885 -278.500174) (xy 288.158156 -278.513866) (xy 288.202618 -278.534964) (xy 288.243121 -278.56292)
			(xy 288.278614 -278.597012) (xy 288.308179 -278.636356) (xy 288.33105 -278.679933) (xy 288.346634 -278.726614)
			(xy 288.354529 -278.775191) (xy 288.355024 -278.799798) (xy 289.644086 -278.799798) (xy 289.648046 -278.750744)
			(xy 289.659823 -278.70296) (xy 289.679114 -278.657684) (xy 289.705417 -278.616088) (xy 289.738052 -278.579251)
			(xy 289.776173 -278.548126) (xy 289.818794 -278.523519) (xy 289.86481 -278.506067) (xy 289.913029 -278.496223)
			(xy 289.962204 -278.494242) (xy 290.011059 -278.500174) (xy 290.05833 -278.513866) (xy 290.102792 -278.534964)
			(xy 290.143295 -278.56292) (xy 290.178788 -278.597012) (xy 290.208353 -278.636356) (xy 290.231224 -278.679933)
			(xy 290.246808 -278.726614) (xy 290.254703 -278.775191) (xy 290.255198 -278.799798) (xy 291.543752 -278.799798)
			(xy 291.547712 -278.750744) (xy 291.559489 -278.70296) (xy 291.57878 -278.657684) (xy 291.605083 -278.616088)
			(xy 291.637718 -278.579251) (xy 291.675839 -278.548126) (xy 291.71846 -278.523519) (xy 291.764476 -278.506067)
			(xy 291.812695 -278.496223) (xy 291.86187 -278.494242) (xy 291.910725 -278.500174) (xy 291.957996 -278.513866)
			(xy 292.002458 -278.534964) (xy 292.042961 -278.56292) (xy 292.078454 -278.597012) (xy 292.108019 -278.636356)
			(xy 292.13089 -278.679933) (xy 292.146474 -278.726614) (xy 292.154369 -278.775191) (xy 292.154864 -278.799798)
			(xy 293.443672 -278.799798) (xy 293.447632 -278.750744) (xy 293.459409 -278.70296) (xy 293.4787 -278.657684)
			(xy 293.505003 -278.616088) (xy 293.537638 -278.579251) (xy 293.575759 -278.548126) (xy 293.61838 -278.523519)
			(xy 293.664396 -278.506067) (xy 293.712615 -278.496223) (xy 293.76179 -278.494242) (xy 293.810645 -278.500174)
			(xy 293.857916 -278.513866) (xy 293.902378 -278.534964) (xy 293.942881 -278.56292) (xy 293.978374 -278.597012)
			(xy 294.007939 -278.636356) (xy 294.03081 -278.679933) (xy 294.046394 -278.726614) (xy 294.054289 -278.775191)
			(xy 294.054784 -278.799798) (xy 295.343846 -278.799798) (xy 295.347806 -278.750744) (xy 295.359583 -278.70296)
			(xy 295.378874 -278.657684) (xy 295.405177 -278.616088) (xy 295.437812 -278.579251) (xy 295.475933 -278.548126)
			(xy 295.518554 -278.523519) (xy 295.56457 -278.506067) (xy 295.612789 -278.496223) (xy 295.661964 -278.494242)
			(xy 295.710819 -278.500174) (xy 295.75809 -278.513866) (xy 295.802552 -278.534964) (xy 295.843055 -278.56292)
			(xy 295.878548 -278.597012) (xy 295.908113 -278.636356) (xy 295.930984 -278.679933) (xy 295.946568 -278.726614)
			(xy 295.954463 -278.775191) (xy 295.954958 -278.799798) (xy 297.243766 -278.799798) (xy 297.247726 -278.750744)
			(xy 297.259503 -278.70296) (xy 297.278794 -278.657684) (xy 297.305097 -278.616088) (xy 297.337732 -278.579251)
			(xy 297.375853 -278.548126) (xy 297.418474 -278.523519) (xy 297.46449 -278.506067) (xy 297.512709 -278.496223)
			(xy 297.561884 -278.494242) (xy 297.610739 -278.500174) (xy 297.65801 -278.513866) (xy 297.702472 -278.534964)
			(xy 297.742975 -278.56292) (xy 297.778468 -278.597012) (xy 297.808033 -278.636356) (xy 297.830904 -278.679933)
			(xy 297.846488 -278.726614) (xy 297.854383 -278.775191) (xy 297.854878 -278.799798) (xy 299.143686 -278.799798)
			(xy 299.147646 -278.750744) (xy 299.159423 -278.70296) (xy 299.178714 -278.657684) (xy 299.205017 -278.616088)
			(xy 299.237652 -278.579251) (xy 299.275773 -278.548126) (xy 299.318394 -278.523519) (xy 299.36441 -278.506067)
			(xy 299.412629 -278.496223) (xy 299.461804 -278.494242) (xy 299.510659 -278.500174) (xy 299.55793 -278.513866)
			(xy 299.602392 -278.534964) (xy 299.642895 -278.56292) (xy 299.678388 -278.597012) (xy 299.707953 -278.636356)
			(xy 299.730824 -278.679933) (xy 299.746408 -278.726614) (xy 299.754303 -278.775191) (xy 299.754798 -278.799798)
			(xy 301.04386 -278.799798) (xy 301.04782 -278.750744) (xy 301.059597 -278.70296) (xy 301.078888 -278.657684)
			(xy 301.105191 -278.616088) (xy 301.137826 -278.579251) (xy 301.175947 -278.548126) (xy 301.218568 -278.523519)
			(xy 301.264584 -278.506067) (xy 301.312803 -278.496223) (xy 301.361978 -278.494242) (xy 301.410833 -278.500174)
			(xy 301.458104 -278.513866) (xy 301.502566 -278.534964) (xy 301.543069 -278.56292) (xy 301.578562 -278.597012)
			(xy 301.608127 -278.636356) (xy 301.630998 -278.679933) (xy 301.646582 -278.726614) (xy 301.654477 -278.775191)
			(xy 301.654972 -278.799798) (xy 302.94378 -278.799798) (xy 302.94774 -278.750744) (xy 302.959517 -278.70296)
			(xy 302.978808 -278.657684) (xy 303.005111 -278.616088) (xy 303.037746 -278.579251) (xy 303.075867 -278.548126)
			(xy 303.118488 -278.523519) (xy 303.164504 -278.506067) (xy 303.212723 -278.496223) (xy 303.261898 -278.494242)
			(xy 303.310753 -278.500174) (xy 303.358024 -278.513866) (xy 303.402486 -278.534964) (xy 303.442989 -278.56292)
			(xy 303.478482 -278.597012) (xy 303.508047 -278.636356) (xy 303.530918 -278.679933) (xy 303.546502 -278.726614)
			(xy 303.554397 -278.775191) (xy 303.554892 -278.799798) (xy 304.8437 -278.799798) (xy 304.84766 -278.750744)
			(xy 304.859437 -278.70296) (xy 304.878728 -278.657684) (xy 304.905031 -278.616088) (xy 304.937666 -278.579251)
			(xy 304.975787 -278.548126) (xy 305.018408 -278.523519) (xy 305.064424 -278.506067) (xy 305.112643 -278.496223)
			(xy 305.161818 -278.494242) (xy 305.210673 -278.500174) (xy 305.257944 -278.513866) (xy 305.302406 -278.534964)
			(xy 305.342909 -278.56292) (xy 305.378402 -278.597012) (xy 305.407967 -278.636356) (xy 305.430838 -278.679933)
			(xy 305.446422 -278.726614) (xy 305.454317 -278.775191) (xy 305.454812 -278.799798) (xy 306.743874 -278.799798)
			(xy 306.747834 -278.750744) (xy 306.759611 -278.70296) (xy 306.778902 -278.657684) (xy 306.805205 -278.616088)
			(xy 306.83784 -278.579251) (xy 306.875961 -278.548126) (xy 306.918582 -278.523519) (xy 306.964598 -278.506067)
			(xy 307.012817 -278.496223) (xy 307.061992 -278.494242) (xy 307.110847 -278.500174) (xy 307.158118 -278.513866)
			(xy 307.20258 -278.534964) (xy 307.243083 -278.56292) (xy 307.278576 -278.597012) (xy 307.308141 -278.636356)
			(xy 307.331012 -278.679933) (xy 307.346596 -278.726614) (xy 307.354491 -278.775191) (xy 307.354986 -278.799798)
			(xy 308.643794 -278.799798) (xy 308.647754 -278.750744) (xy 308.659531 -278.70296) (xy 308.678822 -278.657684)
			(xy 308.705125 -278.616088) (xy 308.73776 -278.579251) (xy 308.775881 -278.548126) (xy 308.818502 -278.523519)
			(xy 308.864518 -278.506067) (xy 308.912737 -278.496223) (xy 308.961912 -278.494242) (xy 309.010767 -278.500174)
			(xy 309.058038 -278.513866) (xy 309.1025 -278.534964) (xy 309.143003 -278.56292) (xy 309.178496 -278.597012)
			(xy 309.208061 -278.636356) (xy 309.230932 -278.679933) (xy 309.246516 -278.726614) (xy 309.254411 -278.775191)
			(xy 309.254906 -278.799798) (xy 310.543714 -278.799798) (xy 310.547674 -278.750744) (xy 310.559451 -278.70296)
			(xy 310.578742 -278.657684) (xy 310.605045 -278.616088) (xy 310.63768 -278.579251) (xy 310.675801 -278.548126)
			(xy 310.718422 -278.523519) (xy 310.764438 -278.506067) (xy 310.812657 -278.496223) (xy 310.861832 -278.494242)
			(xy 310.910687 -278.500174) (xy 310.957958 -278.513866) (xy 311.00242 -278.534964) (xy 311.042923 -278.56292)
			(xy 311.078416 -278.597012) (xy 311.107981 -278.636356) (xy 311.130852 -278.679933) (xy 311.146436 -278.726614)
			(xy 311.154331 -278.775191) (xy 311.154826 -278.799798) (xy 312.443888 -278.799798) (xy 312.447848 -278.750744)
			(xy 312.459625 -278.70296) (xy 312.478916 -278.657684) (xy 312.505219 -278.616088) (xy 312.537854 -278.579251)
			(xy 312.575975 -278.548126) (xy 312.618596 -278.523519) (xy 312.664612 -278.506067) (xy 312.712831 -278.496223)
			(xy 312.762006 -278.494242) (xy 312.810861 -278.500174) (xy 312.858132 -278.513866) (xy 312.902594 -278.534964)
			(xy 312.943097 -278.56292) (xy 312.97859 -278.597012) (xy 313.008155 -278.636356) (xy 313.031026 -278.679933)
			(xy 313.04661 -278.726614) (xy 313.054505 -278.775191) (xy 313.055 -278.799798) (xy 392.443982 -278.799798)
			(xy 392.447942 -278.750744) (xy 392.459719 -278.70296) (xy 392.47901 -278.657684) (xy 392.505313 -278.616088)
			(xy 392.537948 -278.579251) (xy 392.576069 -278.548126) (xy 392.61869 -278.523519) (xy 392.664706 -278.506067)
			(xy 392.712925 -278.496223) (xy 392.7621 -278.494242) (xy 392.810955 -278.500174) (xy 392.858226 -278.513866)
			(xy 392.902688 -278.534964) (xy 392.943191 -278.56292) (xy 392.978684 -278.597012) (xy 393.008249 -278.636356)
			(xy 393.03112 -278.679933) (xy 393.046704 -278.726614) (xy 393.054599 -278.775191) (xy 393.055094 -278.799798)
			(xy 394.344156 -278.799798) (xy 394.348116 -278.750744) (xy 394.359893 -278.70296) (xy 394.379184 -278.657684)
			(xy 394.405487 -278.616088) (xy 394.438122 -278.579251) (xy 394.476243 -278.548126) (xy 394.518864 -278.523519)
			(xy 394.56488 -278.506067) (xy 394.613099 -278.496223) (xy 394.662274 -278.494242) (xy 394.711129 -278.500174)
			(xy 394.7584 -278.513866) (xy 394.802862 -278.534964) (xy 394.843365 -278.56292) (xy 394.878858 -278.597012)
			(xy 394.908423 -278.636356) (xy 394.931294 -278.679933) (xy 394.946878 -278.726614) (xy 394.954773 -278.775191)
			(xy 394.955268 -278.799798) (xy 396.244076 -278.799798) (xy 396.248036 -278.750744) (xy 396.259813 -278.70296)
			(xy 396.279104 -278.657684) (xy 396.305407 -278.616088) (xy 396.338042 -278.579251) (xy 396.376163 -278.548126)
			(xy 396.418784 -278.523519) (xy 396.4648 -278.506067) (xy 396.513019 -278.496223) (xy 396.562194 -278.494242)
			(xy 396.611049 -278.500174) (xy 396.65832 -278.513866) (xy 396.702782 -278.534964) (xy 396.743285 -278.56292)
			(xy 396.778778 -278.597012) (xy 396.808343 -278.636356) (xy 396.831214 -278.679933) (xy 396.846798 -278.726614)
			(xy 396.854693 -278.775191) (xy 396.855188 -278.799798) (xy 398.143996 -278.799798) (xy 398.147956 -278.750744)
			(xy 398.159733 -278.70296) (xy 398.179024 -278.657684) (xy 398.205327 -278.616088) (xy 398.237962 -278.579251)
			(xy 398.276083 -278.548126) (xy 398.318704 -278.523519) (xy 398.36472 -278.506067) (xy 398.412939 -278.496223)
			(xy 398.462114 -278.494242) (xy 398.510969 -278.500174) (xy 398.55824 -278.513866) (xy 398.602702 -278.534964)
			(xy 398.643205 -278.56292) (xy 398.678698 -278.597012) (xy 398.708263 -278.636356) (xy 398.731134 -278.679933)
			(xy 398.746718 -278.726614) (xy 398.754613 -278.775191) (xy 398.755108 -278.799798) (xy 400.04417 -278.799798)
			(xy 400.04813 -278.750744) (xy 400.059907 -278.70296) (xy 400.079198 -278.657684) (xy 400.105501 -278.616088)
			(xy 400.138136 -278.579251) (xy 400.176257 -278.548126) (xy 400.218878 -278.523519) (xy 400.264894 -278.506067)
			(xy 400.313113 -278.496223) (xy 400.362288 -278.494242) (xy 400.411143 -278.500174) (xy 400.458414 -278.513866)
			(xy 400.502876 -278.534964) (xy 400.543379 -278.56292) (xy 400.578872 -278.597012) (xy 400.608437 -278.636356)
			(xy 400.631308 -278.679933) (xy 400.646892 -278.726614) (xy 400.654787 -278.775191) (xy 400.655282 -278.799798)
			(xy 401.94409 -278.799798) (xy 401.94805 -278.750744) (xy 401.959827 -278.70296) (xy 401.979118 -278.657684)
			(xy 402.005421 -278.616088) (xy 402.038056 -278.579251) (xy 402.076177 -278.548126) (xy 402.118798 -278.523519)
			(xy 402.164814 -278.506067) (xy 402.213033 -278.496223) (xy 402.262208 -278.494242) (xy 402.311063 -278.500174)
			(xy 402.358334 -278.513866) (xy 402.402796 -278.534964) (xy 402.443299 -278.56292) (xy 402.478792 -278.597012)
			(xy 402.508357 -278.636356) (xy 402.531228 -278.679933) (xy 402.546812 -278.726614) (xy 402.554707 -278.775191)
			(xy 402.555202 -278.799798) (xy 403.84401 -278.799798) (xy 403.84797 -278.750744) (xy 403.859747 -278.70296)
			(xy 403.879038 -278.657684) (xy 403.905341 -278.616088) (xy 403.937976 -278.579251) (xy 403.976097 -278.548126)
			(xy 404.018718 -278.523519) (xy 404.064734 -278.506067) (xy 404.112953 -278.496223) (xy 404.162128 -278.494242)
			(xy 404.210983 -278.500174) (xy 404.258254 -278.513866) (xy 404.302716 -278.534964) (xy 404.343219 -278.56292)
			(xy 404.378712 -278.597012) (xy 404.408277 -278.636356) (xy 404.431148 -278.679933) (xy 404.446732 -278.726614)
			(xy 404.454627 -278.775191) (xy 404.455122 -278.799798) (xy 405.744184 -278.799798) (xy 405.748144 -278.750744)
			(xy 405.759921 -278.70296) (xy 405.779212 -278.657684) (xy 405.805515 -278.616088) (xy 405.83815 -278.579251)
			(xy 405.876271 -278.548126) (xy 405.918892 -278.523519) (xy 405.964908 -278.506067) (xy 406.013127 -278.496223)
			(xy 406.062302 -278.494242) (xy 406.111157 -278.500174) (xy 406.158428 -278.513866) (xy 406.20289 -278.534964)
			(xy 406.243393 -278.56292) (xy 406.278886 -278.597012) (xy 406.308451 -278.636356) (xy 406.331322 -278.679933)
			(xy 406.346906 -278.726614) (xy 406.354801 -278.775191) (xy 406.355296 -278.799798) (xy 407.64385 -278.799798)
			(xy 407.64781 -278.750744) (xy 407.659587 -278.70296) (xy 407.678878 -278.657684) (xy 407.705181 -278.616088)
			(xy 407.737816 -278.579251) (xy 407.775937 -278.548126) (xy 407.818558 -278.523519) (xy 407.864574 -278.506067)
			(xy 407.912793 -278.496223) (xy 407.961968 -278.494242) (xy 408.010823 -278.500174) (xy 408.058094 -278.513866)
			(xy 408.102556 -278.534964) (xy 408.143059 -278.56292) (xy 408.178552 -278.597012) (xy 408.208117 -278.636356)
			(xy 408.230988 -278.679933) (xy 408.246572 -278.726614) (xy 408.254467 -278.775191) (xy 408.254962 -278.799798)
			(xy 409.54377 -278.799798) (xy 409.54773 -278.750744) (xy 409.559507 -278.70296) (xy 409.578798 -278.657684)
			(xy 409.605101 -278.616088) (xy 409.637736 -278.579251) (xy 409.675857 -278.548126) (xy 409.718478 -278.523519)
			(xy 409.764494 -278.506067) (xy 409.812713 -278.496223) (xy 409.861888 -278.494242) (xy 409.910743 -278.500174)
			(xy 409.958014 -278.513866) (xy 410.002476 -278.534964) (xy 410.042979 -278.56292) (xy 410.078472 -278.597012)
			(xy 410.108037 -278.636356) (xy 410.130908 -278.679933) (xy 410.146492 -278.726614) (xy 410.154387 -278.775191)
			(xy 410.154882 -278.799798) (xy 411.443944 -278.799798) (xy 411.447904 -278.750744) (xy 411.459681 -278.70296)
			(xy 411.478972 -278.657684) (xy 411.505275 -278.616088) (xy 411.53791 -278.579251) (xy 411.576031 -278.548126)
			(xy 411.618652 -278.523519) (xy 411.664668 -278.506067) (xy 411.712887 -278.496223) (xy 411.762062 -278.494242)
			(xy 411.810917 -278.500174) (xy 411.858188 -278.513866) (xy 411.90265 -278.534964) (xy 411.943153 -278.56292)
			(xy 411.978646 -278.597012) (xy 412.008211 -278.636356) (xy 412.031082 -278.679933) (xy 412.046666 -278.726614)
			(xy 412.054561 -278.775191) (xy 412.055056 -278.799798) (xy 413.343864 -278.799798) (xy 413.347824 -278.750744)
			(xy 413.359601 -278.70296) (xy 413.378892 -278.657684) (xy 413.405195 -278.616088) (xy 413.43783 -278.579251)
			(xy 413.475951 -278.548126) (xy 413.518572 -278.523519) (xy 413.564588 -278.506067) (xy 413.612807 -278.496223)
			(xy 413.661982 -278.494242) (xy 413.710837 -278.500174) (xy 413.758108 -278.513866) (xy 413.80257 -278.534964)
			(xy 413.843073 -278.56292) (xy 413.878566 -278.597012) (xy 413.908131 -278.636356) (xy 413.931002 -278.679933)
			(xy 413.946586 -278.726614) (xy 413.954481 -278.775191) (xy 413.954976 -278.799798) (xy 415.243784 -278.799798)
			(xy 415.247744 -278.750744) (xy 415.259521 -278.70296) (xy 415.278812 -278.657684) (xy 415.305115 -278.616088)
			(xy 415.33775 -278.579251) (xy 415.375871 -278.548126) (xy 415.418492 -278.523519) (xy 415.464508 -278.506067)
			(xy 415.512727 -278.496223) (xy 415.561902 -278.494242) (xy 415.610757 -278.500174) (xy 415.658028 -278.513866)
			(xy 415.70249 -278.534964) (xy 415.742993 -278.56292) (xy 415.778486 -278.597012) (xy 415.808051 -278.636356)
			(xy 415.830922 -278.679933) (xy 415.846506 -278.726614) (xy 415.854401 -278.775191) (xy 415.854896 -278.799798)
			(xy 417.143958 -278.799798) (xy 417.147918 -278.750744) (xy 417.159695 -278.70296) (xy 417.178986 -278.657684)
			(xy 417.205289 -278.616088) (xy 417.237924 -278.579251) (xy 417.276045 -278.548126) (xy 417.318666 -278.523519)
			(xy 417.364682 -278.506067) (xy 417.412901 -278.496223) (xy 417.462076 -278.494242) (xy 417.510931 -278.500174)
			(xy 417.558202 -278.513866) (xy 417.602664 -278.534964) (xy 417.643167 -278.56292) (xy 417.67866 -278.597012)
			(xy 417.708225 -278.636356) (xy 417.731096 -278.679933) (xy 417.74668 -278.726614) (xy 417.754575 -278.775191)
			(xy 417.75507 -278.799798) (xy 419.043878 -278.799798) (xy 419.047838 -278.750744) (xy 419.059615 -278.70296)
			(xy 419.078906 -278.657684) (xy 419.105209 -278.616088) (xy 419.137844 -278.579251) (xy 419.175965 -278.548126)
			(xy 419.218586 -278.523519) (xy 419.264602 -278.506067) (xy 419.312821 -278.496223) (xy 419.361996 -278.494242)
			(xy 419.410851 -278.500174) (xy 419.458122 -278.513866) (xy 419.502584 -278.534964) (xy 419.543087 -278.56292)
			(xy 419.57858 -278.597012) (xy 419.608145 -278.636356) (xy 419.631016 -278.679933) (xy 419.6466 -278.726614)
			(xy 419.654495 -278.775191) (xy 419.65499 -278.799798) (xy 420.943798 -278.799798) (xy 420.947758 -278.750744)
			(xy 420.959535 -278.70296) (xy 420.978826 -278.657684) (xy 421.005129 -278.616088) (xy 421.037764 -278.579251)
			(xy 421.075885 -278.548126) (xy 421.118506 -278.523519) (xy 421.164522 -278.506067) (xy 421.212741 -278.496223)
			(xy 421.261916 -278.494242) (xy 421.310771 -278.500174) (xy 421.358042 -278.513866) (xy 421.402504 -278.534964)
			(xy 421.443007 -278.56292) (xy 421.4785 -278.597012) (xy 421.508065 -278.636356) (xy 421.530936 -278.679933)
			(xy 421.54652 -278.726614) (xy 421.554415 -278.775191) (xy 421.55491 -278.799798) (xy 422.843972 -278.799798)
			(xy 422.847932 -278.750744) (xy 422.859709 -278.70296) (xy 422.879 -278.657684) (xy 422.905303 -278.616088)
			(xy 422.937938 -278.579251) (xy 422.976059 -278.548126) (xy 423.01868 -278.523519) (xy 423.064696 -278.506067)
			(xy 423.112915 -278.496223) (xy 423.16209 -278.494242) (xy 423.210945 -278.500174) (xy 423.258216 -278.513866)
			(xy 423.302678 -278.534964) (xy 423.343181 -278.56292) (xy 423.378674 -278.597012) (xy 423.408239 -278.636356)
			(xy 423.43111 -278.679933) (xy 423.446694 -278.726614) (xy 423.454589 -278.775191) (xy 423.455084 -278.799798)
			(xy 424.743892 -278.799798) (xy 424.747852 -278.750744) (xy 424.759629 -278.70296) (xy 424.77892 -278.657684)
			(xy 424.805223 -278.616088) (xy 424.837858 -278.579251) (xy 424.875979 -278.548126) (xy 424.9186 -278.523519)
			(xy 424.964616 -278.506067) (xy 425.012835 -278.496223) (xy 425.06201 -278.494242) (xy 425.110865 -278.500174)
			(xy 425.158136 -278.513866) (xy 425.202598 -278.534964) (xy 425.243101 -278.56292) (xy 425.278594 -278.597012)
			(xy 425.308159 -278.636356) (xy 425.33103 -278.679933) (xy 425.346614 -278.726614) (xy 425.354509 -278.775191)
			(xy 425.355004 -278.799798) (xy 426.643812 -278.799798) (xy 426.647772 -278.750744) (xy 426.659549 -278.70296)
			(xy 426.67884 -278.657684) (xy 426.705143 -278.616088) (xy 426.737778 -278.579251) (xy 426.775899 -278.548126)
			(xy 426.81852 -278.523519) (xy 426.864536 -278.506067) (xy 426.912755 -278.496223) (xy 426.96193 -278.494242)
			(xy 427.010785 -278.500174) (xy 427.058056 -278.513866) (xy 427.102518 -278.534964) (xy 427.143021 -278.56292)
			(xy 427.178514 -278.597012) (xy 427.208079 -278.636356) (xy 427.23095 -278.679933) (xy 427.246534 -278.726614)
			(xy 427.254429 -278.775191) (xy 427.254924 -278.799798) (xy 428.543986 -278.799798) (xy 428.547946 -278.750744)
			(xy 428.559723 -278.70296) (xy 428.579014 -278.657684) (xy 428.605317 -278.616088) (xy 428.637952 -278.579251)
			(xy 428.676073 -278.548126) (xy 428.718694 -278.523519) (xy 428.76471 -278.506067) (xy 428.812929 -278.496223)
			(xy 428.862104 -278.494242) (xy 428.910959 -278.500174) (xy 428.95823 -278.513866) (xy 429.002692 -278.534964)
			(xy 429.043195 -278.56292) (xy 429.078688 -278.597012) (xy 429.108253 -278.636356) (xy 429.131124 -278.679933)
			(xy 429.146708 -278.726614) (xy 429.154603 -278.775191) (xy 429.155098 -278.799798) (xy 429.154603 -278.824405)
			(xy 429.146708 -278.872982) (xy 429.131124 -278.919663) (xy 429.108253 -278.96324) (xy 429.078688 -279.002584)
			(xy 429.043195 -279.036676) (xy 429.002692 -279.064632) (xy 428.95823 -279.08573) (xy 428.910959 -279.099422)
			(xy 428.862104 -279.105354) (xy 428.812929 -279.103373) (xy 428.76471 -279.093529) (xy 428.718694 -279.076077)
			(xy 428.676073 -279.05147) (xy 428.637952 -279.020345) (xy 428.605317 -278.983508) (xy 428.579014 -278.941912)
			(xy 428.559723 -278.896636) (xy 428.547946 -278.848852) (xy 428.543986 -278.799798) (xy 427.254924 -278.799798)
			(xy 427.254429 -278.824405) (xy 427.246534 -278.872982) (xy 427.23095 -278.919663) (xy 427.208079 -278.96324)
			(xy 427.178514 -279.002584) (xy 427.143021 -279.036676) (xy 427.102518 -279.064632) (xy 427.058056 -279.08573)
			(xy 427.010785 -279.099422) (xy 426.96193 -279.105354) (xy 426.912755 -279.103373) (xy 426.864536 -279.093529)
			(xy 426.81852 -279.076077) (xy 426.775899 -279.05147) (xy 426.737778 -279.020345) (xy 426.705143 -278.983508)
			(xy 426.67884 -278.941912) (xy 426.659549 -278.896636) (xy 426.647772 -278.848852) (xy 426.643812 -278.799798)
			(xy 425.355004 -278.799798) (xy 425.354509 -278.824405) (xy 425.346614 -278.872982) (xy 425.33103 -278.919663)
			(xy 425.308159 -278.96324) (xy 425.278594 -279.002584) (xy 425.243101 -279.036676) (xy 425.202598 -279.064632)
			(xy 425.158136 -279.08573) (xy 425.110865 -279.099422) (xy 425.06201 -279.105354) (xy 425.012835 -279.103373)
			(xy 424.964616 -279.093529) (xy 424.9186 -279.076077) (xy 424.875979 -279.05147) (xy 424.837858 -279.020345)
			(xy 424.805223 -278.983508) (xy 424.77892 -278.941912) (xy 424.759629 -278.896636) (xy 424.747852 -278.848852)
			(xy 424.743892 -278.799798) (xy 423.455084 -278.799798) (xy 423.454589 -278.824405) (xy 423.446694 -278.872982)
			(xy 423.43111 -278.919663) (xy 423.408239 -278.96324) (xy 423.378674 -279.002584) (xy 423.343181 -279.036676)
			(xy 423.302678 -279.064632) (xy 423.258216 -279.08573) (xy 423.210945 -279.099422) (xy 423.16209 -279.105354)
			(xy 423.112915 -279.103373) (xy 423.064696 -279.093529) (xy 423.01868 -279.076077) (xy 422.976059 -279.05147)
			(xy 422.937938 -279.020345) (xy 422.905303 -278.983508) (xy 422.879 -278.941912) (xy 422.859709 -278.896636)
			(xy 422.847932 -278.848852) (xy 422.843972 -278.799798) (xy 421.55491 -278.799798) (xy 421.554415 -278.824405)
			(xy 421.54652 -278.872982) (xy 421.530936 -278.919663) (xy 421.508065 -278.96324) (xy 421.4785 -279.002584)
			(xy 421.443007 -279.036676) (xy 421.402504 -279.064632) (xy 421.358042 -279.08573) (xy 421.310771 -279.099422)
			(xy 421.261916 -279.105354) (xy 421.212741 -279.103373) (xy 421.164522 -279.093529) (xy 421.118506 -279.076077)
			(xy 421.075885 -279.05147) (xy 421.037764 -279.020345) (xy 421.005129 -278.983508) (xy 420.978826 -278.941912)
			(xy 420.959535 -278.896636) (xy 420.947758 -278.848852) (xy 420.943798 -278.799798) (xy 419.65499 -278.799798)
			(xy 419.654495 -278.824405) (xy 419.6466 -278.872982) (xy 419.631016 -278.919663) (xy 419.608145 -278.96324)
			(xy 419.57858 -279.002584) (xy 419.543087 -279.036676) (xy 419.502584 -279.064632) (xy 419.458122 -279.08573)
			(xy 419.410851 -279.099422) (xy 419.361996 -279.105354) (xy 419.312821 -279.103373) (xy 419.264602 -279.093529)
			(xy 419.218586 -279.076077) (xy 419.175965 -279.05147) (xy 419.137844 -279.020345) (xy 419.105209 -278.983508)
			(xy 419.078906 -278.941912) (xy 419.059615 -278.896636) (xy 419.047838 -278.848852) (xy 419.043878 -278.799798)
			(xy 417.75507 -278.799798) (xy 417.754575 -278.824405) (xy 417.74668 -278.872982) (xy 417.731096 -278.919663)
			(xy 417.708225 -278.96324) (xy 417.67866 -279.002584) (xy 417.643167 -279.036676) (xy 417.602664 -279.064632)
			(xy 417.558202 -279.08573) (xy 417.510931 -279.099422) (xy 417.462076 -279.105354) (xy 417.412901 -279.103373)
			(xy 417.364682 -279.093529) (xy 417.318666 -279.076077) (xy 417.276045 -279.05147) (xy 417.237924 -279.020345)
			(xy 417.205289 -278.983508) (xy 417.178986 -278.941912) (xy 417.159695 -278.896636) (xy 417.147918 -278.848852)
			(xy 417.143958 -278.799798) (xy 415.854896 -278.799798) (xy 415.854401 -278.824405) (xy 415.846506 -278.872982)
			(xy 415.830922 -278.919663) (xy 415.808051 -278.96324) (xy 415.778486 -279.002584) (xy 415.742993 -279.036676)
			(xy 415.70249 -279.064632) (xy 415.658028 -279.08573) (xy 415.610757 -279.099422) (xy 415.561902 -279.105354)
			(xy 415.512727 -279.103373) (xy 415.464508 -279.093529) (xy 415.418492 -279.076077) (xy 415.375871 -279.05147)
			(xy 415.33775 -279.020345) (xy 415.305115 -278.983508) (xy 415.278812 -278.941912) (xy 415.259521 -278.896636)
			(xy 415.247744 -278.848852) (xy 415.243784 -278.799798) (xy 413.954976 -278.799798) (xy 413.954481 -278.824405)
			(xy 413.946586 -278.872982) (xy 413.931002 -278.919663) (xy 413.908131 -278.96324) (xy 413.878566 -279.002584)
			(xy 413.843073 -279.036676) (xy 413.80257 -279.064632) (xy 413.758108 -279.08573) (xy 413.710837 -279.099422)
			(xy 413.661982 -279.105354) (xy 413.612807 -279.103373) (xy 413.564588 -279.093529) (xy 413.518572 -279.076077)
			(xy 413.475951 -279.05147) (xy 413.43783 -279.020345) (xy 413.405195 -278.983508) (xy 413.378892 -278.941912)
			(xy 413.359601 -278.896636) (xy 413.347824 -278.848852) (xy 413.343864 -278.799798) (xy 412.055056 -278.799798)
			(xy 412.054561 -278.824405) (xy 412.046666 -278.872982) (xy 412.031082 -278.919663) (xy 412.008211 -278.96324)
			(xy 411.978646 -279.002584) (xy 411.943153 -279.036676) (xy 411.90265 -279.064632) (xy 411.858188 -279.08573)
			(xy 411.810917 -279.099422) (xy 411.762062 -279.105354) (xy 411.712887 -279.103373) (xy 411.664668 -279.093529)
			(xy 411.618652 -279.076077) (xy 411.576031 -279.05147) (xy 411.53791 -279.020345) (xy 411.505275 -278.983508)
			(xy 411.478972 -278.941912) (xy 411.459681 -278.896636) (xy 411.447904 -278.848852) (xy 411.443944 -278.799798)
			(xy 410.154882 -278.799798) (xy 410.154387 -278.824405) (xy 410.146492 -278.872982) (xy 410.130908 -278.919663)
			(xy 410.108037 -278.96324) (xy 410.078472 -279.002584) (xy 410.042979 -279.036676) (xy 410.002476 -279.064632)
			(xy 409.958014 -279.08573) (xy 409.910743 -279.099422) (xy 409.861888 -279.105354) (xy 409.812713 -279.103373)
			(xy 409.764494 -279.093529) (xy 409.718478 -279.076077) (xy 409.675857 -279.05147) (xy 409.637736 -279.020345)
			(xy 409.605101 -278.983508) (xy 409.578798 -278.941912) (xy 409.559507 -278.896636) (xy 409.54773 -278.848852)
			(xy 409.54377 -278.799798) (xy 408.254962 -278.799798) (xy 408.254467 -278.824405) (xy 408.246572 -278.872982)
			(xy 408.230988 -278.919663) (xy 408.208117 -278.96324) (xy 408.178552 -279.002584) (xy 408.143059 -279.036676)
			(xy 408.102556 -279.064632) (xy 408.058094 -279.08573) (xy 408.010823 -279.099422) (xy 407.961968 -279.105354)
			(xy 407.912793 -279.103373) (xy 407.864574 -279.093529) (xy 407.818558 -279.076077) (xy 407.775937 -279.05147)
			(xy 407.737816 -279.020345) (xy 407.705181 -278.983508) (xy 407.678878 -278.941912) (xy 407.659587 -278.896636)
			(xy 407.64781 -278.848852) (xy 407.64385 -278.799798) (xy 406.355296 -278.799798) (xy 406.354801 -278.824405)
			(xy 406.346906 -278.872982) (xy 406.331322 -278.919663) (xy 406.308451 -278.96324) (xy 406.278886 -279.002584)
			(xy 406.243393 -279.036676) (xy 406.20289 -279.064632) (xy 406.158428 -279.08573) (xy 406.111157 -279.099422)
			(xy 406.062302 -279.105354) (xy 406.013127 -279.103373) (xy 405.964908 -279.093529) (xy 405.918892 -279.076077)
			(xy 405.876271 -279.05147) (xy 405.83815 -279.020345) (xy 405.805515 -278.983508) (xy 405.779212 -278.941912)
			(xy 405.759921 -278.896636) (xy 405.748144 -278.848852) (xy 405.744184 -278.799798) (xy 404.455122 -278.799798)
			(xy 404.454627 -278.824405) (xy 404.446732 -278.872982) (xy 404.431148 -278.919663) (xy 404.408277 -278.96324)
			(xy 404.378712 -279.002584) (xy 404.343219 -279.036676) (xy 404.302716 -279.064632) (xy 404.258254 -279.08573)
			(xy 404.210983 -279.099422) (xy 404.162128 -279.105354) (xy 404.112953 -279.103373) (xy 404.064734 -279.093529)
			(xy 404.018718 -279.076077) (xy 403.976097 -279.05147) (xy 403.937976 -279.020345) (xy 403.905341 -278.983508)
			(xy 403.879038 -278.941912) (xy 403.859747 -278.896636) (xy 403.84797 -278.848852) (xy 403.84401 -278.799798)
			(xy 402.555202 -278.799798) (xy 402.554707 -278.824405) (xy 402.546812 -278.872982) (xy 402.531228 -278.919663)
			(xy 402.508357 -278.96324) (xy 402.478792 -279.002584) (xy 402.443299 -279.036676) (xy 402.402796 -279.064632)
			(xy 402.358334 -279.08573) (xy 402.311063 -279.099422) (xy 402.262208 -279.105354) (xy 402.213033 -279.103373)
			(xy 402.164814 -279.093529) (xy 402.118798 -279.076077) (xy 402.076177 -279.05147) (xy 402.038056 -279.020345)
			(xy 402.005421 -278.983508) (xy 401.979118 -278.941912) (xy 401.959827 -278.896636) (xy 401.94805 -278.848852)
			(xy 401.94409 -278.799798) (xy 400.655282 -278.799798) (xy 400.654787 -278.824405) (xy 400.646892 -278.872982)
			(xy 400.631308 -278.919663) (xy 400.608437 -278.96324) (xy 400.578872 -279.002584) (xy 400.543379 -279.036676)
			(xy 400.502876 -279.064632) (xy 400.458414 -279.08573) (xy 400.411143 -279.099422) (xy 400.362288 -279.105354)
			(xy 400.313113 -279.103373) (xy 400.264894 -279.093529) (xy 400.218878 -279.076077) (xy 400.176257 -279.05147)
			(xy 400.138136 -279.020345) (xy 400.105501 -278.983508) (xy 400.079198 -278.941912) (xy 400.059907 -278.896636)
			(xy 400.04813 -278.848852) (xy 400.04417 -278.799798) (xy 398.755108 -278.799798) (xy 398.754613 -278.824405)
			(xy 398.746718 -278.872982) (xy 398.731134 -278.919663) (xy 398.708263 -278.96324) (xy 398.678698 -279.002584)
			(xy 398.643205 -279.036676) (xy 398.602702 -279.064632) (xy 398.55824 -279.08573) (xy 398.510969 -279.099422)
			(xy 398.462114 -279.105354) (xy 398.412939 -279.103373) (xy 398.36472 -279.093529) (xy 398.318704 -279.076077)
			(xy 398.276083 -279.05147) (xy 398.237962 -279.020345) (xy 398.205327 -278.983508) (xy 398.179024 -278.941912)
			(xy 398.159733 -278.896636) (xy 398.147956 -278.848852) (xy 398.143996 -278.799798) (xy 396.855188 -278.799798)
			(xy 396.854693 -278.824405) (xy 396.846798 -278.872982) (xy 396.831214 -278.919663) (xy 396.808343 -278.96324)
			(xy 396.778778 -279.002584) (xy 396.743285 -279.036676) (xy 396.702782 -279.064632) (xy 396.65832 -279.08573)
			(xy 396.611049 -279.099422) (xy 396.562194 -279.105354) (xy 396.513019 -279.103373) (xy 396.4648 -279.093529)
			(xy 396.418784 -279.076077) (xy 396.376163 -279.05147) (xy 396.338042 -279.020345) (xy 396.305407 -278.983508)
			(xy 396.279104 -278.941912) (xy 396.259813 -278.896636) (xy 396.248036 -278.848852) (xy 396.244076 -278.799798)
			(xy 394.955268 -278.799798) (xy 394.954773 -278.824405) (xy 394.946878 -278.872982) (xy 394.931294 -278.919663)
			(xy 394.908423 -278.96324) (xy 394.878858 -279.002584) (xy 394.843365 -279.036676) (xy 394.802862 -279.064632)
			(xy 394.7584 -279.08573) (xy 394.711129 -279.099422) (xy 394.662274 -279.105354) (xy 394.613099 -279.103373)
			(xy 394.56488 -279.093529) (xy 394.518864 -279.076077) (xy 394.476243 -279.05147) (xy 394.438122 -279.020345)
			(xy 394.405487 -278.983508) (xy 394.379184 -278.941912) (xy 394.359893 -278.896636) (xy 394.348116 -278.848852)
			(xy 394.344156 -278.799798) (xy 393.055094 -278.799798) (xy 393.054599 -278.824405) (xy 393.046704 -278.872982)
			(xy 393.03112 -278.919663) (xy 393.008249 -278.96324) (xy 392.978684 -279.002584) (xy 392.943191 -279.036676)
			(xy 392.902688 -279.064632) (xy 392.858226 -279.08573) (xy 392.810955 -279.099422) (xy 392.7621 -279.105354)
			(xy 392.712925 -279.103373) (xy 392.664706 -279.093529) (xy 392.61869 -279.076077) (xy 392.576069 -279.05147)
			(xy 392.537948 -279.020345) (xy 392.505313 -278.983508) (xy 392.47901 -278.941912) (xy 392.459719 -278.896636)
			(xy 392.447942 -278.848852) (xy 392.443982 -278.799798) (xy 313.055 -278.799798) (xy 313.054505 -278.824405)
			(xy 313.04661 -278.872982) (xy 313.031026 -278.919663) (xy 313.008155 -278.96324) (xy 312.97859 -279.002584)
			(xy 312.943097 -279.036676) (xy 312.902594 -279.064632) (xy 312.858132 -279.08573) (xy 312.810861 -279.099422)
			(xy 312.762006 -279.105354) (xy 312.712831 -279.103373) (xy 312.664612 -279.093529) (xy 312.618596 -279.076077)
			(xy 312.575975 -279.05147) (xy 312.537854 -279.020345) (xy 312.505219 -278.983508) (xy 312.478916 -278.941912)
			(xy 312.459625 -278.896636) (xy 312.447848 -278.848852) (xy 312.443888 -278.799798) (xy 311.154826 -278.799798)
			(xy 311.154331 -278.824405) (xy 311.146436 -278.872982) (xy 311.130852 -278.919663) (xy 311.107981 -278.96324)
			(xy 311.078416 -279.002584) (xy 311.042923 -279.036676) (xy 311.00242 -279.064632) (xy 310.957958 -279.08573)
			(xy 310.910687 -279.099422) (xy 310.861832 -279.105354) (xy 310.812657 -279.103373) (xy 310.764438 -279.093529)
			(xy 310.718422 -279.076077) (xy 310.675801 -279.05147) (xy 310.63768 -279.020345) (xy 310.605045 -278.983508)
			(xy 310.578742 -278.941912) (xy 310.559451 -278.896636) (xy 310.547674 -278.848852) (xy 310.543714 -278.799798)
			(xy 309.254906 -278.799798) (xy 309.254411 -278.824405) (xy 309.246516 -278.872982) (xy 309.230932 -278.919663)
			(xy 309.208061 -278.96324) (xy 309.178496 -279.002584) (xy 309.143003 -279.036676) (xy 309.1025 -279.064632)
			(xy 309.058038 -279.08573) (xy 309.010767 -279.099422) (xy 308.961912 -279.105354) (xy 308.912737 -279.103373)
			(xy 308.864518 -279.093529) (xy 308.818502 -279.076077) (xy 308.775881 -279.05147) (xy 308.73776 -279.020345)
			(xy 308.705125 -278.983508) (xy 308.678822 -278.941912) (xy 308.659531 -278.896636) (xy 308.647754 -278.848852)
			(xy 308.643794 -278.799798) (xy 307.354986 -278.799798) (xy 307.354491 -278.824405) (xy 307.346596 -278.872982)
			(xy 307.331012 -278.919663) (xy 307.308141 -278.96324) (xy 307.278576 -279.002584) (xy 307.243083 -279.036676)
			(xy 307.20258 -279.064632) (xy 307.158118 -279.08573) (xy 307.110847 -279.099422) (xy 307.061992 -279.105354)
			(xy 307.012817 -279.103373) (xy 306.964598 -279.093529) (xy 306.918582 -279.076077) (xy 306.875961 -279.05147)
			(xy 306.83784 -279.020345) (xy 306.805205 -278.983508) (xy 306.778902 -278.941912) (xy 306.759611 -278.896636)
			(xy 306.747834 -278.848852) (xy 306.743874 -278.799798) (xy 305.454812 -278.799798) (xy 305.454317 -278.824405)
			(xy 305.446422 -278.872982) (xy 305.430838 -278.919663) (xy 305.407967 -278.96324) (xy 305.378402 -279.002584)
			(xy 305.342909 -279.036676) (xy 305.302406 -279.064632) (xy 305.257944 -279.08573) (xy 305.210673 -279.099422)
			(xy 305.161818 -279.105354) (xy 305.112643 -279.103373) (xy 305.064424 -279.093529) (xy 305.018408 -279.076077)
			(xy 304.975787 -279.05147) (xy 304.937666 -279.020345) (xy 304.905031 -278.983508) (xy 304.878728 -278.941912)
			(xy 304.859437 -278.896636) (xy 304.84766 -278.848852) (xy 304.8437 -278.799798) (xy 303.554892 -278.799798)
			(xy 303.554397 -278.824405) (xy 303.546502 -278.872982) (xy 303.530918 -278.919663) (xy 303.508047 -278.96324)
			(xy 303.478482 -279.002584) (xy 303.442989 -279.036676) (xy 303.402486 -279.064632) (xy 303.358024 -279.08573)
			(xy 303.310753 -279.099422) (xy 303.261898 -279.105354) (xy 303.212723 -279.103373) (xy 303.164504 -279.093529)
			(xy 303.118488 -279.076077) (xy 303.075867 -279.05147) (xy 303.037746 -279.020345) (xy 303.005111 -278.983508)
			(xy 302.978808 -278.941912) (xy 302.959517 -278.896636) (xy 302.94774 -278.848852) (xy 302.94378 -278.799798)
			(xy 301.654972 -278.799798) (xy 301.654477 -278.824405) (xy 301.646582 -278.872982) (xy 301.630998 -278.919663)
			(xy 301.608127 -278.96324) (xy 301.578562 -279.002584) (xy 301.543069 -279.036676) (xy 301.502566 -279.064632)
			(xy 301.458104 -279.08573) (xy 301.410833 -279.099422) (xy 301.361978 -279.105354) (xy 301.312803 -279.103373)
			(xy 301.264584 -279.093529) (xy 301.218568 -279.076077) (xy 301.175947 -279.05147) (xy 301.137826 -279.020345)
			(xy 301.105191 -278.983508) (xy 301.078888 -278.941912) (xy 301.059597 -278.896636) (xy 301.04782 -278.848852)
			(xy 301.04386 -278.799798) (xy 299.754798 -278.799798) (xy 299.754303 -278.824405) (xy 299.746408 -278.872982)
			(xy 299.730824 -278.919663) (xy 299.707953 -278.96324) (xy 299.678388 -279.002584) (xy 299.642895 -279.036676)
			(xy 299.602392 -279.064632) (xy 299.55793 -279.08573) (xy 299.510659 -279.099422) (xy 299.461804 -279.105354)
			(xy 299.412629 -279.103373) (xy 299.36441 -279.093529) (xy 299.318394 -279.076077) (xy 299.275773 -279.05147)
			(xy 299.237652 -279.020345) (xy 299.205017 -278.983508) (xy 299.178714 -278.941912) (xy 299.159423 -278.896636)
			(xy 299.147646 -278.848852) (xy 299.143686 -278.799798) (xy 297.854878 -278.799798) (xy 297.854383 -278.824405)
			(xy 297.846488 -278.872982) (xy 297.830904 -278.919663) (xy 297.808033 -278.96324) (xy 297.778468 -279.002584)
			(xy 297.742975 -279.036676) (xy 297.702472 -279.064632) (xy 297.65801 -279.08573) (xy 297.610739 -279.099422)
			(xy 297.561884 -279.105354) (xy 297.512709 -279.103373) (xy 297.46449 -279.093529) (xy 297.418474 -279.076077)
			(xy 297.375853 -279.05147) (xy 297.337732 -279.020345) (xy 297.305097 -278.983508) (xy 297.278794 -278.941912)
			(xy 297.259503 -278.896636) (xy 297.247726 -278.848852) (xy 297.243766 -278.799798) (xy 295.954958 -278.799798)
			(xy 295.954463 -278.824405) (xy 295.946568 -278.872982) (xy 295.930984 -278.919663) (xy 295.908113 -278.96324)
			(xy 295.878548 -279.002584) (xy 295.843055 -279.036676) (xy 295.802552 -279.064632) (xy 295.75809 -279.08573)
			(xy 295.710819 -279.099422) (xy 295.661964 -279.105354) (xy 295.612789 -279.103373) (xy 295.56457 -279.093529)
			(xy 295.518554 -279.076077) (xy 295.475933 -279.05147) (xy 295.437812 -279.020345) (xy 295.405177 -278.983508)
			(xy 295.378874 -278.941912) (xy 295.359583 -278.896636) (xy 295.347806 -278.848852) (xy 295.343846 -278.799798)
			(xy 294.054784 -278.799798) (xy 294.054289 -278.824405) (xy 294.046394 -278.872982) (xy 294.03081 -278.919663)
			(xy 294.007939 -278.96324) (xy 293.978374 -279.002584) (xy 293.942881 -279.036676) (xy 293.902378 -279.064632)
			(xy 293.857916 -279.08573) (xy 293.810645 -279.099422) (xy 293.76179 -279.105354) (xy 293.712615 -279.103373)
			(xy 293.664396 -279.093529) (xy 293.61838 -279.076077) (xy 293.575759 -279.05147) (xy 293.537638 -279.020345)
			(xy 293.505003 -278.983508) (xy 293.4787 -278.941912) (xy 293.459409 -278.896636) (xy 293.447632 -278.848852)
			(xy 293.443672 -278.799798) (xy 292.154864 -278.799798) (xy 292.154369 -278.824405) (xy 292.146474 -278.872982)
			(xy 292.13089 -278.919663) (xy 292.108019 -278.96324) (xy 292.078454 -279.002584) (xy 292.042961 -279.036676)
			(xy 292.002458 -279.064632) (xy 291.957996 -279.08573) (xy 291.910725 -279.099422) (xy 291.86187 -279.105354)
			(xy 291.812695 -279.103373) (xy 291.764476 -279.093529) (xy 291.71846 -279.076077) (xy 291.675839 -279.05147)
			(xy 291.637718 -279.020345) (xy 291.605083 -278.983508) (xy 291.57878 -278.941912) (xy 291.559489 -278.896636)
			(xy 291.547712 -278.848852) (xy 291.543752 -278.799798) (xy 290.255198 -278.799798) (xy 290.254703 -278.824405)
			(xy 290.246808 -278.872982) (xy 290.231224 -278.919663) (xy 290.208353 -278.96324) (xy 290.178788 -279.002584)
			(xy 290.143295 -279.036676) (xy 290.102792 -279.064632) (xy 290.05833 -279.08573) (xy 290.011059 -279.099422)
			(xy 289.962204 -279.105354) (xy 289.913029 -279.103373) (xy 289.86481 -279.093529) (xy 289.818794 -279.076077)
			(xy 289.776173 -279.05147) (xy 289.738052 -279.020345) (xy 289.705417 -278.983508) (xy 289.679114 -278.941912)
			(xy 289.659823 -278.896636) (xy 289.648046 -278.848852) (xy 289.644086 -278.799798) (xy 288.355024 -278.799798)
			(xy 288.354529 -278.824405) (xy 288.346634 -278.872982) (xy 288.33105 -278.919663) (xy 288.308179 -278.96324)
			(xy 288.278614 -279.002584) (xy 288.243121 -279.036676) (xy 288.202618 -279.064632) (xy 288.158156 -279.08573)
			(xy 288.110885 -279.099422) (xy 288.06203 -279.105354) (xy 288.012855 -279.103373) (xy 287.964636 -279.093529)
			(xy 287.91862 -279.076077) (xy 287.875999 -279.05147) (xy 287.837878 -279.020345) (xy 287.805243 -278.983508)
			(xy 287.77894 -278.941912) (xy 287.759649 -278.896636) (xy 287.747872 -278.848852) (xy 287.743912 -278.799798)
			(xy 286.455104 -278.799798) (xy 286.454609 -278.824405) (xy 286.446714 -278.872982) (xy 286.43113 -278.919663)
			(xy 286.408259 -278.96324) (xy 286.378694 -279.002584) (xy 286.343201 -279.036676) (xy 286.302698 -279.064632)
			(xy 286.258236 -279.08573) (xy 286.210965 -279.099422) (xy 286.16211 -279.105354) (xy 286.112935 -279.103373)
			(xy 286.064716 -279.093529) (xy 286.0187 -279.076077) (xy 285.976079 -279.05147) (xy 285.937958 -279.020345)
			(xy 285.905323 -278.983508) (xy 285.87902 -278.941912) (xy 285.859729 -278.896636) (xy 285.847952 -278.848852)
			(xy 285.843992 -278.799798) (xy 284.555184 -278.799798) (xy 284.554689 -278.824405) (xy 284.546794 -278.872982)
			(xy 284.53121 -278.919663) (xy 284.508339 -278.96324) (xy 284.478774 -279.002584) (xy 284.443281 -279.036676)
			(xy 284.402778 -279.064632) (xy 284.358316 -279.08573) (xy 284.311045 -279.099422) (xy 284.26219 -279.105354)
			(xy 284.213015 -279.103373) (xy 284.164796 -279.093529) (xy 284.11878 -279.076077) (xy 284.076159 -279.05147)
			(xy 284.038038 -279.020345) (xy 284.005403 -278.983508) (xy 283.9791 -278.941912) (xy 283.959809 -278.896636)
			(xy 283.948032 -278.848852) (xy 283.944072 -278.799798) (xy 282.65501 -278.799798) (xy 282.654515 -278.824405)
			(xy 282.64662 -278.872982) (xy 282.631036 -278.919663) (xy 282.608165 -278.96324) (xy 282.5786 -279.002584)
			(xy 282.543107 -279.036676) (xy 282.502604 -279.064632) (xy 282.458142 -279.08573) (xy 282.410871 -279.099422)
			(xy 282.362016 -279.105354) (xy 282.312841 -279.103373) (xy 282.264622 -279.093529) (xy 282.218606 -279.076077)
			(xy 282.175985 -279.05147) (xy 282.137864 -279.020345) (xy 282.105229 -278.983508) (xy 282.078926 -278.941912)
			(xy 282.059635 -278.896636) (xy 282.047858 -278.848852) (xy 282.043898 -278.799798) (xy 280.75509 -278.799798)
			(xy 280.754595 -278.824405) (xy 280.7467 -278.872982) (xy 280.731116 -278.919663) (xy 280.708245 -278.96324)
			(xy 280.67868 -279.002584) (xy 280.643187 -279.036676) (xy 280.602684 -279.064632) (xy 280.558222 -279.08573)
			(xy 280.510951 -279.099422) (xy 280.462096 -279.105354) (xy 280.412921 -279.103373) (xy 280.364702 -279.093529)
			(xy 280.318686 -279.076077) (xy 280.276065 -279.05147) (xy 280.237944 -279.020345) (xy 280.205309 -278.983508)
			(xy 280.179006 -278.941912) (xy 280.159715 -278.896636) (xy 280.147938 -278.848852) (xy 280.143978 -278.799798)
			(xy 278.85517 -278.799798) (xy 278.854675 -278.824405) (xy 278.84678 -278.872982) (xy 278.831196 -278.919663)
			(xy 278.808325 -278.96324) (xy 278.77876 -279.002584) (xy 278.743267 -279.036676) (xy 278.702764 -279.064632)
			(xy 278.658302 -279.08573) (xy 278.611031 -279.099422) (xy 278.562176 -279.105354) (xy 278.513001 -279.103373)
			(xy 278.464782 -279.093529) (xy 278.418766 -279.076077) (xy 278.376145 -279.05147) (xy 278.338024 -279.020345)
			(xy 278.305389 -278.983508) (xy 278.279086 -278.941912) (xy 278.259795 -278.896636) (xy 278.248018 -278.848852)
			(xy 278.244058 -278.799798) (xy 276.954996 -278.799798) (xy 276.954501 -278.824405) (xy 276.946606 -278.872982)
			(xy 276.931022 -278.919663) (xy 276.908151 -278.96324) (xy 276.878586 -279.002584) (xy 276.843093 -279.036676)
			(xy 276.80259 -279.064632) (xy 276.758128 -279.08573) (xy 276.710857 -279.099422) (xy 276.662002 -279.105354)
			(xy 276.612827 -279.103373) (xy 276.564608 -279.093529) (xy 276.518592 -279.076077) (xy 276.475971 -279.05147)
			(xy 276.43785 -279.020345) (xy 276.405215 -278.983508) (xy 276.378912 -278.941912) (xy 276.359621 -278.896636)
			(xy 276.347844 -278.848852) (xy 276.343884 -278.799798) (xy 196.955156 -278.799798) (xy 196.954661 -278.824405)
			(xy 196.946766 -278.872982) (xy 196.931182 -278.919663) (xy 196.908311 -278.96324) (xy 196.878746 -279.002584)
			(xy 196.843253 -279.036676) (xy 196.80275 -279.064632) (xy 196.758288 -279.08573) (xy 196.711017 -279.099422)
			(xy 196.662162 -279.105354) (xy 196.612987 -279.103373) (xy 196.564768 -279.093529) (xy 196.518752 -279.076077)
			(xy 196.476131 -279.05147) (xy 196.43801 -279.020345) (xy 196.405375 -278.983508) (xy 196.379072 -278.941912)
			(xy 196.359781 -278.896636) (xy 196.348004 -278.848852) (xy 196.344044 -278.799798) (xy 195.054982 -278.799798)
			(xy 195.054487 -278.824405) (xy 195.046592 -278.872982) (xy 195.031008 -278.919663) (xy 195.008137 -278.96324)
			(xy 194.978572 -279.002584) (xy 194.943079 -279.036676) (xy 194.902576 -279.064632) (xy 194.858114 -279.08573)
			(xy 194.810843 -279.099422) (xy 194.761988 -279.105354) (xy 194.712813 -279.103373) (xy 194.664594 -279.093529)
			(xy 194.618578 -279.076077) (xy 194.575957 -279.05147) (xy 194.537836 -279.020345) (xy 194.505201 -278.983508)
			(xy 194.478898 -278.941912) (xy 194.459607 -278.896636) (xy 194.44783 -278.848852) (xy 194.44387 -278.799798)
			(xy 193.155062 -278.799798) (xy 193.154567 -278.824405) (xy 193.146672 -278.872982) (xy 193.131088 -278.919663)
			(xy 193.108217 -278.96324) (xy 193.078652 -279.002584) (xy 193.043159 -279.036676) (xy 193.002656 -279.064632)
			(xy 192.958194 -279.08573) (xy 192.910923 -279.099422) (xy 192.862068 -279.105354) (xy 192.812893 -279.103373)
			(xy 192.764674 -279.093529) (xy 192.718658 -279.076077) (xy 192.676037 -279.05147) (xy 192.637916 -279.020345)
			(xy 192.605281 -278.983508) (xy 192.578978 -278.941912) (xy 192.559687 -278.896636) (xy 192.54791 -278.848852)
			(xy 192.54395 -278.799798) (xy 191.255142 -278.799798) (xy 191.254647 -278.824405) (xy 191.246752 -278.872982)
			(xy 191.231168 -278.919663) (xy 191.208297 -278.96324) (xy 191.178732 -279.002584) (xy 191.143239 -279.036676)
			(xy 191.102736 -279.064632) (xy 191.058274 -279.08573) (xy 191.011003 -279.099422) (xy 190.962148 -279.105354)
			(xy 190.912973 -279.103373) (xy 190.864754 -279.093529) (xy 190.818738 -279.076077) (xy 190.776117 -279.05147)
			(xy 190.737996 -279.020345) (xy 190.705361 -278.983508) (xy 190.679058 -278.941912) (xy 190.659767 -278.896636)
			(xy 190.64799 -278.848852) (xy 190.64403 -278.799798) (xy 189.354968 -278.799798) (xy 189.354473 -278.824405)
			(xy 189.346578 -278.872982) (xy 189.330994 -278.919663) (xy 189.308123 -278.96324) (xy 189.278558 -279.002584)
			(xy 189.243065 -279.036676) (xy 189.202562 -279.064632) (xy 189.1581 -279.08573) (xy 189.110829 -279.099422)
			(xy 189.061974 -279.105354) (xy 189.012799 -279.103373) (xy 188.96458 -279.093529) (xy 188.918564 -279.076077)
			(xy 188.875943 -279.05147) (xy 188.837822 -279.020345) (xy 188.805187 -278.983508) (xy 188.778884 -278.941912)
			(xy 188.759593 -278.896636) (xy 188.747816 -278.848852) (xy 188.743856 -278.799798) (xy 187.455048 -278.799798)
			(xy 187.454553 -278.824405) (xy 187.446658 -278.872982) (xy 187.431074 -278.919663) (xy 187.408203 -278.96324)
			(xy 187.378638 -279.002584) (xy 187.343145 -279.036676) (xy 187.302642 -279.064632) (xy 187.25818 -279.08573)
			(xy 187.210909 -279.099422) (xy 187.162054 -279.105354) (xy 187.112879 -279.103373) (xy 187.06466 -279.093529)
			(xy 187.018644 -279.076077) (xy 186.976023 -279.05147) (xy 186.937902 -279.020345) (xy 186.905267 -278.983508)
			(xy 186.878964 -278.941912) (xy 186.859673 -278.896636) (xy 186.847896 -278.848852) (xy 186.843936 -278.799798)
			(xy 185.555128 -278.799798) (xy 185.554633 -278.824405) (xy 185.546738 -278.872982) (xy 185.531154 -278.919663)
			(xy 185.508283 -278.96324) (xy 185.478718 -279.002584) (xy 185.443225 -279.036676) (xy 185.402722 -279.064632)
			(xy 185.35826 -279.08573) (xy 185.310989 -279.099422) (xy 185.262134 -279.105354) (xy 185.212959 -279.103373)
			(xy 185.16474 -279.093529) (xy 185.118724 -279.076077) (xy 185.076103 -279.05147) (xy 185.037982 -279.020345)
			(xy 185.005347 -278.983508) (xy 184.979044 -278.941912) (xy 184.959753 -278.896636) (xy 184.947976 -278.848852)
			(xy 184.944016 -278.799798) (xy 183.654954 -278.799798) (xy 183.654459 -278.824405) (xy 183.646564 -278.872982)
			(xy 183.63098 -278.919663) (xy 183.608109 -278.96324) (xy 183.578544 -279.002584) (xy 183.543051 -279.036676)
			(xy 183.502548 -279.064632) (xy 183.458086 -279.08573) (xy 183.410815 -279.099422) (xy 183.36196 -279.105354)
			(xy 183.312785 -279.103373) (xy 183.264566 -279.093529) (xy 183.21855 -279.076077) (xy 183.175929 -279.05147)
			(xy 183.137808 -279.020345) (xy 183.105173 -278.983508) (xy 183.07887 -278.941912) (xy 183.059579 -278.896636)
			(xy 183.047802 -278.848852) (xy 183.043842 -278.799798) (xy 181.755034 -278.799798) (xy 181.754539 -278.824405)
			(xy 181.746644 -278.872982) (xy 181.73106 -278.919663) (xy 181.708189 -278.96324) (xy 181.678624 -279.002584)
			(xy 181.643131 -279.036676) (xy 181.602628 -279.064632) (xy 181.558166 -279.08573) (xy 181.510895 -279.099422)
			(xy 181.46204 -279.105354) (xy 181.412865 -279.103373) (xy 181.364646 -279.093529) (xy 181.31863 -279.076077)
			(xy 181.276009 -279.05147) (xy 181.237888 -279.020345) (xy 181.205253 -278.983508) (xy 181.17895 -278.941912)
			(xy 181.159659 -278.896636) (xy 181.147882 -278.848852) (xy 181.143922 -278.799798) (xy 179.855114 -278.799798)
			(xy 179.854619 -278.824405) (xy 179.846724 -278.872982) (xy 179.83114 -278.919663) (xy 179.808269 -278.96324)
			(xy 179.778704 -279.002584) (xy 179.743211 -279.036676) (xy 179.702708 -279.064632) (xy 179.658246 -279.08573)
			(xy 179.610975 -279.099422) (xy 179.56212 -279.105354) (xy 179.512945 -279.103373) (xy 179.464726 -279.093529)
			(xy 179.41871 -279.076077) (xy 179.376089 -279.05147) (xy 179.337968 -279.020345) (xy 179.305333 -278.983508)
			(xy 179.27903 -278.941912) (xy 179.259739 -278.896636) (xy 179.247962 -278.848852) (xy 179.244002 -278.799798)
			(xy 177.95494 -278.799798) (xy 177.954445 -278.824405) (xy 177.94655 -278.872982) (xy 177.930966 -278.919663)
			(xy 177.908095 -278.96324) (xy 177.87853 -279.002584) (xy 177.843037 -279.036676) (xy 177.802534 -279.064632)
			(xy 177.758072 -279.08573) (xy 177.710801 -279.099422) (xy 177.661946 -279.105354) (xy 177.612771 -279.103373)
			(xy 177.564552 -279.093529) (xy 177.518536 -279.076077) (xy 177.475915 -279.05147) (xy 177.437794 -279.020345)
			(xy 177.405159 -278.983508) (xy 177.378856 -278.941912) (xy 177.359565 -278.896636) (xy 177.347788 -278.848852)
			(xy 177.343828 -278.799798) (xy 176.05502 -278.799798) (xy 176.054525 -278.824405) (xy 176.04663 -278.872982)
			(xy 176.031046 -278.919663) (xy 176.008175 -278.96324) (xy 175.97861 -279.002584) (xy 175.943117 -279.036676)
			(xy 175.902614 -279.064632) (xy 175.858152 -279.08573) (xy 175.810881 -279.099422) (xy 175.762026 -279.105354)
			(xy 175.712851 -279.103373) (xy 175.664632 -279.093529) (xy 175.618616 -279.076077) (xy 175.575995 -279.05147)
			(xy 175.537874 -279.020345) (xy 175.505239 -278.983508) (xy 175.478936 -278.941912) (xy 175.459645 -278.896636)
			(xy 175.447868 -278.848852) (xy 175.443908 -278.799798) (xy 174.155354 -278.799798) (xy 174.154859 -278.824405)
			(xy 174.146964 -278.872982) (xy 174.13138 -278.919663) (xy 174.108509 -278.96324) (xy 174.078944 -279.002584)
			(xy 174.043451 -279.036676) (xy 174.002948 -279.064632) (xy 173.958486 -279.08573) (xy 173.911215 -279.099422)
			(xy 173.86236 -279.105354) (xy 173.813185 -279.103373) (xy 173.764966 -279.093529) (xy 173.71895 -279.076077)
			(xy 173.676329 -279.05147) (xy 173.638208 -279.020345) (xy 173.605573 -278.983508) (xy 173.57927 -278.941912)
			(xy 173.559979 -278.896636) (xy 173.548202 -278.848852) (xy 173.544242 -278.799798) (xy 172.25518 -278.799798)
			(xy 172.254685 -278.824405) (xy 172.24679 -278.872982) (xy 172.231206 -278.919663) (xy 172.208335 -278.96324)
			(xy 172.17877 -279.002584) (xy 172.143277 -279.036676) (xy 172.102774 -279.064632) (xy 172.058312 -279.08573)
			(xy 172.011041 -279.099422) (xy 171.962186 -279.105354) (xy 171.913011 -279.103373) (xy 171.864792 -279.093529)
			(xy 171.818776 -279.076077) (xy 171.776155 -279.05147) (xy 171.738034 -279.020345) (xy 171.705399 -278.983508)
			(xy 171.679096 -278.941912) (xy 171.659805 -278.896636) (xy 171.648028 -278.848852) (xy 171.644068 -278.799798)
			(xy 170.35526 -278.799798) (xy 170.354765 -278.824405) (xy 170.34687 -278.872982) (xy 170.331286 -278.919663)
			(xy 170.308415 -278.96324) (xy 170.27885 -279.002584) (xy 170.243357 -279.036676) (xy 170.202854 -279.064632)
			(xy 170.158392 -279.08573) (xy 170.111121 -279.099422) (xy 170.062266 -279.105354) (xy 170.013091 -279.103373)
			(xy 169.964872 -279.093529) (xy 169.918856 -279.076077) (xy 169.876235 -279.05147) (xy 169.838114 -279.020345)
			(xy 169.805479 -278.983508) (xy 169.779176 -278.941912) (xy 169.759885 -278.896636) (xy 169.748108 -278.848852)
			(xy 169.744148 -278.799798) (xy 168.45534 -278.799798) (xy 168.454845 -278.824405) (xy 168.44695 -278.872982)
			(xy 168.431366 -278.919663) (xy 168.408495 -278.96324) (xy 168.37893 -279.002584) (xy 168.343437 -279.036676)
			(xy 168.302934 -279.064632) (xy 168.258472 -279.08573) (xy 168.211201 -279.099422) (xy 168.162346 -279.105354)
			(xy 168.113171 -279.103373) (xy 168.064952 -279.093529) (xy 168.018936 -279.076077) (xy 167.976315 -279.05147)
			(xy 167.938194 -279.020345) (xy 167.905559 -278.983508) (xy 167.879256 -278.941912) (xy 167.859965 -278.896636)
			(xy 167.848188 -278.848852) (xy 167.844228 -278.799798) (xy 166.555166 -278.799798) (xy 166.554671 -278.824405)
			(xy 166.546776 -278.872982) (xy 166.531192 -278.919663) (xy 166.508321 -278.96324) (xy 166.478756 -279.002584)
			(xy 166.443263 -279.036676) (xy 166.40276 -279.064632) (xy 166.358298 -279.08573) (xy 166.311027 -279.099422)
			(xy 166.262172 -279.105354) (xy 166.212997 -279.103373) (xy 166.164778 -279.093529) (xy 166.118762 -279.076077)
			(xy 166.076141 -279.05147) (xy 166.03802 -279.020345) (xy 166.005385 -278.983508) (xy 165.979082 -278.941912)
			(xy 165.959791 -278.896636) (xy 165.948014 -278.848852) (xy 165.944054 -278.799798) (xy 164.655246 -278.799798)
			(xy 164.654751 -278.824405) (xy 164.646856 -278.872982) (xy 164.631272 -278.919663) (xy 164.608401 -278.96324)
			(xy 164.578836 -279.002584) (xy 164.543343 -279.036676) (xy 164.50284 -279.064632) (xy 164.458378 -279.08573)
			(xy 164.411107 -279.099422) (xy 164.362252 -279.105354) (xy 164.313077 -279.103373) (xy 164.264858 -279.093529)
			(xy 164.218842 -279.076077) (xy 164.176221 -279.05147) (xy 164.1381 -279.020345) (xy 164.105465 -278.983508)
			(xy 164.079162 -278.941912) (xy 164.059871 -278.896636) (xy 164.048094 -278.848852) (xy 164.044134 -278.799798)
			(xy 162.755326 -278.799798) (xy 162.754831 -278.824405) (xy 162.746936 -278.872982) (xy 162.731352 -278.919663)
			(xy 162.708481 -278.96324) (xy 162.678916 -279.002584) (xy 162.643423 -279.036676) (xy 162.60292 -279.064632)
			(xy 162.558458 -279.08573) (xy 162.511187 -279.099422) (xy 162.462332 -279.105354) (xy 162.413157 -279.103373)
			(xy 162.364938 -279.093529) (xy 162.318922 -279.076077) (xy 162.276301 -279.05147) (xy 162.23818 -279.020345)
			(xy 162.205545 -278.983508) (xy 162.179242 -278.941912) (xy 162.159951 -278.896636) (xy 162.148174 -278.848852)
			(xy 162.144214 -278.799798) (xy 160.855152 -278.799798) (xy 160.854657 -278.824405) (xy 160.846762 -278.872982)
			(xy 160.831178 -278.919663) (xy 160.808307 -278.96324) (xy 160.778742 -279.002584) (xy 160.743249 -279.036676)
			(xy 160.702746 -279.064632) (xy 160.658284 -279.08573) (xy 160.611013 -279.099422) (xy 160.562158 -279.105354)
			(xy 160.512983 -279.103373) (xy 160.464764 -279.093529) (xy 160.418748 -279.076077) (xy 160.376127 -279.05147)
			(xy 160.338006 -279.020345) (xy 160.305371 -278.983508) (xy 160.279068 -278.941912) (xy 160.259777 -278.896636)
			(xy 160.248 -278.848852) (xy 160.24404 -278.799798) (xy 80.855058 -278.799798) (xy 80.854563 -278.824405)
			(xy 80.846668 -278.872982) (xy 80.831084 -278.919663) (xy 80.808213 -278.96324) (xy 80.778648 -279.002584)
			(xy 80.743155 -279.036676) (xy 80.702652 -279.064632) (xy 80.65819 -279.08573) (xy 80.610919 -279.099422)
			(xy 80.562064 -279.105354) (xy 80.512889 -279.103373) (xy 80.46467 -279.093529) (xy 80.418654 -279.076077)
			(xy 80.376033 -279.05147) (xy 80.337912 -279.020345) (xy 80.305277 -278.983508) (xy 80.278974 -278.941912)
			(xy 80.259683 -278.896636) (xy 80.247906 -278.848852) (xy 80.243946 -278.799798) (xy 78.954884 -278.799798)
			(xy 78.954389 -278.824405) (xy 78.946494 -278.872982) (xy 78.93091 -278.919663) (xy 78.908039 -278.96324)
			(xy 78.878474 -279.002584) (xy 78.842981 -279.036676) (xy 78.802478 -279.064632) (xy 78.758016 -279.08573)
			(xy 78.710745 -279.099422) (xy 78.66189 -279.105354) (xy 78.612715 -279.103373) (xy 78.564496 -279.093529)
			(xy 78.51848 -279.076077) (xy 78.475859 -279.05147) (xy 78.437738 -279.020345) (xy 78.405103 -278.983508)
			(xy 78.3788 -278.941912) (xy 78.359509 -278.896636) (xy 78.347732 -278.848852) (xy 78.343772 -278.799798)
			(xy 77.054964 -278.799798) (xy 77.054469 -278.824405) (xy 77.046574 -278.872982) (xy 77.03099 -278.919663)
			(xy 77.008119 -278.96324) (xy 76.978554 -279.002584) (xy 76.943061 -279.036676) (xy 76.902558 -279.064632)
			(xy 76.858096 -279.08573) (xy 76.810825 -279.099422) (xy 76.76197 -279.105354) (xy 76.712795 -279.103373)
			(xy 76.664576 -279.093529) (xy 76.61856 -279.076077) (xy 76.575939 -279.05147) (xy 76.537818 -279.020345)
			(xy 76.505183 -278.983508) (xy 76.47888 -278.941912) (xy 76.459589 -278.896636) (xy 76.447812 -278.848852)
			(xy 76.443852 -278.799798) (xy 75.155044 -278.799798) (xy 75.154549 -278.824405) (xy 75.146654 -278.872982)
			(xy 75.13107 -278.919663) (xy 75.108199 -278.96324) (xy 75.078634 -279.002584) (xy 75.043141 -279.036676)
			(xy 75.002638 -279.064632) (xy 74.958176 -279.08573) (xy 74.910905 -279.099422) (xy 74.86205 -279.105354)
			(xy 74.812875 -279.103373) (xy 74.764656 -279.093529) (xy 74.71864 -279.076077) (xy 74.676019 -279.05147)
			(xy 74.637898 -279.020345) (xy 74.605263 -278.983508) (xy 74.57896 -278.941912) (xy 74.559669 -278.896636)
			(xy 74.547892 -278.848852) (xy 74.543932 -278.799798) (xy 73.25487 -278.799798) (xy 73.254375 -278.824405)
			(xy 73.24648 -278.872982) (xy 73.230896 -278.919663) (xy 73.208025 -278.96324) (xy 73.17846 -279.002584)
			(xy 73.142967 -279.036676) (xy 73.102464 -279.064632) (xy 73.058002 -279.08573) (xy 73.010731 -279.099422)
			(xy 72.961876 -279.105354) (xy 72.912701 -279.103373) (xy 72.864482 -279.093529) (xy 72.818466 -279.076077)
			(xy 72.775845 -279.05147) (xy 72.737724 -279.020345) (xy 72.705089 -278.983508) (xy 72.678786 -278.941912)
			(xy 72.659495 -278.896636) (xy 72.647718 -278.848852) (xy 72.643758 -278.799798) (xy 71.35495 -278.799798)
			(xy 71.354455 -278.824405) (xy 71.34656 -278.872982) (xy 71.330976 -278.919663) (xy 71.308105 -278.96324)
			(xy 71.27854 -279.002584) (xy 71.243047 -279.036676) (xy 71.202544 -279.064632) (xy 71.158082 -279.08573)
			(xy 71.110811 -279.099422) (xy 71.061956 -279.105354) (xy 71.012781 -279.103373) (xy 70.964562 -279.093529)
			(xy 70.918546 -279.076077) (xy 70.875925 -279.05147) (xy 70.837804 -279.020345) (xy 70.805169 -278.983508)
			(xy 70.778866 -278.941912) (xy 70.759575 -278.896636) (xy 70.747798 -278.848852) (xy 70.743838 -278.799798)
			(xy 69.45503 -278.799798) (xy 69.454535 -278.824405) (xy 69.44664 -278.872982) (xy 69.431056 -278.919663)
			(xy 69.408185 -278.96324) (xy 69.37862 -279.002584) (xy 69.343127 -279.036676) (xy 69.302624 -279.064632)
			(xy 69.258162 -279.08573) (xy 69.210891 -279.099422) (xy 69.162036 -279.105354) (xy 69.112861 -279.103373)
			(xy 69.064642 -279.093529) (xy 69.018626 -279.076077) (xy 68.976005 -279.05147) (xy 68.937884 -279.020345)
			(xy 68.905249 -278.983508) (xy 68.878946 -278.941912) (xy 68.859655 -278.896636) (xy 68.847878 -278.848852)
			(xy 68.843918 -278.799798) (xy 67.554856 -278.799798) (xy 67.554361 -278.824405) (xy 67.546466 -278.872982)
			(xy 67.530882 -278.919663) (xy 67.508011 -278.96324) (xy 67.478446 -279.002584) (xy 67.442953 -279.036676)
			(xy 67.40245 -279.064632) (xy 67.357988 -279.08573) (xy 67.310717 -279.099422) (xy 67.261862 -279.105354)
			(xy 67.212687 -279.103373) (xy 67.164468 -279.093529) (xy 67.118452 -279.076077) (xy 67.075831 -279.05147)
			(xy 67.03771 -279.020345) (xy 67.005075 -278.983508) (xy 66.978772 -278.941912) (xy 66.959481 -278.896636)
			(xy 66.947704 -278.848852) (xy 66.943744 -278.799798) (xy 65.654936 -278.799798) (xy 65.654441 -278.824405)
			(xy 65.646546 -278.872982) (xy 65.630962 -278.919663) (xy 65.608091 -278.96324) (xy 65.578526 -279.002584)
			(xy 65.543033 -279.036676) (xy 65.50253 -279.064632) (xy 65.458068 -279.08573) (xy 65.410797 -279.099422)
			(xy 65.361942 -279.105354) (xy 65.312767 -279.103373) (xy 65.264548 -279.093529) (xy 65.218532 -279.076077)
			(xy 65.175911 -279.05147) (xy 65.13779 -279.020345) (xy 65.105155 -278.983508) (xy 65.078852 -278.941912)
			(xy 65.059561 -278.896636) (xy 65.047784 -278.848852) (xy 65.043824 -278.799798) (xy 63.755016 -278.799798)
			(xy 63.754521 -278.824405) (xy 63.746626 -278.872982) (xy 63.731042 -278.919663) (xy 63.708171 -278.96324)
			(xy 63.678606 -279.002584) (xy 63.643113 -279.036676) (xy 63.60261 -279.064632) (xy 63.558148 -279.08573)
			(xy 63.510877 -279.099422) (xy 63.462022 -279.105354) (xy 63.412847 -279.103373) (xy 63.364628 -279.093529)
			(xy 63.318612 -279.076077) (xy 63.275991 -279.05147) (xy 63.23787 -279.020345) (xy 63.205235 -278.983508)
			(xy 63.178932 -278.941912) (xy 63.159641 -278.896636) (xy 63.147864 -278.848852) (xy 63.143904 -278.799798)
			(xy 61.854842 -278.799798) (xy 61.854347 -278.824405) (xy 61.846452 -278.872982) (xy 61.830868 -278.919663)
			(xy 61.807997 -278.96324) (xy 61.778432 -279.002584) (xy 61.742939 -279.036676) (xy 61.702436 -279.064632)
			(xy 61.657974 -279.08573) (xy 61.610703 -279.099422) (xy 61.561848 -279.105354) (xy 61.512673 -279.103373)
			(xy 61.464454 -279.093529) (xy 61.418438 -279.076077) (xy 61.375817 -279.05147) (xy 61.337696 -279.020345)
			(xy 61.305061 -278.983508) (xy 61.278758 -278.941912) (xy 61.259467 -278.896636) (xy 61.24769 -278.848852)
			(xy 61.24373 -278.799798) (xy 59.954922 -278.799798) (xy 59.954427 -278.824405) (xy 59.946532 -278.872982)
			(xy 59.930948 -278.919663) (xy 59.908077 -278.96324) (xy 59.878512 -279.002584) (xy 59.843019 -279.036676)
			(xy 59.802516 -279.064632) (xy 59.758054 -279.08573) (xy 59.710783 -279.099422) (xy 59.661928 -279.105354)
			(xy 59.612753 -279.103373) (xy 59.564534 -279.093529) (xy 59.518518 -279.076077) (xy 59.475897 -279.05147)
			(xy 59.437776 -279.020345) (xy 59.405141 -278.983508) (xy 59.378838 -278.941912) (xy 59.359547 -278.896636)
			(xy 59.34777 -278.848852) (xy 59.34381 -278.799798) (xy 58.055256 -278.799798) (xy 58.054761 -278.824405)
			(xy 58.046866 -278.872982) (xy 58.031282 -278.919663) (xy 58.008411 -278.96324) (xy 57.978846 -279.002584)
			(xy 57.943353 -279.036676) (xy 57.90285 -279.064632) (xy 57.858388 -279.08573) (xy 57.811117 -279.099422)
			(xy 57.762262 -279.105354) (xy 57.713087 -279.103373) (xy 57.664868 -279.093529) (xy 57.618852 -279.076077)
			(xy 57.576231 -279.05147) (xy 57.53811 -279.020345) (xy 57.505475 -278.983508) (xy 57.479172 -278.941912)
			(xy 57.459881 -278.896636) (xy 57.448104 -278.848852) (xy 57.444144 -278.799798) (xy 56.155082 -278.799798)
			(xy 56.154587 -278.824405) (xy 56.146692 -278.872982) (xy 56.131108 -278.919663) (xy 56.108237 -278.96324)
			(xy 56.078672 -279.002584) (xy 56.043179 -279.036676) (xy 56.002676 -279.064632) (xy 55.958214 -279.08573)
			(xy 55.910943 -279.099422) (xy 55.862088 -279.105354) (xy 55.812913 -279.103373) (xy 55.764694 -279.093529)
			(xy 55.718678 -279.076077) (xy 55.676057 -279.05147) (xy 55.637936 -279.020345) (xy 55.605301 -278.983508)
			(xy 55.578998 -278.941912) (xy 55.559707 -278.896636) (xy 55.54793 -278.848852) (xy 55.54397 -278.799798)
			(xy 54.255162 -278.799798) (xy 54.254667 -278.824405) (xy 54.246772 -278.872982) (xy 54.231188 -278.919663)
			(xy 54.208317 -278.96324) (xy 54.178752 -279.002584) (xy 54.143259 -279.036676) (xy 54.102756 -279.064632)
			(xy 54.058294 -279.08573) (xy 54.011023 -279.099422) (xy 53.962168 -279.105354) (xy 53.912993 -279.103373)
			(xy 53.864774 -279.093529) (xy 53.818758 -279.076077) (xy 53.776137 -279.05147) (xy 53.738016 -279.020345)
			(xy 53.705381 -278.983508) (xy 53.679078 -278.941912) (xy 53.659787 -278.896636) (xy 53.64801 -278.848852)
			(xy 53.64405 -278.799798) (xy 52.355242 -278.799798) (xy 52.354747 -278.824405) (xy 52.346852 -278.872982)
			(xy 52.331268 -278.919663) (xy 52.308397 -278.96324) (xy 52.278832 -279.002584) (xy 52.243339 -279.036676)
			(xy 52.202836 -279.064632) (xy 52.158374 -279.08573) (xy 52.111103 -279.099422) (xy 52.062248 -279.105354)
			(xy 52.013073 -279.103373) (xy 51.964854 -279.093529) (xy 51.918838 -279.076077) (xy 51.876217 -279.05147)
			(xy 51.838096 -279.020345) (xy 51.805461 -278.983508) (xy 51.779158 -278.941912) (xy 51.759867 -278.896636)
			(xy 51.74809 -278.848852) (xy 51.74413 -278.799798) (xy 50.455068 -278.799798) (xy 50.454573 -278.824405)
			(xy 50.446678 -278.872982) (xy 50.431094 -278.919663) (xy 50.408223 -278.96324) (xy 50.378658 -279.002584)
			(xy 50.343165 -279.036676) (xy 50.302662 -279.064632) (xy 50.2582 -279.08573) (xy 50.210929 -279.099422)
			(xy 50.162074 -279.105354) (xy 50.112899 -279.103373) (xy 50.06468 -279.093529) (xy 50.018664 -279.076077)
			(xy 49.976043 -279.05147) (xy 49.937922 -279.020345) (xy 49.905287 -278.983508) (xy 49.878984 -278.941912)
			(xy 49.859693 -278.896636) (xy 49.847916 -278.848852) (xy 49.843956 -278.799798) (xy 48.555148 -278.799798)
			(xy 48.554653 -278.824405) (xy 48.546758 -278.872982) (xy 48.531174 -278.919663) (xy 48.508303 -278.96324)
			(xy 48.478738 -279.002584) (xy 48.443245 -279.036676) (xy 48.402742 -279.064632) (xy 48.35828 -279.08573)
			(xy 48.311009 -279.099422) (xy 48.262154 -279.105354) (xy 48.212979 -279.103373) (xy 48.16476 -279.093529)
			(xy 48.118744 -279.076077) (xy 48.076123 -279.05147) (xy 48.038002 -279.020345) (xy 48.005367 -278.983508)
			(xy 47.979064 -278.941912) (xy 47.959773 -278.896636) (xy 47.947996 -278.848852) (xy 47.944036 -278.799798)
			(xy 46.655228 -278.799798) (xy 46.654733 -278.824405) (xy 46.646838 -278.872982) (xy 46.631254 -278.919663)
			(xy 46.608383 -278.96324) (xy 46.578818 -279.002584) (xy 46.543325 -279.036676) (xy 46.502822 -279.064632)
			(xy 46.45836 -279.08573) (xy 46.411089 -279.099422) (xy 46.362234 -279.105354) (xy 46.313059 -279.103373)
			(xy 46.26484 -279.093529) (xy 46.218824 -279.076077) (xy 46.176203 -279.05147) (xy 46.138082 -279.020345)
			(xy 46.105447 -278.983508) (xy 46.079144 -278.941912) (xy 46.059853 -278.896636) (xy 46.048076 -278.848852)
			(xy 46.044116 -278.799798) (xy 44.755054 -278.799798) (xy 44.754559 -278.824405) (xy 44.746664 -278.872982)
			(xy 44.73108 -278.919663) (xy 44.708209 -278.96324) (xy 44.678644 -279.002584) (xy 44.643151 -279.036676)
			(xy 44.602648 -279.064632) (xy 44.558186 -279.08573) (xy 44.510915 -279.099422) (xy 44.46206 -279.105354)
			(xy 44.412885 -279.103373) (xy 44.364666 -279.093529) (xy 44.31865 -279.076077) (xy 44.276029 -279.05147)
			(xy 44.237908 -279.020345) (xy 44.205273 -278.983508) (xy 44.17897 -278.941912) (xy 44.159679 -278.896636)
			(xy 44.147902 -278.848852) (xy 44.143942 -278.799798) (xy 0.509016 -278.799798) (xy 0.509016 -279.749504)
			(xy 45.094156 -279.749504) (xy 45.098116 -279.70045) (xy 45.109893 -279.652666) (xy 45.129184 -279.60739)
			(xy 45.155487 -279.565794) (xy 45.188122 -279.528957) (xy 45.226243 -279.497832) (xy 45.268864 -279.473225)
			(xy 45.31488 -279.455773) (xy 45.363099 -279.445929) (xy 45.412274 -279.443948) (xy 45.461129 -279.44988)
			(xy 45.5084 -279.463572) (xy 45.552862 -279.48467) (xy 45.593365 -279.512626) (xy 45.628858 -279.546718)
			(xy 45.658423 -279.586062) (xy 45.681294 -279.629639) (xy 45.696878 -279.67632) (xy 45.704773 -279.724897)
			(xy 45.705268 -279.749504) (xy 46.994076 -279.749504) (xy 46.998036 -279.70045) (xy 47.009813 -279.652666)
			(xy 47.029104 -279.60739) (xy 47.055407 -279.565794) (xy 47.088042 -279.528957) (xy 47.126163 -279.497832)
			(xy 47.168784 -279.473225) (xy 47.2148 -279.455773) (xy 47.263019 -279.445929) (xy 47.312194 -279.443948)
			(xy 47.361049 -279.44988) (xy 47.40832 -279.463572) (xy 47.452782 -279.48467) (xy 47.493285 -279.512626)
			(xy 47.528778 -279.546718) (xy 47.558343 -279.586062) (xy 47.581214 -279.629639) (xy 47.596798 -279.67632)
			(xy 47.604693 -279.724897) (xy 47.605188 -279.749504) (xy 48.893996 -279.749504) (xy 48.897956 -279.70045)
			(xy 48.909733 -279.652666) (xy 48.929024 -279.60739) (xy 48.955327 -279.565794) (xy 48.987962 -279.528957)
			(xy 49.026083 -279.497832) (xy 49.068704 -279.473225) (xy 49.11472 -279.455773) (xy 49.162939 -279.445929)
			(xy 49.212114 -279.443948) (xy 49.260969 -279.44988) (xy 49.30824 -279.463572) (xy 49.352702 -279.48467)
			(xy 49.393205 -279.512626) (xy 49.428698 -279.546718) (xy 49.458263 -279.586062) (xy 49.481134 -279.629639)
			(xy 49.496718 -279.67632) (xy 49.504613 -279.724897) (xy 49.505108 -279.749504) (xy 50.79417 -279.749504)
			(xy 50.79813 -279.70045) (xy 50.809907 -279.652666) (xy 50.829198 -279.60739) (xy 50.855501 -279.565794)
			(xy 50.888136 -279.528957) (xy 50.926257 -279.497832) (xy 50.968878 -279.473225) (xy 51.014894 -279.455773)
			(xy 51.063113 -279.445929) (xy 51.112288 -279.443948) (xy 51.161143 -279.44988) (xy 51.208414 -279.463572)
			(xy 51.252876 -279.48467) (xy 51.293379 -279.512626) (xy 51.328872 -279.546718) (xy 51.358437 -279.586062)
			(xy 51.381308 -279.629639) (xy 51.396892 -279.67632) (xy 51.404787 -279.724897) (xy 51.405282 -279.749504)
			(xy 52.69409 -279.749504) (xy 52.69805 -279.70045) (xy 52.709827 -279.652666) (xy 52.729118 -279.60739)
			(xy 52.755421 -279.565794) (xy 52.788056 -279.528957) (xy 52.826177 -279.497832) (xy 52.868798 -279.473225)
			(xy 52.914814 -279.455773) (xy 52.963033 -279.445929) (xy 53.012208 -279.443948) (xy 53.061063 -279.44988)
			(xy 53.108334 -279.463572) (xy 53.152796 -279.48467) (xy 53.193299 -279.512626) (xy 53.228792 -279.546718)
			(xy 53.258357 -279.586062) (xy 53.281228 -279.629639) (xy 53.296812 -279.67632) (xy 53.304707 -279.724897)
			(xy 53.305202 -279.749504) (xy 54.59401 -279.749504) (xy 54.59797 -279.70045) (xy 54.609747 -279.652666)
			(xy 54.629038 -279.60739) (xy 54.655341 -279.565794) (xy 54.687976 -279.528957) (xy 54.726097 -279.497832)
			(xy 54.768718 -279.473225) (xy 54.814734 -279.455773) (xy 54.862953 -279.445929) (xy 54.912128 -279.443948)
			(xy 54.960983 -279.44988) (xy 55.008254 -279.463572) (xy 55.052716 -279.48467) (xy 55.093219 -279.512626)
			(xy 55.128712 -279.546718) (xy 55.158277 -279.586062) (xy 55.181148 -279.629639) (xy 55.196732 -279.67632)
			(xy 55.204627 -279.724897) (xy 55.205122 -279.749504) (xy 56.49393 -279.749504) (xy 56.49789 -279.70045)
			(xy 56.509667 -279.652666) (xy 56.528958 -279.60739) (xy 56.555261 -279.565794) (xy 56.587896 -279.528957)
			(xy 56.626017 -279.497832) (xy 56.668638 -279.473225) (xy 56.714654 -279.455773) (xy 56.762873 -279.445929)
			(xy 56.812048 -279.443948) (xy 56.860903 -279.44988) (xy 56.908174 -279.463572) (xy 56.952636 -279.48467)
			(xy 56.993139 -279.512626) (xy 57.028632 -279.546718) (xy 57.058197 -279.586062) (xy 57.081068 -279.629639)
			(xy 57.096652 -279.67632) (xy 57.104547 -279.724897) (xy 57.105042 -279.749504) (xy 58.394104 -279.749504)
			(xy 58.398064 -279.70045) (xy 58.409841 -279.652666) (xy 58.429132 -279.60739) (xy 58.455435 -279.565794)
			(xy 58.48807 -279.528957) (xy 58.526191 -279.497832) (xy 58.568812 -279.473225) (xy 58.614828 -279.455773)
			(xy 58.663047 -279.445929) (xy 58.712222 -279.443948) (xy 58.761077 -279.44988) (xy 58.808348 -279.463572)
			(xy 58.85281 -279.48467) (xy 58.893313 -279.512626) (xy 58.928806 -279.546718) (xy 58.958371 -279.586062)
			(xy 58.981242 -279.629639) (xy 58.996826 -279.67632) (xy 59.004721 -279.724897) (xy 59.005216 -279.749504)
			(xy 60.294024 -279.749504) (xy 60.297984 -279.70045) (xy 60.309761 -279.652666) (xy 60.329052 -279.60739)
			(xy 60.355355 -279.565794) (xy 60.38799 -279.528957) (xy 60.426111 -279.497832) (xy 60.468732 -279.473225)
			(xy 60.514748 -279.455773) (xy 60.562967 -279.445929) (xy 60.612142 -279.443948) (xy 60.660997 -279.44988)
			(xy 60.708268 -279.463572) (xy 60.75273 -279.48467) (xy 60.793233 -279.512626) (xy 60.828726 -279.546718)
			(xy 60.858291 -279.586062) (xy 60.881162 -279.629639) (xy 60.896746 -279.67632) (xy 60.904641 -279.724897)
			(xy 60.905136 -279.749504) (xy 62.193944 -279.749504) (xy 62.197904 -279.70045) (xy 62.209681 -279.652666)
			(xy 62.228972 -279.60739) (xy 62.255275 -279.565794) (xy 62.28791 -279.528957) (xy 62.326031 -279.497832)
			(xy 62.368652 -279.473225) (xy 62.414668 -279.455773) (xy 62.462887 -279.445929) (xy 62.512062 -279.443948)
			(xy 62.560917 -279.44988) (xy 62.608188 -279.463572) (xy 62.65265 -279.48467) (xy 62.693153 -279.512626)
			(xy 62.728646 -279.546718) (xy 62.758211 -279.586062) (xy 62.781082 -279.629639) (xy 62.796666 -279.67632)
			(xy 62.804561 -279.724897) (xy 62.805056 -279.749504) (xy 64.094118 -279.749504) (xy 64.098078 -279.70045)
			(xy 64.109855 -279.652666) (xy 64.129146 -279.60739) (xy 64.155449 -279.565794) (xy 64.188084 -279.528957)
			(xy 64.226205 -279.497832) (xy 64.268826 -279.473225) (xy 64.314842 -279.455773) (xy 64.363061 -279.445929)
			(xy 64.412236 -279.443948) (xy 64.461091 -279.44988) (xy 64.508362 -279.463572) (xy 64.552824 -279.48467)
			(xy 64.593327 -279.512626) (xy 64.62882 -279.546718) (xy 64.658385 -279.586062) (xy 64.681256 -279.629639)
			(xy 64.69684 -279.67632) (xy 64.704735 -279.724897) (xy 64.70523 -279.749504) (xy 65.994038 -279.749504)
			(xy 65.997998 -279.70045) (xy 66.009775 -279.652666) (xy 66.029066 -279.60739) (xy 66.055369 -279.565794)
			(xy 66.088004 -279.528957) (xy 66.126125 -279.497832) (xy 66.168746 -279.473225) (xy 66.214762 -279.455773)
			(xy 66.262981 -279.445929) (xy 66.312156 -279.443948) (xy 66.361011 -279.44988) (xy 66.408282 -279.463572)
			(xy 66.452744 -279.48467) (xy 66.493247 -279.512626) (xy 66.52874 -279.546718) (xy 66.558305 -279.586062)
			(xy 66.581176 -279.629639) (xy 66.59676 -279.67632) (xy 66.604655 -279.724897) (xy 66.60515 -279.749504)
			(xy 67.893958 -279.749504) (xy 67.897918 -279.70045) (xy 67.909695 -279.652666) (xy 67.928986 -279.60739)
			(xy 67.955289 -279.565794) (xy 67.987924 -279.528957) (xy 68.026045 -279.497832) (xy 68.068666 -279.473225)
			(xy 68.114682 -279.455773) (xy 68.162901 -279.445929) (xy 68.212076 -279.443948) (xy 68.260931 -279.44988)
			(xy 68.308202 -279.463572) (xy 68.352664 -279.48467) (xy 68.393167 -279.512626) (xy 68.42866 -279.546718)
			(xy 68.458225 -279.586062) (xy 68.481096 -279.629639) (xy 68.49668 -279.67632) (xy 68.504575 -279.724897)
			(xy 68.50507 -279.749504) (xy 69.794132 -279.749504) (xy 69.798092 -279.70045) (xy 69.809869 -279.652666)
			(xy 69.82916 -279.60739) (xy 69.855463 -279.565794) (xy 69.888098 -279.528957) (xy 69.926219 -279.497832)
			(xy 69.96884 -279.473225) (xy 70.014856 -279.455773) (xy 70.063075 -279.445929) (xy 70.11225 -279.443948)
			(xy 70.161105 -279.44988) (xy 70.208376 -279.463572) (xy 70.252838 -279.48467) (xy 70.293341 -279.512626)
			(xy 70.328834 -279.546718) (xy 70.358399 -279.586062) (xy 70.38127 -279.629639) (xy 70.396854 -279.67632)
			(xy 70.404749 -279.724897) (xy 70.405244 -279.749504) (xy 71.694052 -279.749504) (xy 71.698012 -279.70045)
			(xy 71.709789 -279.652666) (xy 71.72908 -279.60739) (xy 71.755383 -279.565794) (xy 71.788018 -279.528957)
			(xy 71.826139 -279.497832) (xy 71.86876 -279.473225) (xy 71.914776 -279.455773) (xy 71.962995 -279.445929)
			(xy 72.01217 -279.443948) (xy 72.061025 -279.44988) (xy 72.108296 -279.463572) (xy 72.152758 -279.48467)
			(xy 72.193261 -279.512626) (xy 72.228754 -279.546718) (xy 72.258319 -279.586062) (xy 72.28119 -279.629639)
			(xy 72.296774 -279.67632) (xy 72.304669 -279.724897) (xy 72.305164 -279.749504) (xy 73.593972 -279.749504)
			(xy 73.597932 -279.70045) (xy 73.609709 -279.652666) (xy 73.629 -279.60739) (xy 73.655303 -279.565794)
			(xy 73.687938 -279.528957) (xy 73.726059 -279.497832) (xy 73.76868 -279.473225) (xy 73.814696 -279.455773)
			(xy 73.862915 -279.445929) (xy 73.91209 -279.443948) (xy 73.960945 -279.44988) (xy 74.008216 -279.463572)
			(xy 74.052678 -279.48467) (xy 74.093181 -279.512626) (xy 74.128674 -279.546718) (xy 74.158239 -279.586062)
			(xy 74.18111 -279.629639) (xy 74.196694 -279.67632) (xy 74.204589 -279.724897) (xy 74.205084 -279.749504)
			(xy 75.494146 -279.749504) (xy 75.498106 -279.70045) (xy 75.509883 -279.652666) (xy 75.529174 -279.60739)
			(xy 75.555477 -279.565794) (xy 75.588112 -279.528957) (xy 75.626233 -279.497832) (xy 75.668854 -279.473225)
			(xy 75.71487 -279.455773) (xy 75.763089 -279.445929) (xy 75.812264 -279.443948) (xy 75.861119 -279.44988)
			(xy 75.90839 -279.463572) (xy 75.952852 -279.48467) (xy 75.993355 -279.512626) (xy 76.028848 -279.546718)
			(xy 76.058413 -279.586062) (xy 76.081284 -279.629639) (xy 76.096868 -279.67632) (xy 76.104763 -279.724897)
			(xy 76.105258 -279.749504) (xy 77.394066 -279.749504) (xy 77.398026 -279.70045) (xy 77.409803 -279.652666)
			(xy 77.429094 -279.60739) (xy 77.455397 -279.565794) (xy 77.488032 -279.528957) (xy 77.526153 -279.497832)
			(xy 77.568774 -279.473225) (xy 77.61479 -279.455773) (xy 77.663009 -279.445929) (xy 77.712184 -279.443948)
			(xy 77.761039 -279.44988) (xy 77.80831 -279.463572) (xy 77.852772 -279.48467) (xy 77.893275 -279.512626)
			(xy 77.928768 -279.546718) (xy 77.958333 -279.586062) (xy 77.981204 -279.629639) (xy 77.996788 -279.67632)
			(xy 78.004683 -279.724897) (xy 78.005178 -279.749504) (xy 78.005173 -279.749758) (xy 79.293986 -279.749758)
			(xy 79.297946 -279.700704) (xy 79.309723 -279.65292) (xy 79.329014 -279.607644) (xy 79.355317 -279.566048)
			(xy 79.387952 -279.529211) (xy 79.426073 -279.498086) (xy 79.468694 -279.473479) (xy 79.51471 -279.456027)
			(xy 79.562929 -279.446183) (xy 79.612104 -279.444202) (xy 79.660959 -279.450134) (xy 79.70823 -279.463826)
			(xy 79.752692 -279.484924) (xy 79.793195 -279.51288) (xy 79.828688 -279.546972) (xy 79.858253 -279.586316)
			(xy 79.881124 -279.629893) (xy 79.896708 -279.676574) (xy 79.904603 -279.725151) (xy 79.905098 -279.749758)
			(xy 81.19416 -279.749758) (xy 81.19812 -279.700704) (xy 81.209897 -279.65292) (xy 81.229188 -279.607644)
			(xy 81.255491 -279.566048) (xy 81.288126 -279.529211) (xy 81.326247 -279.498086) (xy 81.368868 -279.473479)
			(xy 81.414884 -279.456027) (xy 81.463103 -279.446183) (xy 81.512278 -279.444202) (xy 81.561133 -279.450134)
			(xy 81.608404 -279.463826) (xy 81.652866 -279.484924) (xy 81.693369 -279.51288) (xy 81.728862 -279.546972)
			(xy 81.758427 -279.586316) (xy 81.781298 -279.629893) (xy 81.796882 -279.676574) (xy 81.804777 -279.725151)
			(xy 81.805272 -279.749758) (xy 82.14412 -279.749758) (xy 82.14808 -279.700704) (xy 82.159857 -279.65292)
			(xy 82.179148 -279.607644) (xy 82.205451 -279.566048) (xy 82.238086 -279.529211) (xy 82.276207 -279.498086)
			(xy 82.318828 -279.473479) (xy 82.364844 -279.456027) (xy 82.413063 -279.446183) (xy 82.462238 -279.444202)
			(xy 82.511093 -279.450134) (xy 82.558364 -279.463826) (xy 82.602826 -279.484924) (xy 82.643329 -279.51288)
			(xy 82.678822 -279.546972) (xy 82.708387 -279.586316) (xy 82.731258 -279.629893) (xy 82.746842 -279.676574)
			(xy 82.754737 -279.725151) (xy 82.755227 -279.749504) (xy 161.194254 -279.749504) (xy 161.198214 -279.70045)
			(xy 161.209991 -279.652666) (xy 161.229282 -279.60739) (xy 161.255585 -279.565794) (xy 161.28822 -279.528957)
			(xy 161.326341 -279.497832) (xy 161.368962 -279.473225) (xy 161.414978 -279.455773) (xy 161.463197 -279.445929)
			(xy 161.512372 -279.443948) (xy 161.561227 -279.44988) (xy 161.608498 -279.463572) (xy 161.65296 -279.48467)
			(xy 161.693463 -279.512626) (xy 161.728956 -279.546718) (xy 161.758521 -279.586062) (xy 161.781392 -279.629639)
			(xy 161.796976 -279.67632) (xy 161.804871 -279.724897) (xy 161.805366 -279.749504) (xy 163.094174 -279.749504)
			(xy 163.098134 -279.70045) (xy 163.109911 -279.652666) (xy 163.129202 -279.60739) (xy 163.155505 -279.565794)
			(xy 163.18814 -279.528957) (xy 163.226261 -279.497832) (xy 163.268882 -279.473225) (xy 163.314898 -279.455773)
			(xy 163.363117 -279.445929) (xy 163.412292 -279.443948) (xy 163.461147 -279.44988) (xy 163.508418 -279.463572)
			(xy 163.55288 -279.48467) (xy 163.593383 -279.512626) (xy 163.628876 -279.546718) (xy 163.658441 -279.586062)
			(xy 163.681312 -279.629639) (xy 163.696896 -279.67632) (xy 163.704791 -279.724897) (xy 163.705286 -279.749504)
			(xy 164.994094 -279.749504) (xy 164.998054 -279.70045) (xy 165.009831 -279.652666) (xy 165.029122 -279.60739)
			(xy 165.055425 -279.565794) (xy 165.08806 -279.528957) (xy 165.126181 -279.497832) (xy 165.168802 -279.473225)
			(xy 165.214818 -279.455773) (xy 165.263037 -279.445929) (xy 165.312212 -279.443948) (xy 165.361067 -279.44988)
			(xy 165.408338 -279.463572) (xy 165.4528 -279.48467) (xy 165.493303 -279.512626) (xy 165.528796 -279.546718)
			(xy 165.558361 -279.586062) (xy 165.581232 -279.629639) (xy 165.596816 -279.67632) (xy 165.604711 -279.724897)
			(xy 165.605206 -279.749504) (xy 166.894268 -279.749504) (xy 166.898228 -279.70045) (xy 166.910005 -279.652666)
			(xy 166.929296 -279.60739) (xy 166.955599 -279.565794) (xy 166.988234 -279.528957) (xy 167.026355 -279.497832)
			(xy 167.068976 -279.473225) (xy 167.114992 -279.455773) (xy 167.163211 -279.445929) (xy 167.212386 -279.443948)
			(xy 167.261241 -279.44988) (xy 167.308512 -279.463572) (xy 167.352974 -279.48467) (xy 167.393477 -279.512626)
			(xy 167.42897 -279.546718) (xy 167.458535 -279.586062) (xy 167.481406 -279.629639) (xy 167.49699 -279.67632)
			(xy 167.504885 -279.724897) (xy 167.50538 -279.749504) (xy 168.794188 -279.749504) (xy 168.798148 -279.70045)
			(xy 168.809925 -279.652666) (xy 168.829216 -279.60739) (xy 168.855519 -279.565794) (xy 168.888154 -279.528957)
			(xy 168.926275 -279.497832) (xy 168.968896 -279.473225) (xy 169.014912 -279.455773) (xy 169.063131 -279.445929)
			(xy 169.112306 -279.443948) (xy 169.161161 -279.44988) (xy 169.208432 -279.463572) (xy 169.252894 -279.48467)
			(xy 169.293397 -279.512626) (xy 169.32889 -279.546718) (xy 169.358455 -279.586062) (xy 169.381326 -279.629639)
			(xy 169.39691 -279.67632) (xy 169.404805 -279.724897) (xy 169.4053 -279.749504) (xy 170.694108 -279.749504)
			(xy 170.698068 -279.70045) (xy 170.709845 -279.652666) (xy 170.729136 -279.60739) (xy 170.755439 -279.565794)
			(xy 170.788074 -279.528957) (xy 170.826195 -279.497832) (xy 170.868816 -279.473225) (xy 170.914832 -279.455773)
			(xy 170.963051 -279.445929) (xy 171.012226 -279.443948) (xy 171.061081 -279.44988) (xy 171.108352 -279.463572)
			(xy 171.152814 -279.48467) (xy 171.193317 -279.512626) (xy 171.22881 -279.546718) (xy 171.258375 -279.586062)
			(xy 171.281246 -279.629639) (xy 171.29683 -279.67632) (xy 171.304725 -279.724897) (xy 171.30522 -279.749504)
			(xy 172.594028 -279.749504) (xy 172.597988 -279.70045) (xy 172.609765 -279.652666) (xy 172.629056 -279.60739)
			(xy 172.655359 -279.565794) (xy 172.687994 -279.528957) (xy 172.726115 -279.497832) (xy 172.768736 -279.473225)
			(xy 172.814752 -279.455773) (xy 172.862971 -279.445929) (xy 172.912146 -279.443948) (xy 172.961001 -279.44988)
			(xy 173.008272 -279.463572) (xy 173.052734 -279.48467) (xy 173.093237 -279.512626) (xy 173.12873 -279.546718)
			(xy 173.158295 -279.586062) (xy 173.181166 -279.629639) (xy 173.19675 -279.67632) (xy 173.204645 -279.724897)
			(xy 173.20514 -279.749504) (xy 174.494202 -279.749504) (xy 174.498162 -279.70045) (xy 174.509939 -279.652666)
			(xy 174.52923 -279.60739) (xy 174.555533 -279.565794) (xy 174.588168 -279.528957) (xy 174.626289 -279.497832)
			(xy 174.66891 -279.473225) (xy 174.714926 -279.455773) (xy 174.763145 -279.445929) (xy 174.81232 -279.443948)
			(xy 174.861175 -279.44988) (xy 174.908446 -279.463572) (xy 174.952908 -279.48467) (xy 174.993411 -279.512626)
			(xy 175.028904 -279.546718) (xy 175.058469 -279.586062) (xy 175.08134 -279.629639) (xy 175.096924 -279.67632)
			(xy 175.104819 -279.724897) (xy 175.105314 -279.749504) (xy 176.394122 -279.749504) (xy 176.398082 -279.70045)
			(xy 176.409859 -279.652666) (xy 176.42915 -279.60739) (xy 176.455453 -279.565794) (xy 176.488088 -279.528957)
			(xy 176.526209 -279.497832) (xy 176.56883 -279.473225) (xy 176.614846 -279.455773) (xy 176.663065 -279.445929)
			(xy 176.71224 -279.443948) (xy 176.761095 -279.44988) (xy 176.808366 -279.463572) (xy 176.852828 -279.48467)
			(xy 176.893331 -279.512626) (xy 176.928824 -279.546718) (xy 176.958389 -279.586062) (xy 176.98126 -279.629639)
			(xy 176.996844 -279.67632) (xy 177.004739 -279.724897) (xy 177.005234 -279.749504) (xy 178.294042 -279.749504)
			(xy 178.298002 -279.70045) (xy 178.309779 -279.652666) (xy 178.32907 -279.60739) (xy 178.355373 -279.565794)
			(xy 178.388008 -279.528957) (xy 178.426129 -279.497832) (xy 178.46875 -279.473225) (xy 178.514766 -279.455773)
			(xy 178.562985 -279.445929) (xy 178.61216 -279.443948) (xy 178.661015 -279.44988) (xy 178.708286 -279.463572)
			(xy 178.752748 -279.48467) (xy 178.793251 -279.512626) (xy 178.828744 -279.546718) (xy 178.858309 -279.586062)
			(xy 178.88118 -279.629639) (xy 178.896764 -279.67632) (xy 178.904659 -279.724897) (xy 178.905154 -279.749504)
			(xy 180.194216 -279.749504) (xy 180.198176 -279.70045) (xy 180.209953 -279.652666) (xy 180.229244 -279.60739)
			(xy 180.255547 -279.565794) (xy 180.288182 -279.528957) (xy 180.326303 -279.497832) (xy 180.368924 -279.473225)
			(xy 180.41494 -279.455773) (xy 180.463159 -279.445929) (xy 180.512334 -279.443948) (xy 180.561189 -279.44988)
			(xy 180.60846 -279.463572) (xy 180.652922 -279.48467) (xy 180.693425 -279.512626) (xy 180.728918 -279.546718)
			(xy 180.758483 -279.586062) (xy 180.781354 -279.629639) (xy 180.796938 -279.67632) (xy 180.804833 -279.724897)
			(xy 180.805328 -279.749504) (xy 182.094136 -279.749504) (xy 182.098096 -279.70045) (xy 182.109873 -279.652666)
			(xy 182.129164 -279.60739) (xy 182.155467 -279.565794) (xy 182.188102 -279.528957) (xy 182.226223 -279.497832)
			(xy 182.268844 -279.473225) (xy 182.31486 -279.455773) (xy 182.363079 -279.445929) (xy 182.412254 -279.443948)
			(xy 182.461109 -279.44988) (xy 182.50838 -279.463572) (xy 182.552842 -279.48467) (xy 182.593345 -279.512626)
			(xy 182.628838 -279.546718) (xy 182.658403 -279.586062) (xy 182.681274 -279.629639) (xy 182.696858 -279.67632)
			(xy 182.704753 -279.724897) (xy 182.705248 -279.749504) (xy 183.994056 -279.749504) (xy 183.998016 -279.70045)
			(xy 184.009793 -279.652666) (xy 184.029084 -279.60739) (xy 184.055387 -279.565794) (xy 184.088022 -279.528957)
			(xy 184.126143 -279.497832) (xy 184.168764 -279.473225) (xy 184.21478 -279.455773) (xy 184.262999 -279.445929)
			(xy 184.312174 -279.443948) (xy 184.361029 -279.44988) (xy 184.4083 -279.463572) (xy 184.452762 -279.48467)
			(xy 184.493265 -279.512626) (xy 184.528758 -279.546718) (xy 184.558323 -279.586062) (xy 184.581194 -279.629639)
			(xy 184.596778 -279.67632) (xy 184.604673 -279.724897) (xy 184.605168 -279.749504) (xy 185.89423 -279.749504)
			(xy 185.89819 -279.70045) (xy 185.909967 -279.652666) (xy 185.929258 -279.60739) (xy 185.955561 -279.565794)
			(xy 185.988196 -279.528957) (xy 186.026317 -279.497832) (xy 186.068938 -279.473225) (xy 186.114954 -279.455773)
			(xy 186.163173 -279.445929) (xy 186.212348 -279.443948) (xy 186.261203 -279.44988) (xy 186.308474 -279.463572)
			(xy 186.352936 -279.48467) (xy 186.393439 -279.512626) (xy 186.428932 -279.546718) (xy 186.458497 -279.586062)
			(xy 186.481368 -279.629639) (xy 186.496952 -279.67632) (xy 186.504847 -279.724897) (xy 186.505342 -279.749504)
			(xy 187.79415 -279.749504) (xy 187.79811 -279.70045) (xy 187.809887 -279.652666) (xy 187.829178 -279.60739)
			(xy 187.855481 -279.565794) (xy 187.888116 -279.528957) (xy 187.926237 -279.497832) (xy 187.968858 -279.473225)
			(xy 188.014874 -279.455773) (xy 188.063093 -279.445929) (xy 188.112268 -279.443948) (xy 188.161123 -279.44988)
			(xy 188.208394 -279.463572) (xy 188.252856 -279.48467) (xy 188.293359 -279.512626) (xy 188.328852 -279.546718)
			(xy 188.358417 -279.586062) (xy 188.381288 -279.629639) (xy 188.396872 -279.67632) (xy 188.404767 -279.724897)
			(xy 188.405262 -279.749504) (xy 189.69407 -279.749504) (xy 189.69803 -279.70045) (xy 189.709807 -279.652666)
			(xy 189.729098 -279.60739) (xy 189.755401 -279.565794) (xy 189.788036 -279.528957) (xy 189.826157 -279.497832)
			(xy 189.868778 -279.473225) (xy 189.914794 -279.455773) (xy 189.963013 -279.445929) (xy 190.012188 -279.443948)
			(xy 190.061043 -279.44988) (xy 190.108314 -279.463572) (xy 190.152776 -279.48467) (xy 190.193279 -279.512626)
			(xy 190.228772 -279.546718) (xy 190.258337 -279.586062) (xy 190.281208 -279.629639) (xy 190.296792 -279.67632)
			(xy 190.304687 -279.724897) (xy 190.305182 -279.749504) (xy 191.594244 -279.749504) (xy 191.598204 -279.70045)
			(xy 191.609981 -279.652666) (xy 191.629272 -279.60739) (xy 191.655575 -279.565794) (xy 191.68821 -279.528957)
			(xy 191.726331 -279.497832) (xy 191.768952 -279.473225) (xy 191.814968 -279.455773) (xy 191.863187 -279.445929)
			(xy 191.912362 -279.443948) (xy 191.961217 -279.44988) (xy 192.008488 -279.463572) (xy 192.05295 -279.48467)
			(xy 192.093453 -279.512626) (xy 192.128946 -279.546718) (xy 192.158511 -279.586062) (xy 192.181382 -279.629639)
			(xy 192.196966 -279.67632) (xy 192.204861 -279.724897) (xy 192.205356 -279.749504) (xy 193.494164 -279.749504)
			(xy 193.498124 -279.70045) (xy 193.509901 -279.652666) (xy 193.529192 -279.60739) (xy 193.555495 -279.565794)
			(xy 193.58813 -279.528957) (xy 193.626251 -279.497832) (xy 193.668872 -279.473225) (xy 193.714888 -279.455773)
			(xy 193.763107 -279.445929) (xy 193.812282 -279.443948) (xy 193.861137 -279.44988) (xy 193.908408 -279.463572)
			(xy 193.95287 -279.48467) (xy 193.993373 -279.512626) (xy 194.028866 -279.546718) (xy 194.058431 -279.586062)
			(xy 194.081302 -279.629639) (xy 194.096886 -279.67632) (xy 194.104781 -279.724897) (xy 194.105276 -279.749504)
			(xy 194.105271 -279.749758) (xy 195.394084 -279.749758) (xy 195.398044 -279.700704) (xy 195.409821 -279.65292)
			(xy 195.429112 -279.607644) (xy 195.455415 -279.566048) (xy 195.48805 -279.529211) (xy 195.526171 -279.498086)
			(xy 195.568792 -279.473479) (xy 195.614808 -279.456027) (xy 195.663027 -279.446183) (xy 195.712202 -279.444202)
			(xy 195.761057 -279.450134) (xy 195.808328 -279.463826) (xy 195.85279 -279.484924) (xy 195.893293 -279.51288)
			(xy 195.928786 -279.546972) (xy 195.958351 -279.586316) (xy 195.981222 -279.629893) (xy 195.996806 -279.676574)
			(xy 196.004701 -279.725151) (xy 196.005196 -279.749758) (xy 197.294258 -279.749758) (xy 197.298218 -279.700704)
			(xy 197.309995 -279.65292) (xy 197.329286 -279.607644) (xy 197.355589 -279.566048) (xy 197.388224 -279.529211)
			(xy 197.426345 -279.498086) (xy 197.468966 -279.473479) (xy 197.514982 -279.456027) (xy 197.563201 -279.446183)
			(xy 197.612376 -279.444202) (xy 197.661231 -279.450134) (xy 197.708502 -279.463826) (xy 197.752964 -279.484924)
			(xy 197.793467 -279.51288) (xy 197.82896 -279.546972) (xy 197.858525 -279.586316) (xy 197.881396 -279.629893)
			(xy 197.89698 -279.676574) (xy 197.904875 -279.725151) (xy 197.90537 -279.749758) (xy 198.244218 -279.749758)
			(xy 198.248178 -279.700704) (xy 198.259955 -279.65292) (xy 198.279246 -279.607644) (xy 198.305549 -279.566048)
			(xy 198.338184 -279.529211) (xy 198.376305 -279.498086) (xy 198.418926 -279.473479) (xy 198.464942 -279.456027)
			(xy 198.513161 -279.446183) (xy 198.562336 -279.444202) (xy 198.611191 -279.450134) (xy 198.658462 -279.463826)
			(xy 198.702924 -279.484924) (xy 198.743427 -279.51288) (xy 198.77892 -279.546972) (xy 198.808485 -279.586316)
			(xy 198.831356 -279.629893) (xy 198.84694 -279.676574) (xy 198.854835 -279.725151) (xy 198.855325 -279.749504)
			(xy 277.294098 -279.749504) (xy 277.298058 -279.70045) (xy 277.309835 -279.652666) (xy 277.329126 -279.60739)
			(xy 277.355429 -279.565794) (xy 277.388064 -279.528957) (xy 277.426185 -279.497832) (xy 277.468806 -279.473225)
			(xy 277.514822 -279.455773) (xy 277.563041 -279.445929) (xy 277.612216 -279.443948) (xy 277.661071 -279.44988)
			(xy 277.708342 -279.463572) (xy 277.752804 -279.48467) (xy 277.793307 -279.512626) (xy 277.8288 -279.546718)
			(xy 277.858365 -279.586062) (xy 277.881236 -279.629639) (xy 277.89682 -279.67632) (xy 277.904715 -279.724897)
			(xy 277.90521 -279.749504) (xy 279.194018 -279.749504) (xy 279.197978 -279.70045) (xy 279.209755 -279.652666)
			(xy 279.229046 -279.60739) (xy 279.255349 -279.565794) (xy 279.287984 -279.528957) (xy 279.326105 -279.497832)
			(xy 279.368726 -279.473225) (xy 279.414742 -279.455773) (xy 279.462961 -279.445929) (xy 279.512136 -279.443948)
			(xy 279.560991 -279.44988) (xy 279.608262 -279.463572) (xy 279.652724 -279.48467) (xy 279.693227 -279.512626)
			(xy 279.72872 -279.546718) (xy 279.758285 -279.586062) (xy 279.781156 -279.629639) (xy 279.79674 -279.67632)
			(xy 279.804635 -279.724897) (xy 279.80513 -279.749504) (xy 281.093938 -279.749504) (xy 281.097898 -279.70045)
			(xy 281.109675 -279.652666) (xy 281.128966 -279.60739) (xy 281.155269 -279.565794) (xy 281.187904 -279.528957)
			(xy 281.226025 -279.497832) (xy 281.268646 -279.473225) (xy 281.314662 -279.455773) (xy 281.362881 -279.445929)
			(xy 281.412056 -279.443948) (xy 281.460911 -279.44988) (xy 281.508182 -279.463572) (xy 281.552644 -279.48467)
			(xy 281.593147 -279.512626) (xy 281.62864 -279.546718) (xy 281.658205 -279.586062) (xy 281.681076 -279.629639)
			(xy 281.69666 -279.67632) (xy 281.704555 -279.724897) (xy 281.70505 -279.749504) (xy 282.994112 -279.749504)
			(xy 282.998072 -279.70045) (xy 283.009849 -279.652666) (xy 283.02914 -279.60739) (xy 283.055443 -279.565794)
			(xy 283.088078 -279.528957) (xy 283.126199 -279.497832) (xy 283.16882 -279.473225) (xy 283.214836 -279.455773)
			(xy 283.263055 -279.445929) (xy 283.31223 -279.443948) (xy 283.361085 -279.44988) (xy 283.408356 -279.463572)
			(xy 283.452818 -279.48467) (xy 283.493321 -279.512626) (xy 283.528814 -279.546718) (xy 283.558379 -279.586062)
			(xy 283.58125 -279.629639) (xy 283.596834 -279.67632) (xy 283.604729 -279.724897) (xy 283.605224 -279.749504)
			(xy 284.894032 -279.749504) (xy 284.897992 -279.70045) (xy 284.909769 -279.652666) (xy 284.92906 -279.60739)
			(xy 284.955363 -279.565794) (xy 284.987998 -279.528957) (xy 285.026119 -279.497832) (xy 285.06874 -279.473225)
			(xy 285.114756 -279.455773) (xy 285.162975 -279.445929) (xy 285.21215 -279.443948) (xy 285.261005 -279.44988)
			(xy 285.308276 -279.463572) (xy 285.352738 -279.48467) (xy 285.393241 -279.512626) (xy 285.428734 -279.546718)
			(xy 285.458299 -279.586062) (xy 285.48117 -279.629639) (xy 285.496754 -279.67632) (xy 285.504649 -279.724897)
			(xy 285.505144 -279.749504) (xy 286.793952 -279.749504) (xy 286.797912 -279.70045) (xy 286.809689 -279.652666)
			(xy 286.82898 -279.60739) (xy 286.855283 -279.565794) (xy 286.887918 -279.528957) (xy 286.926039 -279.497832)
			(xy 286.96866 -279.473225) (xy 287.014676 -279.455773) (xy 287.062895 -279.445929) (xy 287.11207 -279.443948)
			(xy 287.160925 -279.44988) (xy 287.208196 -279.463572) (xy 287.252658 -279.48467) (xy 287.293161 -279.512626)
			(xy 287.328654 -279.546718) (xy 287.358219 -279.586062) (xy 287.38109 -279.629639) (xy 287.396674 -279.67632)
			(xy 287.404569 -279.724897) (xy 287.405064 -279.749504) (xy 288.693872 -279.749504) (xy 288.697832 -279.70045)
			(xy 288.709609 -279.652666) (xy 288.7289 -279.60739) (xy 288.755203 -279.565794) (xy 288.787838 -279.528957)
			(xy 288.825959 -279.497832) (xy 288.86858 -279.473225) (xy 288.914596 -279.455773) (xy 288.962815 -279.445929)
			(xy 289.01199 -279.443948) (xy 289.060845 -279.44988) (xy 289.108116 -279.463572) (xy 289.152578 -279.48467)
			(xy 289.193081 -279.512626) (xy 289.228574 -279.546718) (xy 289.258139 -279.586062) (xy 289.28101 -279.629639)
			(xy 289.296594 -279.67632) (xy 289.304489 -279.724897) (xy 289.304984 -279.749504) (xy 290.594046 -279.749504)
			(xy 290.598006 -279.70045) (xy 290.609783 -279.652666) (xy 290.629074 -279.60739) (xy 290.655377 -279.565794)
			(xy 290.688012 -279.528957) (xy 290.726133 -279.497832) (xy 290.768754 -279.473225) (xy 290.81477 -279.455773)
			(xy 290.862989 -279.445929) (xy 290.912164 -279.443948) (xy 290.961019 -279.44988) (xy 291.00829 -279.463572)
			(xy 291.052752 -279.48467) (xy 291.093255 -279.512626) (xy 291.128748 -279.546718) (xy 291.158313 -279.586062)
			(xy 291.181184 -279.629639) (xy 291.196768 -279.67632) (xy 291.204663 -279.724897) (xy 291.205158 -279.749504)
			(xy 292.493966 -279.749504) (xy 292.497926 -279.70045) (xy 292.509703 -279.652666) (xy 292.528994 -279.60739)
			(xy 292.555297 -279.565794) (xy 292.587932 -279.528957) (xy 292.626053 -279.497832) (xy 292.668674 -279.473225)
			(xy 292.71469 -279.455773) (xy 292.762909 -279.445929) (xy 292.812084 -279.443948) (xy 292.860939 -279.44988)
			(xy 292.90821 -279.463572) (xy 292.952672 -279.48467) (xy 292.993175 -279.512626) (xy 293.028668 -279.546718)
			(xy 293.058233 -279.586062) (xy 293.081104 -279.629639) (xy 293.096688 -279.67632) (xy 293.104583 -279.724897)
			(xy 293.105078 -279.749504) (xy 294.393886 -279.749504) (xy 294.397846 -279.70045) (xy 294.409623 -279.652666)
			(xy 294.428914 -279.60739) (xy 294.455217 -279.565794) (xy 294.487852 -279.528957) (xy 294.525973 -279.497832)
			(xy 294.568594 -279.473225) (xy 294.61461 -279.455773) (xy 294.662829 -279.445929) (xy 294.712004 -279.443948)
			(xy 294.760859 -279.44988) (xy 294.80813 -279.463572) (xy 294.852592 -279.48467) (xy 294.893095 -279.512626)
			(xy 294.928588 -279.546718) (xy 294.958153 -279.586062) (xy 294.981024 -279.629639) (xy 294.996608 -279.67632)
			(xy 295.004503 -279.724897) (xy 295.004998 -279.749504) (xy 296.29406 -279.749504) (xy 296.29802 -279.70045)
			(xy 296.309797 -279.652666) (xy 296.329088 -279.60739) (xy 296.355391 -279.565794) (xy 296.388026 -279.528957)
			(xy 296.426147 -279.497832) (xy 296.468768 -279.473225) (xy 296.514784 -279.455773) (xy 296.563003 -279.445929)
			(xy 296.612178 -279.443948) (xy 296.661033 -279.44988) (xy 296.708304 -279.463572) (xy 296.752766 -279.48467)
			(xy 296.793269 -279.512626) (xy 296.828762 -279.546718) (xy 296.858327 -279.586062) (xy 296.881198 -279.629639)
			(xy 296.896782 -279.67632) (xy 296.904677 -279.724897) (xy 296.905172 -279.749504) (xy 298.19398 -279.749504)
			(xy 298.19794 -279.70045) (xy 298.209717 -279.652666) (xy 298.229008 -279.60739) (xy 298.255311 -279.565794)
			(xy 298.287946 -279.528957) (xy 298.326067 -279.497832) (xy 298.368688 -279.473225) (xy 298.414704 -279.455773)
			(xy 298.462923 -279.445929) (xy 298.512098 -279.443948) (xy 298.560953 -279.44988) (xy 298.608224 -279.463572)
			(xy 298.652686 -279.48467) (xy 298.693189 -279.512626) (xy 298.728682 -279.546718) (xy 298.758247 -279.586062)
			(xy 298.781118 -279.629639) (xy 298.796702 -279.67632) (xy 298.804597 -279.724897) (xy 298.805092 -279.749504)
			(xy 300.0939 -279.749504) (xy 300.09786 -279.70045) (xy 300.109637 -279.652666) (xy 300.128928 -279.60739)
			(xy 300.155231 -279.565794) (xy 300.187866 -279.528957) (xy 300.225987 -279.497832) (xy 300.268608 -279.473225)
			(xy 300.314624 -279.455773) (xy 300.362843 -279.445929) (xy 300.412018 -279.443948) (xy 300.460873 -279.44988)
			(xy 300.508144 -279.463572) (xy 300.552606 -279.48467) (xy 300.593109 -279.512626) (xy 300.628602 -279.546718)
			(xy 300.658167 -279.586062) (xy 300.681038 -279.629639) (xy 300.696622 -279.67632) (xy 300.704517 -279.724897)
			(xy 300.705012 -279.749504) (xy 301.994074 -279.749504) (xy 301.998034 -279.70045) (xy 302.009811 -279.652666)
			(xy 302.029102 -279.60739) (xy 302.055405 -279.565794) (xy 302.08804 -279.528957) (xy 302.126161 -279.497832)
			(xy 302.168782 -279.473225) (xy 302.214798 -279.455773) (xy 302.263017 -279.445929) (xy 302.312192 -279.443948)
			(xy 302.361047 -279.44988) (xy 302.408318 -279.463572) (xy 302.45278 -279.48467) (xy 302.493283 -279.512626)
			(xy 302.528776 -279.546718) (xy 302.558341 -279.586062) (xy 302.581212 -279.629639) (xy 302.596796 -279.67632)
			(xy 302.604691 -279.724897) (xy 302.605186 -279.749504) (xy 303.893994 -279.749504) (xy 303.897954 -279.70045)
			(xy 303.909731 -279.652666) (xy 303.929022 -279.60739) (xy 303.955325 -279.565794) (xy 303.98796 -279.528957)
			(xy 304.026081 -279.497832) (xy 304.068702 -279.473225) (xy 304.114718 -279.455773) (xy 304.162937 -279.445929)
			(xy 304.212112 -279.443948) (xy 304.260967 -279.44988) (xy 304.308238 -279.463572) (xy 304.3527 -279.48467)
			(xy 304.393203 -279.512626) (xy 304.428696 -279.546718) (xy 304.458261 -279.586062) (xy 304.481132 -279.629639)
			(xy 304.496716 -279.67632) (xy 304.504611 -279.724897) (xy 304.505106 -279.749504) (xy 305.793914 -279.749504)
			(xy 305.797874 -279.70045) (xy 305.809651 -279.652666) (xy 305.828942 -279.60739) (xy 305.855245 -279.565794)
			(xy 305.88788 -279.528957) (xy 305.926001 -279.497832) (xy 305.968622 -279.473225) (xy 306.014638 -279.455773)
			(xy 306.062857 -279.445929) (xy 306.112032 -279.443948) (xy 306.160887 -279.44988) (xy 306.208158 -279.463572)
			(xy 306.25262 -279.48467) (xy 306.293123 -279.512626) (xy 306.328616 -279.546718) (xy 306.358181 -279.586062)
			(xy 306.381052 -279.629639) (xy 306.396636 -279.67632) (xy 306.404531 -279.724897) (xy 306.405026 -279.749504)
			(xy 307.694088 -279.749504) (xy 307.698048 -279.70045) (xy 307.709825 -279.652666) (xy 307.729116 -279.60739)
			(xy 307.755419 -279.565794) (xy 307.788054 -279.528957) (xy 307.826175 -279.497832) (xy 307.868796 -279.473225)
			(xy 307.914812 -279.455773) (xy 307.963031 -279.445929) (xy 308.012206 -279.443948) (xy 308.061061 -279.44988)
			(xy 308.108332 -279.463572) (xy 308.152794 -279.48467) (xy 308.193297 -279.512626) (xy 308.22879 -279.546718)
			(xy 308.258355 -279.586062) (xy 308.281226 -279.629639) (xy 308.29681 -279.67632) (xy 308.304705 -279.724897)
			(xy 308.3052 -279.749504) (xy 309.594008 -279.749504) (xy 309.597968 -279.70045) (xy 309.609745 -279.652666)
			(xy 309.629036 -279.60739) (xy 309.655339 -279.565794) (xy 309.687974 -279.528957) (xy 309.726095 -279.497832)
			(xy 309.768716 -279.473225) (xy 309.814732 -279.455773) (xy 309.862951 -279.445929) (xy 309.912126 -279.443948)
			(xy 309.960981 -279.44988) (xy 310.008252 -279.463572) (xy 310.052714 -279.48467) (xy 310.093217 -279.512626)
			(xy 310.12871 -279.546718) (xy 310.158275 -279.586062) (xy 310.181146 -279.629639) (xy 310.19673 -279.67632)
			(xy 310.204625 -279.724897) (xy 310.20512 -279.749504) (xy 310.205115 -279.749758) (xy 311.493928 -279.749758)
			(xy 311.497888 -279.700704) (xy 311.509665 -279.65292) (xy 311.528956 -279.607644) (xy 311.555259 -279.566048)
			(xy 311.587894 -279.529211) (xy 311.626015 -279.498086) (xy 311.668636 -279.473479) (xy 311.714652 -279.456027)
			(xy 311.762871 -279.446183) (xy 311.812046 -279.444202) (xy 311.860901 -279.450134) (xy 311.908172 -279.463826)
			(xy 311.952634 -279.484924) (xy 311.993137 -279.51288) (xy 312.02863 -279.546972) (xy 312.058195 -279.586316)
			(xy 312.081066 -279.629893) (xy 312.09665 -279.676574) (xy 312.104545 -279.725151) (xy 312.10504 -279.749758)
			(xy 313.394102 -279.749758) (xy 313.398062 -279.700704) (xy 313.409839 -279.65292) (xy 313.42913 -279.607644)
			(xy 313.455433 -279.566048) (xy 313.488068 -279.529211) (xy 313.526189 -279.498086) (xy 313.56881 -279.473479)
			(xy 313.614826 -279.456027) (xy 313.663045 -279.446183) (xy 313.71222 -279.444202) (xy 313.761075 -279.450134)
			(xy 313.808346 -279.463826) (xy 313.852808 -279.484924) (xy 313.893311 -279.51288) (xy 313.928804 -279.546972)
			(xy 313.958369 -279.586316) (xy 313.98124 -279.629893) (xy 313.996824 -279.676574) (xy 314.004719 -279.725151)
			(xy 314.005214 -279.749758) (xy 314.344062 -279.749758) (xy 314.348022 -279.700704) (xy 314.359799 -279.65292)
			(xy 314.37909 -279.607644) (xy 314.405393 -279.566048) (xy 314.438028 -279.529211) (xy 314.476149 -279.498086)
			(xy 314.51877 -279.473479) (xy 314.564786 -279.456027) (xy 314.613005 -279.446183) (xy 314.66218 -279.444202)
			(xy 314.711035 -279.450134) (xy 314.758306 -279.463826) (xy 314.802768 -279.484924) (xy 314.843271 -279.51288)
			(xy 314.878764 -279.546972) (xy 314.908329 -279.586316) (xy 314.9312 -279.629893) (xy 314.946784 -279.676574)
			(xy 314.954679 -279.725151) (xy 314.955169 -279.749504) (xy 393.394196 -279.749504) (xy 393.398156 -279.70045)
			(xy 393.409933 -279.652666) (xy 393.429224 -279.60739) (xy 393.455527 -279.565794) (xy 393.488162 -279.528957)
			(xy 393.526283 -279.497832) (xy 393.568904 -279.473225) (xy 393.61492 -279.455773) (xy 393.663139 -279.445929)
			(xy 393.712314 -279.443948) (xy 393.761169 -279.44988) (xy 393.80844 -279.463572) (xy 393.852902 -279.48467)
			(xy 393.893405 -279.512626) (xy 393.928898 -279.546718) (xy 393.958463 -279.586062) (xy 393.981334 -279.629639)
			(xy 393.996918 -279.67632) (xy 394.004813 -279.724897) (xy 394.005308 -279.749504) (xy 395.294116 -279.749504)
			(xy 395.298076 -279.70045) (xy 395.309853 -279.652666) (xy 395.329144 -279.60739) (xy 395.355447 -279.565794)
			(xy 395.388082 -279.528957) (xy 395.426203 -279.497832) (xy 395.468824 -279.473225) (xy 395.51484 -279.455773)
			(xy 395.563059 -279.445929) (xy 395.612234 -279.443948) (xy 395.661089 -279.44988) (xy 395.70836 -279.463572)
			(xy 395.752822 -279.48467) (xy 395.793325 -279.512626) (xy 395.828818 -279.546718) (xy 395.858383 -279.586062)
			(xy 395.881254 -279.629639) (xy 395.896838 -279.67632) (xy 395.904733 -279.724897) (xy 395.905228 -279.749504)
			(xy 397.194036 -279.749504) (xy 397.197996 -279.70045) (xy 397.209773 -279.652666) (xy 397.229064 -279.60739)
			(xy 397.255367 -279.565794) (xy 397.288002 -279.528957) (xy 397.326123 -279.497832) (xy 397.368744 -279.473225)
			(xy 397.41476 -279.455773) (xy 397.462979 -279.445929) (xy 397.512154 -279.443948) (xy 397.561009 -279.44988)
			(xy 397.60828 -279.463572) (xy 397.652742 -279.48467) (xy 397.693245 -279.512626) (xy 397.728738 -279.546718)
			(xy 397.758303 -279.586062) (xy 397.781174 -279.629639) (xy 397.796758 -279.67632) (xy 397.804653 -279.724897)
			(xy 397.805148 -279.749504) (xy 399.09421 -279.749504) (xy 399.09817 -279.70045) (xy 399.109947 -279.652666)
			(xy 399.129238 -279.60739) (xy 399.155541 -279.565794) (xy 399.188176 -279.528957) (xy 399.226297 -279.497832)
			(xy 399.268918 -279.473225) (xy 399.314934 -279.455773) (xy 399.363153 -279.445929) (xy 399.412328 -279.443948)
			(xy 399.461183 -279.44988) (xy 399.508454 -279.463572) (xy 399.552916 -279.48467) (xy 399.593419 -279.512626)
			(xy 399.628912 -279.546718) (xy 399.658477 -279.586062) (xy 399.681348 -279.629639) (xy 399.696932 -279.67632)
			(xy 399.704827 -279.724897) (xy 399.705322 -279.749504) (xy 400.99413 -279.749504) (xy 400.99809 -279.70045)
			(xy 401.009867 -279.652666) (xy 401.029158 -279.60739) (xy 401.055461 -279.565794) (xy 401.088096 -279.528957)
			(xy 401.126217 -279.497832) (xy 401.168838 -279.473225) (xy 401.214854 -279.455773) (xy 401.263073 -279.445929)
			(xy 401.312248 -279.443948) (xy 401.361103 -279.44988) (xy 401.408374 -279.463572) (xy 401.452836 -279.48467)
			(xy 401.493339 -279.512626) (xy 401.528832 -279.546718) (xy 401.558397 -279.586062) (xy 401.581268 -279.629639)
			(xy 401.596852 -279.67632) (xy 401.604747 -279.724897) (xy 401.605242 -279.749504) (xy 402.89405 -279.749504)
			(xy 402.89801 -279.70045) (xy 402.909787 -279.652666) (xy 402.929078 -279.60739) (xy 402.955381 -279.565794)
			(xy 402.988016 -279.528957) (xy 403.026137 -279.497832) (xy 403.068758 -279.473225) (xy 403.114774 -279.455773)
			(xy 403.162993 -279.445929) (xy 403.212168 -279.443948) (xy 403.261023 -279.44988) (xy 403.308294 -279.463572)
			(xy 403.352756 -279.48467) (xy 403.393259 -279.512626) (xy 403.428752 -279.546718) (xy 403.458317 -279.586062)
			(xy 403.481188 -279.629639) (xy 403.496772 -279.67632) (xy 403.504667 -279.724897) (xy 403.505162 -279.749504)
			(xy 404.79397 -279.749504) (xy 404.79793 -279.70045) (xy 404.809707 -279.652666) (xy 404.828998 -279.60739)
			(xy 404.855301 -279.565794) (xy 404.887936 -279.528957) (xy 404.926057 -279.497832) (xy 404.968678 -279.473225)
			(xy 405.014694 -279.455773) (xy 405.062913 -279.445929) (xy 405.112088 -279.443948) (xy 405.160943 -279.44988)
			(xy 405.208214 -279.463572) (xy 405.252676 -279.48467) (xy 405.293179 -279.512626) (xy 405.328672 -279.546718)
			(xy 405.358237 -279.586062) (xy 405.381108 -279.629639) (xy 405.396692 -279.67632) (xy 405.404587 -279.724897)
			(xy 405.405082 -279.749504) (xy 406.694144 -279.749504) (xy 406.698104 -279.70045) (xy 406.709881 -279.652666)
			(xy 406.729172 -279.60739) (xy 406.755475 -279.565794) (xy 406.78811 -279.528957) (xy 406.826231 -279.497832)
			(xy 406.868852 -279.473225) (xy 406.914868 -279.455773) (xy 406.963087 -279.445929) (xy 407.012262 -279.443948)
			(xy 407.061117 -279.44988) (xy 407.108388 -279.463572) (xy 407.15285 -279.48467) (xy 407.193353 -279.512626)
			(xy 407.228846 -279.546718) (xy 407.258411 -279.586062) (xy 407.281282 -279.629639) (xy 407.296866 -279.67632)
			(xy 407.304761 -279.724897) (xy 407.305256 -279.749504) (xy 408.594064 -279.749504) (xy 408.598024 -279.70045)
			(xy 408.609801 -279.652666) (xy 408.629092 -279.60739) (xy 408.655395 -279.565794) (xy 408.68803 -279.528957)
			(xy 408.726151 -279.497832) (xy 408.768772 -279.473225) (xy 408.814788 -279.455773) (xy 408.863007 -279.445929)
			(xy 408.912182 -279.443948) (xy 408.961037 -279.44988) (xy 409.008308 -279.463572) (xy 409.05277 -279.48467)
			(xy 409.093273 -279.512626) (xy 409.128766 -279.546718) (xy 409.158331 -279.586062) (xy 409.181202 -279.629639)
			(xy 409.196786 -279.67632) (xy 409.204681 -279.724897) (xy 409.205176 -279.749504) (xy 410.493984 -279.749504)
			(xy 410.497944 -279.70045) (xy 410.509721 -279.652666) (xy 410.529012 -279.60739) (xy 410.555315 -279.565794)
			(xy 410.58795 -279.528957) (xy 410.626071 -279.497832) (xy 410.668692 -279.473225) (xy 410.714708 -279.455773)
			(xy 410.762927 -279.445929) (xy 410.812102 -279.443948) (xy 410.860957 -279.44988) (xy 410.908228 -279.463572)
			(xy 410.95269 -279.48467) (xy 410.993193 -279.512626) (xy 411.028686 -279.546718) (xy 411.058251 -279.586062)
			(xy 411.081122 -279.629639) (xy 411.096706 -279.67632) (xy 411.104601 -279.724897) (xy 411.105096 -279.749504)
			(xy 412.394158 -279.749504) (xy 412.398118 -279.70045) (xy 412.409895 -279.652666) (xy 412.429186 -279.60739)
			(xy 412.455489 -279.565794) (xy 412.488124 -279.528957) (xy 412.526245 -279.497832) (xy 412.568866 -279.473225)
			(xy 412.614882 -279.455773) (xy 412.663101 -279.445929) (xy 412.712276 -279.443948) (xy 412.761131 -279.44988)
			(xy 412.808402 -279.463572) (xy 412.852864 -279.48467) (xy 412.893367 -279.512626) (xy 412.92886 -279.546718)
			(xy 412.958425 -279.586062) (xy 412.981296 -279.629639) (xy 412.99688 -279.67632) (xy 413.004775 -279.724897)
			(xy 413.00527 -279.749504) (xy 414.294078 -279.749504) (xy 414.298038 -279.70045) (xy 414.309815 -279.652666)
			(xy 414.329106 -279.60739) (xy 414.355409 -279.565794) (xy 414.388044 -279.528957) (xy 414.426165 -279.497832)
			(xy 414.468786 -279.473225) (xy 414.514802 -279.455773) (xy 414.563021 -279.445929) (xy 414.612196 -279.443948)
			(xy 414.661051 -279.44988) (xy 414.708322 -279.463572) (xy 414.752784 -279.48467) (xy 414.793287 -279.512626)
			(xy 414.82878 -279.546718) (xy 414.858345 -279.586062) (xy 414.881216 -279.629639) (xy 414.8968 -279.67632)
			(xy 414.904695 -279.724897) (xy 414.90519 -279.749504) (xy 416.193998 -279.749504) (xy 416.197958 -279.70045)
			(xy 416.209735 -279.652666) (xy 416.229026 -279.60739) (xy 416.255329 -279.565794) (xy 416.287964 -279.528957)
			(xy 416.326085 -279.497832) (xy 416.368706 -279.473225) (xy 416.414722 -279.455773) (xy 416.462941 -279.445929)
			(xy 416.512116 -279.443948) (xy 416.560971 -279.44988) (xy 416.608242 -279.463572) (xy 416.652704 -279.48467)
			(xy 416.693207 -279.512626) (xy 416.7287 -279.546718) (xy 416.758265 -279.586062) (xy 416.781136 -279.629639)
			(xy 416.79672 -279.67632) (xy 416.804615 -279.724897) (xy 416.80511 -279.749504) (xy 418.094172 -279.749504)
			(xy 418.098132 -279.70045) (xy 418.109909 -279.652666) (xy 418.1292 -279.60739) (xy 418.155503 -279.565794)
			(xy 418.188138 -279.528957) (xy 418.226259 -279.497832) (xy 418.26888 -279.473225) (xy 418.314896 -279.455773)
			(xy 418.363115 -279.445929) (xy 418.41229 -279.443948) (xy 418.461145 -279.44988) (xy 418.508416 -279.463572)
			(xy 418.552878 -279.48467) (xy 418.593381 -279.512626) (xy 418.628874 -279.546718) (xy 418.658439 -279.586062)
			(xy 418.68131 -279.629639) (xy 418.696894 -279.67632) (xy 418.704789 -279.724897) (xy 418.705284 -279.749504)
			(xy 419.994092 -279.749504) (xy 419.998052 -279.70045) (xy 420.009829 -279.652666) (xy 420.02912 -279.60739)
			(xy 420.055423 -279.565794) (xy 420.088058 -279.528957) (xy 420.126179 -279.497832) (xy 420.1688 -279.473225)
			(xy 420.214816 -279.455773) (xy 420.263035 -279.445929) (xy 420.31221 -279.443948) (xy 420.361065 -279.44988)
			(xy 420.408336 -279.463572) (xy 420.452798 -279.48467) (xy 420.493301 -279.512626) (xy 420.528794 -279.546718)
			(xy 420.558359 -279.586062) (xy 420.58123 -279.629639) (xy 420.596814 -279.67632) (xy 420.604709 -279.724897)
			(xy 420.605204 -279.749504) (xy 421.894012 -279.749504) (xy 421.897972 -279.70045) (xy 421.909749 -279.652666)
			(xy 421.92904 -279.60739) (xy 421.955343 -279.565794) (xy 421.987978 -279.528957) (xy 422.026099 -279.497832)
			(xy 422.06872 -279.473225) (xy 422.114736 -279.455773) (xy 422.162955 -279.445929) (xy 422.21213 -279.443948)
			(xy 422.260985 -279.44988) (xy 422.308256 -279.463572) (xy 422.352718 -279.48467) (xy 422.393221 -279.512626)
			(xy 422.428714 -279.546718) (xy 422.458279 -279.586062) (xy 422.48115 -279.629639) (xy 422.496734 -279.67632)
			(xy 422.504629 -279.724897) (xy 422.505124 -279.749504) (xy 423.794186 -279.749504) (xy 423.798146 -279.70045)
			(xy 423.809923 -279.652666) (xy 423.829214 -279.60739) (xy 423.855517 -279.565794) (xy 423.888152 -279.528957)
			(xy 423.926273 -279.497832) (xy 423.968894 -279.473225) (xy 424.01491 -279.455773) (xy 424.063129 -279.445929)
			(xy 424.112304 -279.443948) (xy 424.161159 -279.44988) (xy 424.20843 -279.463572) (xy 424.252892 -279.48467)
			(xy 424.293395 -279.512626) (xy 424.328888 -279.546718) (xy 424.358453 -279.586062) (xy 424.381324 -279.629639)
			(xy 424.396908 -279.67632) (xy 424.404803 -279.724897) (xy 424.405298 -279.749504) (xy 425.694106 -279.749504)
			(xy 425.698066 -279.70045) (xy 425.709843 -279.652666) (xy 425.729134 -279.60739) (xy 425.755437 -279.565794)
			(xy 425.788072 -279.528957) (xy 425.826193 -279.497832) (xy 425.868814 -279.473225) (xy 425.91483 -279.455773)
			(xy 425.963049 -279.445929) (xy 426.012224 -279.443948) (xy 426.061079 -279.44988) (xy 426.10835 -279.463572)
			(xy 426.152812 -279.48467) (xy 426.193315 -279.512626) (xy 426.228808 -279.546718) (xy 426.258373 -279.586062)
			(xy 426.281244 -279.629639) (xy 426.296828 -279.67632) (xy 426.304723 -279.724897) (xy 426.305218 -279.749504)
			(xy 426.305213 -279.749758) (xy 427.594026 -279.749758) (xy 427.597986 -279.700704) (xy 427.609763 -279.65292)
			(xy 427.629054 -279.607644) (xy 427.655357 -279.566048) (xy 427.687992 -279.529211) (xy 427.726113 -279.498086)
			(xy 427.768734 -279.473479) (xy 427.81475 -279.456027) (xy 427.862969 -279.446183) (xy 427.912144 -279.444202)
			(xy 427.960999 -279.450134) (xy 428.00827 -279.463826) (xy 428.052732 -279.484924) (xy 428.093235 -279.51288)
			(xy 428.128728 -279.546972) (xy 428.158293 -279.586316) (xy 428.181164 -279.629893) (xy 428.196748 -279.676574)
			(xy 428.204643 -279.725151) (xy 428.205138 -279.749758) (xy 429.4942 -279.749758) (xy 429.49816 -279.700704)
			(xy 429.509937 -279.65292) (xy 429.529228 -279.607644) (xy 429.555531 -279.566048) (xy 429.588166 -279.529211)
			(xy 429.626287 -279.498086) (xy 429.668908 -279.473479) (xy 429.714924 -279.456027) (xy 429.763143 -279.446183)
			(xy 429.812318 -279.444202) (xy 429.861173 -279.450134) (xy 429.908444 -279.463826) (xy 429.952906 -279.484924)
			(xy 429.993409 -279.51288) (xy 430.028902 -279.546972) (xy 430.058467 -279.586316) (xy 430.081338 -279.629893)
			(xy 430.096922 -279.676574) (xy 430.104817 -279.725151) (xy 430.105312 -279.749758) (xy 430.44416 -279.749758)
			(xy 430.44812 -279.700704) (xy 430.459897 -279.65292) (xy 430.479188 -279.607644) (xy 430.505491 -279.566048)
			(xy 430.538126 -279.529211) (xy 430.576247 -279.498086) (xy 430.618868 -279.473479) (xy 430.664884 -279.456027)
			(xy 430.713103 -279.446183) (xy 430.762278 -279.444202) (xy 430.811133 -279.450134) (xy 430.858404 -279.463826)
			(xy 430.902866 -279.484924) (xy 430.943369 -279.51288) (xy 430.978862 -279.546972) (xy 431.008427 -279.586316)
			(xy 431.031298 -279.629893) (xy 431.046882 -279.676574) (xy 431.054777 -279.725151) (xy 431.055272 -279.749758)
			(xy 431.054777 -279.774365) (xy 431.046882 -279.822942) (xy 431.031298 -279.869623) (xy 431.008427 -279.9132)
			(xy 430.978862 -279.952544) (xy 430.943369 -279.986636) (xy 430.902866 -280.014592) (xy 430.858404 -280.03569)
			(xy 430.811133 -280.049382) (xy 430.762278 -280.055314) (xy 430.713103 -280.053333) (xy 430.664884 -280.043489)
			(xy 430.618868 -280.026037) (xy 430.576247 -280.00143) (xy 430.538126 -279.970305) (xy 430.505491 -279.933468)
			(xy 430.479188 -279.891872) (xy 430.459897 -279.846596) (xy 430.44812 -279.798812) (xy 430.44416 -279.749758)
			(xy 430.105312 -279.749758) (xy 430.104817 -279.774365) (xy 430.096922 -279.822942) (xy 430.081338 -279.869623)
			(xy 430.058467 -279.9132) (xy 430.028902 -279.952544) (xy 429.993409 -279.986636) (xy 429.952906 -280.014592)
			(xy 429.908444 -280.03569) (xy 429.861173 -280.049382) (xy 429.812318 -280.055314) (xy 429.763143 -280.053333)
			(xy 429.714924 -280.043489) (xy 429.668908 -280.026037) (xy 429.626287 -280.00143) (xy 429.588166 -279.970305)
			(xy 429.555531 -279.933468) (xy 429.529228 -279.891872) (xy 429.509937 -279.846596) (xy 429.49816 -279.798812)
			(xy 429.4942 -279.749758) (xy 428.205138 -279.749758) (xy 428.204643 -279.774365) (xy 428.196748 -279.822942)
			(xy 428.181164 -279.869623) (xy 428.158293 -279.9132) (xy 428.128728 -279.952544) (xy 428.093235 -279.986636)
			(xy 428.052732 -280.014592) (xy 428.00827 -280.03569) (xy 427.960999 -280.049382) (xy 427.912144 -280.055314)
			(xy 427.862969 -280.053333) (xy 427.81475 -280.043489) (xy 427.768734 -280.026037) (xy 427.726113 -280.00143)
			(xy 427.687992 -279.970305) (xy 427.655357 -279.933468) (xy 427.629054 -279.891872) (xy 427.609763 -279.846596)
			(xy 427.597986 -279.798812) (xy 427.594026 -279.749758) (xy 426.305213 -279.749758) (xy 426.304723 -279.774111)
			(xy 426.296828 -279.822688) (xy 426.281244 -279.869369) (xy 426.258373 -279.912946) (xy 426.228808 -279.95229)
			(xy 426.193315 -279.986382) (xy 426.152812 -280.014338) (xy 426.10835 -280.035436) (xy 426.061079 -280.049128)
			(xy 426.012224 -280.05506) (xy 425.963049 -280.053079) (xy 425.91483 -280.043235) (xy 425.868814 -280.025783)
			(xy 425.826193 -280.001176) (xy 425.788072 -279.970051) (xy 425.755437 -279.933214) (xy 425.729134 -279.891618)
			(xy 425.709843 -279.846342) (xy 425.698066 -279.798558) (xy 425.694106 -279.749504) (xy 424.405298 -279.749504)
			(xy 424.404803 -279.774111) (xy 424.396908 -279.822688) (xy 424.381324 -279.869369) (xy 424.358453 -279.912946)
			(xy 424.328888 -279.95229) (xy 424.293395 -279.986382) (xy 424.252892 -280.014338) (xy 424.20843 -280.035436)
			(xy 424.161159 -280.049128) (xy 424.112304 -280.05506) (xy 424.063129 -280.053079) (xy 424.01491 -280.043235)
			(xy 423.968894 -280.025783) (xy 423.926273 -280.001176) (xy 423.888152 -279.970051) (xy 423.855517 -279.933214)
			(xy 423.829214 -279.891618) (xy 423.809923 -279.846342) (xy 423.798146 -279.798558) (xy 423.794186 -279.749504)
			(xy 422.505124 -279.749504) (xy 422.504629 -279.774111) (xy 422.496734 -279.822688) (xy 422.48115 -279.869369)
			(xy 422.458279 -279.912946) (xy 422.428714 -279.95229) (xy 422.393221 -279.986382) (xy 422.352718 -280.014338)
			(xy 422.308256 -280.035436) (xy 422.260985 -280.049128) (xy 422.21213 -280.05506) (xy 422.162955 -280.053079)
			(xy 422.114736 -280.043235) (xy 422.06872 -280.025783) (xy 422.026099 -280.001176) (xy 421.987978 -279.970051)
			(xy 421.955343 -279.933214) (xy 421.92904 -279.891618) (xy 421.909749 -279.846342) (xy 421.897972 -279.798558)
			(xy 421.894012 -279.749504) (xy 420.605204 -279.749504) (xy 420.604709 -279.774111) (xy 420.596814 -279.822688)
			(xy 420.58123 -279.869369) (xy 420.558359 -279.912946) (xy 420.528794 -279.95229) (xy 420.493301 -279.986382)
			(xy 420.452798 -280.014338) (xy 420.408336 -280.035436) (xy 420.361065 -280.049128) (xy 420.31221 -280.05506)
			(xy 420.263035 -280.053079) (xy 420.214816 -280.043235) (xy 420.1688 -280.025783) (xy 420.126179 -280.001176)
			(xy 420.088058 -279.970051) (xy 420.055423 -279.933214) (xy 420.02912 -279.891618) (xy 420.009829 -279.846342)
			(xy 419.998052 -279.798558) (xy 419.994092 -279.749504) (xy 418.705284 -279.749504) (xy 418.704789 -279.774111)
			(xy 418.696894 -279.822688) (xy 418.68131 -279.869369) (xy 418.658439 -279.912946) (xy 418.628874 -279.95229)
			(xy 418.593381 -279.986382) (xy 418.552878 -280.014338) (xy 418.508416 -280.035436) (xy 418.461145 -280.049128)
			(xy 418.41229 -280.05506) (xy 418.363115 -280.053079) (xy 418.314896 -280.043235) (xy 418.26888 -280.025783)
			(xy 418.226259 -280.001176) (xy 418.188138 -279.970051) (xy 418.155503 -279.933214) (xy 418.1292 -279.891618)
			(xy 418.109909 -279.846342) (xy 418.098132 -279.798558) (xy 418.094172 -279.749504) (xy 416.80511 -279.749504)
			(xy 416.804615 -279.774111) (xy 416.79672 -279.822688) (xy 416.781136 -279.869369) (xy 416.758265 -279.912946)
			(xy 416.7287 -279.95229) (xy 416.693207 -279.986382) (xy 416.652704 -280.014338) (xy 416.608242 -280.035436)
			(xy 416.560971 -280.049128) (xy 416.512116 -280.05506) (xy 416.462941 -280.053079) (xy 416.414722 -280.043235)
			(xy 416.368706 -280.025783) (xy 416.326085 -280.001176) (xy 416.287964 -279.970051) (xy 416.255329 -279.933214)
			(xy 416.229026 -279.891618) (xy 416.209735 -279.846342) (xy 416.197958 -279.798558) (xy 416.193998 -279.749504)
			(xy 414.90519 -279.749504) (xy 414.904695 -279.774111) (xy 414.8968 -279.822688) (xy 414.881216 -279.869369)
			(xy 414.858345 -279.912946) (xy 414.82878 -279.95229) (xy 414.793287 -279.986382) (xy 414.752784 -280.014338)
			(xy 414.708322 -280.035436) (xy 414.661051 -280.049128) (xy 414.612196 -280.05506) (xy 414.563021 -280.053079)
			(xy 414.514802 -280.043235) (xy 414.468786 -280.025783) (xy 414.426165 -280.001176) (xy 414.388044 -279.970051)
			(xy 414.355409 -279.933214) (xy 414.329106 -279.891618) (xy 414.309815 -279.846342) (xy 414.298038 -279.798558)
			(xy 414.294078 -279.749504) (xy 413.00527 -279.749504) (xy 413.004775 -279.774111) (xy 412.99688 -279.822688)
			(xy 412.981296 -279.869369) (xy 412.958425 -279.912946) (xy 412.92886 -279.95229) (xy 412.893367 -279.986382)
			(xy 412.852864 -280.014338) (xy 412.808402 -280.035436) (xy 412.761131 -280.049128) (xy 412.712276 -280.05506)
			(xy 412.663101 -280.053079) (xy 412.614882 -280.043235) (xy 412.568866 -280.025783) (xy 412.526245 -280.001176)
			(xy 412.488124 -279.970051) (xy 412.455489 -279.933214) (xy 412.429186 -279.891618) (xy 412.409895 -279.846342)
			(xy 412.398118 -279.798558) (xy 412.394158 -279.749504) (xy 411.105096 -279.749504) (xy 411.104601 -279.774111)
			(xy 411.096706 -279.822688) (xy 411.081122 -279.869369) (xy 411.058251 -279.912946) (xy 411.028686 -279.95229)
			(xy 410.993193 -279.986382) (xy 410.95269 -280.014338) (xy 410.908228 -280.035436) (xy 410.860957 -280.049128)
			(xy 410.812102 -280.05506) (xy 410.762927 -280.053079) (xy 410.714708 -280.043235) (xy 410.668692 -280.025783)
			(xy 410.626071 -280.001176) (xy 410.58795 -279.970051) (xy 410.555315 -279.933214) (xy 410.529012 -279.891618)
			(xy 410.509721 -279.846342) (xy 410.497944 -279.798558) (xy 410.493984 -279.749504) (xy 409.205176 -279.749504)
			(xy 409.204681 -279.774111) (xy 409.196786 -279.822688) (xy 409.181202 -279.869369) (xy 409.158331 -279.912946)
			(xy 409.128766 -279.95229) (xy 409.093273 -279.986382) (xy 409.05277 -280.014338) (xy 409.008308 -280.035436)
			(xy 408.961037 -280.049128) (xy 408.912182 -280.05506) (xy 408.863007 -280.053079) (xy 408.814788 -280.043235)
			(xy 408.768772 -280.025783) (xy 408.726151 -280.001176) (xy 408.68803 -279.970051) (xy 408.655395 -279.933214)
			(xy 408.629092 -279.891618) (xy 408.609801 -279.846342) (xy 408.598024 -279.798558) (xy 408.594064 -279.749504)
			(xy 407.305256 -279.749504) (xy 407.304761 -279.774111) (xy 407.296866 -279.822688) (xy 407.281282 -279.869369)
			(xy 407.258411 -279.912946) (xy 407.228846 -279.95229) (xy 407.193353 -279.986382) (xy 407.15285 -280.014338)
			(xy 407.108388 -280.035436) (xy 407.061117 -280.049128) (xy 407.012262 -280.05506) (xy 406.963087 -280.053079)
			(xy 406.914868 -280.043235) (xy 406.868852 -280.025783) (xy 406.826231 -280.001176) (xy 406.78811 -279.970051)
			(xy 406.755475 -279.933214) (xy 406.729172 -279.891618) (xy 406.709881 -279.846342) (xy 406.698104 -279.798558)
			(xy 406.694144 -279.749504) (xy 405.405082 -279.749504) (xy 405.404587 -279.774111) (xy 405.396692 -279.822688)
			(xy 405.381108 -279.869369) (xy 405.358237 -279.912946) (xy 405.328672 -279.95229) (xy 405.293179 -279.986382)
			(xy 405.252676 -280.014338) (xy 405.208214 -280.035436) (xy 405.160943 -280.049128) (xy 405.112088 -280.05506)
			(xy 405.062913 -280.053079) (xy 405.014694 -280.043235) (xy 404.968678 -280.025783) (xy 404.926057 -280.001176)
			(xy 404.887936 -279.970051) (xy 404.855301 -279.933214) (xy 404.828998 -279.891618) (xy 404.809707 -279.846342)
			(xy 404.79793 -279.798558) (xy 404.79397 -279.749504) (xy 403.505162 -279.749504) (xy 403.504667 -279.774111)
			(xy 403.496772 -279.822688) (xy 403.481188 -279.869369) (xy 403.458317 -279.912946) (xy 403.428752 -279.95229)
			(xy 403.393259 -279.986382) (xy 403.352756 -280.014338) (xy 403.308294 -280.035436) (xy 403.261023 -280.049128)
			(xy 403.212168 -280.05506) (xy 403.162993 -280.053079) (xy 403.114774 -280.043235) (xy 403.068758 -280.025783)
			(xy 403.026137 -280.001176) (xy 402.988016 -279.970051) (xy 402.955381 -279.933214) (xy 402.929078 -279.891618)
			(xy 402.909787 -279.846342) (xy 402.89801 -279.798558) (xy 402.89405 -279.749504) (xy 401.605242 -279.749504)
			(xy 401.604747 -279.774111) (xy 401.596852 -279.822688) (xy 401.581268 -279.869369) (xy 401.558397 -279.912946)
			(xy 401.528832 -279.95229) (xy 401.493339 -279.986382) (xy 401.452836 -280.014338) (xy 401.408374 -280.035436)
			(xy 401.361103 -280.049128) (xy 401.312248 -280.05506) (xy 401.263073 -280.053079) (xy 401.214854 -280.043235)
			(xy 401.168838 -280.025783) (xy 401.126217 -280.001176) (xy 401.088096 -279.970051) (xy 401.055461 -279.933214)
			(xy 401.029158 -279.891618) (xy 401.009867 -279.846342) (xy 400.99809 -279.798558) (xy 400.99413 -279.749504)
			(xy 399.705322 -279.749504) (xy 399.704827 -279.774111) (xy 399.696932 -279.822688) (xy 399.681348 -279.869369)
			(xy 399.658477 -279.912946) (xy 399.628912 -279.95229) (xy 399.593419 -279.986382) (xy 399.552916 -280.014338)
			(xy 399.508454 -280.035436) (xy 399.461183 -280.049128) (xy 399.412328 -280.05506) (xy 399.363153 -280.053079)
			(xy 399.314934 -280.043235) (xy 399.268918 -280.025783) (xy 399.226297 -280.001176) (xy 399.188176 -279.970051)
			(xy 399.155541 -279.933214) (xy 399.129238 -279.891618) (xy 399.109947 -279.846342) (xy 399.09817 -279.798558)
			(xy 399.09421 -279.749504) (xy 397.805148 -279.749504) (xy 397.804653 -279.774111) (xy 397.796758 -279.822688)
			(xy 397.781174 -279.869369) (xy 397.758303 -279.912946) (xy 397.728738 -279.95229) (xy 397.693245 -279.986382)
			(xy 397.652742 -280.014338) (xy 397.60828 -280.035436) (xy 397.561009 -280.049128) (xy 397.512154 -280.05506)
			(xy 397.462979 -280.053079) (xy 397.41476 -280.043235) (xy 397.368744 -280.025783) (xy 397.326123 -280.001176)
			(xy 397.288002 -279.970051) (xy 397.255367 -279.933214) (xy 397.229064 -279.891618) (xy 397.209773 -279.846342)
			(xy 397.197996 -279.798558) (xy 397.194036 -279.749504) (xy 395.905228 -279.749504) (xy 395.904733 -279.774111)
			(xy 395.896838 -279.822688) (xy 395.881254 -279.869369) (xy 395.858383 -279.912946) (xy 395.828818 -279.95229)
			(xy 395.793325 -279.986382) (xy 395.752822 -280.014338) (xy 395.70836 -280.035436) (xy 395.661089 -280.049128)
			(xy 395.612234 -280.05506) (xy 395.563059 -280.053079) (xy 395.51484 -280.043235) (xy 395.468824 -280.025783)
			(xy 395.426203 -280.001176) (xy 395.388082 -279.970051) (xy 395.355447 -279.933214) (xy 395.329144 -279.891618)
			(xy 395.309853 -279.846342) (xy 395.298076 -279.798558) (xy 395.294116 -279.749504) (xy 394.005308 -279.749504)
			(xy 394.004813 -279.774111) (xy 393.996918 -279.822688) (xy 393.981334 -279.869369) (xy 393.958463 -279.912946)
			(xy 393.928898 -279.95229) (xy 393.893405 -279.986382) (xy 393.852902 -280.014338) (xy 393.80844 -280.035436)
			(xy 393.761169 -280.049128) (xy 393.712314 -280.05506) (xy 393.663139 -280.053079) (xy 393.61492 -280.043235)
			(xy 393.568904 -280.025783) (xy 393.526283 -280.001176) (xy 393.488162 -279.970051) (xy 393.455527 -279.933214)
			(xy 393.429224 -279.891618) (xy 393.409933 -279.846342) (xy 393.398156 -279.798558) (xy 393.394196 -279.749504)
			(xy 314.955169 -279.749504) (xy 314.955174 -279.749758) (xy 314.954679 -279.774365) (xy 314.946784 -279.822942)
			(xy 314.9312 -279.869623) (xy 314.908329 -279.9132) (xy 314.878764 -279.952544) (xy 314.843271 -279.986636)
			(xy 314.802768 -280.014592) (xy 314.758306 -280.03569) (xy 314.711035 -280.049382) (xy 314.66218 -280.055314)
			(xy 314.613005 -280.053333) (xy 314.564786 -280.043489) (xy 314.51877 -280.026037) (xy 314.476149 -280.00143)
			(xy 314.438028 -279.970305) (xy 314.405393 -279.933468) (xy 314.37909 -279.891872) (xy 314.359799 -279.846596)
			(xy 314.348022 -279.798812) (xy 314.344062 -279.749758) (xy 314.005214 -279.749758) (xy 314.004719 -279.774365)
			(xy 313.996824 -279.822942) (xy 313.98124 -279.869623) (xy 313.958369 -279.9132) (xy 313.928804 -279.952544)
			(xy 313.893311 -279.986636) (xy 313.852808 -280.014592) (xy 313.808346 -280.03569) (xy 313.761075 -280.049382)
			(xy 313.71222 -280.055314) (xy 313.663045 -280.053333) (xy 313.614826 -280.043489) (xy 313.56881 -280.026037)
			(xy 313.526189 -280.00143) (xy 313.488068 -279.970305) (xy 313.455433 -279.933468) (xy 313.42913 -279.891872)
			(xy 313.409839 -279.846596) (xy 313.398062 -279.798812) (xy 313.394102 -279.749758) (xy 312.10504 -279.749758)
			(xy 312.104545 -279.774365) (xy 312.09665 -279.822942) (xy 312.081066 -279.869623) (xy 312.058195 -279.9132)
			(xy 312.02863 -279.952544) (xy 311.993137 -279.986636) (xy 311.952634 -280.014592) (xy 311.908172 -280.03569)
			(xy 311.860901 -280.049382) (xy 311.812046 -280.055314) (xy 311.762871 -280.053333) (xy 311.714652 -280.043489)
			(xy 311.668636 -280.026037) (xy 311.626015 -280.00143) (xy 311.587894 -279.970305) (xy 311.555259 -279.933468)
			(xy 311.528956 -279.891872) (xy 311.509665 -279.846596) (xy 311.497888 -279.798812) (xy 311.493928 -279.749758)
			(xy 310.205115 -279.749758) (xy 310.204625 -279.774111) (xy 310.19673 -279.822688) (xy 310.181146 -279.869369)
			(xy 310.158275 -279.912946) (xy 310.12871 -279.95229) (xy 310.093217 -279.986382) (xy 310.052714 -280.014338)
			(xy 310.008252 -280.035436) (xy 309.960981 -280.049128) (xy 309.912126 -280.05506) (xy 309.862951 -280.053079)
			(xy 309.814732 -280.043235) (xy 309.768716 -280.025783) (xy 309.726095 -280.001176) (xy 309.687974 -279.970051)
			(xy 309.655339 -279.933214) (xy 309.629036 -279.891618) (xy 309.609745 -279.846342) (xy 309.597968 -279.798558)
			(xy 309.594008 -279.749504) (xy 308.3052 -279.749504) (xy 308.304705 -279.774111) (xy 308.29681 -279.822688)
			(xy 308.281226 -279.869369) (xy 308.258355 -279.912946) (xy 308.22879 -279.95229) (xy 308.193297 -279.986382)
			(xy 308.152794 -280.014338) (xy 308.108332 -280.035436) (xy 308.061061 -280.049128) (xy 308.012206 -280.05506)
			(xy 307.963031 -280.053079) (xy 307.914812 -280.043235) (xy 307.868796 -280.025783) (xy 307.826175 -280.001176)
			(xy 307.788054 -279.970051) (xy 307.755419 -279.933214) (xy 307.729116 -279.891618) (xy 307.709825 -279.846342)
			(xy 307.698048 -279.798558) (xy 307.694088 -279.749504) (xy 306.405026 -279.749504) (xy 306.404531 -279.774111)
			(xy 306.396636 -279.822688) (xy 306.381052 -279.869369) (xy 306.358181 -279.912946) (xy 306.328616 -279.95229)
			(xy 306.293123 -279.986382) (xy 306.25262 -280.014338) (xy 306.208158 -280.035436) (xy 306.160887 -280.049128)
			(xy 306.112032 -280.05506) (xy 306.062857 -280.053079) (xy 306.014638 -280.043235) (xy 305.968622 -280.025783)
			(xy 305.926001 -280.001176) (xy 305.88788 -279.970051) (xy 305.855245 -279.933214) (xy 305.828942 -279.891618)
			(xy 305.809651 -279.846342) (xy 305.797874 -279.798558) (xy 305.793914 -279.749504) (xy 304.505106 -279.749504)
			(xy 304.504611 -279.774111) (xy 304.496716 -279.822688) (xy 304.481132 -279.869369) (xy 304.458261 -279.912946)
			(xy 304.428696 -279.95229) (xy 304.393203 -279.986382) (xy 304.3527 -280.014338) (xy 304.308238 -280.035436)
			(xy 304.260967 -280.049128) (xy 304.212112 -280.05506) (xy 304.162937 -280.053079) (xy 304.114718 -280.043235)
			(xy 304.068702 -280.025783) (xy 304.026081 -280.001176) (xy 303.98796 -279.970051) (xy 303.955325 -279.933214)
			(xy 303.929022 -279.891618) (xy 303.909731 -279.846342) (xy 303.897954 -279.798558) (xy 303.893994 -279.749504)
			(xy 302.605186 -279.749504) (xy 302.604691 -279.774111) (xy 302.596796 -279.822688) (xy 302.581212 -279.869369)
			(xy 302.558341 -279.912946) (xy 302.528776 -279.95229) (xy 302.493283 -279.986382) (xy 302.45278 -280.014338)
			(xy 302.408318 -280.035436) (xy 302.361047 -280.049128) (xy 302.312192 -280.05506) (xy 302.263017 -280.053079)
			(xy 302.214798 -280.043235) (xy 302.168782 -280.025783) (xy 302.126161 -280.001176) (xy 302.08804 -279.970051)
			(xy 302.055405 -279.933214) (xy 302.029102 -279.891618) (xy 302.009811 -279.846342) (xy 301.998034 -279.798558)
			(xy 301.994074 -279.749504) (xy 300.705012 -279.749504) (xy 300.704517 -279.774111) (xy 300.696622 -279.822688)
			(xy 300.681038 -279.869369) (xy 300.658167 -279.912946) (xy 300.628602 -279.95229) (xy 300.593109 -279.986382)
			(xy 300.552606 -280.014338) (xy 300.508144 -280.035436) (xy 300.460873 -280.049128) (xy 300.412018 -280.05506)
			(xy 300.362843 -280.053079) (xy 300.314624 -280.043235) (xy 300.268608 -280.025783) (xy 300.225987 -280.001176)
			(xy 300.187866 -279.970051) (xy 300.155231 -279.933214) (xy 300.128928 -279.891618) (xy 300.109637 -279.846342)
			(xy 300.09786 -279.798558) (xy 300.0939 -279.749504) (xy 298.805092 -279.749504) (xy 298.804597 -279.774111)
			(xy 298.796702 -279.822688) (xy 298.781118 -279.869369) (xy 298.758247 -279.912946) (xy 298.728682 -279.95229)
			(xy 298.693189 -279.986382) (xy 298.652686 -280.014338) (xy 298.608224 -280.035436) (xy 298.560953 -280.049128)
			(xy 298.512098 -280.05506) (xy 298.462923 -280.053079) (xy 298.414704 -280.043235) (xy 298.368688 -280.025783)
			(xy 298.326067 -280.001176) (xy 298.287946 -279.970051) (xy 298.255311 -279.933214) (xy 298.229008 -279.891618)
			(xy 298.209717 -279.846342) (xy 298.19794 -279.798558) (xy 298.19398 -279.749504) (xy 296.905172 -279.749504)
			(xy 296.904677 -279.774111) (xy 296.896782 -279.822688) (xy 296.881198 -279.869369) (xy 296.858327 -279.912946)
			(xy 296.828762 -279.95229) (xy 296.793269 -279.986382) (xy 296.752766 -280.014338) (xy 296.708304 -280.035436)
			(xy 296.661033 -280.049128) (xy 296.612178 -280.05506) (xy 296.563003 -280.053079) (xy 296.514784 -280.043235)
			(xy 296.468768 -280.025783) (xy 296.426147 -280.001176) (xy 296.388026 -279.970051) (xy 296.355391 -279.933214)
			(xy 296.329088 -279.891618) (xy 296.309797 -279.846342) (xy 296.29802 -279.798558) (xy 296.29406 -279.749504)
			(xy 295.004998 -279.749504) (xy 295.004503 -279.774111) (xy 294.996608 -279.822688) (xy 294.981024 -279.869369)
			(xy 294.958153 -279.912946) (xy 294.928588 -279.95229) (xy 294.893095 -279.986382) (xy 294.852592 -280.014338)
			(xy 294.80813 -280.035436) (xy 294.760859 -280.049128) (xy 294.712004 -280.05506) (xy 294.662829 -280.053079)
			(xy 294.61461 -280.043235) (xy 294.568594 -280.025783) (xy 294.525973 -280.001176) (xy 294.487852 -279.970051)
			(xy 294.455217 -279.933214) (xy 294.428914 -279.891618) (xy 294.409623 -279.846342) (xy 294.397846 -279.798558)
			(xy 294.393886 -279.749504) (xy 293.105078 -279.749504) (xy 293.104583 -279.774111) (xy 293.096688 -279.822688)
			(xy 293.081104 -279.869369) (xy 293.058233 -279.912946) (xy 293.028668 -279.95229) (xy 292.993175 -279.986382)
			(xy 292.952672 -280.014338) (xy 292.90821 -280.035436) (xy 292.860939 -280.049128) (xy 292.812084 -280.05506)
			(xy 292.762909 -280.053079) (xy 292.71469 -280.043235) (xy 292.668674 -280.025783) (xy 292.626053 -280.001176)
			(xy 292.587932 -279.970051) (xy 292.555297 -279.933214) (xy 292.528994 -279.891618) (xy 292.509703 -279.846342)
			(xy 292.497926 -279.798558) (xy 292.493966 -279.749504) (xy 291.205158 -279.749504) (xy 291.204663 -279.774111)
			(xy 291.196768 -279.822688) (xy 291.181184 -279.869369) (xy 291.158313 -279.912946) (xy 291.128748 -279.95229)
			(xy 291.093255 -279.986382) (xy 291.052752 -280.014338) (xy 291.00829 -280.035436) (xy 290.961019 -280.049128)
			(xy 290.912164 -280.05506) (xy 290.862989 -280.053079) (xy 290.81477 -280.043235) (xy 290.768754 -280.025783)
			(xy 290.726133 -280.001176) (xy 290.688012 -279.970051) (xy 290.655377 -279.933214) (xy 290.629074 -279.891618)
			(xy 290.609783 -279.846342) (xy 290.598006 -279.798558) (xy 290.594046 -279.749504) (xy 289.304984 -279.749504)
			(xy 289.304489 -279.774111) (xy 289.296594 -279.822688) (xy 289.28101 -279.869369) (xy 289.258139 -279.912946)
			(xy 289.228574 -279.95229) (xy 289.193081 -279.986382) (xy 289.152578 -280.014338) (xy 289.108116 -280.035436)
			(xy 289.060845 -280.049128) (xy 289.01199 -280.05506) (xy 288.962815 -280.053079) (xy 288.914596 -280.043235)
			(xy 288.86858 -280.025783) (xy 288.825959 -280.001176) (xy 288.787838 -279.970051) (xy 288.755203 -279.933214)
			(xy 288.7289 -279.891618) (xy 288.709609 -279.846342) (xy 288.697832 -279.798558) (xy 288.693872 -279.749504)
			(xy 287.405064 -279.749504) (xy 287.404569 -279.774111) (xy 287.396674 -279.822688) (xy 287.38109 -279.869369)
			(xy 287.358219 -279.912946) (xy 287.328654 -279.95229) (xy 287.293161 -279.986382) (xy 287.252658 -280.014338)
			(xy 287.208196 -280.035436) (xy 287.160925 -280.049128) (xy 287.11207 -280.05506) (xy 287.062895 -280.053079)
			(xy 287.014676 -280.043235) (xy 286.96866 -280.025783) (xy 286.926039 -280.001176) (xy 286.887918 -279.970051)
			(xy 286.855283 -279.933214) (xy 286.82898 -279.891618) (xy 286.809689 -279.846342) (xy 286.797912 -279.798558)
			(xy 286.793952 -279.749504) (xy 285.505144 -279.749504) (xy 285.504649 -279.774111) (xy 285.496754 -279.822688)
			(xy 285.48117 -279.869369) (xy 285.458299 -279.912946) (xy 285.428734 -279.95229) (xy 285.393241 -279.986382)
			(xy 285.352738 -280.014338) (xy 285.308276 -280.035436) (xy 285.261005 -280.049128) (xy 285.21215 -280.05506)
			(xy 285.162975 -280.053079) (xy 285.114756 -280.043235) (xy 285.06874 -280.025783) (xy 285.026119 -280.001176)
			(xy 284.987998 -279.970051) (xy 284.955363 -279.933214) (xy 284.92906 -279.891618) (xy 284.909769 -279.846342)
			(xy 284.897992 -279.798558) (xy 284.894032 -279.749504) (xy 283.605224 -279.749504) (xy 283.604729 -279.774111)
			(xy 283.596834 -279.822688) (xy 283.58125 -279.869369) (xy 283.558379 -279.912946) (xy 283.528814 -279.95229)
			(xy 283.493321 -279.986382) (xy 283.452818 -280.014338) (xy 283.408356 -280.035436) (xy 283.361085 -280.049128)
			(xy 283.31223 -280.05506) (xy 283.263055 -280.053079) (xy 283.214836 -280.043235) (xy 283.16882 -280.025783)
			(xy 283.126199 -280.001176) (xy 283.088078 -279.970051) (xy 283.055443 -279.933214) (xy 283.02914 -279.891618)
			(xy 283.009849 -279.846342) (xy 282.998072 -279.798558) (xy 282.994112 -279.749504) (xy 281.70505 -279.749504)
			(xy 281.704555 -279.774111) (xy 281.69666 -279.822688) (xy 281.681076 -279.869369) (xy 281.658205 -279.912946)
			(xy 281.62864 -279.95229) (xy 281.593147 -279.986382) (xy 281.552644 -280.014338) (xy 281.508182 -280.035436)
			(xy 281.460911 -280.049128) (xy 281.412056 -280.05506) (xy 281.362881 -280.053079) (xy 281.314662 -280.043235)
			(xy 281.268646 -280.025783) (xy 281.226025 -280.001176) (xy 281.187904 -279.970051) (xy 281.155269 -279.933214)
			(xy 281.128966 -279.891618) (xy 281.109675 -279.846342) (xy 281.097898 -279.798558) (xy 281.093938 -279.749504)
			(xy 279.80513 -279.749504) (xy 279.804635 -279.774111) (xy 279.79674 -279.822688) (xy 279.781156 -279.869369)
			(xy 279.758285 -279.912946) (xy 279.72872 -279.95229) (xy 279.693227 -279.986382) (xy 279.652724 -280.014338)
			(xy 279.608262 -280.035436) (xy 279.560991 -280.049128) (xy 279.512136 -280.05506) (xy 279.462961 -280.053079)
			(xy 279.414742 -280.043235) (xy 279.368726 -280.025783) (xy 279.326105 -280.001176) (xy 279.287984 -279.970051)
			(xy 279.255349 -279.933214) (xy 279.229046 -279.891618) (xy 279.209755 -279.846342) (xy 279.197978 -279.798558)
			(xy 279.194018 -279.749504) (xy 277.90521 -279.749504) (xy 277.904715 -279.774111) (xy 277.89682 -279.822688)
			(xy 277.881236 -279.869369) (xy 277.858365 -279.912946) (xy 277.8288 -279.95229) (xy 277.793307 -279.986382)
			(xy 277.752804 -280.014338) (xy 277.708342 -280.035436) (xy 277.661071 -280.049128) (xy 277.612216 -280.05506)
			(xy 277.563041 -280.053079) (xy 277.514822 -280.043235) (xy 277.468806 -280.025783) (xy 277.426185 -280.001176)
			(xy 277.388064 -279.970051) (xy 277.355429 -279.933214) (xy 277.329126 -279.891618) (xy 277.309835 -279.846342)
			(xy 277.298058 -279.798558) (xy 277.294098 -279.749504) (xy 198.855325 -279.749504) (xy 198.85533 -279.749758)
			(xy 198.854835 -279.774365) (xy 198.84694 -279.822942) (xy 198.831356 -279.869623) (xy 198.808485 -279.9132)
			(xy 198.77892 -279.952544) (xy 198.743427 -279.986636) (xy 198.702924 -280.014592) (xy 198.658462 -280.03569)
			(xy 198.611191 -280.049382) (xy 198.562336 -280.055314) (xy 198.513161 -280.053333) (xy 198.464942 -280.043489)
			(xy 198.418926 -280.026037) (xy 198.376305 -280.00143) (xy 198.338184 -279.970305) (xy 198.305549 -279.933468)
			(xy 198.279246 -279.891872) (xy 198.259955 -279.846596) (xy 198.248178 -279.798812) (xy 198.244218 -279.749758)
			(xy 197.90537 -279.749758) (xy 197.904875 -279.774365) (xy 197.89698 -279.822942) (xy 197.881396 -279.869623)
			(xy 197.858525 -279.9132) (xy 197.82896 -279.952544) (xy 197.793467 -279.986636) (xy 197.752964 -280.014592)
			(xy 197.708502 -280.03569) (xy 197.661231 -280.049382) (xy 197.612376 -280.055314) (xy 197.563201 -280.053333)
			(xy 197.514982 -280.043489) (xy 197.468966 -280.026037) (xy 197.426345 -280.00143) (xy 197.388224 -279.970305)
			(xy 197.355589 -279.933468) (xy 197.329286 -279.891872) (xy 197.309995 -279.846596) (xy 197.298218 -279.798812)
			(xy 197.294258 -279.749758) (xy 196.005196 -279.749758) (xy 196.004701 -279.774365) (xy 195.996806 -279.822942)
			(xy 195.981222 -279.869623) (xy 195.958351 -279.9132) (xy 195.928786 -279.952544) (xy 195.893293 -279.986636)
			(xy 195.85279 -280.014592) (xy 195.808328 -280.03569) (xy 195.761057 -280.049382) (xy 195.712202 -280.055314)
			(xy 195.663027 -280.053333) (xy 195.614808 -280.043489) (xy 195.568792 -280.026037) (xy 195.526171 -280.00143)
			(xy 195.48805 -279.970305) (xy 195.455415 -279.933468) (xy 195.429112 -279.891872) (xy 195.409821 -279.846596)
			(xy 195.398044 -279.798812) (xy 195.394084 -279.749758) (xy 194.105271 -279.749758) (xy 194.104781 -279.774111)
			(xy 194.096886 -279.822688) (xy 194.081302 -279.869369) (xy 194.058431 -279.912946) (xy 194.028866 -279.95229)
			(xy 193.993373 -279.986382) (xy 193.95287 -280.014338) (xy 193.908408 -280.035436) (xy 193.861137 -280.049128)
			(xy 193.812282 -280.05506) (xy 193.763107 -280.053079) (xy 193.714888 -280.043235) (xy 193.668872 -280.025783)
			(xy 193.626251 -280.001176) (xy 193.58813 -279.970051) (xy 193.555495 -279.933214) (xy 193.529192 -279.891618)
			(xy 193.509901 -279.846342) (xy 193.498124 -279.798558) (xy 193.494164 -279.749504) (xy 192.205356 -279.749504)
			(xy 192.204861 -279.774111) (xy 192.196966 -279.822688) (xy 192.181382 -279.869369) (xy 192.158511 -279.912946)
			(xy 192.128946 -279.95229) (xy 192.093453 -279.986382) (xy 192.05295 -280.014338) (xy 192.008488 -280.035436)
			(xy 191.961217 -280.049128) (xy 191.912362 -280.05506) (xy 191.863187 -280.053079) (xy 191.814968 -280.043235)
			(xy 191.768952 -280.025783) (xy 191.726331 -280.001176) (xy 191.68821 -279.970051) (xy 191.655575 -279.933214)
			(xy 191.629272 -279.891618) (xy 191.609981 -279.846342) (xy 191.598204 -279.798558) (xy 191.594244 -279.749504)
			(xy 190.305182 -279.749504) (xy 190.304687 -279.774111) (xy 190.296792 -279.822688) (xy 190.281208 -279.869369)
			(xy 190.258337 -279.912946) (xy 190.228772 -279.95229) (xy 190.193279 -279.986382) (xy 190.152776 -280.014338)
			(xy 190.108314 -280.035436) (xy 190.061043 -280.049128) (xy 190.012188 -280.05506) (xy 189.963013 -280.053079)
			(xy 189.914794 -280.043235) (xy 189.868778 -280.025783) (xy 189.826157 -280.001176) (xy 189.788036 -279.970051)
			(xy 189.755401 -279.933214) (xy 189.729098 -279.891618) (xy 189.709807 -279.846342) (xy 189.69803 -279.798558)
			(xy 189.69407 -279.749504) (xy 188.405262 -279.749504) (xy 188.404767 -279.774111) (xy 188.396872 -279.822688)
			(xy 188.381288 -279.869369) (xy 188.358417 -279.912946) (xy 188.328852 -279.95229) (xy 188.293359 -279.986382)
			(xy 188.252856 -280.014338) (xy 188.208394 -280.035436) (xy 188.161123 -280.049128) (xy 188.112268 -280.05506)
			(xy 188.063093 -280.053079) (xy 188.014874 -280.043235) (xy 187.968858 -280.025783) (xy 187.926237 -280.001176)
			(xy 187.888116 -279.970051) (xy 187.855481 -279.933214) (xy 187.829178 -279.891618) (xy 187.809887 -279.846342)
			(xy 187.79811 -279.798558) (xy 187.79415 -279.749504) (xy 186.505342 -279.749504) (xy 186.504847 -279.774111)
			(xy 186.496952 -279.822688) (xy 186.481368 -279.869369) (xy 186.458497 -279.912946) (xy 186.428932 -279.95229)
			(xy 186.393439 -279.986382) (xy 186.352936 -280.014338) (xy 186.308474 -280.035436) (xy 186.261203 -280.049128)
			(xy 186.212348 -280.05506) (xy 186.163173 -280.053079) (xy 186.114954 -280.043235) (xy 186.068938 -280.025783)
			(xy 186.026317 -280.001176) (xy 185.988196 -279.970051) (xy 185.955561 -279.933214) (xy 185.929258 -279.891618)
			(xy 185.909967 -279.846342) (xy 185.89819 -279.798558) (xy 185.89423 -279.749504) (xy 184.605168 -279.749504)
			(xy 184.604673 -279.774111) (xy 184.596778 -279.822688) (xy 184.581194 -279.869369) (xy 184.558323 -279.912946)
			(xy 184.528758 -279.95229) (xy 184.493265 -279.986382) (xy 184.452762 -280.014338) (xy 184.4083 -280.035436)
			(xy 184.361029 -280.049128) (xy 184.312174 -280.05506) (xy 184.262999 -280.053079) (xy 184.21478 -280.043235)
			(xy 184.168764 -280.025783) (xy 184.126143 -280.001176) (xy 184.088022 -279.970051) (xy 184.055387 -279.933214)
			(xy 184.029084 -279.891618) (xy 184.009793 -279.846342) (xy 183.998016 -279.798558) (xy 183.994056 -279.749504)
			(xy 182.705248 -279.749504) (xy 182.704753 -279.774111) (xy 182.696858 -279.822688) (xy 182.681274 -279.869369)
			(xy 182.658403 -279.912946) (xy 182.628838 -279.95229) (xy 182.593345 -279.986382) (xy 182.552842 -280.014338)
			(xy 182.50838 -280.035436) (xy 182.461109 -280.049128) (xy 182.412254 -280.05506) (xy 182.363079 -280.053079)
			(xy 182.31486 -280.043235) (xy 182.268844 -280.025783) (xy 182.226223 -280.001176) (xy 182.188102 -279.970051)
			(xy 182.155467 -279.933214) (xy 182.129164 -279.891618) (xy 182.109873 -279.846342) (xy 182.098096 -279.798558)
			(xy 182.094136 -279.749504) (xy 180.805328 -279.749504) (xy 180.804833 -279.774111) (xy 180.796938 -279.822688)
			(xy 180.781354 -279.869369) (xy 180.758483 -279.912946) (xy 180.728918 -279.95229) (xy 180.693425 -279.986382)
			(xy 180.652922 -280.014338) (xy 180.60846 -280.035436) (xy 180.561189 -280.049128) (xy 180.512334 -280.05506)
			(xy 180.463159 -280.053079) (xy 180.41494 -280.043235) (xy 180.368924 -280.025783) (xy 180.326303 -280.001176)
			(xy 180.288182 -279.970051) (xy 180.255547 -279.933214) (xy 180.229244 -279.891618) (xy 180.209953 -279.846342)
			(xy 180.198176 -279.798558) (xy 180.194216 -279.749504) (xy 178.905154 -279.749504) (xy 178.904659 -279.774111)
			(xy 178.896764 -279.822688) (xy 178.88118 -279.869369) (xy 178.858309 -279.912946) (xy 178.828744 -279.95229)
			(xy 178.793251 -279.986382) (xy 178.752748 -280.014338) (xy 178.708286 -280.035436) (xy 178.661015 -280.049128)
			(xy 178.61216 -280.05506) (xy 178.562985 -280.053079) (xy 178.514766 -280.043235) (xy 178.46875 -280.025783)
			(xy 178.426129 -280.001176) (xy 178.388008 -279.970051) (xy 178.355373 -279.933214) (xy 178.32907 -279.891618)
			(xy 178.309779 -279.846342) (xy 178.298002 -279.798558) (xy 178.294042 -279.749504) (xy 177.005234 -279.749504)
			(xy 177.004739 -279.774111) (xy 176.996844 -279.822688) (xy 176.98126 -279.869369) (xy 176.958389 -279.912946)
			(xy 176.928824 -279.95229) (xy 176.893331 -279.986382) (xy 176.852828 -280.014338) (xy 176.808366 -280.035436)
			(xy 176.761095 -280.049128) (xy 176.71224 -280.05506) (xy 176.663065 -280.053079) (xy 176.614846 -280.043235)
			(xy 176.56883 -280.025783) (xy 176.526209 -280.001176) (xy 176.488088 -279.970051) (xy 176.455453 -279.933214)
			(xy 176.42915 -279.891618) (xy 176.409859 -279.846342) (xy 176.398082 -279.798558) (xy 176.394122 -279.749504)
			(xy 175.105314 -279.749504) (xy 175.104819 -279.774111) (xy 175.096924 -279.822688) (xy 175.08134 -279.869369)
			(xy 175.058469 -279.912946) (xy 175.028904 -279.95229) (xy 174.993411 -279.986382) (xy 174.952908 -280.014338)
			(xy 174.908446 -280.035436) (xy 174.861175 -280.049128) (xy 174.81232 -280.05506) (xy 174.763145 -280.053079)
			(xy 174.714926 -280.043235) (xy 174.66891 -280.025783) (xy 174.626289 -280.001176) (xy 174.588168 -279.970051)
			(xy 174.555533 -279.933214) (xy 174.52923 -279.891618) (xy 174.509939 -279.846342) (xy 174.498162 -279.798558)
			(xy 174.494202 -279.749504) (xy 173.20514 -279.749504) (xy 173.204645 -279.774111) (xy 173.19675 -279.822688)
			(xy 173.181166 -279.869369) (xy 173.158295 -279.912946) (xy 173.12873 -279.95229) (xy 173.093237 -279.986382)
			(xy 173.052734 -280.014338) (xy 173.008272 -280.035436) (xy 172.961001 -280.049128) (xy 172.912146 -280.05506)
			(xy 172.862971 -280.053079) (xy 172.814752 -280.043235) (xy 172.768736 -280.025783) (xy 172.726115 -280.001176)
			(xy 172.687994 -279.970051) (xy 172.655359 -279.933214) (xy 172.629056 -279.891618) (xy 172.609765 -279.846342)
			(xy 172.597988 -279.798558) (xy 172.594028 -279.749504) (xy 171.30522 -279.749504) (xy 171.304725 -279.774111)
			(xy 171.29683 -279.822688) (xy 171.281246 -279.869369) (xy 171.258375 -279.912946) (xy 171.22881 -279.95229)
			(xy 171.193317 -279.986382) (xy 171.152814 -280.014338) (xy 171.108352 -280.035436) (xy 171.061081 -280.049128)
			(xy 171.012226 -280.05506) (xy 170.963051 -280.053079) (xy 170.914832 -280.043235) (xy 170.868816 -280.025783)
			(xy 170.826195 -280.001176) (xy 170.788074 -279.970051) (xy 170.755439 -279.933214) (xy 170.729136 -279.891618)
			(xy 170.709845 -279.846342) (xy 170.698068 -279.798558) (xy 170.694108 -279.749504) (xy 169.4053 -279.749504)
			(xy 169.404805 -279.774111) (xy 169.39691 -279.822688) (xy 169.381326 -279.869369) (xy 169.358455 -279.912946)
			(xy 169.32889 -279.95229) (xy 169.293397 -279.986382) (xy 169.252894 -280.014338) (xy 169.208432 -280.035436)
			(xy 169.161161 -280.049128) (xy 169.112306 -280.05506) (xy 169.063131 -280.053079) (xy 169.014912 -280.043235)
			(xy 168.968896 -280.025783) (xy 168.926275 -280.001176) (xy 168.888154 -279.970051) (xy 168.855519 -279.933214)
			(xy 168.829216 -279.891618) (xy 168.809925 -279.846342) (xy 168.798148 -279.798558) (xy 168.794188 -279.749504)
			(xy 167.50538 -279.749504) (xy 167.504885 -279.774111) (xy 167.49699 -279.822688) (xy 167.481406 -279.869369)
			(xy 167.458535 -279.912946) (xy 167.42897 -279.95229) (xy 167.393477 -279.986382) (xy 167.352974 -280.014338)
			(xy 167.308512 -280.035436) (xy 167.261241 -280.049128) (xy 167.212386 -280.05506) (xy 167.163211 -280.053079)
			(xy 167.114992 -280.043235) (xy 167.068976 -280.025783) (xy 167.026355 -280.001176) (xy 166.988234 -279.970051)
			(xy 166.955599 -279.933214) (xy 166.929296 -279.891618) (xy 166.910005 -279.846342) (xy 166.898228 -279.798558)
			(xy 166.894268 -279.749504) (xy 165.605206 -279.749504) (xy 165.604711 -279.774111) (xy 165.596816 -279.822688)
			(xy 165.581232 -279.869369) (xy 165.558361 -279.912946) (xy 165.528796 -279.95229) (xy 165.493303 -279.986382)
			(xy 165.4528 -280.014338) (xy 165.408338 -280.035436) (xy 165.361067 -280.049128) (xy 165.312212 -280.05506)
			(xy 165.263037 -280.053079) (xy 165.214818 -280.043235) (xy 165.168802 -280.025783) (xy 165.126181 -280.001176)
			(xy 165.08806 -279.970051) (xy 165.055425 -279.933214) (xy 165.029122 -279.891618) (xy 165.009831 -279.846342)
			(xy 164.998054 -279.798558) (xy 164.994094 -279.749504) (xy 163.705286 -279.749504) (xy 163.704791 -279.774111)
			(xy 163.696896 -279.822688) (xy 163.681312 -279.869369) (xy 163.658441 -279.912946) (xy 163.628876 -279.95229)
			(xy 163.593383 -279.986382) (xy 163.55288 -280.014338) (xy 163.508418 -280.035436) (xy 163.461147 -280.049128)
			(xy 163.412292 -280.05506) (xy 163.363117 -280.053079) (xy 163.314898 -280.043235) (xy 163.268882 -280.025783)
			(xy 163.226261 -280.001176) (xy 163.18814 -279.970051) (xy 163.155505 -279.933214) (xy 163.129202 -279.891618)
			(xy 163.109911 -279.846342) (xy 163.098134 -279.798558) (xy 163.094174 -279.749504) (xy 161.805366 -279.749504)
			(xy 161.804871 -279.774111) (xy 161.796976 -279.822688) (xy 161.781392 -279.869369) (xy 161.758521 -279.912946)
			(xy 161.728956 -279.95229) (xy 161.693463 -279.986382) (xy 161.65296 -280.014338) (xy 161.608498 -280.035436)
			(xy 161.561227 -280.049128) (xy 161.512372 -280.05506) (xy 161.463197 -280.053079) (xy 161.414978 -280.043235)
			(xy 161.368962 -280.025783) (xy 161.326341 -280.001176) (xy 161.28822 -279.970051) (xy 161.255585 -279.933214)
			(xy 161.229282 -279.891618) (xy 161.209991 -279.846342) (xy 161.198214 -279.798558) (xy 161.194254 -279.749504)
			(xy 82.755227 -279.749504) (xy 82.755232 -279.749758) (xy 82.754737 -279.774365) (xy 82.746842 -279.822942)
			(xy 82.731258 -279.869623) (xy 82.708387 -279.9132) (xy 82.678822 -279.952544) (xy 82.643329 -279.986636)
			(xy 82.602826 -280.014592) (xy 82.558364 -280.03569) (xy 82.511093 -280.049382) (xy 82.462238 -280.055314)
			(xy 82.413063 -280.053333) (xy 82.364844 -280.043489) (xy 82.318828 -280.026037) (xy 82.276207 -280.00143)
			(xy 82.238086 -279.970305) (xy 82.205451 -279.933468) (xy 82.179148 -279.891872) (xy 82.159857 -279.846596)
			(xy 82.14808 -279.798812) (xy 82.14412 -279.749758) (xy 81.805272 -279.749758) (xy 81.804777 -279.774365)
			(xy 81.796882 -279.822942) (xy 81.781298 -279.869623) (xy 81.758427 -279.9132) (xy 81.728862 -279.952544)
			(xy 81.693369 -279.986636) (xy 81.652866 -280.014592) (xy 81.608404 -280.03569) (xy 81.561133 -280.049382)
			(xy 81.512278 -280.055314) (xy 81.463103 -280.053333) (xy 81.414884 -280.043489) (xy 81.368868 -280.026037)
			(xy 81.326247 -280.00143) (xy 81.288126 -279.970305) (xy 81.255491 -279.933468) (xy 81.229188 -279.891872)
			(xy 81.209897 -279.846596) (xy 81.19812 -279.798812) (xy 81.19416 -279.749758) (xy 79.905098 -279.749758)
			(xy 79.904603 -279.774365) (xy 79.896708 -279.822942) (xy 79.881124 -279.869623) (xy 79.858253 -279.9132)
			(xy 79.828688 -279.952544) (xy 79.793195 -279.986636) (xy 79.752692 -280.014592) (xy 79.70823 -280.03569)
			(xy 79.660959 -280.049382) (xy 79.612104 -280.055314) (xy 79.562929 -280.053333) (xy 79.51471 -280.043489)
			(xy 79.468694 -280.026037) (xy 79.426073 -280.00143) (xy 79.387952 -279.970305) (xy 79.355317 -279.933468)
			(xy 79.329014 -279.891872) (xy 79.309723 -279.846596) (xy 79.297946 -279.798812) (xy 79.293986 -279.749758)
			(xy 78.005173 -279.749758) (xy 78.004683 -279.774111) (xy 77.996788 -279.822688) (xy 77.981204 -279.869369)
			(xy 77.958333 -279.912946) (xy 77.928768 -279.95229) (xy 77.893275 -279.986382) (xy 77.852772 -280.014338)
			(xy 77.80831 -280.035436) (xy 77.761039 -280.049128) (xy 77.712184 -280.05506) (xy 77.663009 -280.053079)
			(xy 77.61479 -280.043235) (xy 77.568774 -280.025783) (xy 77.526153 -280.001176) (xy 77.488032 -279.970051)
			(xy 77.455397 -279.933214) (xy 77.429094 -279.891618) (xy 77.409803 -279.846342) (xy 77.398026 -279.798558)
			(xy 77.394066 -279.749504) (xy 76.105258 -279.749504) (xy 76.104763 -279.774111) (xy 76.096868 -279.822688)
			(xy 76.081284 -279.869369) (xy 76.058413 -279.912946) (xy 76.028848 -279.95229) (xy 75.993355 -279.986382)
			(xy 75.952852 -280.014338) (xy 75.90839 -280.035436) (xy 75.861119 -280.049128) (xy 75.812264 -280.05506)
			(xy 75.763089 -280.053079) (xy 75.71487 -280.043235) (xy 75.668854 -280.025783) (xy 75.626233 -280.001176)
			(xy 75.588112 -279.970051) (xy 75.555477 -279.933214) (xy 75.529174 -279.891618) (xy 75.509883 -279.846342)
			(xy 75.498106 -279.798558) (xy 75.494146 -279.749504) (xy 74.205084 -279.749504) (xy 74.204589 -279.774111)
			(xy 74.196694 -279.822688) (xy 74.18111 -279.869369) (xy 74.158239 -279.912946) (xy 74.128674 -279.95229)
			(xy 74.093181 -279.986382) (xy 74.052678 -280.014338) (xy 74.008216 -280.035436) (xy 73.960945 -280.049128)
			(xy 73.91209 -280.05506) (xy 73.862915 -280.053079) (xy 73.814696 -280.043235) (xy 73.76868 -280.025783)
			(xy 73.726059 -280.001176) (xy 73.687938 -279.970051) (xy 73.655303 -279.933214) (xy 73.629 -279.891618)
			(xy 73.609709 -279.846342) (xy 73.597932 -279.798558) (xy 73.593972 -279.749504) (xy 72.305164 -279.749504)
			(xy 72.304669 -279.774111) (xy 72.296774 -279.822688) (xy 72.28119 -279.869369) (xy 72.258319 -279.912946)
			(xy 72.228754 -279.95229) (xy 72.193261 -279.986382) (xy 72.152758 -280.014338) (xy 72.108296 -280.035436)
			(xy 72.061025 -280.049128) (xy 72.01217 -280.05506) (xy 71.962995 -280.053079) (xy 71.914776 -280.043235)
			(xy 71.86876 -280.025783) (xy 71.826139 -280.001176) (xy 71.788018 -279.970051) (xy 71.755383 -279.933214)
			(xy 71.72908 -279.891618) (xy 71.709789 -279.846342) (xy 71.698012 -279.798558) (xy 71.694052 -279.749504)
			(xy 70.405244 -279.749504) (xy 70.404749 -279.774111) (xy 70.396854 -279.822688) (xy 70.38127 -279.869369)
			(xy 70.358399 -279.912946) (xy 70.328834 -279.95229) (xy 70.293341 -279.986382) (xy 70.252838 -280.014338)
			(xy 70.208376 -280.035436) (xy 70.161105 -280.049128) (xy 70.11225 -280.05506) (xy 70.063075 -280.053079)
			(xy 70.014856 -280.043235) (xy 69.96884 -280.025783) (xy 69.926219 -280.001176) (xy 69.888098 -279.970051)
			(xy 69.855463 -279.933214) (xy 69.82916 -279.891618) (xy 69.809869 -279.846342) (xy 69.798092 -279.798558)
			(xy 69.794132 -279.749504) (xy 68.50507 -279.749504) (xy 68.504575 -279.774111) (xy 68.49668 -279.822688)
			(xy 68.481096 -279.869369) (xy 68.458225 -279.912946) (xy 68.42866 -279.95229) (xy 68.393167 -279.986382)
			(xy 68.352664 -280.014338) (xy 68.308202 -280.035436) (xy 68.260931 -280.049128) (xy 68.212076 -280.05506)
			(xy 68.162901 -280.053079) (xy 68.114682 -280.043235) (xy 68.068666 -280.025783) (xy 68.026045 -280.001176)
			(xy 67.987924 -279.970051) (xy 67.955289 -279.933214) (xy 67.928986 -279.891618) (xy 67.909695 -279.846342)
			(xy 67.897918 -279.798558) (xy 67.893958 -279.749504) (xy 66.60515 -279.749504) (xy 66.604655 -279.774111)
			(xy 66.59676 -279.822688) (xy 66.581176 -279.869369) (xy 66.558305 -279.912946) (xy 66.52874 -279.95229)
			(xy 66.493247 -279.986382) (xy 66.452744 -280.014338) (xy 66.408282 -280.035436) (xy 66.361011 -280.049128)
			(xy 66.312156 -280.05506) (xy 66.262981 -280.053079) (xy 66.214762 -280.043235) (xy 66.168746 -280.025783)
			(xy 66.126125 -280.001176) (xy 66.088004 -279.970051) (xy 66.055369 -279.933214) (xy 66.029066 -279.891618)
			(xy 66.009775 -279.846342) (xy 65.997998 -279.798558) (xy 65.994038 -279.749504) (xy 64.70523 -279.749504)
			(xy 64.704735 -279.774111) (xy 64.69684 -279.822688) (xy 64.681256 -279.869369) (xy 64.658385 -279.912946)
			(xy 64.62882 -279.95229) (xy 64.593327 -279.986382) (xy 64.552824 -280.014338) (xy 64.508362 -280.035436)
			(xy 64.461091 -280.049128) (xy 64.412236 -280.05506) (xy 64.363061 -280.053079) (xy 64.314842 -280.043235)
			(xy 64.268826 -280.025783) (xy 64.226205 -280.001176) (xy 64.188084 -279.970051) (xy 64.155449 -279.933214)
			(xy 64.129146 -279.891618) (xy 64.109855 -279.846342) (xy 64.098078 -279.798558) (xy 64.094118 -279.749504)
			(xy 62.805056 -279.749504) (xy 62.804561 -279.774111) (xy 62.796666 -279.822688) (xy 62.781082 -279.869369)
			(xy 62.758211 -279.912946) (xy 62.728646 -279.95229) (xy 62.693153 -279.986382) (xy 62.65265 -280.014338)
			(xy 62.608188 -280.035436) (xy 62.560917 -280.049128) (xy 62.512062 -280.05506) (xy 62.462887 -280.053079)
			(xy 62.414668 -280.043235) (xy 62.368652 -280.025783) (xy 62.326031 -280.001176) (xy 62.28791 -279.970051)
			(xy 62.255275 -279.933214) (xy 62.228972 -279.891618) (xy 62.209681 -279.846342) (xy 62.197904 -279.798558)
			(xy 62.193944 -279.749504) (xy 60.905136 -279.749504) (xy 60.904641 -279.774111) (xy 60.896746 -279.822688)
			(xy 60.881162 -279.869369) (xy 60.858291 -279.912946) (xy 60.828726 -279.95229) (xy 60.793233 -279.986382)
			(xy 60.75273 -280.014338) (xy 60.708268 -280.035436) (xy 60.660997 -280.049128) (xy 60.612142 -280.05506)
			(xy 60.562967 -280.053079) (xy 60.514748 -280.043235) (xy 60.468732 -280.025783) (xy 60.426111 -280.001176)
			(xy 60.38799 -279.970051) (xy 60.355355 -279.933214) (xy 60.329052 -279.891618) (xy 60.309761 -279.846342)
			(xy 60.297984 -279.798558) (xy 60.294024 -279.749504) (xy 59.005216 -279.749504) (xy 59.004721 -279.774111)
			(xy 58.996826 -279.822688) (xy 58.981242 -279.869369) (xy 58.958371 -279.912946) (xy 58.928806 -279.95229)
			(xy 58.893313 -279.986382) (xy 58.85281 -280.014338) (xy 58.808348 -280.035436) (xy 58.761077 -280.049128)
			(xy 58.712222 -280.05506) (xy 58.663047 -280.053079) (xy 58.614828 -280.043235) (xy 58.568812 -280.025783)
			(xy 58.526191 -280.001176) (xy 58.48807 -279.970051) (xy 58.455435 -279.933214) (xy 58.429132 -279.891618)
			(xy 58.409841 -279.846342) (xy 58.398064 -279.798558) (xy 58.394104 -279.749504) (xy 57.105042 -279.749504)
			(xy 57.104547 -279.774111) (xy 57.096652 -279.822688) (xy 57.081068 -279.869369) (xy 57.058197 -279.912946)
			(xy 57.028632 -279.95229) (xy 56.993139 -279.986382) (xy 56.952636 -280.014338) (xy 56.908174 -280.035436)
			(xy 56.860903 -280.049128) (xy 56.812048 -280.05506) (xy 56.762873 -280.053079) (xy 56.714654 -280.043235)
			(xy 56.668638 -280.025783) (xy 56.626017 -280.001176) (xy 56.587896 -279.970051) (xy 56.555261 -279.933214)
			(xy 56.528958 -279.891618) (xy 56.509667 -279.846342) (xy 56.49789 -279.798558) (xy 56.49393 -279.749504)
			(xy 55.205122 -279.749504) (xy 55.204627 -279.774111) (xy 55.196732 -279.822688) (xy 55.181148 -279.869369)
			(xy 55.158277 -279.912946) (xy 55.128712 -279.95229) (xy 55.093219 -279.986382) (xy 55.052716 -280.014338)
			(xy 55.008254 -280.035436) (xy 54.960983 -280.049128) (xy 54.912128 -280.05506) (xy 54.862953 -280.053079)
			(xy 54.814734 -280.043235) (xy 54.768718 -280.025783) (xy 54.726097 -280.001176) (xy 54.687976 -279.970051)
			(xy 54.655341 -279.933214) (xy 54.629038 -279.891618) (xy 54.609747 -279.846342) (xy 54.59797 -279.798558)
			(xy 54.59401 -279.749504) (xy 53.305202 -279.749504) (xy 53.304707 -279.774111) (xy 53.296812 -279.822688)
			(xy 53.281228 -279.869369) (xy 53.258357 -279.912946) (xy 53.228792 -279.95229) (xy 53.193299 -279.986382)
			(xy 53.152796 -280.014338) (xy 53.108334 -280.035436) (xy 53.061063 -280.049128) (xy 53.012208 -280.05506)
			(xy 52.963033 -280.053079) (xy 52.914814 -280.043235) (xy 52.868798 -280.025783) (xy 52.826177 -280.001176)
			(xy 52.788056 -279.970051) (xy 52.755421 -279.933214) (xy 52.729118 -279.891618) (xy 52.709827 -279.846342)
			(xy 52.69805 -279.798558) (xy 52.69409 -279.749504) (xy 51.405282 -279.749504) (xy 51.404787 -279.774111)
			(xy 51.396892 -279.822688) (xy 51.381308 -279.869369) (xy 51.358437 -279.912946) (xy 51.328872 -279.95229)
			(xy 51.293379 -279.986382) (xy 51.252876 -280.014338) (xy 51.208414 -280.035436) (xy 51.161143 -280.049128)
			(xy 51.112288 -280.05506) (xy 51.063113 -280.053079) (xy 51.014894 -280.043235) (xy 50.968878 -280.025783)
			(xy 50.926257 -280.001176) (xy 50.888136 -279.970051) (xy 50.855501 -279.933214) (xy 50.829198 -279.891618)
			(xy 50.809907 -279.846342) (xy 50.79813 -279.798558) (xy 50.79417 -279.749504) (xy 49.505108 -279.749504)
			(xy 49.504613 -279.774111) (xy 49.496718 -279.822688) (xy 49.481134 -279.869369) (xy 49.458263 -279.912946)
			(xy 49.428698 -279.95229) (xy 49.393205 -279.986382) (xy 49.352702 -280.014338) (xy 49.30824 -280.035436)
			(xy 49.260969 -280.049128) (xy 49.212114 -280.05506) (xy 49.162939 -280.053079) (xy 49.11472 -280.043235)
			(xy 49.068704 -280.025783) (xy 49.026083 -280.001176) (xy 48.987962 -279.970051) (xy 48.955327 -279.933214)
			(xy 48.929024 -279.891618) (xy 48.909733 -279.846342) (xy 48.897956 -279.798558) (xy 48.893996 -279.749504)
			(xy 47.605188 -279.749504) (xy 47.604693 -279.774111) (xy 47.596798 -279.822688) (xy 47.581214 -279.869369)
			(xy 47.558343 -279.912946) (xy 47.528778 -279.95229) (xy 47.493285 -279.986382) (xy 47.452782 -280.014338)
			(xy 47.40832 -280.035436) (xy 47.361049 -280.049128) (xy 47.312194 -280.05506) (xy 47.263019 -280.053079)
			(xy 47.2148 -280.043235) (xy 47.168784 -280.025783) (xy 47.126163 -280.001176) (xy 47.088042 -279.970051)
			(xy 47.055407 -279.933214) (xy 47.029104 -279.891618) (xy 47.009813 -279.846342) (xy 46.998036 -279.798558)
			(xy 46.994076 -279.749504) (xy 45.705268 -279.749504) (xy 45.704773 -279.774111) (xy 45.696878 -279.822688)
			(xy 45.681294 -279.869369) (xy 45.658423 -279.912946) (xy 45.628858 -279.95229) (xy 45.593365 -279.986382)
			(xy 45.552862 -280.014338) (xy 45.5084 -280.035436) (xy 45.461129 -280.049128) (xy 45.412274 -280.05506)
			(xy 45.363099 -280.053079) (xy 45.31488 -280.043235) (xy 45.268864 -280.025783) (xy 45.226243 -280.001176)
			(xy 45.188122 -279.970051) (xy 45.155487 -279.933214) (xy 45.129184 -279.891618) (xy 45.109893 -279.846342)
			(xy 45.098116 -279.798558) (xy 45.094156 -279.749504) (xy 0.509016 -279.749504) (xy 0.509016 -280.699718)
			(xy 45.094156 -280.699718) (xy 45.098116 -280.650664) (xy 45.109893 -280.60288) (xy 45.129184 -280.557604)
			(xy 45.155487 -280.516008) (xy 45.188122 -280.479171) (xy 45.226243 -280.448046) (xy 45.268864 -280.423439)
			(xy 45.31488 -280.405987) (xy 45.363099 -280.396143) (xy 45.412274 -280.394162) (xy 45.461129 -280.400094)
			(xy 45.5084 -280.413786) (xy 45.552862 -280.434884) (xy 45.593365 -280.46284) (xy 45.628858 -280.496932)
			(xy 45.658423 -280.536276) (xy 45.681294 -280.579853) (xy 45.696878 -280.626534) (xy 45.704773 -280.675111)
			(xy 45.705268 -280.699718) (xy 46.994076 -280.699718) (xy 46.998036 -280.650664) (xy 47.009813 -280.60288)
			(xy 47.029104 -280.557604) (xy 47.055407 -280.516008) (xy 47.088042 -280.479171) (xy 47.126163 -280.448046)
			(xy 47.168784 -280.423439) (xy 47.2148 -280.405987) (xy 47.263019 -280.396143) (xy 47.312194 -280.394162)
			(xy 47.361049 -280.400094) (xy 47.40832 -280.413786) (xy 47.452782 -280.434884) (xy 47.493285 -280.46284)
			(xy 47.528778 -280.496932) (xy 47.558343 -280.536276) (xy 47.581214 -280.579853) (xy 47.596798 -280.626534)
			(xy 47.604693 -280.675111) (xy 47.605188 -280.699718) (xy 48.893996 -280.699718) (xy 48.897956 -280.650664)
			(xy 48.909733 -280.60288) (xy 48.929024 -280.557604) (xy 48.955327 -280.516008) (xy 48.987962 -280.479171)
			(xy 49.026083 -280.448046) (xy 49.068704 -280.423439) (xy 49.11472 -280.405987) (xy 49.162939 -280.396143)
			(xy 49.212114 -280.394162) (xy 49.260969 -280.400094) (xy 49.30824 -280.413786) (xy 49.352702 -280.434884)
			(xy 49.393205 -280.46284) (xy 49.428698 -280.496932) (xy 49.458263 -280.536276) (xy 49.481134 -280.579853)
			(xy 49.496718 -280.626534) (xy 49.504613 -280.675111) (xy 49.505108 -280.699718) (xy 50.79417 -280.699718)
			(xy 50.79813 -280.650664) (xy 50.809907 -280.60288) (xy 50.829198 -280.557604) (xy 50.855501 -280.516008)
			(xy 50.888136 -280.479171) (xy 50.926257 -280.448046) (xy 50.968878 -280.423439) (xy 51.014894 -280.405987)
			(xy 51.063113 -280.396143) (xy 51.112288 -280.394162) (xy 51.161143 -280.400094) (xy 51.208414 -280.413786)
			(xy 51.252876 -280.434884) (xy 51.293379 -280.46284) (xy 51.328872 -280.496932) (xy 51.358437 -280.536276)
			(xy 51.381308 -280.579853) (xy 51.396892 -280.626534) (xy 51.404787 -280.675111) (xy 51.405282 -280.699718)
			(xy 52.69409 -280.699718) (xy 52.69805 -280.650664) (xy 52.709827 -280.60288) (xy 52.729118 -280.557604)
			(xy 52.755421 -280.516008) (xy 52.788056 -280.479171) (xy 52.826177 -280.448046) (xy 52.868798 -280.423439)
			(xy 52.914814 -280.405987) (xy 52.963033 -280.396143) (xy 53.012208 -280.394162) (xy 53.061063 -280.400094)
			(xy 53.108334 -280.413786) (xy 53.152796 -280.434884) (xy 53.193299 -280.46284) (xy 53.228792 -280.496932)
			(xy 53.258357 -280.536276) (xy 53.281228 -280.579853) (xy 53.296812 -280.626534) (xy 53.304707 -280.675111)
			(xy 53.305202 -280.699718) (xy 54.59401 -280.699718) (xy 54.59797 -280.650664) (xy 54.609747 -280.60288)
			(xy 54.629038 -280.557604) (xy 54.655341 -280.516008) (xy 54.687976 -280.479171) (xy 54.726097 -280.448046)
			(xy 54.768718 -280.423439) (xy 54.814734 -280.405987) (xy 54.862953 -280.396143) (xy 54.912128 -280.394162)
			(xy 54.960983 -280.400094) (xy 55.008254 -280.413786) (xy 55.052716 -280.434884) (xy 55.093219 -280.46284)
			(xy 55.128712 -280.496932) (xy 55.158277 -280.536276) (xy 55.181148 -280.579853) (xy 55.196732 -280.626534)
			(xy 55.204627 -280.675111) (xy 55.205122 -280.699718) (xy 56.49393 -280.699718) (xy 56.49789 -280.650664)
			(xy 56.509667 -280.60288) (xy 56.528958 -280.557604) (xy 56.555261 -280.516008) (xy 56.587896 -280.479171)
			(xy 56.626017 -280.448046) (xy 56.668638 -280.423439) (xy 56.714654 -280.405987) (xy 56.762873 -280.396143)
			(xy 56.812048 -280.394162) (xy 56.860903 -280.400094) (xy 56.908174 -280.413786) (xy 56.952636 -280.434884)
			(xy 56.993139 -280.46284) (xy 57.028632 -280.496932) (xy 57.058197 -280.536276) (xy 57.081068 -280.579853)
			(xy 57.096652 -280.626534) (xy 57.104547 -280.675111) (xy 57.105042 -280.699718) (xy 58.394104 -280.699718)
			(xy 58.398064 -280.650664) (xy 58.409841 -280.60288) (xy 58.429132 -280.557604) (xy 58.455435 -280.516008)
			(xy 58.48807 -280.479171) (xy 58.526191 -280.448046) (xy 58.568812 -280.423439) (xy 58.614828 -280.405987)
			(xy 58.663047 -280.396143) (xy 58.712222 -280.394162) (xy 58.761077 -280.400094) (xy 58.808348 -280.413786)
			(xy 58.85281 -280.434884) (xy 58.893313 -280.46284) (xy 58.928806 -280.496932) (xy 58.958371 -280.536276)
			(xy 58.981242 -280.579853) (xy 58.996826 -280.626534) (xy 59.004721 -280.675111) (xy 59.005216 -280.699718)
			(xy 60.294024 -280.699718) (xy 60.297984 -280.650664) (xy 60.309761 -280.60288) (xy 60.329052 -280.557604)
			(xy 60.355355 -280.516008) (xy 60.38799 -280.479171) (xy 60.426111 -280.448046) (xy 60.468732 -280.423439)
			(xy 60.514748 -280.405987) (xy 60.562967 -280.396143) (xy 60.612142 -280.394162) (xy 60.660997 -280.400094)
			(xy 60.708268 -280.413786) (xy 60.75273 -280.434884) (xy 60.793233 -280.46284) (xy 60.828726 -280.496932)
			(xy 60.858291 -280.536276) (xy 60.881162 -280.579853) (xy 60.896746 -280.626534) (xy 60.904641 -280.675111)
			(xy 60.905136 -280.699718) (xy 62.193944 -280.699718) (xy 62.197904 -280.650664) (xy 62.209681 -280.60288)
			(xy 62.228972 -280.557604) (xy 62.255275 -280.516008) (xy 62.28791 -280.479171) (xy 62.326031 -280.448046)
			(xy 62.368652 -280.423439) (xy 62.414668 -280.405987) (xy 62.462887 -280.396143) (xy 62.512062 -280.394162)
			(xy 62.560917 -280.400094) (xy 62.608188 -280.413786) (xy 62.65265 -280.434884) (xy 62.693153 -280.46284)
			(xy 62.728646 -280.496932) (xy 62.758211 -280.536276) (xy 62.781082 -280.579853) (xy 62.796666 -280.626534)
			(xy 62.804561 -280.675111) (xy 62.805056 -280.699718) (xy 64.094118 -280.699718) (xy 64.098078 -280.650664)
			(xy 64.109855 -280.60288) (xy 64.129146 -280.557604) (xy 64.155449 -280.516008) (xy 64.188084 -280.479171)
			(xy 64.226205 -280.448046) (xy 64.268826 -280.423439) (xy 64.314842 -280.405987) (xy 64.363061 -280.396143)
			(xy 64.412236 -280.394162) (xy 64.461091 -280.400094) (xy 64.508362 -280.413786) (xy 64.552824 -280.434884)
			(xy 64.593327 -280.46284) (xy 64.62882 -280.496932) (xy 64.658385 -280.536276) (xy 64.681256 -280.579853)
			(xy 64.69684 -280.626534) (xy 64.704735 -280.675111) (xy 64.70523 -280.699718) (xy 65.994038 -280.699718)
			(xy 65.997998 -280.650664) (xy 66.009775 -280.60288) (xy 66.029066 -280.557604) (xy 66.055369 -280.516008)
			(xy 66.088004 -280.479171) (xy 66.126125 -280.448046) (xy 66.168746 -280.423439) (xy 66.214762 -280.405987)
			(xy 66.262981 -280.396143) (xy 66.312156 -280.394162) (xy 66.361011 -280.400094) (xy 66.408282 -280.413786)
			(xy 66.452744 -280.434884) (xy 66.493247 -280.46284) (xy 66.52874 -280.496932) (xy 66.558305 -280.536276)
			(xy 66.581176 -280.579853) (xy 66.59676 -280.626534) (xy 66.604655 -280.675111) (xy 66.60515 -280.699718)
			(xy 67.893958 -280.699718) (xy 67.897918 -280.650664) (xy 67.909695 -280.60288) (xy 67.928986 -280.557604)
			(xy 67.955289 -280.516008) (xy 67.987924 -280.479171) (xy 68.026045 -280.448046) (xy 68.068666 -280.423439)
			(xy 68.114682 -280.405987) (xy 68.162901 -280.396143) (xy 68.212076 -280.394162) (xy 68.260931 -280.400094)
			(xy 68.308202 -280.413786) (xy 68.352664 -280.434884) (xy 68.393167 -280.46284) (xy 68.42866 -280.496932)
			(xy 68.458225 -280.536276) (xy 68.481096 -280.579853) (xy 68.49668 -280.626534) (xy 68.504575 -280.675111)
			(xy 68.50507 -280.699718) (xy 69.794132 -280.699718) (xy 69.798092 -280.650664) (xy 69.809869 -280.60288)
			(xy 69.82916 -280.557604) (xy 69.855463 -280.516008) (xy 69.888098 -280.479171) (xy 69.926219 -280.448046)
			(xy 69.96884 -280.423439) (xy 70.014856 -280.405987) (xy 70.063075 -280.396143) (xy 70.11225 -280.394162)
			(xy 70.161105 -280.400094) (xy 70.208376 -280.413786) (xy 70.252838 -280.434884) (xy 70.293341 -280.46284)
			(xy 70.328834 -280.496932) (xy 70.358399 -280.536276) (xy 70.38127 -280.579853) (xy 70.396854 -280.626534)
			(xy 70.404749 -280.675111) (xy 70.405244 -280.699718) (xy 71.694052 -280.699718) (xy 71.698012 -280.650664)
			(xy 71.709789 -280.60288) (xy 71.72908 -280.557604) (xy 71.755383 -280.516008) (xy 71.788018 -280.479171)
			(xy 71.826139 -280.448046) (xy 71.86876 -280.423439) (xy 71.914776 -280.405987) (xy 71.962995 -280.396143)
			(xy 72.01217 -280.394162) (xy 72.061025 -280.400094) (xy 72.108296 -280.413786) (xy 72.152758 -280.434884)
			(xy 72.193261 -280.46284) (xy 72.228754 -280.496932) (xy 72.258319 -280.536276) (xy 72.28119 -280.579853)
			(xy 72.296774 -280.626534) (xy 72.304669 -280.675111) (xy 72.305164 -280.699718) (xy 73.593972 -280.699718)
			(xy 73.597932 -280.650664) (xy 73.609709 -280.60288) (xy 73.629 -280.557604) (xy 73.655303 -280.516008)
			(xy 73.687938 -280.479171) (xy 73.726059 -280.448046) (xy 73.76868 -280.423439) (xy 73.814696 -280.405987)
			(xy 73.862915 -280.396143) (xy 73.91209 -280.394162) (xy 73.960945 -280.400094) (xy 74.008216 -280.413786)
			(xy 74.052678 -280.434884) (xy 74.093181 -280.46284) (xy 74.128674 -280.496932) (xy 74.158239 -280.536276)
			(xy 74.18111 -280.579853) (xy 74.196694 -280.626534) (xy 74.204589 -280.675111) (xy 74.205084 -280.699718)
			(xy 75.494146 -280.699718) (xy 75.498106 -280.650664) (xy 75.509883 -280.60288) (xy 75.529174 -280.557604)
			(xy 75.555477 -280.516008) (xy 75.588112 -280.479171) (xy 75.626233 -280.448046) (xy 75.668854 -280.423439)
			(xy 75.71487 -280.405987) (xy 75.763089 -280.396143) (xy 75.812264 -280.394162) (xy 75.861119 -280.400094)
			(xy 75.90839 -280.413786) (xy 75.952852 -280.434884) (xy 75.993355 -280.46284) (xy 76.028848 -280.496932)
			(xy 76.058413 -280.536276) (xy 76.081284 -280.579853) (xy 76.096868 -280.626534) (xy 76.104763 -280.675111)
			(xy 76.105258 -280.699718) (xy 77.394066 -280.699718) (xy 77.398026 -280.650664) (xy 77.409803 -280.60288)
			(xy 77.429094 -280.557604) (xy 77.455397 -280.516008) (xy 77.488032 -280.479171) (xy 77.526153 -280.448046)
			(xy 77.568774 -280.423439) (xy 77.61479 -280.405987) (xy 77.663009 -280.396143) (xy 77.712184 -280.394162)
			(xy 77.761039 -280.400094) (xy 77.80831 -280.413786) (xy 77.852772 -280.434884) (xy 77.893275 -280.46284)
			(xy 77.928768 -280.496932) (xy 77.958333 -280.536276) (xy 77.981204 -280.579853) (xy 77.996788 -280.626534)
			(xy 78.004683 -280.675111) (xy 78.005178 -280.699718) (xy 79.293986 -280.699718) (xy 79.297946 -280.650664)
			(xy 79.309723 -280.60288) (xy 79.329014 -280.557604) (xy 79.355317 -280.516008) (xy 79.387952 -280.479171)
			(xy 79.426073 -280.448046) (xy 79.468694 -280.423439) (xy 79.51471 -280.405987) (xy 79.562929 -280.396143)
			(xy 79.612104 -280.394162) (xy 79.660959 -280.400094) (xy 79.70823 -280.413786) (xy 79.752692 -280.434884)
			(xy 79.793195 -280.46284) (xy 79.828688 -280.496932) (xy 79.858253 -280.536276) (xy 79.881124 -280.579853)
			(xy 79.896708 -280.626534) (xy 79.904603 -280.675111) (xy 79.905098 -280.699718) (xy 161.194254 -280.699718)
			(xy 161.198214 -280.650664) (xy 161.209991 -280.60288) (xy 161.229282 -280.557604) (xy 161.255585 -280.516008)
			(xy 161.28822 -280.479171) (xy 161.326341 -280.448046) (xy 161.368962 -280.423439) (xy 161.414978 -280.405987)
			(xy 161.463197 -280.396143) (xy 161.512372 -280.394162) (xy 161.561227 -280.400094) (xy 161.608498 -280.413786)
			(xy 161.65296 -280.434884) (xy 161.693463 -280.46284) (xy 161.728956 -280.496932) (xy 161.758521 -280.536276)
			(xy 161.781392 -280.579853) (xy 161.796976 -280.626534) (xy 161.804871 -280.675111) (xy 161.805366 -280.699718)
			(xy 163.094174 -280.699718) (xy 163.098134 -280.650664) (xy 163.109911 -280.60288) (xy 163.129202 -280.557604)
			(xy 163.155505 -280.516008) (xy 163.18814 -280.479171) (xy 163.226261 -280.448046) (xy 163.268882 -280.423439)
			(xy 163.314898 -280.405987) (xy 163.363117 -280.396143) (xy 163.412292 -280.394162) (xy 163.461147 -280.400094)
			(xy 163.508418 -280.413786) (xy 163.55288 -280.434884) (xy 163.593383 -280.46284) (xy 163.628876 -280.496932)
			(xy 163.658441 -280.536276) (xy 163.681312 -280.579853) (xy 163.696896 -280.626534) (xy 163.704791 -280.675111)
			(xy 163.705286 -280.699718) (xy 164.994094 -280.699718) (xy 164.998054 -280.650664) (xy 165.009831 -280.60288)
			(xy 165.029122 -280.557604) (xy 165.055425 -280.516008) (xy 165.08806 -280.479171) (xy 165.126181 -280.448046)
			(xy 165.168802 -280.423439) (xy 165.214818 -280.405987) (xy 165.263037 -280.396143) (xy 165.312212 -280.394162)
			(xy 165.361067 -280.400094) (xy 165.408338 -280.413786) (xy 165.4528 -280.434884) (xy 165.493303 -280.46284)
			(xy 165.528796 -280.496932) (xy 165.558361 -280.536276) (xy 165.581232 -280.579853) (xy 165.596816 -280.626534)
			(xy 165.604711 -280.675111) (xy 165.605206 -280.699718) (xy 166.894268 -280.699718) (xy 166.898228 -280.650664)
			(xy 166.910005 -280.60288) (xy 166.929296 -280.557604) (xy 166.955599 -280.516008) (xy 166.988234 -280.479171)
			(xy 167.026355 -280.448046) (xy 167.068976 -280.423439) (xy 167.114992 -280.405987) (xy 167.163211 -280.396143)
			(xy 167.212386 -280.394162) (xy 167.261241 -280.400094) (xy 167.308512 -280.413786) (xy 167.352974 -280.434884)
			(xy 167.393477 -280.46284) (xy 167.42897 -280.496932) (xy 167.458535 -280.536276) (xy 167.481406 -280.579853)
			(xy 167.49699 -280.626534) (xy 167.504885 -280.675111) (xy 167.50538 -280.699718) (xy 168.794188 -280.699718)
			(xy 168.798148 -280.650664) (xy 168.809925 -280.60288) (xy 168.829216 -280.557604) (xy 168.855519 -280.516008)
			(xy 168.888154 -280.479171) (xy 168.926275 -280.448046) (xy 168.968896 -280.423439) (xy 169.014912 -280.405987)
			(xy 169.063131 -280.396143) (xy 169.112306 -280.394162) (xy 169.161161 -280.400094) (xy 169.208432 -280.413786)
			(xy 169.252894 -280.434884) (xy 169.293397 -280.46284) (xy 169.32889 -280.496932) (xy 169.358455 -280.536276)
			(xy 169.381326 -280.579853) (xy 169.39691 -280.626534) (xy 169.404805 -280.675111) (xy 169.4053 -280.699718)
			(xy 170.694108 -280.699718) (xy 170.698068 -280.650664) (xy 170.709845 -280.60288) (xy 170.729136 -280.557604)
			(xy 170.755439 -280.516008) (xy 170.788074 -280.479171) (xy 170.826195 -280.448046) (xy 170.868816 -280.423439)
			(xy 170.914832 -280.405987) (xy 170.963051 -280.396143) (xy 171.012226 -280.394162) (xy 171.061081 -280.400094)
			(xy 171.108352 -280.413786) (xy 171.152814 -280.434884) (xy 171.193317 -280.46284) (xy 171.22881 -280.496932)
			(xy 171.258375 -280.536276) (xy 171.281246 -280.579853) (xy 171.29683 -280.626534) (xy 171.304725 -280.675111)
			(xy 171.30522 -280.699718) (xy 172.594028 -280.699718) (xy 172.597988 -280.650664) (xy 172.609765 -280.60288)
			(xy 172.629056 -280.557604) (xy 172.655359 -280.516008) (xy 172.687994 -280.479171) (xy 172.726115 -280.448046)
			(xy 172.768736 -280.423439) (xy 172.814752 -280.405987) (xy 172.862971 -280.396143) (xy 172.912146 -280.394162)
			(xy 172.961001 -280.400094) (xy 173.008272 -280.413786) (xy 173.052734 -280.434884) (xy 173.093237 -280.46284)
			(xy 173.12873 -280.496932) (xy 173.158295 -280.536276) (xy 173.181166 -280.579853) (xy 173.19675 -280.626534)
			(xy 173.204645 -280.675111) (xy 173.20514 -280.699718) (xy 174.494202 -280.699718) (xy 174.498162 -280.650664)
			(xy 174.509939 -280.60288) (xy 174.52923 -280.557604) (xy 174.555533 -280.516008) (xy 174.588168 -280.479171)
			(xy 174.626289 -280.448046) (xy 174.66891 -280.423439) (xy 174.714926 -280.405987) (xy 174.763145 -280.396143)
			(xy 174.81232 -280.394162) (xy 174.861175 -280.400094) (xy 174.908446 -280.413786) (xy 174.952908 -280.434884)
			(xy 174.993411 -280.46284) (xy 175.028904 -280.496932) (xy 175.058469 -280.536276) (xy 175.08134 -280.579853)
			(xy 175.096924 -280.626534) (xy 175.104819 -280.675111) (xy 175.105314 -280.699718) (xy 176.394122 -280.699718)
			(xy 176.398082 -280.650664) (xy 176.409859 -280.60288) (xy 176.42915 -280.557604) (xy 176.455453 -280.516008)
			(xy 176.488088 -280.479171) (xy 176.526209 -280.448046) (xy 176.56883 -280.423439) (xy 176.614846 -280.405987)
			(xy 176.663065 -280.396143) (xy 176.71224 -280.394162) (xy 176.761095 -280.400094) (xy 176.808366 -280.413786)
			(xy 176.852828 -280.434884) (xy 176.893331 -280.46284) (xy 176.928824 -280.496932) (xy 176.958389 -280.536276)
			(xy 176.98126 -280.579853) (xy 176.996844 -280.626534) (xy 177.004739 -280.675111) (xy 177.005234 -280.699718)
			(xy 178.294042 -280.699718) (xy 178.298002 -280.650664) (xy 178.309779 -280.60288) (xy 178.32907 -280.557604)
			(xy 178.355373 -280.516008) (xy 178.388008 -280.479171) (xy 178.426129 -280.448046) (xy 178.46875 -280.423439)
			(xy 178.514766 -280.405987) (xy 178.562985 -280.396143) (xy 178.61216 -280.394162) (xy 178.661015 -280.400094)
			(xy 178.708286 -280.413786) (xy 178.752748 -280.434884) (xy 178.793251 -280.46284) (xy 178.828744 -280.496932)
			(xy 178.858309 -280.536276) (xy 178.88118 -280.579853) (xy 178.896764 -280.626534) (xy 178.904659 -280.675111)
			(xy 178.905154 -280.699718) (xy 180.194216 -280.699718) (xy 180.198176 -280.650664) (xy 180.209953 -280.60288)
			(xy 180.229244 -280.557604) (xy 180.255547 -280.516008) (xy 180.288182 -280.479171) (xy 180.326303 -280.448046)
			(xy 180.368924 -280.423439) (xy 180.41494 -280.405987) (xy 180.463159 -280.396143) (xy 180.512334 -280.394162)
			(xy 180.561189 -280.400094) (xy 180.60846 -280.413786) (xy 180.652922 -280.434884) (xy 180.693425 -280.46284)
			(xy 180.728918 -280.496932) (xy 180.758483 -280.536276) (xy 180.781354 -280.579853) (xy 180.796938 -280.626534)
			(xy 180.804833 -280.675111) (xy 180.805328 -280.699718) (xy 182.094136 -280.699718) (xy 182.098096 -280.650664)
			(xy 182.109873 -280.60288) (xy 182.129164 -280.557604) (xy 182.155467 -280.516008) (xy 182.188102 -280.479171)
			(xy 182.226223 -280.448046) (xy 182.268844 -280.423439) (xy 182.31486 -280.405987) (xy 182.363079 -280.396143)
			(xy 182.412254 -280.394162) (xy 182.461109 -280.400094) (xy 182.50838 -280.413786) (xy 182.552842 -280.434884)
			(xy 182.593345 -280.46284) (xy 182.628838 -280.496932) (xy 182.658403 -280.536276) (xy 182.681274 -280.579853)
			(xy 182.696858 -280.626534) (xy 182.704753 -280.675111) (xy 182.705248 -280.699718) (xy 183.994056 -280.699718)
			(xy 183.998016 -280.650664) (xy 184.009793 -280.60288) (xy 184.029084 -280.557604) (xy 184.055387 -280.516008)
			(xy 184.088022 -280.479171) (xy 184.126143 -280.448046) (xy 184.168764 -280.423439) (xy 184.21478 -280.405987)
			(xy 184.262999 -280.396143) (xy 184.312174 -280.394162) (xy 184.361029 -280.400094) (xy 184.4083 -280.413786)
			(xy 184.452762 -280.434884) (xy 184.493265 -280.46284) (xy 184.528758 -280.496932) (xy 184.558323 -280.536276)
			(xy 184.581194 -280.579853) (xy 184.596778 -280.626534) (xy 184.604673 -280.675111) (xy 184.605168 -280.699718)
			(xy 185.89423 -280.699718) (xy 185.89819 -280.650664) (xy 185.909967 -280.60288) (xy 185.929258 -280.557604)
			(xy 185.955561 -280.516008) (xy 185.988196 -280.479171) (xy 186.026317 -280.448046) (xy 186.068938 -280.423439)
			(xy 186.114954 -280.405987) (xy 186.163173 -280.396143) (xy 186.212348 -280.394162) (xy 186.261203 -280.400094)
			(xy 186.308474 -280.413786) (xy 186.352936 -280.434884) (xy 186.393439 -280.46284) (xy 186.428932 -280.496932)
			(xy 186.458497 -280.536276) (xy 186.481368 -280.579853) (xy 186.496952 -280.626534) (xy 186.504847 -280.675111)
			(xy 186.505342 -280.699718) (xy 187.79415 -280.699718) (xy 187.79811 -280.650664) (xy 187.809887 -280.60288)
			(xy 187.829178 -280.557604) (xy 187.855481 -280.516008) (xy 187.888116 -280.479171) (xy 187.926237 -280.448046)
			(xy 187.968858 -280.423439) (xy 188.014874 -280.405987) (xy 188.063093 -280.396143) (xy 188.112268 -280.394162)
			(xy 188.161123 -280.400094) (xy 188.208394 -280.413786) (xy 188.252856 -280.434884) (xy 188.293359 -280.46284)
			(xy 188.328852 -280.496932) (xy 188.358417 -280.536276) (xy 188.381288 -280.579853) (xy 188.396872 -280.626534)
			(xy 188.404767 -280.675111) (xy 188.405262 -280.699718) (xy 189.69407 -280.699718) (xy 189.69803 -280.650664)
			(xy 189.709807 -280.60288) (xy 189.729098 -280.557604) (xy 189.755401 -280.516008) (xy 189.788036 -280.479171)
			(xy 189.826157 -280.448046) (xy 189.868778 -280.423439) (xy 189.914794 -280.405987) (xy 189.963013 -280.396143)
			(xy 190.012188 -280.394162) (xy 190.061043 -280.400094) (xy 190.108314 -280.413786) (xy 190.152776 -280.434884)
			(xy 190.193279 -280.46284) (xy 190.228772 -280.496932) (xy 190.258337 -280.536276) (xy 190.281208 -280.579853)
			(xy 190.296792 -280.626534) (xy 190.304687 -280.675111) (xy 190.305182 -280.699718) (xy 191.594244 -280.699718)
			(xy 191.598204 -280.650664) (xy 191.609981 -280.60288) (xy 191.629272 -280.557604) (xy 191.655575 -280.516008)
			(xy 191.68821 -280.479171) (xy 191.726331 -280.448046) (xy 191.768952 -280.423439) (xy 191.814968 -280.405987)
			(xy 191.863187 -280.396143) (xy 191.912362 -280.394162) (xy 191.961217 -280.400094) (xy 192.008488 -280.413786)
			(xy 192.05295 -280.434884) (xy 192.093453 -280.46284) (xy 192.128946 -280.496932) (xy 192.158511 -280.536276)
			(xy 192.181382 -280.579853) (xy 192.196966 -280.626534) (xy 192.204861 -280.675111) (xy 192.205356 -280.699718)
			(xy 193.494164 -280.699718) (xy 193.498124 -280.650664) (xy 193.509901 -280.60288) (xy 193.529192 -280.557604)
			(xy 193.555495 -280.516008) (xy 193.58813 -280.479171) (xy 193.626251 -280.448046) (xy 193.668872 -280.423439)
			(xy 193.714888 -280.405987) (xy 193.763107 -280.396143) (xy 193.812282 -280.394162) (xy 193.861137 -280.400094)
			(xy 193.908408 -280.413786) (xy 193.95287 -280.434884) (xy 193.993373 -280.46284) (xy 194.028866 -280.496932)
			(xy 194.058431 -280.536276) (xy 194.081302 -280.579853) (xy 194.096886 -280.626534) (xy 194.104781 -280.675111)
			(xy 194.105276 -280.699718) (xy 195.394084 -280.699718) (xy 195.398044 -280.650664) (xy 195.409821 -280.60288)
			(xy 195.429112 -280.557604) (xy 195.455415 -280.516008) (xy 195.48805 -280.479171) (xy 195.526171 -280.448046)
			(xy 195.568792 -280.423439) (xy 195.614808 -280.405987) (xy 195.663027 -280.396143) (xy 195.712202 -280.394162)
			(xy 195.761057 -280.400094) (xy 195.808328 -280.413786) (xy 195.85279 -280.434884) (xy 195.893293 -280.46284)
			(xy 195.928786 -280.496932) (xy 195.958351 -280.536276) (xy 195.981222 -280.579853) (xy 195.996806 -280.626534)
			(xy 196.004701 -280.675111) (xy 196.005191 -280.699464) (xy 277.294098 -280.699464) (xy 277.298058 -280.65041)
			(xy 277.309835 -280.602626) (xy 277.329126 -280.55735) (xy 277.355429 -280.515754) (xy 277.388064 -280.478917)
			(xy 277.426185 -280.447792) (xy 277.468806 -280.423185) (xy 277.514822 -280.405733) (xy 277.563041 -280.395889)
			(xy 277.612216 -280.393908) (xy 277.661071 -280.39984) (xy 277.708342 -280.413532) (xy 277.752804 -280.43463)
			(xy 277.793307 -280.462586) (xy 277.8288 -280.496678) (xy 277.858365 -280.536022) (xy 277.881236 -280.579599)
			(xy 277.89682 -280.62628) (xy 277.904715 -280.674857) (xy 277.90521 -280.699464) (xy 279.194018 -280.699464)
			(xy 279.197978 -280.65041) (xy 279.209755 -280.602626) (xy 279.229046 -280.55735) (xy 279.255349 -280.515754)
			(xy 279.287984 -280.478917) (xy 279.326105 -280.447792) (xy 279.368726 -280.423185) (xy 279.414742 -280.405733)
			(xy 279.462961 -280.395889) (xy 279.512136 -280.393908) (xy 279.560991 -280.39984) (xy 279.608262 -280.413532)
			(xy 279.652724 -280.43463) (xy 279.693227 -280.462586) (xy 279.72872 -280.496678) (xy 279.758285 -280.536022)
			(xy 279.781156 -280.579599) (xy 279.79674 -280.62628) (xy 279.804635 -280.674857) (xy 279.80513 -280.699464)
			(xy 281.093938 -280.699464) (xy 281.097898 -280.65041) (xy 281.109675 -280.602626) (xy 281.128966 -280.55735)
			(xy 281.155269 -280.515754) (xy 281.187904 -280.478917) (xy 281.226025 -280.447792) (xy 281.268646 -280.423185)
			(xy 281.314662 -280.405733) (xy 281.362881 -280.395889) (xy 281.412056 -280.393908) (xy 281.460911 -280.39984)
			(xy 281.508182 -280.413532) (xy 281.552644 -280.43463) (xy 281.593147 -280.462586) (xy 281.62864 -280.496678)
			(xy 281.658205 -280.536022) (xy 281.681076 -280.579599) (xy 281.69666 -280.62628) (xy 281.704555 -280.674857)
			(xy 281.70505 -280.699464) (xy 282.994112 -280.699464) (xy 282.998072 -280.65041) (xy 283.009849 -280.602626)
			(xy 283.02914 -280.55735) (xy 283.055443 -280.515754) (xy 283.088078 -280.478917) (xy 283.126199 -280.447792)
			(xy 283.16882 -280.423185) (xy 283.214836 -280.405733) (xy 283.263055 -280.395889) (xy 283.31223 -280.393908)
			(xy 283.361085 -280.39984) (xy 283.408356 -280.413532) (xy 283.452818 -280.43463) (xy 283.493321 -280.462586)
			(xy 283.528814 -280.496678) (xy 283.558379 -280.536022) (xy 283.58125 -280.579599) (xy 283.596834 -280.62628)
			(xy 283.604729 -280.674857) (xy 283.605224 -280.699464) (xy 284.894032 -280.699464) (xy 284.897992 -280.65041)
			(xy 284.909769 -280.602626) (xy 284.92906 -280.55735) (xy 284.955363 -280.515754) (xy 284.987998 -280.478917)
			(xy 285.026119 -280.447792) (xy 285.06874 -280.423185) (xy 285.114756 -280.405733) (xy 285.162975 -280.395889)
			(xy 285.21215 -280.393908) (xy 285.261005 -280.39984) (xy 285.308276 -280.413532) (xy 285.352738 -280.43463)
			(xy 285.393241 -280.462586) (xy 285.428734 -280.496678) (xy 285.458299 -280.536022) (xy 285.48117 -280.579599)
			(xy 285.496754 -280.62628) (xy 285.504649 -280.674857) (xy 285.505144 -280.699464) (xy 286.793952 -280.699464)
			(xy 286.797912 -280.65041) (xy 286.809689 -280.602626) (xy 286.82898 -280.55735) (xy 286.855283 -280.515754)
			(xy 286.887918 -280.478917) (xy 286.926039 -280.447792) (xy 286.96866 -280.423185) (xy 287.014676 -280.405733)
			(xy 287.062895 -280.395889) (xy 287.11207 -280.393908) (xy 287.160925 -280.39984) (xy 287.208196 -280.413532)
			(xy 287.252658 -280.43463) (xy 287.293161 -280.462586) (xy 287.328654 -280.496678) (xy 287.358219 -280.536022)
			(xy 287.38109 -280.579599) (xy 287.396674 -280.62628) (xy 287.404569 -280.674857) (xy 287.405064 -280.699464)
			(xy 288.693872 -280.699464) (xy 288.697832 -280.65041) (xy 288.709609 -280.602626) (xy 288.7289 -280.55735)
			(xy 288.755203 -280.515754) (xy 288.787838 -280.478917) (xy 288.825959 -280.447792) (xy 288.86858 -280.423185)
			(xy 288.914596 -280.405733) (xy 288.962815 -280.395889) (xy 289.01199 -280.393908) (xy 289.060845 -280.39984)
			(xy 289.108116 -280.413532) (xy 289.152578 -280.43463) (xy 289.193081 -280.462586) (xy 289.228574 -280.496678)
			(xy 289.258139 -280.536022) (xy 289.28101 -280.579599) (xy 289.296594 -280.62628) (xy 289.304489 -280.674857)
			(xy 289.304984 -280.699464) (xy 290.594046 -280.699464) (xy 290.598006 -280.65041) (xy 290.609783 -280.602626)
			(xy 290.629074 -280.55735) (xy 290.655377 -280.515754) (xy 290.688012 -280.478917) (xy 290.726133 -280.447792)
			(xy 290.768754 -280.423185) (xy 290.81477 -280.405733) (xy 290.862989 -280.395889) (xy 290.912164 -280.393908)
			(xy 290.961019 -280.39984) (xy 291.00829 -280.413532) (xy 291.052752 -280.43463) (xy 291.093255 -280.462586)
			(xy 291.128748 -280.496678) (xy 291.158313 -280.536022) (xy 291.181184 -280.579599) (xy 291.196768 -280.62628)
			(xy 291.204663 -280.674857) (xy 291.205158 -280.699464) (xy 292.493966 -280.699464) (xy 292.497926 -280.65041)
			(xy 292.509703 -280.602626) (xy 292.528994 -280.55735) (xy 292.555297 -280.515754) (xy 292.587932 -280.478917)
			(xy 292.626053 -280.447792) (xy 292.668674 -280.423185) (xy 292.71469 -280.405733) (xy 292.762909 -280.395889)
			(xy 292.812084 -280.393908) (xy 292.860939 -280.39984) (xy 292.90821 -280.413532) (xy 292.952672 -280.43463)
			(xy 292.993175 -280.462586) (xy 293.028668 -280.496678) (xy 293.058233 -280.536022) (xy 293.081104 -280.579599)
			(xy 293.096688 -280.62628) (xy 293.104583 -280.674857) (xy 293.105078 -280.699464) (xy 294.393886 -280.699464)
			(xy 294.397846 -280.65041) (xy 294.409623 -280.602626) (xy 294.428914 -280.55735) (xy 294.455217 -280.515754)
			(xy 294.487852 -280.478917) (xy 294.525973 -280.447792) (xy 294.568594 -280.423185) (xy 294.61461 -280.405733)
			(xy 294.662829 -280.395889) (xy 294.712004 -280.393908) (xy 294.760859 -280.39984) (xy 294.80813 -280.413532)
			(xy 294.852592 -280.43463) (xy 294.893095 -280.462586) (xy 294.928588 -280.496678) (xy 294.958153 -280.536022)
			(xy 294.981024 -280.579599) (xy 294.996608 -280.62628) (xy 295.004503 -280.674857) (xy 295.004998 -280.699464)
			(xy 296.29406 -280.699464) (xy 296.29802 -280.65041) (xy 296.309797 -280.602626) (xy 296.329088 -280.55735)
			(xy 296.355391 -280.515754) (xy 296.388026 -280.478917) (xy 296.426147 -280.447792) (xy 296.468768 -280.423185)
			(xy 296.514784 -280.405733) (xy 296.563003 -280.395889) (xy 296.612178 -280.393908) (xy 296.661033 -280.39984)
			(xy 296.708304 -280.413532) (xy 296.752766 -280.43463) (xy 296.793269 -280.462586) (xy 296.828762 -280.496678)
			(xy 296.858327 -280.536022) (xy 296.881198 -280.579599) (xy 296.896782 -280.62628) (xy 296.904677 -280.674857)
			(xy 296.905172 -280.699464) (xy 298.19398 -280.699464) (xy 298.19794 -280.65041) (xy 298.209717 -280.602626)
			(xy 298.229008 -280.55735) (xy 298.255311 -280.515754) (xy 298.287946 -280.478917) (xy 298.326067 -280.447792)
			(xy 298.368688 -280.423185) (xy 298.414704 -280.405733) (xy 298.462923 -280.395889) (xy 298.512098 -280.393908)
			(xy 298.560953 -280.39984) (xy 298.608224 -280.413532) (xy 298.652686 -280.43463) (xy 298.693189 -280.462586)
			(xy 298.728682 -280.496678) (xy 298.758247 -280.536022) (xy 298.781118 -280.579599) (xy 298.796702 -280.62628)
			(xy 298.804597 -280.674857) (xy 298.805092 -280.699464) (xy 300.0939 -280.699464) (xy 300.09786 -280.65041)
			(xy 300.109637 -280.602626) (xy 300.128928 -280.55735) (xy 300.155231 -280.515754) (xy 300.187866 -280.478917)
			(xy 300.225987 -280.447792) (xy 300.268608 -280.423185) (xy 300.314624 -280.405733) (xy 300.362843 -280.395889)
			(xy 300.412018 -280.393908) (xy 300.460873 -280.39984) (xy 300.508144 -280.413532) (xy 300.552606 -280.43463)
			(xy 300.593109 -280.462586) (xy 300.628602 -280.496678) (xy 300.658167 -280.536022) (xy 300.681038 -280.579599)
			(xy 300.696622 -280.62628) (xy 300.704517 -280.674857) (xy 300.705012 -280.699464) (xy 301.994074 -280.699464)
			(xy 301.998034 -280.65041) (xy 302.009811 -280.602626) (xy 302.029102 -280.55735) (xy 302.055405 -280.515754)
			(xy 302.08804 -280.478917) (xy 302.126161 -280.447792) (xy 302.168782 -280.423185) (xy 302.214798 -280.405733)
			(xy 302.263017 -280.395889) (xy 302.312192 -280.393908) (xy 302.361047 -280.39984) (xy 302.408318 -280.413532)
			(xy 302.45278 -280.43463) (xy 302.493283 -280.462586) (xy 302.528776 -280.496678) (xy 302.558341 -280.536022)
			(xy 302.581212 -280.579599) (xy 302.596796 -280.62628) (xy 302.604691 -280.674857) (xy 302.605186 -280.699464)
			(xy 303.893994 -280.699464) (xy 303.897954 -280.65041) (xy 303.909731 -280.602626) (xy 303.929022 -280.55735)
			(xy 303.955325 -280.515754) (xy 303.98796 -280.478917) (xy 304.026081 -280.447792) (xy 304.068702 -280.423185)
			(xy 304.114718 -280.405733) (xy 304.162937 -280.395889) (xy 304.212112 -280.393908) (xy 304.260967 -280.39984)
			(xy 304.308238 -280.413532) (xy 304.3527 -280.43463) (xy 304.393203 -280.462586) (xy 304.428696 -280.496678)
			(xy 304.458261 -280.536022) (xy 304.481132 -280.579599) (xy 304.496716 -280.62628) (xy 304.504611 -280.674857)
			(xy 304.505106 -280.699464) (xy 305.793914 -280.699464) (xy 305.797874 -280.65041) (xy 305.809651 -280.602626)
			(xy 305.828942 -280.55735) (xy 305.855245 -280.515754) (xy 305.88788 -280.478917) (xy 305.926001 -280.447792)
			(xy 305.968622 -280.423185) (xy 306.014638 -280.405733) (xy 306.062857 -280.395889) (xy 306.112032 -280.393908)
			(xy 306.160887 -280.39984) (xy 306.208158 -280.413532) (xy 306.25262 -280.43463) (xy 306.293123 -280.462586)
			(xy 306.328616 -280.496678) (xy 306.358181 -280.536022) (xy 306.381052 -280.579599) (xy 306.396636 -280.62628)
			(xy 306.404531 -280.674857) (xy 306.405026 -280.699464) (xy 307.694088 -280.699464) (xy 307.698048 -280.65041)
			(xy 307.709825 -280.602626) (xy 307.729116 -280.55735) (xy 307.755419 -280.515754) (xy 307.788054 -280.478917)
			(xy 307.826175 -280.447792) (xy 307.868796 -280.423185) (xy 307.914812 -280.405733) (xy 307.963031 -280.395889)
			(xy 308.012206 -280.393908) (xy 308.061061 -280.39984) (xy 308.108332 -280.413532) (xy 308.152794 -280.43463)
			(xy 308.193297 -280.462586) (xy 308.22879 -280.496678) (xy 308.258355 -280.536022) (xy 308.281226 -280.579599)
			(xy 308.29681 -280.62628) (xy 308.304705 -280.674857) (xy 308.3052 -280.699464) (xy 309.594008 -280.699464)
			(xy 309.597968 -280.65041) (xy 309.609745 -280.602626) (xy 309.629036 -280.55735) (xy 309.655339 -280.515754)
			(xy 309.687974 -280.478917) (xy 309.726095 -280.447792) (xy 309.768716 -280.423185) (xy 309.814732 -280.405733)
			(xy 309.862951 -280.395889) (xy 309.912126 -280.393908) (xy 309.960981 -280.39984) (xy 310.008252 -280.413532)
			(xy 310.052714 -280.43463) (xy 310.093217 -280.462586) (xy 310.12871 -280.496678) (xy 310.158275 -280.536022)
			(xy 310.181146 -280.579599) (xy 310.19673 -280.62628) (xy 310.204625 -280.674857) (xy 310.20512 -280.699464)
			(xy 310.205115 -280.699718) (xy 311.493928 -280.699718) (xy 311.497888 -280.650664) (xy 311.509665 -280.60288)
			(xy 311.528956 -280.557604) (xy 311.555259 -280.516008) (xy 311.587894 -280.479171) (xy 311.626015 -280.448046)
			(xy 311.668636 -280.423439) (xy 311.714652 -280.405987) (xy 311.762871 -280.396143) (xy 311.812046 -280.394162)
			(xy 311.860901 -280.400094) (xy 311.908172 -280.413786) (xy 311.952634 -280.434884) (xy 311.993137 -280.46284)
			(xy 312.02863 -280.496932) (xy 312.058195 -280.536276) (xy 312.081066 -280.579853) (xy 312.09665 -280.626534)
			(xy 312.104545 -280.675111) (xy 312.105035 -280.699464) (xy 393.394196 -280.699464) (xy 393.398156 -280.65041)
			(xy 393.409933 -280.602626) (xy 393.429224 -280.55735) (xy 393.455527 -280.515754) (xy 393.488162 -280.478917)
			(xy 393.526283 -280.447792) (xy 393.568904 -280.423185) (xy 393.61492 -280.405733) (xy 393.663139 -280.395889)
			(xy 393.712314 -280.393908) (xy 393.761169 -280.39984) (xy 393.80844 -280.413532) (xy 393.852902 -280.43463)
			(xy 393.893405 -280.462586) (xy 393.928898 -280.496678) (xy 393.958463 -280.536022) (xy 393.981334 -280.579599)
			(xy 393.996918 -280.62628) (xy 394.004813 -280.674857) (xy 394.005308 -280.699464) (xy 395.294116 -280.699464)
			(xy 395.298076 -280.65041) (xy 395.309853 -280.602626) (xy 395.329144 -280.55735) (xy 395.355447 -280.515754)
			(xy 395.388082 -280.478917) (xy 395.426203 -280.447792) (xy 395.468824 -280.423185) (xy 395.51484 -280.405733)
			(xy 395.563059 -280.395889) (xy 395.612234 -280.393908) (xy 395.661089 -280.39984) (xy 395.70836 -280.413532)
			(xy 395.752822 -280.43463) (xy 395.793325 -280.462586) (xy 395.828818 -280.496678) (xy 395.858383 -280.536022)
			(xy 395.881254 -280.579599) (xy 395.896838 -280.62628) (xy 395.904733 -280.674857) (xy 395.905228 -280.699464)
			(xy 397.194036 -280.699464) (xy 397.197996 -280.65041) (xy 397.209773 -280.602626) (xy 397.229064 -280.55735)
			(xy 397.255367 -280.515754) (xy 397.288002 -280.478917) (xy 397.326123 -280.447792) (xy 397.368744 -280.423185)
			(xy 397.41476 -280.405733) (xy 397.462979 -280.395889) (xy 397.512154 -280.393908) (xy 397.561009 -280.39984)
			(xy 397.60828 -280.413532) (xy 397.652742 -280.43463) (xy 397.693245 -280.462586) (xy 397.728738 -280.496678)
			(xy 397.758303 -280.536022) (xy 397.781174 -280.579599) (xy 397.796758 -280.62628) (xy 397.804653 -280.674857)
			(xy 397.805148 -280.699464) (xy 399.09421 -280.699464) (xy 399.09817 -280.65041) (xy 399.109947 -280.602626)
			(xy 399.129238 -280.55735) (xy 399.155541 -280.515754) (xy 399.188176 -280.478917) (xy 399.226297 -280.447792)
			(xy 399.268918 -280.423185) (xy 399.314934 -280.405733) (xy 399.363153 -280.395889) (xy 399.412328 -280.393908)
			(xy 399.461183 -280.39984) (xy 399.508454 -280.413532) (xy 399.552916 -280.43463) (xy 399.593419 -280.462586)
			(xy 399.628912 -280.496678) (xy 399.658477 -280.536022) (xy 399.681348 -280.579599) (xy 399.696932 -280.62628)
			(xy 399.704827 -280.674857) (xy 399.705322 -280.699464) (xy 400.99413 -280.699464) (xy 400.99809 -280.65041)
			(xy 401.009867 -280.602626) (xy 401.029158 -280.55735) (xy 401.055461 -280.515754) (xy 401.088096 -280.478917)
			(xy 401.126217 -280.447792) (xy 401.168838 -280.423185) (xy 401.214854 -280.405733) (xy 401.263073 -280.395889)
			(xy 401.312248 -280.393908) (xy 401.361103 -280.39984) (xy 401.408374 -280.413532) (xy 401.452836 -280.43463)
			(xy 401.493339 -280.462586) (xy 401.528832 -280.496678) (xy 401.558397 -280.536022) (xy 401.581268 -280.579599)
			(xy 401.596852 -280.62628) (xy 401.604747 -280.674857) (xy 401.605242 -280.699464) (xy 402.89405 -280.699464)
			(xy 402.89801 -280.65041) (xy 402.909787 -280.602626) (xy 402.929078 -280.55735) (xy 402.955381 -280.515754)
			(xy 402.988016 -280.478917) (xy 403.026137 -280.447792) (xy 403.068758 -280.423185) (xy 403.114774 -280.405733)
			(xy 403.162993 -280.395889) (xy 403.212168 -280.393908) (xy 403.261023 -280.39984) (xy 403.308294 -280.413532)
			(xy 403.352756 -280.43463) (xy 403.393259 -280.462586) (xy 403.428752 -280.496678) (xy 403.458317 -280.536022)
			(xy 403.481188 -280.579599) (xy 403.496772 -280.62628) (xy 403.504667 -280.674857) (xy 403.505162 -280.699464)
			(xy 404.79397 -280.699464) (xy 404.79793 -280.65041) (xy 404.809707 -280.602626) (xy 404.828998 -280.55735)
			(xy 404.855301 -280.515754) (xy 404.887936 -280.478917) (xy 404.926057 -280.447792) (xy 404.968678 -280.423185)
			(xy 405.014694 -280.405733) (xy 405.062913 -280.395889) (xy 405.112088 -280.393908) (xy 405.160943 -280.39984)
			(xy 405.208214 -280.413532) (xy 405.252676 -280.43463) (xy 405.293179 -280.462586) (xy 405.328672 -280.496678)
			(xy 405.358237 -280.536022) (xy 405.381108 -280.579599) (xy 405.396692 -280.62628) (xy 405.404587 -280.674857)
			(xy 405.405082 -280.699464) (xy 406.694144 -280.699464) (xy 406.698104 -280.65041) (xy 406.709881 -280.602626)
			(xy 406.729172 -280.55735) (xy 406.755475 -280.515754) (xy 406.78811 -280.478917) (xy 406.826231 -280.447792)
			(xy 406.868852 -280.423185) (xy 406.914868 -280.405733) (xy 406.963087 -280.395889) (xy 407.012262 -280.393908)
			(xy 407.061117 -280.39984) (xy 407.108388 -280.413532) (xy 407.15285 -280.43463) (xy 407.193353 -280.462586)
			(xy 407.228846 -280.496678) (xy 407.258411 -280.536022) (xy 407.281282 -280.579599) (xy 407.296866 -280.62628)
			(xy 407.304761 -280.674857) (xy 407.305256 -280.699464) (xy 408.594064 -280.699464) (xy 408.598024 -280.65041)
			(xy 408.609801 -280.602626) (xy 408.629092 -280.55735) (xy 408.655395 -280.515754) (xy 408.68803 -280.478917)
			(xy 408.726151 -280.447792) (xy 408.768772 -280.423185) (xy 408.814788 -280.405733) (xy 408.863007 -280.395889)
			(xy 408.912182 -280.393908) (xy 408.961037 -280.39984) (xy 409.008308 -280.413532) (xy 409.05277 -280.43463)
			(xy 409.093273 -280.462586) (xy 409.128766 -280.496678) (xy 409.158331 -280.536022) (xy 409.181202 -280.579599)
			(xy 409.196786 -280.62628) (xy 409.204681 -280.674857) (xy 409.205176 -280.699464) (xy 410.493984 -280.699464)
			(xy 410.497944 -280.65041) (xy 410.509721 -280.602626) (xy 410.529012 -280.55735) (xy 410.555315 -280.515754)
			(xy 410.58795 -280.478917) (xy 410.626071 -280.447792) (xy 410.668692 -280.423185) (xy 410.714708 -280.405733)
			(xy 410.762927 -280.395889) (xy 410.812102 -280.393908) (xy 410.860957 -280.39984) (xy 410.908228 -280.413532)
			(xy 410.95269 -280.43463) (xy 410.993193 -280.462586) (xy 411.028686 -280.496678) (xy 411.058251 -280.536022)
			(xy 411.081122 -280.579599) (xy 411.096706 -280.62628) (xy 411.104601 -280.674857) (xy 411.105096 -280.699464)
			(xy 412.394158 -280.699464) (xy 412.398118 -280.65041) (xy 412.409895 -280.602626) (xy 412.429186 -280.55735)
			(xy 412.455489 -280.515754) (xy 412.488124 -280.478917) (xy 412.526245 -280.447792) (xy 412.568866 -280.423185)
			(xy 412.614882 -280.405733) (xy 412.663101 -280.395889) (xy 412.712276 -280.393908) (xy 412.761131 -280.39984)
			(xy 412.808402 -280.413532) (xy 412.852864 -280.43463) (xy 412.893367 -280.462586) (xy 412.92886 -280.496678)
			(xy 412.958425 -280.536022) (xy 412.981296 -280.579599) (xy 412.99688 -280.62628) (xy 413.004775 -280.674857)
			(xy 413.00527 -280.699464) (xy 414.294078 -280.699464) (xy 414.298038 -280.65041) (xy 414.309815 -280.602626)
			(xy 414.329106 -280.55735) (xy 414.355409 -280.515754) (xy 414.388044 -280.478917) (xy 414.426165 -280.447792)
			(xy 414.468786 -280.423185) (xy 414.514802 -280.405733) (xy 414.563021 -280.395889) (xy 414.612196 -280.393908)
			(xy 414.661051 -280.39984) (xy 414.708322 -280.413532) (xy 414.752784 -280.43463) (xy 414.793287 -280.462586)
			(xy 414.82878 -280.496678) (xy 414.858345 -280.536022) (xy 414.881216 -280.579599) (xy 414.8968 -280.62628)
			(xy 414.904695 -280.674857) (xy 414.90519 -280.699464) (xy 416.193998 -280.699464) (xy 416.197958 -280.65041)
			(xy 416.209735 -280.602626) (xy 416.229026 -280.55735) (xy 416.255329 -280.515754) (xy 416.287964 -280.478917)
			(xy 416.326085 -280.447792) (xy 416.368706 -280.423185) (xy 416.414722 -280.405733) (xy 416.462941 -280.395889)
			(xy 416.512116 -280.393908) (xy 416.560971 -280.39984) (xy 416.608242 -280.413532) (xy 416.652704 -280.43463)
			(xy 416.693207 -280.462586) (xy 416.7287 -280.496678) (xy 416.758265 -280.536022) (xy 416.781136 -280.579599)
			(xy 416.79672 -280.62628) (xy 416.804615 -280.674857) (xy 416.80511 -280.699464) (xy 418.094172 -280.699464)
			(xy 418.098132 -280.65041) (xy 418.109909 -280.602626) (xy 418.1292 -280.55735) (xy 418.155503 -280.515754)
			(xy 418.188138 -280.478917) (xy 418.226259 -280.447792) (xy 418.26888 -280.423185) (xy 418.314896 -280.405733)
			(xy 418.363115 -280.395889) (xy 418.41229 -280.393908) (xy 418.461145 -280.39984) (xy 418.508416 -280.413532)
			(xy 418.552878 -280.43463) (xy 418.593381 -280.462586) (xy 418.628874 -280.496678) (xy 418.658439 -280.536022)
			(xy 418.68131 -280.579599) (xy 418.696894 -280.62628) (xy 418.704789 -280.674857) (xy 418.705284 -280.699464)
			(xy 419.994092 -280.699464) (xy 419.998052 -280.65041) (xy 420.009829 -280.602626) (xy 420.02912 -280.55735)
			(xy 420.055423 -280.515754) (xy 420.088058 -280.478917) (xy 420.126179 -280.447792) (xy 420.1688 -280.423185)
			(xy 420.214816 -280.405733) (xy 420.263035 -280.395889) (xy 420.31221 -280.393908) (xy 420.361065 -280.39984)
			(xy 420.408336 -280.413532) (xy 420.452798 -280.43463) (xy 420.493301 -280.462586) (xy 420.528794 -280.496678)
			(xy 420.558359 -280.536022) (xy 420.58123 -280.579599) (xy 420.596814 -280.62628) (xy 420.604709 -280.674857)
			(xy 420.605204 -280.699464) (xy 421.894012 -280.699464) (xy 421.897972 -280.65041) (xy 421.909749 -280.602626)
			(xy 421.92904 -280.55735) (xy 421.955343 -280.515754) (xy 421.987978 -280.478917) (xy 422.026099 -280.447792)
			(xy 422.06872 -280.423185) (xy 422.114736 -280.405733) (xy 422.162955 -280.395889) (xy 422.21213 -280.393908)
			(xy 422.260985 -280.39984) (xy 422.308256 -280.413532) (xy 422.352718 -280.43463) (xy 422.393221 -280.462586)
			(xy 422.428714 -280.496678) (xy 422.458279 -280.536022) (xy 422.48115 -280.579599) (xy 422.496734 -280.62628)
			(xy 422.504629 -280.674857) (xy 422.505124 -280.699464) (xy 423.794186 -280.699464) (xy 423.798146 -280.65041)
			(xy 423.809923 -280.602626) (xy 423.829214 -280.55735) (xy 423.855517 -280.515754) (xy 423.888152 -280.478917)
			(xy 423.926273 -280.447792) (xy 423.968894 -280.423185) (xy 424.01491 -280.405733) (xy 424.063129 -280.395889)
			(xy 424.112304 -280.393908) (xy 424.161159 -280.39984) (xy 424.20843 -280.413532) (xy 424.252892 -280.43463)
			(xy 424.293395 -280.462586) (xy 424.328888 -280.496678) (xy 424.358453 -280.536022) (xy 424.381324 -280.579599)
			(xy 424.396908 -280.62628) (xy 424.404803 -280.674857) (xy 424.405298 -280.699464) (xy 425.694106 -280.699464)
			(xy 425.698066 -280.65041) (xy 425.709843 -280.602626) (xy 425.729134 -280.55735) (xy 425.755437 -280.515754)
			(xy 425.788072 -280.478917) (xy 425.826193 -280.447792) (xy 425.868814 -280.423185) (xy 425.91483 -280.405733)
			(xy 425.963049 -280.395889) (xy 426.012224 -280.393908) (xy 426.061079 -280.39984) (xy 426.10835 -280.413532)
			(xy 426.152812 -280.43463) (xy 426.193315 -280.462586) (xy 426.228808 -280.496678) (xy 426.258373 -280.536022)
			(xy 426.281244 -280.579599) (xy 426.296828 -280.62628) (xy 426.304723 -280.674857) (xy 426.305218 -280.699464)
			(xy 426.305213 -280.699718) (xy 427.594026 -280.699718) (xy 427.597986 -280.650664) (xy 427.609763 -280.60288)
			(xy 427.629054 -280.557604) (xy 427.655357 -280.516008) (xy 427.687992 -280.479171) (xy 427.726113 -280.448046)
			(xy 427.768734 -280.423439) (xy 427.81475 -280.405987) (xy 427.862969 -280.396143) (xy 427.912144 -280.394162)
			(xy 427.960999 -280.400094) (xy 428.00827 -280.413786) (xy 428.052732 -280.434884) (xy 428.093235 -280.46284)
			(xy 428.128728 -280.496932) (xy 428.158293 -280.536276) (xy 428.181164 -280.579853) (xy 428.196748 -280.626534)
			(xy 428.204643 -280.675111) (xy 428.205138 -280.699718) (xy 428.204643 -280.724325) (xy 428.196748 -280.772902)
			(xy 428.181164 -280.819583) (xy 428.158293 -280.86316) (xy 428.128728 -280.902504) (xy 428.093235 -280.936596)
			(xy 428.052732 -280.964552) (xy 428.00827 -280.98565) (xy 427.960999 -280.999342) (xy 427.912144 -281.005274)
			(xy 427.862969 -281.003293) (xy 427.81475 -280.993449) (xy 427.768734 -280.975997) (xy 427.726113 -280.95139)
			(xy 427.687992 -280.920265) (xy 427.655357 -280.883428) (xy 427.629054 -280.841832) (xy 427.609763 -280.796556)
			(xy 427.597986 -280.748772) (xy 427.594026 -280.699718) (xy 426.305213 -280.699718) (xy 426.304723 -280.724071)
			(xy 426.296828 -280.772648) (xy 426.281244 -280.819329) (xy 426.258373 -280.862906) (xy 426.228808 -280.90225)
			(xy 426.193315 -280.936342) (xy 426.152812 -280.964298) (xy 426.10835 -280.985396) (xy 426.061079 -280.999088)
			(xy 426.012224 -281.00502) (xy 425.963049 -281.003039) (xy 425.91483 -280.993195) (xy 425.868814 -280.975743)
			(xy 425.826193 -280.951136) (xy 425.788072 -280.920011) (xy 425.755437 -280.883174) (xy 425.729134 -280.841578)
			(xy 425.709843 -280.796302) (xy 425.698066 -280.748518) (xy 425.694106 -280.699464) (xy 424.405298 -280.699464)
			(xy 424.404803 -280.724071) (xy 424.396908 -280.772648) (xy 424.381324 -280.819329) (xy 424.358453 -280.862906)
			(xy 424.328888 -280.90225) (xy 424.293395 -280.936342) (xy 424.252892 -280.964298) (xy 424.20843 -280.985396)
			(xy 424.161159 -280.999088) (xy 424.112304 -281.00502) (xy 424.063129 -281.003039) (xy 424.01491 -280.993195)
			(xy 423.968894 -280.975743) (xy 423.926273 -280.951136) (xy 423.888152 -280.920011) (xy 423.855517 -280.883174)
			(xy 423.829214 -280.841578) (xy 423.809923 -280.796302) (xy 423.798146 -280.748518) (xy 423.794186 -280.699464)
			(xy 422.505124 -280.699464) (xy 422.504629 -280.724071) (xy 422.496734 -280.772648) (xy 422.48115 -280.819329)
			(xy 422.458279 -280.862906) (xy 422.428714 -280.90225) (xy 422.393221 -280.936342) (xy 422.352718 -280.964298)
			(xy 422.308256 -280.985396) (xy 422.260985 -280.999088) (xy 422.21213 -281.00502) (xy 422.162955 -281.003039)
			(xy 422.114736 -280.993195) (xy 422.06872 -280.975743) (xy 422.026099 -280.951136) (xy 421.987978 -280.920011)
			(xy 421.955343 -280.883174) (xy 421.92904 -280.841578) (xy 421.909749 -280.796302) (xy 421.897972 -280.748518)
			(xy 421.894012 -280.699464) (xy 420.605204 -280.699464) (xy 420.604709 -280.724071) (xy 420.596814 -280.772648)
			(xy 420.58123 -280.819329) (xy 420.558359 -280.862906) (xy 420.528794 -280.90225) (xy 420.493301 -280.936342)
			(xy 420.452798 -280.964298) (xy 420.408336 -280.985396) (xy 420.361065 -280.999088) (xy 420.31221 -281.00502)
			(xy 420.263035 -281.003039) (xy 420.214816 -280.993195) (xy 420.1688 -280.975743) (xy 420.126179 -280.951136)
			(xy 420.088058 -280.920011) (xy 420.055423 -280.883174) (xy 420.02912 -280.841578) (xy 420.009829 -280.796302)
			(xy 419.998052 -280.748518) (xy 419.994092 -280.699464) (xy 418.705284 -280.699464) (xy 418.704789 -280.724071)
			(xy 418.696894 -280.772648) (xy 418.68131 -280.819329) (xy 418.658439 -280.862906) (xy 418.628874 -280.90225)
			(xy 418.593381 -280.936342) (xy 418.552878 -280.964298) (xy 418.508416 -280.985396) (xy 418.461145 -280.999088)
			(xy 418.41229 -281.00502) (xy 418.363115 -281.003039) (xy 418.314896 -280.993195) (xy 418.26888 -280.975743)
			(xy 418.226259 -280.951136) (xy 418.188138 -280.920011) (xy 418.155503 -280.883174) (xy 418.1292 -280.841578)
			(xy 418.109909 -280.796302) (xy 418.098132 -280.748518) (xy 418.094172 -280.699464) (xy 416.80511 -280.699464)
			(xy 416.804615 -280.724071) (xy 416.79672 -280.772648) (xy 416.781136 -280.819329) (xy 416.758265 -280.862906)
			(xy 416.7287 -280.90225) (xy 416.693207 -280.936342) (xy 416.652704 -280.964298) (xy 416.608242 -280.985396)
			(xy 416.560971 -280.999088) (xy 416.512116 -281.00502) (xy 416.462941 -281.003039) (xy 416.414722 -280.993195)
			(xy 416.368706 -280.975743) (xy 416.326085 -280.951136) (xy 416.287964 -280.920011) (xy 416.255329 -280.883174)
			(xy 416.229026 -280.841578) (xy 416.209735 -280.796302) (xy 416.197958 -280.748518) (xy 416.193998 -280.699464)
			(xy 414.90519 -280.699464) (xy 414.904695 -280.724071) (xy 414.8968 -280.772648) (xy 414.881216 -280.819329)
			(xy 414.858345 -280.862906) (xy 414.82878 -280.90225) (xy 414.793287 -280.936342) (xy 414.752784 -280.964298)
			(xy 414.708322 -280.985396) (xy 414.661051 -280.999088) (xy 414.612196 -281.00502) (xy 414.563021 -281.003039)
			(xy 414.514802 -280.993195) (xy 414.468786 -280.975743) (xy 414.426165 -280.951136) (xy 414.388044 -280.920011)
			(xy 414.355409 -280.883174) (xy 414.329106 -280.841578) (xy 414.309815 -280.796302) (xy 414.298038 -280.748518)
			(xy 414.294078 -280.699464) (xy 413.00527 -280.699464) (xy 413.004775 -280.724071) (xy 412.99688 -280.772648)
			(xy 412.981296 -280.819329) (xy 412.958425 -280.862906) (xy 412.92886 -280.90225) (xy 412.893367 -280.936342)
			(xy 412.852864 -280.964298) (xy 412.808402 -280.985396) (xy 412.761131 -280.999088) (xy 412.712276 -281.00502)
			(xy 412.663101 -281.003039) (xy 412.614882 -280.993195) (xy 412.568866 -280.975743) (xy 412.526245 -280.951136)
			(xy 412.488124 -280.920011) (xy 412.455489 -280.883174) (xy 412.429186 -280.841578) (xy 412.409895 -280.796302)
			(xy 412.398118 -280.748518) (xy 412.394158 -280.699464) (xy 411.105096 -280.699464) (xy 411.104601 -280.724071)
			(xy 411.096706 -280.772648) (xy 411.081122 -280.819329) (xy 411.058251 -280.862906) (xy 411.028686 -280.90225)
			(xy 410.993193 -280.936342) (xy 410.95269 -280.964298) (xy 410.908228 -280.985396) (xy 410.860957 -280.999088)
			(xy 410.812102 -281.00502) (xy 410.762927 -281.003039) (xy 410.714708 -280.993195) (xy 410.668692 -280.975743)
			(xy 410.626071 -280.951136) (xy 410.58795 -280.920011) (xy 410.555315 -280.883174) (xy 410.529012 -280.841578)
			(xy 410.509721 -280.796302) (xy 410.497944 -280.748518) (xy 410.493984 -280.699464) (xy 409.205176 -280.699464)
			(xy 409.204681 -280.724071) (xy 409.196786 -280.772648) (xy 409.181202 -280.819329) (xy 409.158331 -280.862906)
			(xy 409.128766 -280.90225) (xy 409.093273 -280.936342) (xy 409.05277 -280.964298) (xy 409.008308 -280.985396)
			(xy 408.961037 -280.999088) (xy 408.912182 -281.00502) (xy 408.863007 -281.003039) (xy 408.814788 -280.993195)
			(xy 408.768772 -280.975743) (xy 408.726151 -280.951136) (xy 408.68803 -280.920011) (xy 408.655395 -280.883174)
			(xy 408.629092 -280.841578) (xy 408.609801 -280.796302) (xy 408.598024 -280.748518) (xy 408.594064 -280.699464)
			(xy 407.305256 -280.699464) (xy 407.304761 -280.724071) (xy 407.296866 -280.772648) (xy 407.281282 -280.819329)
			(xy 407.258411 -280.862906) (xy 407.228846 -280.90225) (xy 407.193353 -280.936342) (xy 407.15285 -280.964298)
			(xy 407.108388 -280.985396) (xy 407.061117 -280.999088) (xy 407.012262 -281.00502) (xy 406.963087 -281.003039)
			(xy 406.914868 -280.993195) (xy 406.868852 -280.975743) (xy 406.826231 -280.951136) (xy 406.78811 -280.920011)
			(xy 406.755475 -280.883174) (xy 406.729172 -280.841578) (xy 406.709881 -280.796302) (xy 406.698104 -280.748518)
			(xy 406.694144 -280.699464) (xy 405.405082 -280.699464) (xy 405.404587 -280.724071) (xy 405.396692 -280.772648)
			(xy 405.381108 -280.819329) (xy 405.358237 -280.862906) (xy 405.328672 -280.90225) (xy 405.293179 -280.936342)
			(xy 405.252676 -280.964298) (xy 405.208214 -280.985396) (xy 405.160943 -280.999088) (xy 405.112088 -281.00502)
			(xy 405.062913 -281.003039) (xy 405.014694 -280.993195) (xy 404.968678 -280.975743) (xy 404.926057 -280.951136)
			(xy 404.887936 -280.920011) (xy 404.855301 -280.883174) (xy 404.828998 -280.841578) (xy 404.809707 -280.796302)
			(xy 404.79793 -280.748518) (xy 404.79397 -280.699464) (xy 403.505162 -280.699464) (xy 403.504667 -280.724071)
			(xy 403.496772 -280.772648) (xy 403.481188 -280.819329) (xy 403.458317 -280.862906) (xy 403.428752 -280.90225)
			(xy 403.393259 -280.936342) (xy 403.352756 -280.964298) (xy 403.308294 -280.985396) (xy 403.261023 -280.999088)
			(xy 403.212168 -281.00502) (xy 403.162993 -281.003039) (xy 403.114774 -280.993195) (xy 403.068758 -280.975743)
			(xy 403.026137 -280.951136) (xy 402.988016 -280.920011) (xy 402.955381 -280.883174) (xy 402.929078 -280.841578)
			(xy 402.909787 -280.796302) (xy 402.89801 -280.748518) (xy 402.89405 -280.699464) (xy 401.605242 -280.699464)
			(xy 401.604747 -280.724071) (xy 401.596852 -280.772648) (xy 401.581268 -280.819329) (xy 401.558397 -280.862906)
			(xy 401.528832 -280.90225) (xy 401.493339 -280.936342) (xy 401.452836 -280.964298) (xy 401.408374 -280.985396)
			(xy 401.361103 -280.999088) (xy 401.312248 -281.00502) (xy 401.263073 -281.003039) (xy 401.214854 -280.993195)
			(xy 401.168838 -280.975743) (xy 401.126217 -280.951136) (xy 401.088096 -280.920011) (xy 401.055461 -280.883174)
			(xy 401.029158 -280.841578) (xy 401.009867 -280.796302) (xy 400.99809 -280.748518) (xy 400.99413 -280.699464)
			(xy 399.705322 -280.699464) (xy 399.704827 -280.724071) (xy 399.696932 -280.772648) (xy 399.681348 -280.819329)
			(xy 399.658477 -280.862906) (xy 399.628912 -280.90225) (xy 399.593419 -280.936342) (xy 399.552916 -280.964298)
			(xy 399.508454 -280.985396) (xy 399.461183 -280.999088) (xy 399.412328 -281.00502) (xy 399.363153 -281.003039)
			(xy 399.314934 -280.993195) (xy 399.268918 -280.975743) (xy 399.226297 -280.951136) (xy 399.188176 -280.920011)
			(xy 399.155541 -280.883174) (xy 399.129238 -280.841578) (xy 399.109947 -280.796302) (xy 399.09817 -280.748518)
			(xy 399.09421 -280.699464) (xy 397.805148 -280.699464) (xy 397.804653 -280.724071) (xy 397.796758 -280.772648)
			(xy 397.781174 -280.819329) (xy 397.758303 -280.862906) (xy 397.728738 -280.90225) (xy 397.693245 -280.936342)
			(xy 397.652742 -280.964298) (xy 397.60828 -280.985396) (xy 397.561009 -280.999088) (xy 397.512154 -281.00502)
			(xy 397.462979 -281.003039) (xy 397.41476 -280.993195) (xy 397.368744 -280.975743) (xy 397.326123 -280.951136)
			(xy 397.288002 -280.920011) (xy 397.255367 -280.883174) (xy 397.229064 -280.841578) (xy 397.209773 -280.796302)
			(xy 397.197996 -280.748518) (xy 397.194036 -280.699464) (xy 395.905228 -280.699464) (xy 395.904733 -280.724071)
			(xy 395.896838 -280.772648) (xy 395.881254 -280.819329) (xy 395.858383 -280.862906) (xy 395.828818 -280.90225)
			(xy 395.793325 -280.936342) (xy 395.752822 -280.964298) (xy 395.70836 -280.985396) (xy 395.661089 -280.999088)
			(xy 395.612234 -281.00502) (xy 395.563059 -281.003039) (xy 395.51484 -280.993195) (xy 395.468824 -280.975743)
			(xy 395.426203 -280.951136) (xy 395.388082 -280.920011) (xy 395.355447 -280.883174) (xy 395.329144 -280.841578)
			(xy 395.309853 -280.796302) (xy 395.298076 -280.748518) (xy 395.294116 -280.699464) (xy 394.005308 -280.699464)
			(xy 394.004813 -280.724071) (xy 393.996918 -280.772648) (xy 393.981334 -280.819329) (xy 393.958463 -280.862906)
			(xy 393.928898 -280.90225) (xy 393.893405 -280.936342) (xy 393.852902 -280.964298) (xy 393.80844 -280.985396)
			(xy 393.761169 -280.999088) (xy 393.712314 -281.00502) (xy 393.663139 -281.003039) (xy 393.61492 -280.993195)
			(xy 393.568904 -280.975743) (xy 393.526283 -280.951136) (xy 393.488162 -280.920011) (xy 393.455527 -280.883174)
			(xy 393.429224 -280.841578) (xy 393.409933 -280.796302) (xy 393.398156 -280.748518) (xy 393.394196 -280.699464)
			(xy 312.105035 -280.699464) (xy 312.10504 -280.699718) (xy 312.104545 -280.724325) (xy 312.09665 -280.772902)
			(xy 312.081066 -280.819583) (xy 312.058195 -280.86316) (xy 312.02863 -280.902504) (xy 311.993137 -280.936596)
			(xy 311.952634 -280.964552) (xy 311.908172 -280.98565) (xy 311.860901 -280.999342) (xy 311.812046 -281.005274)
			(xy 311.762871 -281.003293) (xy 311.714652 -280.993449) (xy 311.668636 -280.975997) (xy 311.626015 -280.95139)
			(xy 311.587894 -280.920265) (xy 311.555259 -280.883428) (xy 311.528956 -280.841832) (xy 311.509665 -280.796556)
			(xy 311.497888 -280.748772) (xy 311.493928 -280.699718) (xy 310.205115 -280.699718) (xy 310.204625 -280.724071)
			(xy 310.19673 -280.772648) (xy 310.181146 -280.819329) (xy 310.158275 -280.862906) (xy 310.12871 -280.90225)
			(xy 310.093217 -280.936342) (xy 310.052714 -280.964298) (xy 310.008252 -280.985396) (xy 309.960981 -280.999088)
			(xy 309.912126 -281.00502) (xy 309.862951 -281.003039) (xy 309.814732 -280.993195) (xy 309.768716 -280.975743)
			(xy 309.726095 -280.951136) (xy 309.687974 -280.920011) (xy 309.655339 -280.883174) (xy 309.629036 -280.841578)
			(xy 309.609745 -280.796302) (xy 309.597968 -280.748518) (xy 309.594008 -280.699464) (xy 308.3052 -280.699464)
			(xy 308.304705 -280.724071) (xy 308.29681 -280.772648) (xy 308.281226 -280.819329) (xy 308.258355 -280.862906)
			(xy 308.22879 -280.90225) (xy 308.193297 -280.936342) (xy 308.152794 -280.964298) (xy 308.108332 -280.985396)
			(xy 308.061061 -280.999088) (xy 308.012206 -281.00502) (xy 307.963031 -281.003039) (xy 307.914812 -280.993195)
			(xy 307.868796 -280.975743) (xy 307.826175 -280.951136) (xy 307.788054 -280.920011) (xy 307.755419 -280.883174)
			(xy 307.729116 -280.841578) (xy 307.709825 -280.796302) (xy 307.698048 -280.748518) (xy 307.694088 -280.699464)
			(xy 306.405026 -280.699464) (xy 306.404531 -280.724071) (xy 306.396636 -280.772648) (xy 306.381052 -280.819329)
			(xy 306.358181 -280.862906) (xy 306.328616 -280.90225) (xy 306.293123 -280.936342) (xy 306.25262 -280.964298)
			(xy 306.208158 -280.985396) (xy 306.160887 -280.999088) (xy 306.112032 -281.00502) (xy 306.062857 -281.003039)
			(xy 306.014638 -280.993195) (xy 305.968622 -280.975743) (xy 305.926001 -280.951136) (xy 305.88788 -280.920011)
			(xy 305.855245 -280.883174) (xy 305.828942 -280.841578) (xy 305.809651 -280.796302) (xy 305.797874 -280.748518)
			(xy 305.793914 -280.699464) (xy 304.505106 -280.699464) (xy 304.504611 -280.724071) (xy 304.496716 -280.772648)
			(xy 304.481132 -280.819329) (xy 304.458261 -280.862906) (xy 304.428696 -280.90225) (xy 304.393203 -280.936342)
			(xy 304.3527 -280.964298) (xy 304.308238 -280.985396) (xy 304.260967 -280.999088) (xy 304.212112 -281.00502)
			(xy 304.162937 -281.003039) (xy 304.114718 -280.993195) (xy 304.068702 -280.975743) (xy 304.026081 -280.951136)
			(xy 303.98796 -280.920011) (xy 303.955325 -280.883174) (xy 303.929022 -280.841578) (xy 303.909731 -280.796302)
			(xy 303.897954 -280.748518) (xy 303.893994 -280.699464) (xy 302.605186 -280.699464) (xy 302.604691 -280.724071)
			(xy 302.596796 -280.772648) (xy 302.581212 -280.819329) (xy 302.558341 -280.862906) (xy 302.528776 -280.90225)
			(xy 302.493283 -280.936342) (xy 302.45278 -280.964298) (xy 302.408318 -280.985396) (xy 302.361047 -280.999088)
			(xy 302.312192 -281.00502) (xy 302.263017 -281.003039) (xy 302.214798 -280.993195) (xy 302.168782 -280.975743)
			(xy 302.126161 -280.951136) (xy 302.08804 -280.920011) (xy 302.055405 -280.883174) (xy 302.029102 -280.841578)
			(xy 302.009811 -280.796302) (xy 301.998034 -280.748518) (xy 301.994074 -280.699464) (xy 300.705012 -280.699464)
			(xy 300.704517 -280.724071) (xy 300.696622 -280.772648) (xy 300.681038 -280.819329) (xy 300.658167 -280.862906)
			(xy 300.628602 -280.90225) (xy 300.593109 -280.936342) (xy 300.552606 -280.964298) (xy 300.508144 -280.985396)
			(xy 300.460873 -280.999088) (xy 300.412018 -281.00502) (xy 300.362843 -281.003039) (xy 300.314624 -280.993195)
			(xy 300.268608 -280.975743) (xy 300.225987 -280.951136) (xy 300.187866 -280.920011) (xy 300.155231 -280.883174)
			(xy 300.128928 -280.841578) (xy 300.109637 -280.796302) (xy 300.09786 -280.748518) (xy 300.0939 -280.699464)
			(xy 298.805092 -280.699464) (xy 298.804597 -280.724071) (xy 298.796702 -280.772648) (xy 298.781118 -280.819329)
			(xy 298.758247 -280.862906) (xy 298.728682 -280.90225) (xy 298.693189 -280.936342) (xy 298.652686 -280.964298)
			(xy 298.608224 -280.985396) (xy 298.560953 -280.999088) (xy 298.512098 -281.00502) (xy 298.462923 -281.003039)
			(xy 298.414704 -280.993195) (xy 298.368688 -280.975743) (xy 298.326067 -280.951136) (xy 298.287946 -280.920011)
			(xy 298.255311 -280.883174) (xy 298.229008 -280.841578) (xy 298.209717 -280.796302) (xy 298.19794 -280.748518)
			(xy 298.19398 -280.699464) (xy 296.905172 -280.699464) (xy 296.904677 -280.724071) (xy 296.896782 -280.772648)
			(xy 296.881198 -280.819329) (xy 296.858327 -280.862906) (xy 296.828762 -280.90225) (xy 296.793269 -280.936342)
			(xy 296.752766 -280.964298) (xy 296.708304 -280.985396) (xy 296.661033 -280.999088) (xy 296.612178 -281.00502)
			(xy 296.563003 -281.003039) (xy 296.514784 -280.993195) (xy 296.468768 -280.975743) (xy 296.426147 -280.951136)
			(xy 296.388026 -280.920011) (xy 296.355391 -280.883174) (xy 296.329088 -280.841578) (xy 296.309797 -280.796302)
			(xy 296.29802 -280.748518) (xy 296.29406 -280.699464) (xy 295.004998 -280.699464) (xy 295.004503 -280.724071)
			(xy 294.996608 -280.772648) (xy 294.981024 -280.819329) (xy 294.958153 -280.862906) (xy 294.928588 -280.90225)
			(xy 294.893095 -280.936342) (xy 294.852592 -280.964298) (xy 294.80813 -280.985396) (xy 294.760859 -280.999088)
			(xy 294.712004 -281.00502) (xy 294.662829 -281.003039) (xy 294.61461 -280.993195) (xy 294.568594 -280.975743)
			(xy 294.525973 -280.951136) (xy 294.487852 -280.920011) (xy 294.455217 -280.883174) (xy 294.428914 -280.841578)
			(xy 294.409623 -280.796302) (xy 294.397846 -280.748518) (xy 294.393886 -280.699464) (xy 293.105078 -280.699464)
			(xy 293.104583 -280.724071) (xy 293.096688 -280.772648) (xy 293.081104 -280.819329) (xy 293.058233 -280.862906)
			(xy 293.028668 -280.90225) (xy 292.993175 -280.936342) (xy 292.952672 -280.964298) (xy 292.90821 -280.985396)
			(xy 292.860939 -280.999088) (xy 292.812084 -281.00502) (xy 292.762909 -281.003039) (xy 292.71469 -280.993195)
			(xy 292.668674 -280.975743) (xy 292.626053 -280.951136) (xy 292.587932 -280.920011) (xy 292.555297 -280.883174)
			(xy 292.528994 -280.841578) (xy 292.509703 -280.796302) (xy 292.497926 -280.748518) (xy 292.493966 -280.699464)
			(xy 291.205158 -280.699464) (xy 291.204663 -280.724071) (xy 291.196768 -280.772648) (xy 291.181184 -280.819329)
			(xy 291.158313 -280.862906) (xy 291.128748 -280.90225) (xy 291.093255 -280.936342) (xy 291.052752 -280.964298)
			(xy 291.00829 -280.985396) (xy 290.961019 -280.999088) (xy 290.912164 -281.00502) (xy 290.862989 -281.003039)
			(xy 290.81477 -280.993195) (xy 290.768754 -280.975743) (xy 290.726133 -280.951136) (xy 290.688012 -280.920011)
			(xy 290.655377 -280.883174) (xy 290.629074 -280.841578) (xy 290.609783 -280.796302) (xy 290.598006 -280.748518)
			(xy 290.594046 -280.699464) (xy 289.304984 -280.699464) (xy 289.304489 -280.724071) (xy 289.296594 -280.772648)
			(xy 289.28101 -280.819329) (xy 289.258139 -280.862906) (xy 289.228574 -280.90225) (xy 289.193081 -280.936342)
			(xy 289.152578 -280.964298) (xy 289.108116 -280.985396) (xy 289.060845 -280.999088) (xy 289.01199 -281.00502)
			(xy 288.962815 -281.003039) (xy 288.914596 -280.993195) (xy 288.86858 -280.975743) (xy 288.825959 -280.951136)
			(xy 288.787838 -280.920011) (xy 288.755203 -280.883174) (xy 288.7289 -280.841578) (xy 288.709609 -280.796302)
			(xy 288.697832 -280.748518) (xy 288.693872 -280.699464) (xy 287.405064 -280.699464) (xy 287.404569 -280.724071)
			(xy 287.396674 -280.772648) (xy 287.38109 -280.819329) (xy 287.358219 -280.862906) (xy 287.328654 -280.90225)
			(xy 287.293161 -280.936342) (xy 287.252658 -280.964298) (xy 287.208196 -280.985396) (xy 287.160925 -280.999088)
			(xy 287.11207 -281.00502) (xy 287.062895 -281.003039) (xy 287.014676 -280.993195) (xy 286.96866 -280.975743)
			(xy 286.926039 -280.951136) (xy 286.887918 -280.920011) (xy 286.855283 -280.883174) (xy 286.82898 -280.841578)
			(xy 286.809689 -280.796302) (xy 286.797912 -280.748518) (xy 286.793952 -280.699464) (xy 285.505144 -280.699464)
			(xy 285.504649 -280.724071) (xy 285.496754 -280.772648) (xy 285.48117 -280.819329) (xy 285.458299 -280.862906)
			(xy 285.428734 -280.90225) (xy 285.393241 -280.936342) (xy 285.352738 -280.964298) (xy 285.308276 -280.985396)
			(xy 285.261005 -280.999088) (xy 285.21215 -281.00502) (xy 285.162975 -281.003039) (xy 285.114756 -280.993195)
			(xy 285.06874 -280.975743) (xy 285.026119 -280.951136) (xy 284.987998 -280.920011) (xy 284.955363 -280.883174)
			(xy 284.92906 -280.841578) (xy 284.909769 -280.796302) (xy 284.897992 -280.748518) (xy 284.894032 -280.699464)
			(xy 283.605224 -280.699464) (xy 283.604729 -280.724071) (xy 283.596834 -280.772648) (xy 283.58125 -280.819329)
			(xy 283.558379 -280.862906) (xy 283.528814 -280.90225) (xy 283.493321 -280.936342) (xy 283.452818 -280.964298)
			(xy 283.408356 -280.985396) (xy 283.361085 -280.999088) (xy 283.31223 -281.00502) (xy 283.263055 -281.003039)
			(xy 283.214836 -280.993195) (xy 283.16882 -280.975743) (xy 283.126199 -280.951136) (xy 283.088078 -280.920011)
			(xy 283.055443 -280.883174) (xy 283.02914 -280.841578) (xy 283.009849 -280.796302) (xy 282.998072 -280.748518)
			(xy 282.994112 -280.699464) (xy 281.70505 -280.699464) (xy 281.704555 -280.724071) (xy 281.69666 -280.772648)
			(xy 281.681076 -280.819329) (xy 281.658205 -280.862906) (xy 281.62864 -280.90225) (xy 281.593147 -280.936342)
			(xy 281.552644 -280.964298) (xy 281.508182 -280.985396) (xy 281.460911 -280.999088) (xy 281.412056 -281.00502)
			(xy 281.362881 -281.003039) (xy 281.314662 -280.993195) (xy 281.268646 -280.975743) (xy 281.226025 -280.951136)
			(xy 281.187904 -280.920011) (xy 281.155269 -280.883174) (xy 281.128966 -280.841578) (xy 281.109675 -280.796302)
			(xy 281.097898 -280.748518) (xy 281.093938 -280.699464) (xy 279.80513 -280.699464) (xy 279.804635 -280.724071)
			(xy 279.79674 -280.772648) (xy 279.781156 -280.819329) (xy 279.758285 -280.862906) (xy 279.72872 -280.90225)
			(xy 279.693227 -280.936342) (xy 279.652724 -280.964298) (xy 279.608262 -280.985396) (xy 279.560991 -280.999088)
			(xy 279.512136 -281.00502) (xy 279.462961 -281.003039) (xy 279.414742 -280.993195) (xy 279.368726 -280.975743)
			(xy 279.326105 -280.951136) (xy 279.287984 -280.920011) (xy 279.255349 -280.883174) (xy 279.229046 -280.841578)
			(xy 279.209755 -280.796302) (xy 279.197978 -280.748518) (xy 279.194018 -280.699464) (xy 277.90521 -280.699464)
			(xy 277.904715 -280.724071) (xy 277.89682 -280.772648) (xy 277.881236 -280.819329) (xy 277.858365 -280.862906)
			(xy 277.8288 -280.90225) (xy 277.793307 -280.936342) (xy 277.752804 -280.964298) (xy 277.708342 -280.985396)
			(xy 277.661071 -280.999088) (xy 277.612216 -281.00502) (xy 277.563041 -281.003039) (xy 277.514822 -280.993195)
			(xy 277.468806 -280.975743) (xy 277.426185 -280.951136) (xy 277.388064 -280.920011) (xy 277.355429 -280.883174)
			(xy 277.329126 -280.841578) (xy 277.309835 -280.796302) (xy 277.298058 -280.748518) (xy 277.294098 -280.699464)
			(xy 196.005191 -280.699464) (xy 196.005196 -280.699718) (xy 196.004701 -280.724325) (xy 195.996806 -280.772902)
			(xy 195.981222 -280.819583) (xy 195.958351 -280.86316) (xy 195.928786 -280.902504) (xy 195.893293 -280.936596)
			(xy 195.85279 -280.964552) (xy 195.808328 -280.98565) (xy 195.761057 -280.999342) (xy 195.712202 -281.005274)
			(xy 195.663027 -281.003293) (xy 195.614808 -280.993449) (xy 195.568792 -280.975997) (xy 195.526171 -280.95139)
			(xy 195.48805 -280.920265) (xy 195.455415 -280.883428) (xy 195.429112 -280.841832) (xy 195.409821 -280.796556)
			(xy 195.398044 -280.748772) (xy 195.394084 -280.699718) (xy 194.105276 -280.699718) (xy 194.104781 -280.724325)
			(xy 194.096886 -280.772902) (xy 194.081302 -280.819583) (xy 194.058431 -280.86316) (xy 194.028866 -280.902504)
			(xy 193.993373 -280.936596) (xy 193.95287 -280.964552) (xy 193.908408 -280.98565) (xy 193.861137 -280.999342)
			(xy 193.812282 -281.005274) (xy 193.763107 -281.003293) (xy 193.714888 -280.993449) (xy 193.668872 -280.975997)
			(xy 193.626251 -280.95139) (xy 193.58813 -280.920265) (xy 193.555495 -280.883428) (xy 193.529192 -280.841832)
			(xy 193.509901 -280.796556) (xy 193.498124 -280.748772) (xy 193.494164 -280.699718) (xy 192.205356 -280.699718)
			(xy 192.204861 -280.724325) (xy 192.196966 -280.772902) (xy 192.181382 -280.819583) (xy 192.158511 -280.86316)
			(xy 192.128946 -280.902504) (xy 192.093453 -280.936596) (xy 192.05295 -280.964552) (xy 192.008488 -280.98565)
			(xy 191.961217 -280.999342) (xy 191.912362 -281.005274) (xy 191.863187 -281.003293) (xy 191.814968 -280.993449)
			(xy 191.768952 -280.975997) (xy 191.726331 -280.95139) (xy 191.68821 -280.920265) (xy 191.655575 -280.883428)
			(xy 191.629272 -280.841832) (xy 191.609981 -280.796556) (xy 191.598204 -280.748772) (xy 191.594244 -280.699718)
			(xy 190.305182 -280.699718) (xy 190.304687 -280.724325) (xy 190.296792 -280.772902) (xy 190.281208 -280.819583)
			(xy 190.258337 -280.86316) (xy 190.228772 -280.902504) (xy 190.193279 -280.936596) (xy 190.152776 -280.964552)
			(xy 190.108314 -280.98565) (xy 190.061043 -280.999342) (xy 190.012188 -281.005274) (xy 189.963013 -281.003293)
			(xy 189.914794 -280.993449) (xy 189.868778 -280.975997) (xy 189.826157 -280.95139) (xy 189.788036 -280.920265)
			(xy 189.755401 -280.883428) (xy 189.729098 -280.841832) (xy 189.709807 -280.796556) (xy 189.69803 -280.748772)
			(xy 189.69407 -280.699718) (xy 188.405262 -280.699718) (xy 188.404767 -280.724325) (xy 188.396872 -280.772902)
			(xy 188.381288 -280.819583) (xy 188.358417 -280.86316) (xy 188.328852 -280.902504) (xy 188.293359 -280.936596)
			(xy 188.252856 -280.964552) (xy 188.208394 -280.98565) (xy 188.161123 -280.999342) (xy 188.112268 -281.005274)
			(xy 188.063093 -281.003293) (xy 188.014874 -280.993449) (xy 187.968858 -280.975997) (xy 187.926237 -280.95139)
			(xy 187.888116 -280.920265) (xy 187.855481 -280.883428) (xy 187.829178 -280.841832) (xy 187.809887 -280.796556)
			(xy 187.79811 -280.748772) (xy 187.79415 -280.699718) (xy 186.505342 -280.699718) (xy 186.504847 -280.724325)
			(xy 186.496952 -280.772902) (xy 186.481368 -280.819583) (xy 186.458497 -280.86316) (xy 186.428932 -280.902504)
			(xy 186.393439 -280.936596) (xy 186.352936 -280.964552) (xy 186.308474 -280.98565) (xy 186.261203 -280.999342)
			(xy 186.212348 -281.005274) (xy 186.163173 -281.003293) (xy 186.114954 -280.993449) (xy 186.068938 -280.975997)
			(xy 186.026317 -280.95139) (xy 185.988196 -280.920265) (xy 185.955561 -280.883428) (xy 185.929258 -280.841832)
			(xy 185.909967 -280.796556) (xy 185.89819 -280.748772) (xy 185.89423 -280.699718) (xy 184.605168 -280.699718)
			(xy 184.604673 -280.724325) (xy 184.596778 -280.772902) (xy 184.581194 -280.819583) (xy 184.558323 -280.86316)
			(xy 184.528758 -280.902504) (xy 184.493265 -280.936596) (xy 184.452762 -280.964552) (xy 184.4083 -280.98565)
			(xy 184.361029 -280.999342) (xy 184.312174 -281.005274) (xy 184.262999 -281.003293) (xy 184.21478 -280.993449)
			(xy 184.168764 -280.975997) (xy 184.126143 -280.95139) (xy 184.088022 -280.920265) (xy 184.055387 -280.883428)
			(xy 184.029084 -280.841832) (xy 184.009793 -280.796556) (xy 183.998016 -280.748772) (xy 183.994056 -280.699718)
			(xy 182.705248 -280.699718) (xy 182.704753 -280.724325) (xy 182.696858 -280.772902) (xy 182.681274 -280.819583)
			(xy 182.658403 -280.86316) (xy 182.628838 -280.902504) (xy 182.593345 -280.936596) (xy 182.552842 -280.964552)
			(xy 182.50838 -280.98565) (xy 182.461109 -280.999342) (xy 182.412254 -281.005274) (xy 182.363079 -281.003293)
			(xy 182.31486 -280.993449) (xy 182.268844 -280.975997) (xy 182.226223 -280.95139) (xy 182.188102 -280.920265)
			(xy 182.155467 -280.883428) (xy 182.129164 -280.841832) (xy 182.109873 -280.796556) (xy 182.098096 -280.748772)
			(xy 182.094136 -280.699718) (xy 180.805328 -280.699718) (xy 180.804833 -280.724325) (xy 180.796938 -280.772902)
			(xy 180.781354 -280.819583) (xy 180.758483 -280.86316) (xy 180.728918 -280.902504) (xy 180.693425 -280.936596)
			(xy 180.652922 -280.964552) (xy 180.60846 -280.98565) (xy 180.561189 -280.999342) (xy 180.512334 -281.005274)
			(xy 180.463159 -281.003293) (xy 180.41494 -280.993449) (xy 180.368924 -280.975997) (xy 180.326303 -280.95139)
			(xy 180.288182 -280.920265) (xy 180.255547 -280.883428) (xy 180.229244 -280.841832) (xy 180.209953 -280.796556)
			(xy 180.198176 -280.748772) (xy 180.194216 -280.699718) (xy 178.905154 -280.699718) (xy 178.904659 -280.724325)
			(xy 178.896764 -280.772902) (xy 178.88118 -280.819583) (xy 178.858309 -280.86316) (xy 178.828744 -280.902504)
			(xy 178.793251 -280.936596) (xy 178.752748 -280.964552) (xy 178.708286 -280.98565) (xy 178.661015 -280.999342)
			(xy 178.61216 -281.005274) (xy 178.562985 -281.003293) (xy 178.514766 -280.993449) (xy 178.46875 -280.975997)
			(xy 178.426129 -280.95139) (xy 178.388008 -280.920265) (xy 178.355373 -280.883428) (xy 178.32907 -280.841832)
			(xy 178.309779 -280.796556) (xy 178.298002 -280.748772) (xy 178.294042 -280.699718) (xy 177.005234 -280.699718)
			(xy 177.004739 -280.724325) (xy 176.996844 -280.772902) (xy 176.98126 -280.819583) (xy 176.958389 -280.86316)
			(xy 176.928824 -280.902504) (xy 176.893331 -280.936596) (xy 176.852828 -280.964552) (xy 176.808366 -280.98565)
			(xy 176.761095 -280.999342) (xy 176.71224 -281.005274) (xy 176.663065 -281.003293) (xy 176.614846 -280.993449)
			(xy 176.56883 -280.975997) (xy 176.526209 -280.95139) (xy 176.488088 -280.920265) (xy 176.455453 -280.883428)
			(xy 176.42915 -280.841832) (xy 176.409859 -280.796556) (xy 176.398082 -280.748772) (xy 176.394122 -280.699718)
			(xy 175.105314 -280.699718) (xy 175.104819 -280.724325) (xy 175.096924 -280.772902) (xy 175.08134 -280.819583)
			(xy 175.058469 -280.86316) (xy 175.028904 -280.902504) (xy 174.993411 -280.936596) (xy 174.952908 -280.964552)
			(xy 174.908446 -280.98565) (xy 174.861175 -280.999342) (xy 174.81232 -281.005274) (xy 174.763145 -281.003293)
			(xy 174.714926 -280.993449) (xy 174.66891 -280.975997) (xy 174.626289 -280.95139) (xy 174.588168 -280.920265)
			(xy 174.555533 -280.883428) (xy 174.52923 -280.841832) (xy 174.509939 -280.796556) (xy 174.498162 -280.748772)
			(xy 174.494202 -280.699718) (xy 173.20514 -280.699718) (xy 173.204645 -280.724325) (xy 173.19675 -280.772902)
			(xy 173.181166 -280.819583) (xy 173.158295 -280.86316) (xy 173.12873 -280.902504) (xy 173.093237 -280.936596)
			(xy 173.052734 -280.964552) (xy 173.008272 -280.98565) (xy 172.961001 -280.999342) (xy 172.912146 -281.005274)
			(xy 172.862971 -281.003293) (xy 172.814752 -280.993449) (xy 172.768736 -280.975997) (xy 172.726115 -280.95139)
			(xy 172.687994 -280.920265) (xy 172.655359 -280.883428) (xy 172.629056 -280.841832) (xy 172.609765 -280.796556)
			(xy 172.597988 -280.748772) (xy 172.594028 -280.699718) (xy 171.30522 -280.699718) (xy 171.304725 -280.724325)
			(xy 171.29683 -280.772902) (xy 171.281246 -280.819583) (xy 171.258375 -280.86316) (xy 171.22881 -280.902504)
			(xy 171.193317 -280.936596) (xy 171.152814 -280.964552) (xy 171.108352 -280.98565) (xy 171.061081 -280.999342)
			(xy 171.012226 -281.005274) (xy 170.963051 -281.003293) (xy 170.914832 -280.993449) (xy 170.868816 -280.975997)
			(xy 170.826195 -280.95139) (xy 170.788074 -280.920265) (xy 170.755439 -280.883428) (xy 170.729136 -280.841832)
			(xy 170.709845 -280.796556) (xy 170.698068 -280.748772) (xy 170.694108 -280.699718) (xy 169.4053 -280.699718)
			(xy 169.404805 -280.724325) (xy 169.39691 -280.772902) (xy 169.381326 -280.819583) (xy 169.358455 -280.86316)
			(xy 169.32889 -280.902504) (xy 169.293397 -280.936596) (xy 169.252894 -280.964552) (xy 169.208432 -280.98565)
			(xy 169.161161 -280.999342) (xy 169.112306 -281.005274) (xy 169.063131 -281.003293) (xy 169.014912 -280.993449)
			(xy 168.968896 -280.975997) (xy 168.926275 -280.95139) (xy 168.888154 -280.920265) (xy 168.855519 -280.883428)
			(xy 168.829216 -280.841832) (xy 168.809925 -280.796556) (xy 168.798148 -280.748772) (xy 168.794188 -280.699718)
			(xy 167.50538 -280.699718) (xy 167.504885 -280.724325) (xy 167.49699 -280.772902) (xy 167.481406 -280.819583)
			(xy 167.458535 -280.86316) (xy 167.42897 -280.902504) (xy 167.393477 -280.936596) (xy 167.352974 -280.964552)
			(xy 167.308512 -280.98565) (xy 167.261241 -280.999342) (xy 167.212386 -281.005274) (xy 167.163211 -281.003293)
			(xy 167.114992 -280.993449) (xy 167.068976 -280.975997) (xy 167.026355 -280.95139) (xy 166.988234 -280.920265)
			(xy 166.955599 -280.883428) (xy 166.929296 -280.841832) (xy 166.910005 -280.796556) (xy 166.898228 -280.748772)
			(xy 166.894268 -280.699718) (xy 165.605206 -280.699718) (xy 165.604711 -280.724325) (xy 165.596816 -280.772902)
			(xy 165.581232 -280.819583) (xy 165.558361 -280.86316) (xy 165.528796 -280.902504) (xy 165.493303 -280.936596)
			(xy 165.4528 -280.964552) (xy 165.408338 -280.98565) (xy 165.361067 -280.999342) (xy 165.312212 -281.005274)
			(xy 165.263037 -281.003293) (xy 165.214818 -280.993449) (xy 165.168802 -280.975997) (xy 165.126181 -280.95139)
			(xy 165.08806 -280.920265) (xy 165.055425 -280.883428) (xy 165.029122 -280.841832) (xy 165.009831 -280.796556)
			(xy 164.998054 -280.748772) (xy 164.994094 -280.699718) (xy 163.705286 -280.699718) (xy 163.704791 -280.724325)
			(xy 163.696896 -280.772902) (xy 163.681312 -280.819583) (xy 163.658441 -280.86316) (xy 163.628876 -280.902504)
			(xy 163.593383 -280.936596) (xy 163.55288 -280.964552) (xy 163.508418 -280.98565) (xy 163.461147 -280.999342)
			(xy 163.412292 -281.005274) (xy 163.363117 -281.003293) (xy 163.314898 -280.993449) (xy 163.268882 -280.975997)
			(xy 163.226261 -280.95139) (xy 163.18814 -280.920265) (xy 163.155505 -280.883428) (xy 163.129202 -280.841832)
			(xy 163.109911 -280.796556) (xy 163.098134 -280.748772) (xy 163.094174 -280.699718) (xy 161.805366 -280.699718)
			(xy 161.804871 -280.724325) (xy 161.796976 -280.772902) (xy 161.781392 -280.819583) (xy 161.758521 -280.86316)
			(xy 161.728956 -280.902504) (xy 161.693463 -280.936596) (xy 161.65296 -280.964552) (xy 161.608498 -280.98565)
			(xy 161.561227 -280.999342) (xy 161.512372 -281.005274) (xy 161.463197 -281.003293) (xy 161.414978 -280.993449)
			(xy 161.368962 -280.975997) (xy 161.326341 -280.95139) (xy 161.28822 -280.920265) (xy 161.255585 -280.883428)
			(xy 161.229282 -280.841832) (xy 161.209991 -280.796556) (xy 161.198214 -280.748772) (xy 161.194254 -280.699718)
			(xy 79.905098 -280.699718) (xy 79.904603 -280.724325) (xy 79.896708 -280.772902) (xy 79.881124 -280.819583)
			(xy 79.858253 -280.86316) (xy 79.828688 -280.902504) (xy 79.793195 -280.936596) (xy 79.752692 -280.964552)
			(xy 79.70823 -280.98565) (xy 79.660959 -280.999342) (xy 79.612104 -281.005274) (xy 79.562929 -281.003293)
			(xy 79.51471 -280.993449) (xy 79.468694 -280.975997) (xy 79.426073 -280.95139) (xy 79.387952 -280.920265)
			(xy 79.355317 -280.883428) (xy 79.329014 -280.841832) (xy 79.309723 -280.796556) (xy 79.297946 -280.748772)
			(xy 79.293986 -280.699718) (xy 78.005178 -280.699718) (xy 78.004683 -280.724325) (xy 77.996788 -280.772902)
			(xy 77.981204 -280.819583) (xy 77.958333 -280.86316) (xy 77.928768 -280.902504) (xy 77.893275 -280.936596)
			(xy 77.852772 -280.964552) (xy 77.80831 -280.98565) (xy 77.761039 -280.999342) (xy 77.712184 -281.005274)
			(xy 77.663009 -281.003293) (xy 77.61479 -280.993449) (xy 77.568774 -280.975997) (xy 77.526153 -280.95139)
			(xy 77.488032 -280.920265) (xy 77.455397 -280.883428) (xy 77.429094 -280.841832) (xy 77.409803 -280.796556)
			(xy 77.398026 -280.748772) (xy 77.394066 -280.699718) (xy 76.105258 -280.699718) (xy 76.104763 -280.724325)
			(xy 76.096868 -280.772902) (xy 76.081284 -280.819583) (xy 76.058413 -280.86316) (xy 76.028848 -280.902504)
			(xy 75.993355 -280.936596) (xy 75.952852 -280.964552) (xy 75.90839 -280.98565) (xy 75.861119 -280.999342)
			(xy 75.812264 -281.005274) (xy 75.763089 -281.003293) (xy 75.71487 -280.993449) (xy 75.668854 -280.975997)
			(xy 75.626233 -280.95139) (xy 75.588112 -280.920265) (xy 75.555477 -280.883428) (xy 75.529174 -280.841832)
			(xy 75.509883 -280.796556) (xy 75.498106 -280.748772) (xy 75.494146 -280.699718) (xy 74.205084 -280.699718)
			(xy 74.204589 -280.724325) (xy 74.196694 -280.772902) (xy 74.18111 -280.819583) (xy 74.158239 -280.86316)
			(xy 74.128674 -280.902504) (xy 74.093181 -280.936596) (xy 74.052678 -280.964552) (xy 74.008216 -280.98565)
			(xy 73.960945 -280.999342) (xy 73.91209 -281.005274) (xy 73.862915 -281.003293) (xy 73.814696 -280.993449)
			(xy 73.76868 -280.975997) (xy 73.726059 -280.95139) (xy 73.687938 -280.920265) (xy 73.655303 -280.883428)
			(xy 73.629 -280.841832) (xy 73.609709 -280.796556) (xy 73.597932 -280.748772) (xy 73.593972 -280.699718)
			(xy 72.305164 -280.699718) (xy 72.304669 -280.724325) (xy 72.296774 -280.772902) (xy 72.28119 -280.819583)
			(xy 72.258319 -280.86316) (xy 72.228754 -280.902504) (xy 72.193261 -280.936596) (xy 72.152758 -280.964552)
			(xy 72.108296 -280.98565) (xy 72.061025 -280.999342) (xy 72.01217 -281.005274) (xy 71.962995 -281.003293)
			(xy 71.914776 -280.993449) (xy 71.86876 -280.975997) (xy 71.826139 -280.95139) (xy 71.788018 -280.920265)
			(xy 71.755383 -280.883428) (xy 71.72908 -280.841832) (xy 71.709789 -280.796556) (xy 71.698012 -280.748772)
			(xy 71.694052 -280.699718) (xy 70.405244 -280.699718) (xy 70.404749 -280.724325) (xy 70.396854 -280.772902)
			(xy 70.38127 -280.819583) (xy 70.358399 -280.86316) (xy 70.328834 -280.902504) (xy 70.293341 -280.936596)
			(xy 70.252838 -280.964552) (xy 70.208376 -280.98565) (xy 70.161105 -280.999342) (xy 70.11225 -281.005274)
			(xy 70.063075 -281.003293) (xy 70.014856 -280.993449) (xy 69.96884 -280.975997) (xy 69.926219 -280.95139)
			(xy 69.888098 -280.920265) (xy 69.855463 -280.883428) (xy 69.82916 -280.841832) (xy 69.809869 -280.796556)
			(xy 69.798092 -280.748772) (xy 69.794132 -280.699718) (xy 68.50507 -280.699718) (xy 68.504575 -280.724325)
			(xy 68.49668 -280.772902) (xy 68.481096 -280.819583) (xy 68.458225 -280.86316) (xy 68.42866 -280.902504)
			(xy 68.393167 -280.936596) (xy 68.352664 -280.964552) (xy 68.308202 -280.98565) (xy 68.260931 -280.999342)
			(xy 68.212076 -281.005274) (xy 68.162901 -281.003293) (xy 68.114682 -280.993449) (xy 68.068666 -280.975997)
			(xy 68.026045 -280.95139) (xy 67.987924 -280.920265) (xy 67.955289 -280.883428) (xy 67.928986 -280.841832)
			(xy 67.909695 -280.796556) (xy 67.897918 -280.748772) (xy 67.893958 -280.699718) (xy 66.60515 -280.699718)
			(xy 66.604655 -280.724325) (xy 66.59676 -280.772902) (xy 66.581176 -280.819583) (xy 66.558305 -280.86316)
			(xy 66.52874 -280.902504) (xy 66.493247 -280.936596) (xy 66.452744 -280.964552) (xy 66.408282 -280.98565)
			(xy 66.361011 -280.999342) (xy 66.312156 -281.005274) (xy 66.262981 -281.003293) (xy 66.214762 -280.993449)
			(xy 66.168746 -280.975997) (xy 66.126125 -280.95139) (xy 66.088004 -280.920265) (xy 66.055369 -280.883428)
			(xy 66.029066 -280.841832) (xy 66.009775 -280.796556) (xy 65.997998 -280.748772) (xy 65.994038 -280.699718)
			(xy 64.70523 -280.699718) (xy 64.704735 -280.724325) (xy 64.69684 -280.772902) (xy 64.681256 -280.819583)
			(xy 64.658385 -280.86316) (xy 64.62882 -280.902504) (xy 64.593327 -280.936596) (xy 64.552824 -280.964552)
			(xy 64.508362 -280.98565) (xy 64.461091 -280.999342) (xy 64.412236 -281.005274) (xy 64.363061 -281.003293)
			(xy 64.314842 -280.993449) (xy 64.268826 -280.975997) (xy 64.226205 -280.95139) (xy 64.188084 -280.920265)
			(xy 64.155449 -280.883428) (xy 64.129146 -280.841832) (xy 64.109855 -280.796556) (xy 64.098078 -280.748772)
			(xy 64.094118 -280.699718) (xy 62.805056 -280.699718) (xy 62.804561 -280.724325) (xy 62.796666 -280.772902)
			(xy 62.781082 -280.819583) (xy 62.758211 -280.86316) (xy 62.728646 -280.902504) (xy 62.693153 -280.936596)
			(xy 62.65265 -280.964552) (xy 62.608188 -280.98565) (xy 62.560917 -280.999342) (xy 62.512062 -281.005274)
			(xy 62.462887 -281.003293) (xy 62.414668 -280.993449) (xy 62.368652 -280.975997) (xy 62.326031 -280.95139)
			(xy 62.28791 -280.920265) (xy 62.255275 -280.883428) (xy 62.228972 -280.841832) (xy 62.209681 -280.796556)
			(xy 62.197904 -280.748772) (xy 62.193944 -280.699718) (xy 60.905136 -280.699718) (xy 60.904641 -280.724325)
			(xy 60.896746 -280.772902) (xy 60.881162 -280.819583) (xy 60.858291 -280.86316) (xy 60.828726 -280.902504)
			(xy 60.793233 -280.936596) (xy 60.75273 -280.964552) (xy 60.708268 -280.98565) (xy 60.660997 -280.999342)
			(xy 60.612142 -281.005274) (xy 60.562967 -281.003293) (xy 60.514748 -280.993449) (xy 60.468732 -280.975997)
			(xy 60.426111 -280.95139) (xy 60.38799 -280.920265) (xy 60.355355 -280.883428) (xy 60.329052 -280.841832)
			(xy 60.309761 -280.796556) (xy 60.297984 -280.748772) (xy 60.294024 -280.699718) (xy 59.005216 -280.699718)
			(xy 59.004721 -280.724325) (xy 58.996826 -280.772902) (xy 58.981242 -280.819583) (xy 58.958371 -280.86316)
			(xy 58.928806 -280.902504) (xy 58.893313 -280.936596) (xy 58.85281 -280.964552) (xy 58.808348 -280.98565)
			(xy 58.761077 -280.999342) (xy 58.712222 -281.005274) (xy 58.663047 -281.003293) (xy 58.614828 -280.993449)
			(xy 58.568812 -280.975997) (xy 58.526191 -280.95139) (xy 58.48807 -280.920265) (xy 58.455435 -280.883428)
			(xy 58.429132 -280.841832) (xy 58.409841 -280.796556) (xy 58.398064 -280.748772) (xy 58.394104 -280.699718)
			(xy 57.105042 -280.699718) (xy 57.104547 -280.724325) (xy 57.096652 -280.772902) (xy 57.081068 -280.819583)
			(xy 57.058197 -280.86316) (xy 57.028632 -280.902504) (xy 56.993139 -280.936596) (xy 56.952636 -280.964552)
			(xy 56.908174 -280.98565) (xy 56.860903 -280.999342) (xy 56.812048 -281.005274) (xy 56.762873 -281.003293)
			(xy 56.714654 -280.993449) (xy 56.668638 -280.975997) (xy 56.626017 -280.95139) (xy 56.587896 -280.920265)
			(xy 56.555261 -280.883428) (xy 56.528958 -280.841832) (xy 56.509667 -280.796556) (xy 56.49789 -280.748772)
			(xy 56.49393 -280.699718) (xy 55.205122 -280.699718) (xy 55.204627 -280.724325) (xy 55.196732 -280.772902)
			(xy 55.181148 -280.819583) (xy 55.158277 -280.86316) (xy 55.128712 -280.902504) (xy 55.093219 -280.936596)
			(xy 55.052716 -280.964552) (xy 55.008254 -280.98565) (xy 54.960983 -280.999342) (xy 54.912128 -281.005274)
			(xy 54.862953 -281.003293) (xy 54.814734 -280.993449) (xy 54.768718 -280.975997) (xy 54.726097 -280.95139)
			(xy 54.687976 -280.920265) (xy 54.655341 -280.883428) (xy 54.629038 -280.841832) (xy 54.609747 -280.796556)
			(xy 54.59797 -280.748772) (xy 54.59401 -280.699718) (xy 53.305202 -280.699718) (xy 53.304707 -280.724325)
			(xy 53.296812 -280.772902) (xy 53.281228 -280.819583) (xy 53.258357 -280.86316) (xy 53.228792 -280.902504)
			(xy 53.193299 -280.936596) (xy 53.152796 -280.964552) (xy 53.108334 -280.98565) (xy 53.061063 -280.999342)
			(xy 53.012208 -281.005274) (xy 52.963033 -281.003293) (xy 52.914814 -280.993449) (xy 52.868798 -280.975997)
			(xy 52.826177 -280.95139) (xy 52.788056 -280.920265) (xy 52.755421 -280.883428) (xy 52.729118 -280.841832)
			(xy 52.709827 -280.796556) (xy 52.69805 -280.748772) (xy 52.69409 -280.699718) (xy 51.405282 -280.699718)
			(xy 51.404787 -280.724325) (xy 51.396892 -280.772902) (xy 51.381308 -280.819583) (xy 51.358437 -280.86316)
			(xy 51.328872 -280.902504) (xy 51.293379 -280.936596) (xy 51.252876 -280.964552) (xy 51.208414 -280.98565)
			(xy 51.161143 -280.999342) (xy 51.112288 -281.005274) (xy 51.063113 -281.003293) (xy 51.014894 -280.993449)
			(xy 50.968878 -280.975997) (xy 50.926257 -280.95139) (xy 50.888136 -280.920265) (xy 50.855501 -280.883428)
			(xy 50.829198 -280.841832) (xy 50.809907 -280.796556) (xy 50.79813 -280.748772) (xy 50.79417 -280.699718)
			(xy 49.505108 -280.699718) (xy 49.504613 -280.724325) (xy 49.496718 -280.772902) (xy 49.481134 -280.819583)
			(xy 49.458263 -280.86316) (xy 49.428698 -280.902504) (xy 49.393205 -280.936596) (xy 49.352702 -280.964552)
			(xy 49.30824 -280.98565) (xy 49.260969 -280.999342) (xy 49.212114 -281.005274) (xy 49.162939 -281.003293)
			(xy 49.11472 -280.993449) (xy 49.068704 -280.975997) (xy 49.026083 -280.95139) (xy 48.987962 -280.920265)
			(xy 48.955327 -280.883428) (xy 48.929024 -280.841832) (xy 48.909733 -280.796556) (xy 48.897956 -280.748772)
			(xy 48.893996 -280.699718) (xy 47.605188 -280.699718) (xy 47.604693 -280.724325) (xy 47.596798 -280.772902)
			(xy 47.581214 -280.819583) (xy 47.558343 -280.86316) (xy 47.528778 -280.902504) (xy 47.493285 -280.936596)
			(xy 47.452782 -280.964552) (xy 47.40832 -280.98565) (xy 47.361049 -280.999342) (xy 47.312194 -281.005274)
			(xy 47.263019 -281.003293) (xy 47.2148 -280.993449) (xy 47.168784 -280.975997) (xy 47.126163 -280.95139)
			(xy 47.088042 -280.920265) (xy 47.055407 -280.883428) (xy 47.029104 -280.841832) (xy 47.009813 -280.796556)
			(xy 46.998036 -280.748772) (xy 46.994076 -280.699718) (xy 45.705268 -280.699718) (xy 45.704773 -280.724325)
			(xy 45.696878 -280.772902) (xy 45.681294 -280.819583) (xy 45.658423 -280.86316) (xy 45.628858 -280.902504)
			(xy 45.593365 -280.936596) (xy 45.552862 -280.964552) (xy 45.5084 -280.98565) (xy 45.461129 -280.999342)
			(xy 45.412274 -281.005274) (xy 45.363099 -281.003293) (xy 45.31488 -280.993449) (xy 45.268864 -280.975997)
			(xy 45.226243 -280.95139) (xy 45.188122 -280.920265) (xy 45.155487 -280.883428) (xy 45.129184 -280.841832)
			(xy 45.109893 -280.796556) (xy 45.098116 -280.748772) (xy 45.094156 -280.699718) (xy 0.509016 -280.699718)
			(xy 0.509016 -281.649932) (xy 81.19416 -281.649932) (xy 81.19812 -281.600878) (xy 81.209897 -281.553094)
			(xy 81.229188 -281.507818) (xy 81.255491 -281.466222) (xy 81.288126 -281.429385) (xy 81.326247 -281.39826)
			(xy 81.368868 -281.373653) (xy 81.414884 -281.356201) (xy 81.463103 -281.346357) (xy 81.512278 -281.344376)
			(xy 81.561133 -281.350308) (xy 81.608404 -281.364) (xy 81.652866 -281.385098) (xy 81.693369 -281.413054)
			(xy 81.728862 -281.447146) (xy 81.758427 -281.48649) (xy 81.781298 -281.530067) (xy 81.796882 -281.576748)
			(xy 81.804777 -281.625325) (xy 81.805272 -281.649932) (xy 82.14412 -281.649932) (xy 82.14808 -281.600878)
			(xy 82.159857 -281.553094) (xy 82.179148 -281.507818) (xy 82.205451 -281.466222) (xy 82.238086 -281.429385)
			(xy 82.276207 -281.39826) (xy 82.318828 -281.373653) (xy 82.364844 -281.356201) (xy 82.413063 -281.346357)
			(xy 82.462238 -281.344376) (xy 82.511093 -281.350308) (xy 82.558364 -281.364) (xy 82.602826 -281.385098)
			(xy 82.643329 -281.413054) (xy 82.678822 -281.447146) (xy 82.708387 -281.48649) (xy 82.731258 -281.530067)
			(xy 82.746842 -281.576748) (xy 82.754737 -281.625325) (xy 82.755232 -281.649932) (xy 197.294258 -281.649932)
			(xy 197.298218 -281.600878) (xy 197.309995 -281.553094) (xy 197.329286 -281.507818) (xy 197.355589 -281.466222)
			(xy 197.388224 -281.429385) (xy 197.426345 -281.39826) (xy 197.468966 -281.373653) (xy 197.514982 -281.356201)
			(xy 197.563201 -281.346357) (xy 197.612376 -281.344376) (xy 197.661231 -281.350308) (xy 197.708502 -281.364)
			(xy 197.752964 -281.385098) (xy 197.793467 -281.413054) (xy 197.82896 -281.447146) (xy 197.858525 -281.48649)
			(xy 197.881396 -281.530067) (xy 197.89698 -281.576748) (xy 197.904875 -281.625325) (xy 197.90537 -281.649932)
			(xy 198.244218 -281.649932) (xy 198.248178 -281.600878) (xy 198.259955 -281.553094) (xy 198.279246 -281.507818)
			(xy 198.305549 -281.466222) (xy 198.338184 -281.429385) (xy 198.376305 -281.39826) (xy 198.418926 -281.373653)
			(xy 198.464942 -281.356201) (xy 198.513161 -281.346357) (xy 198.562336 -281.344376) (xy 198.611191 -281.350308)
			(xy 198.658462 -281.364) (xy 198.702924 -281.385098) (xy 198.743427 -281.413054) (xy 198.77892 -281.447146)
			(xy 198.808485 -281.48649) (xy 198.831356 -281.530067) (xy 198.84694 -281.576748) (xy 198.854835 -281.625325)
			(xy 198.85533 -281.649932) (xy 313.394102 -281.649932) (xy 313.398062 -281.600878) (xy 313.409839 -281.553094)
			(xy 313.42913 -281.507818) (xy 313.455433 -281.466222) (xy 313.488068 -281.429385) (xy 313.526189 -281.39826)
			(xy 313.56881 -281.373653) (xy 313.614826 -281.356201) (xy 313.663045 -281.346357) (xy 313.71222 -281.344376)
			(xy 313.761075 -281.350308) (xy 313.808346 -281.364) (xy 313.852808 -281.385098) (xy 313.893311 -281.413054)
			(xy 313.928804 -281.447146) (xy 313.958369 -281.48649) (xy 313.98124 -281.530067) (xy 313.996824 -281.576748)
			(xy 314.004719 -281.625325) (xy 314.005214 -281.649932) (xy 314.344062 -281.649932) (xy 314.348022 -281.600878)
			(xy 314.359799 -281.553094) (xy 314.37909 -281.507818) (xy 314.405393 -281.466222) (xy 314.438028 -281.429385)
			(xy 314.476149 -281.39826) (xy 314.51877 -281.373653) (xy 314.564786 -281.356201) (xy 314.613005 -281.346357)
			(xy 314.66218 -281.344376) (xy 314.711035 -281.350308) (xy 314.758306 -281.364) (xy 314.802768 -281.385098)
			(xy 314.843271 -281.413054) (xy 314.878764 -281.447146) (xy 314.908329 -281.48649) (xy 314.9312 -281.530067)
			(xy 314.946784 -281.576748) (xy 314.954679 -281.625325) (xy 314.955174 -281.649932) (xy 429.4942 -281.649932)
			(xy 429.49816 -281.600878) (xy 429.509937 -281.553094) (xy 429.529228 -281.507818) (xy 429.555531 -281.466222)
			(xy 429.588166 -281.429385) (xy 429.626287 -281.39826) (xy 429.668908 -281.373653) (xy 429.714924 -281.356201)
			(xy 429.763143 -281.346357) (xy 429.812318 -281.344376) (xy 429.861173 -281.350308) (xy 429.908444 -281.364)
			(xy 429.952906 -281.385098) (xy 429.993409 -281.413054) (xy 430.028902 -281.447146) (xy 430.058467 -281.48649)
			(xy 430.081338 -281.530067) (xy 430.096922 -281.576748) (xy 430.104817 -281.625325) (xy 430.105312 -281.649932)
			(xy 430.44416 -281.649932) (xy 430.44812 -281.600878) (xy 430.459897 -281.553094) (xy 430.479188 -281.507818)
			(xy 430.505491 -281.466222) (xy 430.538126 -281.429385) (xy 430.576247 -281.39826) (xy 430.618868 -281.373653)
			(xy 430.664884 -281.356201) (xy 430.713103 -281.346357) (xy 430.762278 -281.344376) (xy 430.811133 -281.350308)
			(xy 430.858404 -281.364) (xy 430.902866 -281.385098) (xy 430.943369 -281.413054) (xy 430.978862 -281.447146)
			(xy 431.008427 -281.48649) (xy 431.031298 -281.530067) (xy 431.046882 -281.576748) (xy 431.054777 -281.625325)
			(xy 431.055272 -281.649932) (xy 431.054777 -281.674539) (xy 431.046882 -281.723116) (xy 431.031298 -281.769797)
			(xy 431.008427 -281.813374) (xy 430.978862 -281.852718) (xy 430.943369 -281.88681) (xy 430.902866 -281.914766)
			(xy 430.858404 -281.935864) (xy 430.811133 -281.949556) (xy 430.762278 -281.955488) (xy 430.713103 -281.953507)
			(xy 430.664884 -281.943663) (xy 430.618868 -281.926211) (xy 430.576247 -281.901604) (xy 430.538126 -281.870479)
			(xy 430.505491 -281.833642) (xy 430.479188 -281.792046) (xy 430.459897 -281.74677) (xy 430.44812 -281.698986)
			(xy 430.44416 -281.649932) (xy 430.105312 -281.649932) (xy 430.104817 -281.674539) (xy 430.096922 -281.723116)
			(xy 430.081338 -281.769797) (xy 430.058467 -281.813374) (xy 430.028902 -281.852718) (xy 429.993409 -281.88681)
			(xy 429.952906 -281.914766) (xy 429.908444 -281.935864) (xy 429.861173 -281.949556) (xy 429.812318 -281.955488)
			(xy 429.763143 -281.953507) (xy 429.714924 -281.943663) (xy 429.668908 -281.926211) (xy 429.626287 -281.901604)
			(xy 429.588166 -281.870479) (xy 429.555531 -281.833642) (xy 429.529228 -281.792046) (xy 429.509937 -281.74677)
			(xy 429.49816 -281.698986) (xy 429.4942 -281.649932) (xy 314.955174 -281.649932) (xy 314.954679 -281.674539)
			(xy 314.946784 -281.723116) (xy 314.9312 -281.769797) (xy 314.908329 -281.813374) (xy 314.878764 -281.852718)
			(xy 314.843271 -281.88681) (xy 314.802768 -281.914766) (xy 314.758306 -281.935864) (xy 314.711035 -281.949556)
			(xy 314.66218 -281.955488) (xy 314.613005 -281.953507) (xy 314.564786 -281.943663) (xy 314.51877 -281.926211)
			(xy 314.476149 -281.901604) (xy 314.438028 -281.870479) (xy 314.405393 -281.833642) (xy 314.37909 -281.792046)
			(xy 314.359799 -281.74677) (xy 314.348022 -281.698986) (xy 314.344062 -281.649932) (xy 314.005214 -281.649932)
			(xy 314.004719 -281.674539) (xy 313.996824 -281.723116) (xy 313.98124 -281.769797) (xy 313.958369 -281.813374)
			(xy 313.928804 -281.852718) (xy 313.893311 -281.88681) (xy 313.852808 -281.914766) (xy 313.808346 -281.935864)
			(xy 313.761075 -281.949556) (xy 313.71222 -281.955488) (xy 313.663045 -281.953507) (xy 313.614826 -281.943663)
			(xy 313.56881 -281.926211) (xy 313.526189 -281.901604) (xy 313.488068 -281.870479) (xy 313.455433 -281.833642)
			(xy 313.42913 -281.792046) (xy 313.409839 -281.74677) (xy 313.398062 -281.698986) (xy 313.394102 -281.649932)
			(xy 198.85533 -281.649932) (xy 198.854835 -281.674539) (xy 198.84694 -281.723116) (xy 198.831356 -281.769797)
			(xy 198.808485 -281.813374) (xy 198.77892 -281.852718) (xy 198.743427 -281.88681) (xy 198.702924 -281.914766)
			(xy 198.658462 -281.935864) (xy 198.611191 -281.949556) (xy 198.562336 -281.955488) (xy 198.513161 -281.953507)
			(xy 198.464942 -281.943663) (xy 198.418926 -281.926211) (xy 198.376305 -281.901604) (xy 198.338184 -281.870479)
			(xy 198.305549 -281.833642) (xy 198.279246 -281.792046) (xy 198.259955 -281.74677) (xy 198.248178 -281.698986)
			(xy 198.244218 -281.649932) (xy 197.90537 -281.649932) (xy 197.904875 -281.674539) (xy 197.89698 -281.723116)
			(xy 197.881396 -281.769797) (xy 197.858525 -281.813374) (xy 197.82896 -281.852718) (xy 197.793467 -281.88681)
			(xy 197.752964 -281.914766) (xy 197.708502 -281.935864) (xy 197.661231 -281.949556) (xy 197.612376 -281.955488)
			(xy 197.563201 -281.953507) (xy 197.514982 -281.943663) (xy 197.468966 -281.926211) (xy 197.426345 -281.901604)
			(xy 197.388224 -281.870479) (xy 197.355589 -281.833642) (xy 197.329286 -281.792046) (xy 197.309995 -281.74677)
			(xy 197.298218 -281.698986) (xy 197.294258 -281.649932) (xy 82.755232 -281.649932) (xy 82.754737 -281.674539)
			(xy 82.746842 -281.723116) (xy 82.731258 -281.769797) (xy 82.708387 -281.813374) (xy 82.678822 -281.852718)
			(xy 82.643329 -281.88681) (xy 82.602826 -281.914766) (xy 82.558364 -281.935864) (xy 82.511093 -281.949556)
			(xy 82.462238 -281.955488) (xy 82.413063 -281.953507) (xy 82.364844 -281.943663) (xy 82.318828 -281.926211)
			(xy 82.276207 -281.901604) (xy 82.238086 -281.870479) (xy 82.205451 -281.833642) (xy 82.179148 -281.792046)
			(xy 82.159857 -281.74677) (xy 82.14808 -281.698986) (xy 82.14412 -281.649932) (xy 81.805272 -281.649932)
			(xy 81.804777 -281.674539) (xy 81.796882 -281.723116) (xy 81.781298 -281.769797) (xy 81.758427 -281.813374)
			(xy 81.728862 -281.852718) (xy 81.693369 -281.88681) (xy 81.652866 -281.914766) (xy 81.608404 -281.935864)
			(xy 81.561133 -281.949556) (xy 81.512278 -281.955488) (xy 81.463103 -281.953507) (xy 81.414884 -281.943663)
			(xy 81.368868 -281.926211) (xy 81.326247 -281.901604) (xy 81.288126 -281.870479) (xy 81.255491 -281.833642)
			(xy 81.229188 -281.792046) (xy 81.209897 -281.74677) (xy 81.19812 -281.698986) (xy 81.19416 -281.649932)
			(xy 0.509016 -281.649932) (xy 0.509016 -282.599892) (xy 76.444106 -282.599892) (xy 76.448066 -282.550838)
			(xy 76.459843 -282.503054) (xy 76.479134 -282.457778) (xy 76.505437 -282.416182) (xy 76.538072 -282.379345)
			(xy 76.576193 -282.34822) (xy 76.618814 -282.323613) (xy 76.66483 -282.306161) (xy 76.713049 -282.296317)
			(xy 76.762224 -282.294336) (xy 76.811079 -282.300268) (xy 76.85835 -282.31396) (xy 76.902812 -282.335058)
			(xy 76.943315 -282.363014) (xy 76.978808 -282.397106) (xy 77.008373 -282.43645) (xy 77.031244 -282.480027)
			(xy 77.046828 -282.526708) (xy 77.054723 -282.575285) (xy 77.055218 -282.599892) (xy 77.394066 -282.599892)
			(xy 77.398026 -282.550838) (xy 77.409803 -282.503054) (xy 77.429094 -282.457778) (xy 77.455397 -282.416182)
			(xy 77.488032 -282.379345) (xy 77.526153 -282.34822) (xy 77.568774 -282.323613) (xy 77.61479 -282.306161)
			(xy 77.663009 -282.296317) (xy 77.712184 -282.294336) (xy 77.761039 -282.300268) (xy 77.80831 -282.31396)
			(xy 77.852772 -282.335058) (xy 77.893275 -282.363014) (xy 77.928768 -282.397106) (xy 77.958333 -282.43645)
			(xy 77.981204 -282.480027) (xy 77.996788 -282.526708) (xy 78.004683 -282.575285) (xy 78.005178 -282.599892)
			(xy 79.293986 -282.599892) (xy 79.297946 -282.550838) (xy 79.309723 -282.503054) (xy 79.329014 -282.457778)
			(xy 79.355317 -282.416182) (xy 79.387952 -282.379345) (xy 79.426073 -282.34822) (xy 79.468694 -282.323613)
			(xy 79.51471 -282.306161) (xy 79.562929 -282.296317) (xy 79.612104 -282.294336) (xy 79.660959 -282.300268)
			(xy 79.70823 -282.31396) (xy 79.752692 -282.335058) (xy 79.793195 -282.363014) (xy 79.828688 -282.397106)
			(xy 79.858253 -282.43645) (xy 79.881124 -282.480027) (xy 79.896708 -282.526708) (xy 79.904603 -282.575285)
			(xy 79.905098 -282.599892) (xy 80.243946 -282.599892) (xy 80.247906 -282.550838) (xy 80.259683 -282.503054)
			(xy 80.278974 -282.457778) (xy 80.305277 -282.416182) (xy 80.337912 -282.379345) (xy 80.376033 -282.34822)
			(xy 80.418654 -282.323613) (xy 80.46467 -282.306161) (xy 80.512889 -282.296317) (xy 80.562064 -282.294336)
			(xy 80.610919 -282.300268) (xy 80.65819 -282.31396) (xy 80.702652 -282.335058) (xy 80.743155 -282.363014)
			(xy 80.778648 -282.397106) (xy 80.808213 -282.43645) (xy 80.831084 -282.480027) (xy 80.846668 -282.526708)
			(xy 80.854563 -282.575285) (xy 80.855058 -282.599892) (xy 192.544204 -282.599892) (xy 192.548164 -282.550838)
			(xy 192.559941 -282.503054) (xy 192.579232 -282.457778) (xy 192.605535 -282.416182) (xy 192.63817 -282.379345)
			(xy 192.676291 -282.34822) (xy 192.718912 -282.323613) (xy 192.764928 -282.306161) (xy 192.813147 -282.296317)
			(xy 192.862322 -282.294336) (xy 192.911177 -282.300268) (xy 192.958448 -282.31396) (xy 193.00291 -282.335058)
			(xy 193.043413 -282.363014) (xy 193.078906 -282.397106) (xy 193.108471 -282.43645) (xy 193.131342 -282.480027)
			(xy 193.146926 -282.526708) (xy 193.154821 -282.575285) (xy 193.155316 -282.599892) (xy 193.494164 -282.599892)
			(xy 193.498124 -282.550838) (xy 193.509901 -282.503054) (xy 193.529192 -282.457778) (xy 193.555495 -282.416182)
			(xy 193.58813 -282.379345) (xy 193.626251 -282.34822) (xy 193.668872 -282.323613) (xy 193.714888 -282.306161)
			(xy 193.763107 -282.296317) (xy 193.812282 -282.294336) (xy 193.861137 -282.300268) (xy 193.908408 -282.31396)
			(xy 193.95287 -282.335058) (xy 193.993373 -282.363014) (xy 194.028866 -282.397106) (xy 194.058431 -282.43645)
			(xy 194.081302 -282.480027) (xy 194.096886 -282.526708) (xy 194.104781 -282.575285) (xy 194.105276 -282.599892)
			(xy 195.394084 -282.599892) (xy 195.398044 -282.550838) (xy 195.409821 -282.503054) (xy 195.429112 -282.457778)
			(xy 195.455415 -282.416182) (xy 195.48805 -282.379345) (xy 195.526171 -282.34822) (xy 195.568792 -282.323613)
			(xy 195.614808 -282.306161) (xy 195.663027 -282.296317) (xy 195.712202 -282.294336) (xy 195.761057 -282.300268)
			(xy 195.808328 -282.31396) (xy 195.85279 -282.335058) (xy 195.893293 -282.363014) (xy 195.928786 -282.397106)
			(xy 195.958351 -282.43645) (xy 195.981222 -282.480027) (xy 195.996806 -282.526708) (xy 196.004701 -282.575285)
			(xy 196.005196 -282.599892) (xy 196.344044 -282.599892) (xy 196.348004 -282.550838) (xy 196.359781 -282.503054)
			(xy 196.379072 -282.457778) (xy 196.405375 -282.416182) (xy 196.43801 -282.379345) (xy 196.476131 -282.34822)
			(xy 196.518752 -282.323613) (xy 196.564768 -282.306161) (xy 196.612987 -282.296317) (xy 196.662162 -282.294336)
			(xy 196.711017 -282.300268) (xy 196.758288 -282.31396) (xy 196.80275 -282.335058) (xy 196.843253 -282.363014)
			(xy 196.878746 -282.397106) (xy 196.908311 -282.43645) (xy 196.931182 -282.480027) (xy 196.946766 -282.526708)
			(xy 196.954661 -282.575285) (xy 196.955156 -282.599892) (xy 308.644048 -282.599892) (xy 308.648008 -282.550838)
			(xy 308.659785 -282.503054) (xy 308.679076 -282.457778) (xy 308.705379 -282.416182) (xy 308.738014 -282.379345)
			(xy 308.776135 -282.34822) (xy 308.818756 -282.323613) (xy 308.864772 -282.306161) (xy 308.912991 -282.296317)
			(xy 308.962166 -282.294336) (xy 309.011021 -282.300268) (xy 309.058292 -282.31396) (xy 309.102754 -282.335058)
			(xy 309.143257 -282.363014) (xy 309.17875 -282.397106) (xy 309.208315 -282.43645) (xy 309.231186 -282.480027)
			(xy 309.24677 -282.526708) (xy 309.254665 -282.575285) (xy 309.25516 -282.599892) (xy 309.594008 -282.599892)
			(xy 309.597968 -282.550838) (xy 309.609745 -282.503054) (xy 309.629036 -282.457778) (xy 309.655339 -282.416182)
			(xy 309.687974 -282.379345) (xy 309.726095 -282.34822) (xy 309.768716 -282.323613) (xy 309.814732 -282.306161)
			(xy 309.862951 -282.296317) (xy 309.912126 -282.294336) (xy 309.960981 -282.300268) (xy 310.008252 -282.31396)
			(xy 310.052714 -282.335058) (xy 310.093217 -282.363014) (xy 310.12871 -282.397106) (xy 310.158275 -282.43645)
			(xy 310.181146 -282.480027) (xy 310.19673 -282.526708) (xy 310.204625 -282.575285) (xy 310.20512 -282.599892)
			(xy 311.493928 -282.599892) (xy 311.497888 -282.550838) (xy 311.509665 -282.503054) (xy 311.528956 -282.457778)
			(xy 311.555259 -282.416182) (xy 311.587894 -282.379345) (xy 311.626015 -282.34822) (xy 311.668636 -282.323613)
			(xy 311.714652 -282.306161) (xy 311.762871 -282.296317) (xy 311.812046 -282.294336) (xy 311.860901 -282.300268)
			(xy 311.908172 -282.31396) (xy 311.952634 -282.335058) (xy 311.993137 -282.363014) (xy 312.02863 -282.397106)
			(xy 312.058195 -282.43645) (xy 312.081066 -282.480027) (xy 312.09665 -282.526708) (xy 312.104545 -282.575285)
			(xy 312.10504 -282.599892) (xy 312.443888 -282.599892) (xy 312.447848 -282.550838) (xy 312.459625 -282.503054)
			(xy 312.478916 -282.457778) (xy 312.505219 -282.416182) (xy 312.537854 -282.379345) (xy 312.575975 -282.34822)
			(xy 312.618596 -282.323613) (xy 312.664612 -282.306161) (xy 312.712831 -282.296317) (xy 312.762006 -282.294336)
			(xy 312.810861 -282.300268) (xy 312.858132 -282.31396) (xy 312.902594 -282.335058) (xy 312.943097 -282.363014)
			(xy 312.97859 -282.397106) (xy 313.008155 -282.43645) (xy 313.031026 -282.480027) (xy 313.04661 -282.526708)
			(xy 313.054505 -282.575285) (xy 313.055 -282.599892) (xy 424.744146 -282.599892) (xy 424.748106 -282.550838)
			(xy 424.759883 -282.503054) (xy 424.779174 -282.457778) (xy 424.805477 -282.416182) (xy 424.838112 -282.379345)
			(xy 424.876233 -282.34822) (xy 424.918854 -282.323613) (xy 424.96487 -282.306161) (xy 425.013089 -282.296317)
			(xy 425.062264 -282.294336) (xy 425.111119 -282.300268) (xy 425.15839 -282.31396) (xy 425.202852 -282.335058)
			(xy 425.243355 -282.363014) (xy 425.278848 -282.397106) (xy 425.308413 -282.43645) (xy 425.331284 -282.480027)
			(xy 425.346868 -282.526708) (xy 425.354763 -282.575285) (xy 425.355258 -282.599892) (xy 425.694106 -282.599892)
			(xy 425.698066 -282.550838) (xy 425.709843 -282.503054) (xy 425.729134 -282.457778) (xy 425.755437 -282.416182)
			(xy 425.788072 -282.379345) (xy 425.826193 -282.34822) (xy 425.868814 -282.323613) (xy 425.91483 -282.306161)
			(xy 425.963049 -282.296317) (xy 426.012224 -282.294336) (xy 426.061079 -282.300268) (xy 426.10835 -282.31396)
			(xy 426.152812 -282.335058) (xy 426.193315 -282.363014) (xy 426.228808 -282.397106) (xy 426.258373 -282.43645)
			(xy 426.281244 -282.480027) (xy 426.296828 -282.526708) (xy 426.304723 -282.575285) (xy 426.305218 -282.599892)
			(xy 427.594026 -282.599892) (xy 427.597986 -282.550838) (xy 427.609763 -282.503054) (xy 427.629054 -282.457778)
			(xy 427.655357 -282.416182) (xy 427.687992 -282.379345) (xy 427.726113 -282.34822) (xy 427.768734 -282.323613)
			(xy 427.81475 -282.306161) (xy 427.862969 -282.296317) (xy 427.912144 -282.294336) (xy 427.960999 -282.300268)
			(xy 428.00827 -282.31396) (xy 428.052732 -282.335058) (xy 428.093235 -282.363014) (xy 428.128728 -282.397106)
			(xy 428.158293 -282.43645) (xy 428.181164 -282.480027) (xy 428.196748 -282.526708) (xy 428.204643 -282.575285)
			(xy 428.205138 -282.599892) (xy 428.543986 -282.599892) (xy 428.547946 -282.550838) (xy 428.559723 -282.503054)
			(xy 428.579014 -282.457778) (xy 428.605317 -282.416182) (xy 428.637952 -282.379345) (xy 428.676073 -282.34822)
			(xy 428.718694 -282.323613) (xy 428.76471 -282.306161) (xy 428.812929 -282.296317) (xy 428.862104 -282.294336)
			(xy 428.910959 -282.300268) (xy 428.95823 -282.31396) (xy 429.002692 -282.335058) (xy 429.043195 -282.363014)
			(xy 429.078688 -282.397106) (xy 429.108253 -282.43645) (xy 429.131124 -282.480027) (xy 429.146708 -282.526708)
			(xy 429.154603 -282.575285) (xy 429.155098 -282.599892) (xy 429.154603 -282.624499) (xy 429.146708 -282.673076)
			(xy 429.131124 -282.719757) (xy 429.108253 -282.763334) (xy 429.078688 -282.802678) (xy 429.043195 -282.83677)
			(xy 429.002692 -282.864726) (xy 428.95823 -282.885824) (xy 428.910959 -282.899516) (xy 428.862104 -282.905448)
			(xy 428.812929 -282.903467) (xy 428.76471 -282.893623) (xy 428.718694 -282.876171) (xy 428.676073 -282.851564)
			(xy 428.637952 -282.820439) (xy 428.605317 -282.783602) (xy 428.579014 -282.742006) (xy 428.559723 -282.69673)
			(xy 428.547946 -282.648946) (xy 428.543986 -282.599892) (xy 428.205138 -282.599892) (xy 428.204643 -282.624499)
			(xy 428.196748 -282.673076) (xy 428.181164 -282.719757) (xy 428.158293 -282.763334) (xy 428.128728 -282.802678)
			(xy 428.093235 -282.83677) (xy 428.052732 -282.864726) (xy 428.00827 -282.885824) (xy 427.960999 -282.899516)
			(xy 427.912144 -282.905448) (xy 427.862969 -282.903467) (xy 427.81475 -282.893623) (xy 427.768734 -282.876171)
			(xy 427.726113 -282.851564) (xy 427.687992 -282.820439) (xy 427.655357 -282.783602) (xy 427.629054 -282.742006)
			(xy 427.609763 -282.69673) (xy 427.597986 -282.648946) (xy 427.594026 -282.599892) (xy 426.305218 -282.599892)
			(xy 426.304723 -282.624499) (xy 426.296828 -282.673076) (xy 426.281244 -282.719757) (xy 426.258373 -282.763334)
			(xy 426.228808 -282.802678) (xy 426.193315 -282.83677) (xy 426.152812 -282.864726) (xy 426.10835 -282.885824)
			(xy 426.061079 -282.899516) (xy 426.012224 -282.905448) (xy 425.963049 -282.903467) (xy 425.91483 -282.893623)
			(xy 425.868814 -282.876171) (xy 425.826193 -282.851564) (xy 425.788072 -282.820439) (xy 425.755437 -282.783602)
			(xy 425.729134 -282.742006) (xy 425.709843 -282.69673) (xy 425.698066 -282.648946) (xy 425.694106 -282.599892)
			(xy 425.355258 -282.599892) (xy 425.354763 -282.624499) (xy 425.346868 -282.673076) (xy 425.331284 -282.719757)
			(xy 425.308413 -282.763334) (xy 425.278848 -282.802678) (xy 425.243355 -282.83677) (xy 425.202852 -282.864726)
			(xy 425.15839 -282.885824) (xy 425.111119 -282.899516) (xy 425.062264 -282.905448) (xy 425.013089 -282.903467)
			(xy 424.96487 -282.893623) (xy 424.918854 -282.876171) (xy 424.876233 -282.851564) (xy 424.838112 -282.820439)
			(xy 424.805477 -282.783602) (xy 424.779174 -282.742006) (xy 424.759883 -282.69673) (xy 424.748106 -282.648946)
			(xy 424.744146 -282.599892) (xy 313.055 -282.599892) (xy 313.054505 -282.624499) (xy 313.04661 -282.673076)
			(xy 313.031026 -282.719757) (xy 313.008155 -282.763334) (xy 312.97859 -282.802678) (xy 312.943097 -282.83677)
			(xy 312.902594 -282.864726) (xy 312.858132 -282.885824) (xy 312.810861 -282.899516) (xy 312.762006 -282.905448)
			(xy 312.712831 -282.903467) (xy 312.664612 -282.893623) (xy 312.618596 -282.876171) (xy 312.575975 -282.851564)
			(xy 312.537854 -282.820439) (xy 312.505219 -282.783602) (xy 312.478916 -282.742006) (xy 312.459625 -282.69673)
			(xy 312.447848 -282.648946) (xy 312.443888 -282.599892) (xy 312.10504 -282.599892) (xy 312.104545 -282.624499)
			(xy 312.09665 -282.673076) (xy 312.081066 -282.719757) (xy 312.058195 -282.763334) (xy 312.02863 -282.802678)
			(xy 311.993137 -282.83677) (xy 311.952634 -282.864726) (xy 311.908172 -282.885824) (xy 311.860901 -282.899516)
			(xy 311.812046 -282.905448) (xy 311.762871 -282.903467) (xy 311.714652 -282.893623) (xy 311.668636 -282.876171)
			(xy 311.626015 -282.851564) (xy 311.587894 -282.820439) (xy 311.555259 -282.783602) (xy 311.528956 -282.742006)
			(xy 311.509665 -282.69673) (xy 311.497888 -282.648946) (xy 311.493928 -282.599892) (xy 310.20512 -282.599892)
			(xy 310.204625 -282.624499) (xy 310.19673 -282.673076) (xy 310.181146 -282.719757) (xy 310.158275 -282.763334)
			(xy 310.12871 -282.802678) (xy 310.093217 -282.83677) (xy 310.052714 -282.864726) (xy 310.008252 -282.885824)
			(xy 309.960981 -282.899516) (xy 309.912126 -282.905448) (xy 309.862951 -282.903467) (xy 309.814732 -282.893623)
			(xy 309.768716 -282.876171) (xy 309.726095 -282.851564) (xy 309.687974 -282.820439) (xy 309.655339 -282.783602)
			(xy 309.629036 -282.742006) (xy 309.609745 -282.69673) (xy 309.597968 -282.648946) (xy 309.594008 -282.599892)
			(xy 309.25516 -282.599892) (xy 309.254665 -282.624499) (xy 309.24677 -282.673076) (xy 309.231186 -282.719757)
			(xy 309.208315 -282.763334) (xy 309.17875 -282.802678) (xy 309.143257 -282.83677) (xy 309.102754 -282.864726)
			(xy 309.058292 -282.885824) (xy 309.011021 -282.899516) (xy 308.962166 -282.905448) (xy 308.912991 -282.903467)
			(xy 308.864772 -282.893623) (xy 308.818756 -282.876171) (xy 308.776135 -282.851564) (xy 308.738014 -282.820439)
			(xy 308.705379 -282.783602) (xy 308.679076 -282.742006) (xy 308.659785 -282.69673) (xy 308.648008 -282.648946)
			(xy 308.644048 -282.599892) (xy 196.955156 -282.599892) (xy 196.954661 -282.624499) (xy 196.946766 -282.673076)
			(xy 196.931182 -282.719757) (xy 196.908311 -282.763334) (xy 196.878746 -282.802678) (xy 196.843253 -282.83677)
			(xy 196.80275 -282.864726) (xy 196.758288 -282.885824) (xy 196.711017 -282.899516) (xy 196.662162 -282.905448)
			(xy 196.612987 -282.903467) (xy 196.564768 -282.893623) (xy 196.518752 -282.876171) (xy 196.476131 -282.851564)
			(xy 196.43801 -282.820439) (xy 196.405375 -282.783602) (xy 196.379072 -282.742006) (xy 196.359781 -282.69673)
			(xy 196.348004 -282.648946) (xy 196.344044 -282.599892) (xy 196.005196 -282.599892) (xy 196.004701 -282.624499)
			(xy 195.996806 -282.673076) (xy 195.981222 -282.719757) (xy 195.958351 -282.763334) (xy 195.928786 -282.802678)
			(xy 195.893293 -282.83677) (xy 195.85279 -282.864726) (xy 195.808328 -282.885824) (xy 195.761057 -282.899516)
			(xy 195.712202 -282.905448) (xy 195.663027 -282.903467) (xy 195.614808 -282.893623) (xy 195.568792 -282.876171)
			(xy 195.526171 -282.851564) (xy 195.48805 -282.820439) (xy 195.455415 -282.783602) (xy 195.429112 -282.742006)
			(xy 195.409821 -282.69673) (xy 195.398044 -282.648946) (xy 195.394084 -282.599892) (xy 194.105276 -282.599892)
			(xy 194.104781 -282.624499) (xy 194.096886 -282.673076) (xy 194.081302 -282.719757) (xy 194.058431 -282.763334)
			(xy 194.028866 -282.802678) (xy 193.993373 -282.83677) (xy 193.95287 -282.864726) (xy 193.908408 -282.885824)
			(xy 193.861137 -282.899516) (xy 193.812282 -282.905448) (xy 193.763107 -282.903467) (xy 193.714888 -282.893623)
			(xy 193.668872 -282.876171) (xy 193.626251 -282.851564) (xy 193.58813 -282.820439) (xy 193.555495 -282.783602)
			(xy 193.529192 -282.742006) (xy 193.509901 -282.69673) (xy 193.498124 -282.648946) (xy 193.494164 -282.599892)
			(xy 193.155316 -282.599892) (xy 193.154821 -282.624499) (xy 193.146926 -282.673076) (xy 193.131342 -282.719757)
			(xy 193.108471 -282.763334) (xy 193.078906 -282.802678) (xy 193.043413 -282.83677) (xy 193.00291 -282.864726)
			(xy 192.958448 -282.885824) (xy 192.911177 -282.899516) (xy 192.862322 -282.905448) (xy 192.813147 -282.903467)
			(xy 192.764928 -282.893623) (xy 192.718912 -282.876171) (xy 192.676291 -282.851564) (xy 192.63817 -282.820439)
			(xy 192.605535 -282.783602) (xy 192.579232 -282.742006) (xy 192.559941 -282.69673) (xy 192.548164 -282.648946)
			(xy 192.544204 -282.599892) (xy 80.855058 -282.599892) (xy 80.854563 -282.624499) (xy 80.846668 -282.673076)
			(xy 80.831084 -282.719757) (xy 80.808213 -282.763334) (xy 80.778648 -282.802678) (xy 80.743155 -282.83677)
			(xy 80.702652 -282.864726) (xy 80.65819 -282.885824) (xy 80.610919 -282.899516) (xy 80.562064 -282.905448)
			(xy 80.512889 -282.903467) (xy 80.46467 -282.893623) (xy 80.418654 -282.876171) (xy 80.376033 -282.851564)
			(xy 80.337912 -282.820439) (xy 80.305277 -282.783602) (xy 80.278974 -282.742006) (xy 80.259683 -282.69673)
			(xy 80.247906 -282.648946) (xy 80.243946 -282.599892) (xy 79.905098 -282.599892) (xy 79.904603 -282.624499)
			(xy 79.896708 -282.673076) (xy 79.881124 -282.719757) (xy 79.858253 -282.763334) (xy 79.828688 -282.802678)
			(xy 79.793195 -282.83677) (xy 79.752692 -282.864726) (xy 79.70823 -282.885824) (xy 79.660959 -282.899516)
			(xy 79.612104 -282.905448) (xy 79.562929 -282.903467) (xy 79.51471 -282.893623) (xy 79.468694 -282.876171)
			(xy 79.426073 -282.851564) (xy 79.387952 -282.820439) (xy 79.355317 -282.783602) (xy 79.329014 -282.742006)
			(xy 79.309723 -282.69673) (xy 79.297946 -282.648946) (xy 79.293986 -282.599892) (xy 78.005178 -282.599892)
			(xy 78.004683 -282.624499) (xy 77.996788 -282.673076) (xy 77.981204 -282.719757) (xy 77.958333 -282.763334)
			(xy 77.928768 -282.802678) (xy 77.893275 -282.83677) (xy 77.852772 -282.864726) (xy 77.80831 -282.885824)
			(xy 77.761039 -282.899516) (xy 77.712184 -282.905448) (xy 77.663009 -282.903467) (xy 77.61479 -282.893623)
			(xy 77.568774 -282.876171) (xy 77.526153 -282.851564) (xy 77.488032 -282.820439) (xy 77.455397 -282.783602)
			(xy 77.429094 -282.742006) (xy 77.409803 -282.69673) (xy 77.398026 -282.648946) (xy 77.394066 -282.599892)
			(xy 77.055218 -282.599892) (xy 77.054723 -282.624499) (xy 77.046828 -282.673076) (xy 77.031244 -282.719757)
			(xy 77.008373 -282.763334) (xy 76.978808 -282.802678) (xy 76.943315 -282.83677) (xy 76.902812 -282.864726)
			(xy 76.85835 -282.885824) (xy 76.811079 -282.899516) (xy 76.762224 -282.905448) (xy 76.713049 -282.903467)
			(xy 76.66483 -282.893623) (xy 76.618814 -282.876171) (xy 76.576193 -282.851564) (xy 76.538072 -282.820439)
			(xy 76.505437 -282.783602) (xy 76.479134 -282.742006) (xy 76.459843 -282.69673) (xy 76.448066 -282.648946)
			(xy 76.444106 -282.599892) (xy 0.509016 -282.599892) (xy 0.509016 -283.549852) (xy 74.543932 -283.549852)
			(xy 74.547892 -283.500798) (xy 74.559669 -283.453014) (xy 74.57896 -283.407738) (xy 74.605263 -283.366142)
			(xy 74.637898 -283.329305) (xy 74.676019 -283.29818) (xy 74.71864 -283.273573) (xy 74.764656 -283.256121)
			(xy 74.812875 -283.246277) (xy 74.86205 -283.244296) (xy 74.910905 -283.250228) (xy 74.958176 -283.26392)
			(xy 75.002638 -283.285018) (xy 75.043141 -283.312974) (xy 75.078634 -283.347066) (xy 75.108199 -283.38641)
			(xy 75.13107 -283.429987) (xy 75.146654 -283.476668) (xy 75.154549 -283.525245) (xy 75.155044 -283.549852)
			(xy 75.494146 -283.549852) (xy 75.498106 -283.500798) (xy 75.509883 -283.453014) (xy 75.529174 -283.407738)
			(xy 75.555477 -283.366142) (xy 75.588112 -283.329305) (xy 75.626233 -283.29818) (xy 75.668854 -283.273573)
			(xy 75.71487 -283.256121) (xy 75.763089 -283.246277) (xy 75.812264 -283.244296) (xy 75.861119 -283.250228)
			(xy 75.90839 -283.26392) (xy 75.952852 -283.285018) (xy 75.993355 -283.312974) (xy 76.028848 -283.347066)
			(xy 76.058413 -283.38641) (xy 76.081284 -283.429987) (xy 76.096868 -283.476668) (xy 76.104763 -283.525245)
			(xy 76.105258 -283.549852) (xy 81.19416 -283.549852) (xy 81.19812 -283.500798) (xy 81.209897 -283.453014)
			(xy 81.229188 -283.407738) (xy 81.255491 -283.366142) (xy 81.288126 -283.329305) (xy 81.326247 -283.29818)
			(xy 81.368868 -283.273573) (xy 81.414884 -283.256121) (xy 81.463103 -283.246277) (xy 81.512278 -283.244296)
			(xy 81.561133 -283.250228) (xy 81.608404 -283.26392) (xy 81.652866 -283.285018) (xy 81.693369 -283.312974)
			(xy 81.728862 -283.347066) (xy 81.758427 -283.38641) (xy 81.781298 -283.429987) (xy 81.796882 -283.476668)
			(xy 81.804777 -283.525245) (xy 81.805272 -283.549852) (xy 82.14412 -283.549852) (xy 82.14808 -283.500798)
			(xy 82.159857 -283.453014) (xy 82.179148 -283.407738) (xy 82.205451 -283.366142) (xy 82.238086 -283.329305)
			(xy 82.276207 -283.29818) (xy 82.318828 -283.273573) (xy 82.364844 -283.256121) (xy 82.413063 -283.246277)
			(xy 82.462238 -283.244296) (xy 82.511093 -283.250228) (xy 82.558364 -283.26392) (xy 82.602826 -283.285018)
			(xy 82.643329 -283.312974) (xy 82.678822 -283.347066) (xy 82.708387 -283.38641) (xy 82.731258 -283.429987)
			(xy 82.746842 -283.476668) (xy 82.754737 -283.525245) (xy 82.755232 -283.549852) (xy 190.64403 -283.549852)
			(xy 190.64799 -283.500798) (xy 190.659767 -283.453014) (xy 190.679058 -283.407738) (xy 190.705361 -283.366142)
			(xy 190.737996 -283.329305) (xy 190.776117 -283.29818) (xy 190.818738 -283.273573) (xy 190.864754 -283.256121)
			(xy 190.912973 -283.246277) (xy 190.962148 -283.244296) (xy 191.011003 -283.250228) (xy 191.058274 -283.26392)
			(xy 191.102736 -283.285018) (xy 191.143239 -283.312974) (xy 191.178732 -283.347066) (xy 191.208297 -283.38641)
			(xy 191.231168 -283.429987) (xy 191.246752 -283.476668) (xy 191.254647 -283.525245) (xy 191.255142 -283.549852)
			(xy 191.594244 -283.549852) (xy 191.598204 -283.500798) (xy 191.609981 -283.453014) (xy 191.629272 -283.407738)
			(xy 191.655575 -283.366142) (xy 191.68821 -283.329305) (xy 191.726331 -283.29818) (xy 191.768952 -283.273573)
			(xy 191.814968 -283.256121) (xy 191.863187 -283.246277) (xy 191.912362 -283.244296) (xy 191.961217 -283.250228)
			(xy 192.008488 -283.26392) (xy 192.05295 -283.285018) (xy 192.093453 -283.312974) (xy 192.128946 -283.347066)
			(xy 192.158511 -283.38641) (xy 192.181382 -283.429987) (xy 192.196966 -283.476668) (xy 192.204861 -283.525245)
			(xy 192.205356 -283.549852) (xy 197.294258 -283.549852) (xy 197.298218 -283.500798) (xy 197.309995 -283.453014)
			(xy 197.329286 -283.407738) (xy 197.355589 -283.366142) (xy 197.388224 -283.329305) (xy 197.426345 -283.29818)
			(xy 197.468966 -283.273573) (xy 197.514982 -283.256121) (xy 197.563201 -283.246277) (xy 197.612376 -283.244296)
			(xy 197.661231 -283.250228) (xy 197.708502 -283.26392) (xy 197.752964 -283.285018) (xy 197.793467 -283.312974)
			(xy 197.82896 -283.347066) (xy 197.858525 -283.38641) (xy 197.881396 -283.429987) (xy 197.89698 -283.476668)
			(xy 197.904875 -283.525245) (xy 197.90537 -283.549852) (xy 198.244218 -283.549852) (xy 198.248178 -283.500798)
			(xy 198.259955 -283.453014) (xy 198.279246 -283.407738) (xy 198.305549 -283.366142) (xy 198.338184 -283.329305)
			(xy 198.376305 -283.29818) (xy 198.418926 -283.273573) (xy 198.464942 -283.256121) (xy 198.513161 -283.246277)
			(xy 198.562336 -283.244296) (xy 198.611191 -283.250228) (xy 198.658462 -283.26392) (xy 198.702924 -283.285018)
			(xy 198.743427 -283.312974) (xy 198.77892 -283.347066) (xy 198.808485 -283.38641) (xy 198.831356 -283.429987)
			(xy 198.84694 -283.476668) (xy 198.854835 -283.525245) (xy 198.85533 -283.549852) (xy 306.744128 -283.549852)
			(xy 306.748088 -283.500798) (xy 306.759865 -283.453014) (xy 306.779156 -283.407738) (xy 306.805459 -283.366142)
			(xy 306.838094 -283.329305) (xy 306.876215 -283.29818) (xy 306.918836 -283.273573) (xy 306.964852 -283.256121)
			(xy 307.013071 -283.246277) (xy 307.062246 -283.244296) (xy 307.111101 -283.250228) (xy 307.158372 -283.26392)
			(xy 307.202834 -283.285018) (xy 307.243337 -283.312974) (xy 307.27883 -283.347066) (xy 307.308395 -283.38641)
			(xy 307.331266 -283.429987) (xy 307.34685 -283.476668) (xy 307.354745 -283.525245) (xy 307.35524 -283.549852)
			(xy 307.694088 -283.549852) (xy 307.698048 -283.500798) (xy 307.709825 -283.453014) (xy 307.729116 -283.407738)
			(xy 307.755419 -283.366142) (xy 307.788054 -283.329305) (xy 307.826175 -283.29818) (xy 307.868796 -283.273573)
			(xy 307.914812 -283.256121) (xy 307.963031 -283.246277) (xy 308.012206 -283.244296) (xy 308.061061 -283.250228)
			(xy 308.108332 -283.26392) (xy 308.152794 -283.285018) (xy 308.193297 -283.312974) (xy 308.22879 -283.347066)
			(xy 308.258355 -283.38641) (xy 308.281226 -283.429987) (xy 308.29681 -283.476668) (xy 308.304705 -283.525245)
			(xy 308.3052 -283.549852) (xy 313.394102 -283.549852) (xy 313.398062 -283.500798) (xy 313.409839 -283.453014)
			(xy 313.42913 -283.407738) (xy 313.455433 -283.366142) (xy 313.488068 -283.329305) (xy 313.526189 -283.29818)
			(xy 313.56881 -283.273573) (xy 313.614826 -283.256121) (xy 313.663045 -283.246277) (xy 313.71222 -283.244296)
			(xy 313.761075 -283.250228) (xy 313.808346 -283.26392) (xy 313.852808 -283.285018) (xy 313.893311 -283.312974)
			(xy 313.928804 -283.347066) (xy 313.958369 -283.38641) (xy 313.98124 -283.429987) (xy 313.996824 -283.476668)
			(xy 314.004719 -283.525245) (xy 314.005214 -283.549852) (xy 314.344062 -283.549852) (xy 314.348022 -283.500798)
			(xy 314.359799 -283.453014) (xy 314.37909 -283.407738) (xy 314.405393 -283.366142) (xy 314.438028 -283.329305)
			(xy 314.476149 -283.29818) (xy 314.51877 -283.273573) (xy 314.564786 -283.256121) (xy 314.613005 -283.246277)
			(xy 314.66218 -283.244296) (xy 314.711035 -283.250228) (xy 314.758306 -283.26392) (xy 314.802768 -283.285018)
			(xy 314.843271 -283.312974) (xy 314.878764 -283.347066) (xy 314.908329 -283.38641) (xy 314.9312 -283.429987)
			(xy 314.946784 -283.476668) (xy 314.954679 -283.525245) (xy 314.955174 -283.549852) (xy 422.844226 -283.549852)
			(xy 422.848186 -283.500798) (xy 422.859963 -283.453014) (xy 422.879254 -283.407738) (xy 422.905557 -283.366142)
			(xy 422.938192 -283.329305) (xy 422.976313 -283.29818) (xy 423.018934 -283.273573) (xy 423.06495 -283.256121)
			(xy 423.113169 -283.246277) (xy 423.162344 -283.244296) (xy 423.211199 -283.250228) (xy 423.25847 -283.26392)
			(xy 423.302932 -283.285018) (xy 423.343435 -283.312974) (xy 423.378928 -283.347066) (xy 423.408493 -283.38641)
			(xy 423.431364 -283.429987) (xy 423.446948 -283.476668) (xy 423.454843 -283.525245) (xy 423.455338 -283.549852)
			(xy 423.794186 -283.549852) (xy 423.798146 -283.500798) (xy 423.809923 -283.453014) (xy 423.829214 -283.407738)
			(xy 423.855517 -283.366142) (xy 423.888152 -283.329305) (xy 423.926273 -283.29818) (xy 423.968894 -283.273573)
			(xy 424.01491 -283.256121) (xy 424.063129 -283.246277) (xy 424.112304 -283.244296) (xy 424.161159 -283.250228)
			(xy 424.20843 -283.26392) (xy 424.252892 -283.285018) (xy 424.293395 -283.312974) (xy 424.328888 -283.347066)
			(xy 424.358453 -283.38641) (xy 424.381324 -283.429987) (xy 424.396908 -283.476668) (xy 424.404803 -283.525245)
			(xy 424.405298 -283.549852) (xy 429.4942 -283.549852) (xy 429.49816 -283.500798) (xy 429.509937 -283.453014)
			(xy 429.529228 -283.407738) (xy 429.555531 -283.366142) (xy 429.588166 -283.329305) (xy 429.626287 -283.29818)
			(xy 429.668908 -283.273573) (xy 429.714924 -283.256121) (xy 429.763143 -283.246277) (xy 429.812318 -283.244296)
			(xy 429.861173 -283.250228) (xy 429.908444 -283.26392) (xy 429.952906 -283.285018) (xy 429.993409 -283.312974)
			(xy 430.028902 -283.347066) (xy 430.058467 -283.38641) (xy 430.081338 -283.429987) (xy 430.096922 -283.476668)
			(xy 430.104817 -283.525245) (xy 430.105312 -283.549852) (xy 430.44416 -283.549852) (xy 430.44812 -283.500798)
			(xy 430.459897 -283.453014) (xy 430.479188 -283.407738) (xy 430.505491 -283.366142) (xy 430.538126 -283.329305)
			(xy 430.576247 -283.29818) (xy 430.618868 -283.273573) (xy 430.664884 -283.256121) (xy 430.713103 -283.246277)
			(xy 430.762278 -283.244296) (xy 430.811133 -283.250228) (xy 430.858404 -283.26392) (xy 430.902866 -283.285018)
			(xy 430.943369 -283.312974) (xy 430.978862 -283.347066) (xy 431.008427 -283.38641) (xy 431.031298 -283.429987)
			(xy 431.046882 -283.476668) (xy 431.054777 -283.525245) (xy 431.055272 -283.549852) (xy 431.054777 -283.574459)
			(xy 431.046882 -283.623036) (xy 431.031298 -283.669717) (xy 431.008427 -283.713294) (xy 430.978862 -283.752638)
			(xy 430.943369 -283.78673) (xy 430.902866 -283.814686) (xy 430.858404 -283.835784) (xy 430.811133 -283.849476)
			(xy 430.762278 -283.855408) (xy 430.713103 -283.853427) (xy 430.664884 -283.843583) (xy 430.618868 -283.826131)
			(xy 430.576247 -283.801524) (xy 430.538126 -283.770399) (xy 430.505491 -283.733562) (xy 430.479188 -283.691966)
			(xy 430.459897 -283.64669) (xy 430.44812 -283.598906) (xy 430.44416 -283.549852) (xy 430.105312 -283.549852)
			(xy 430.104817 -283.574459) (xy 430.096922 -283.623036) (xy 430.081338 -283.669717) (xy 430.058467 -283.713294)
			(xy 430.028902 -283.752638) (xy 429.993409 -283.78673) (xy 429.952906 -283.814686) (xy 429.908444 -283.835784)
			(xy 429.861173 -283.849476) (xy 429.812318 -283.855408) (xy 429.763143 -283.853427) (xy 429.714924 -283.843583)
			(xy 429.668908 -283.826131) (xy 429.626287 -283.801524) (xy 429.588166 -283.770399) (xy 429.555531 -283.733562)
			(xy 429.529228 -283.691966) (xy 429.509937 -283.64669) (xy 429.49816 -283.598906) (xy 429.4942 -283.549852)
			(xy 424.405298 -283.549852) (xy 424.404803 -283.574459) (xy 424.396908 -283.623036) (xy 424.381324 -283.669717)
			(xy 424.358453 -283.713294) (xy 424.328888 -283.752638) (xy 424.293395 -283.78673) (xy 424.252892 -283.814686)
			(xy 424.20843 -283.835784) (xy 424.161159 -283.849476) (xy 424.112304 -283.855408) (xy 424.063129 -283.853427)
			(xy 424.01491 -283.843583) (xy 423.968894 -283.826131) (xy 423.926273 -283.801524) (xy 423.888152 -283.770399)
			(xy 423.855517 -283.733562) (xy 423.829214 -283.691966) (xy 423.809923 -283.64669) (xy 423.798146 -283.598906)
			(xy 423.794186 -283.549852) (xy 423.455338 -283.549852) (xy 423.454843 -283.574459) (xy 423.446948 -283.623036)
			(xy 423.431364 -283.669717) (xy 423.408493 -283.713294) (xy 423.378928 -283.752638) (xy 423.343435 -283.78673)
			(xy 423.302932 -283.814686) (xy 423.25847 -283.835784) (xy 423.211199 -283.849476) (xy 423.162344 -283.855408)
			(xy 423.113169 -283.853427) (xy 423.06495 -283.843583) (xy 423.018934 -283.826131) (xy 422.976313 -283.801524)
			(xy 422.938192 -283.770399) (xy 422.905557 -283.733562) (xy 422.879254 -283.691966) (xy 422.859963 -283.64669)
			(xy 422.848186 -283.598906) (xy 422.844226 -283.549852) (xy 314.955174 -283.549852) (xy 314.954679 -283.574459)
			(xy 314.946784 -283.623036) (xy 314.9312 -283.669717) (xy 314.908329 -283.713294) (xy 314.878764 -283.752638)
			(xy 314.843271 -283.78673) (xy 314.802768 -283.814686) (xy 314.758306 -283.835784) (xy 314.711035 -283.849476)
			(xy 314.66218 -283.855408) (xy 314.613005 -283.853427) (xy 314.564786 -283.843583) (xy 314.51877 -283.826131)
			(xy 314.476149 -283.801524) (xy 314.438028 -283.770399) (xy 314.405393 -283.733562) (xy 314.37909 -283.691966)
			(xy 314.359799 -283.64669) (xy 314.348022 -283.598906) (xy 314.344062 -283.549852) (xy 314.005214 -283.549852)
			(xy 314.004719 -283.574459) (xy 313.996824 -283.623036) (xy 313.98124 -283.669717) (xy 313.958369 -283.713294)
			(xy 313.928804 -283.752638) (xy 313.893311 -283.78673) (xy 313.852808 -283.814686) (xy 313.808346 -283.835784)
			(xy 313.761075 -283.849476) (xy 313.71222 -283.855408) (xy 313.663045 -283.853427) (xy 313.614826 -283.843583)
			(xy 313.56881 -283.826131) (xy 313.526189 -283.801524) (xy 313.488068 -283.770399) (xy 313.455433 -283.733562)
			(xy 313.42913 -283.691966) (xy 313.409839 -283.64669) (xy 313.398062 -283.598906) (xy 313.394102 -283.549852)
			(xy 308.3052 -283.549852) (xy 308.304705 -283.574459) (xy 308.29681 -283.623036) (xy 308.281226 -283.669717)
			(xy 308.258355 -283.713294) (xy 308.22879 -283.752638) (xy 308.193297 -283.78673) (xy 308.152794 -283.814686)
			(xy 308.108332 -283.835784) (xy 308.061061 -283.849476) (xy 308.012206 -283.855408) (xy 307.963031 -283.853427)
			(xy 307.914812 -283.843583) (xy 307.868796 -283.826131) (xy 307.826175 -283.801524) (xy 307.788054 -283.770399)
			(xy 307.755419 -283.733562) (xy 307.729116 -283.691966) (xy 307.709825 -283.64669) (xy 307.698048 -283.598906)
			(xy 307.694088 -283.549852) (xy 307.35524 -283.549852) (xy 307.354745 -283.574459) (xy 307.34685 -283.623036)
			(xy 307.331266 -283.669717) (xy 307.308395 -283.713294) (xy 307.27883 -283.752638) (xy 307.243337 -283.78673)
			(xy 307.202834 -283.814686) (xy 307.158372 -283.835784) (xy 307.111101 -283.849476) (xy 307.062246 -283.855408)
			(xy 307.013071 -283.853427) (xy 306.964852 -283.843583) (xy 306.918836 -283.826131) (xy 306.876215 -283.801524)
			(xy 306.838094 -283.770399) (xy 306.805459 -283.733562) (xy 306.779156 -283.691966) (xy 306.759865 -283.64669)
			(xy 306.748088 -283.598906) (xy 306.744128 -283.549852) (xy 198.85533 -283.549852) (xy 198.854835 -283.574459)
			(xy 198.84694 -283.623036) (xy 198.831356 -283.669717) (xy 198.808485 -283.713294) (xy 198.77892 -283.752638)
			(xy 198.743427 -283.78673) (xy 198.702924 -283.814686) (xy 198.658462 -283.835784) (xy 198.611191 -283.849476)
			(xy 198.562336 -283.855408) (xy 198.513161 -283.853427) (xy 198.464942 -283.843583) (xy 198.418926 -283.826131)
			(xy 198.376305 -283.801524) (xy 198.338184 -283.770399) (xy 198.305549 -283.733562) (xy 198.279246 -283.691966)
			(xy 198.259955 -283.64669) (xy 198.248178 -283.598906) (xy 198.244218 -283.549852) (xy 197.90537 -283.549852)
			(xy 197.904875 -283.574459) (xy 197.89698 -283.623036) (xy 197.881396 -283.669717) (xy 197.858525 -283.713294)
			(xy 197.82896 -283.752638) (xy 197.793467 -283.78673) (xy 197.752964 -283.814686) (xy 197.708502 -283.835784)
			(xy 197.661231 -283.849476) (xy 197.612376 -283.855408) (xy 197.563201 -283.853427) (xy 197.514982 -283.843583)
			(xy 197.468966 -283.826131) (xy 197.426345 -283.801524) (xy 197.388224 -283.770399) (xy 197.355589 -283.733562)
			(xy 197.329286 -283.691966) (xy 197.309995 -283.64669) (xy 197.298218 -283.598906) (xy 197.294258 -283.549852)
			(xy 192.205356 -283.549852) (xy 192.204861 -283.574459) (xy 192.196966 -283.623036) (xy 192.181382 -283.669717)
			(xy 192.158511 -283.713294) (xy 192.128946 -283.752638) (xy 192.093453 -283.78673) (xy 192.05295 -283.814686)
			(xy 192.008488 -283.835784) (xy 191.961217 -283.849476) (xy 191.912362 -283.855408) (xy 191.863187 -283.853427)
			(xy 191.814968 -283.843583) (xy 191.768952 -283.826131) (xy 191.726331 -283.801524) (xy 191.68821 -283.770399)
			(xy 191.655575 -283.733562) (xy 191.629272 -283.691966) (xy 191.609981 -283.64669) (xy 191.598204 -283.598906)
			(xy 191.594244 -283.549852) (xy 191.255142 -283.549852) (xy 191.254647 -283.574459) (xy 191.246752 -283.623036)
			(xy 191.231168 -283.669717) (xy 191.208297 -283.713294) (xy 191.178732 -283.752638) (xy 191.143239 -283.78673)
			(xy 191.102736 -283.814686) (xy 191.058274 -283.835784) (xy 191.011003 -283.849476) (xy 190.962148 -283.855408)
			(xy 190.912973 -283.853427) (xy 190.864754 -283.843583) (xy 190.818738 -283.826131) (xy 190.776117 -283.801524)
			(xy 190.737996 -283.770399) (xy 190.705361 -283.733562) (xy 190.679058 -283.691966) (xy 190.659767 -283.64669)
			(xy 190.64799 -283.598906) (xy 190.64403 -283.549852) (xy 82.755232 -283.549852) (xy 82.754737 -283.574459)
			(xy 82.746842 -283.623036) (xy 82.731258 -283.669717) (xy 82.708387 -283.713294) (xy 82.678822 -283.752638)
			(xy 82.643329 -283.78673) (xy 82.602826 -283.814686) (xy 82.558364 -283.835784) (xy 82.511093 -283.849476)
			(xy 82.462238 -283.855408) (xy 82.413063 -283.853427) (xy 82.364844 -283.843583) (xy 82.318828 -283.826131)
			(xy 82.276207 -283.801524) (xy 82.238086 -283.770399) (xy 82.205451 -283.733562) (xy 82.179148 -283.691966)
			(xy 82.159857 -283.64669) (xy 82.14808 -283.598906) (xy 82.14412 -283.549852) (xy 81.805272 -283.549852)
			(xy 81.804777 -283.574459) (xy 81.796882 -283.623036) (xy 81.781298 -283.669717) (xy 81.758427 -283.713294)
			(xy 81.728862 -283.752638) (xy 81.693369 -283.78673) (xy 81.652866 -283.814686) (xy 81.608404 -283.835784)
			(xy 81.561133 -283.849476) (xy 81.512278 -283.855408) (xy 81.463103 -283.853427) (xy 81.414884 -283.843583)
			(xy 81.368868 -283.826131) (xy 81.326247 -283.801524) (xy 81.288126 -283.770399) (xy 81.255491 -283.733562)
			(xy 81.229188 -283.691966) (xy 81.209897 -283.64669) (xy 81.19812 -283.598906) (xy 81.19416 -283.549852)
			(xy 76.105258 -283.549852) (xy 76.104763 -283.574459) (xy 76.096868 -283.623036) (xy 76.081284 -283.669717)
			(xy 76.058413 -283.713294) (xy 76.028848 -283.752638) (xy 75.993355 -283.78673) (xy 75.952852 -283.814686)
			(xy 75.90839 -283.835784) (xy 75.861119 -283.849476) (xy 75.812264 -283.855408) (xy 75.763089 -283.853427)
			(xy 75.71487 -283.843583) (xy 75.668854 -283.826131) (xy 75.626233 -283.801524) (xy 75.588112 -283.770399)
			(xy 75.555477 -283.733562) (xy 75.529174 -283.691966) (xy 75.509883 -283.64669) (xy 75.498106 -283.598906)
			(xy 75.494146 -283.549852) (xy 75.155044 -283.549852) (xy 75.154549 -283.574459) (xy 75.146654 -283.623036)
			(xy 75.13107 -283.669717) (xy 75.108199 -283.713294) (xy 75.078634 -283.752638) (xy 75.043141 -283.78673)
			(xy 75.002638 -283.814686) (xy 74.958176 -283.835784) (xy 74.910905 -283.849476) (xy 74.86205 -283.855408)
			(xy 74.812875 -283.853427) (xy 74.764656 -283.843583) (xy 74.71864 -283.826131) (xy 74.676019 -283.801524)
			(xy 74.637898 -283.770399) (xy 74.605263 -283.733562) (xy 74.57896 -283.691966) (xy 74.559669 -283.64669)
			(xy 74.547892 -283.598906) (xy 74.543932 -283.549852) (xy 0.509016 -283.549852) (xy 0.509016 -284.499812)
			(xy 76.444106 -284.499812) (xy 76.448066 -284.450758) (xy 76.459843 -284.402974) (xy 76.479134 -284.357698)
			(xy 76.505437 -284.316102) (xy 76.538072 -284.279265) (xy 76.576193 -284.24814) (xy 76.618814 -284.223533)
			(xy 76.66483 -284.206081) (xy 76.713049 -284.196237) (xy 76.762224 -284.194256) (xy 76.811079 -284.200188)
			(xy 76.85835 -284.21388) (xy 76.902812 -284.234978) (xy 76.943315 -284.262934) (xy 76.978808 -284.297026)
			(xy 77.008373 -284.33637) (xy 77.031244 -284.379947) (xy 77.046828 -284.426628) (xy 77.054723 -284.475205)
			(xy 77.055218 -284.499812) (xy 77.394066 -284.499812) (xy 77.398026 -284.450758) (xy 77.409803 -284.402974)
			(xy 77.429094 -284.357698) (xy 77.455397 -284.316102) (xy 77.488032 -284.279265) (xy 77.526153 -284.24814)
			(xy 77.568774 -284.223533) (xy 77.61479 -284.206081) (xy 77.663009 -284.196237) (xy 77.712184 -284.194256)
			(xy 77.761039 -284.200188) (xy 77.80831 -284.21388) (xy 77.852772 -284.234978) (xy 77.893275 -284.262934)
			(xy 77.928768 -284.297026) (xy 77.958333 -284.33637) (xy 77.981204 -284.379947) (xy 77.996788 -284.426628)
			(xy 78.004683 -284.475205) (xy 78.005178 -284.499812) (xy 79.293986 -284.499812) (xy 79.297946 -284.450758)
			(xy 79.309723 -284.402974) (xy 79.329014 -284.357698) (xy 79.355317 -284.316102) (xy 79.387952 -284.279265)
			(xy 79.426073 -284.24814) (xy 79.468694 -284.223533) (xy 79.51471 -284.206081) (xy 79.562929 -284.196237)
			(xy 79.612104 -284.194256) (xy 79.660959 -284.200188) (xy 79.70823 -284.21388) (xy 79.752692 -284.234978)
			(xy 79.793195 -284.262934) (xy 79.828688 -284.297026) (xy 79.858253 -284.33637) (xy 79.881124 -284.379947)
			(xy 79.896708 -284.426628) (xy 79.904603 -284.475205) (xy 79.905098 -284.499812) (xy 80.243946 -284.499812)
			(xy 80.247906 -284.450758) (xy 80.259683 -284.402974) (xy 80.278974 -284.357698) (xy 80.305277 -284.316102)
			(xy 80.337912 -284.279265) (xy 80.376033 -284.24814) (xy 80.418654 -284.223533) (xy 80.46467 -284.206081)
			(xy 80.512889 -284.196237) (xy 80.562064 -284.194256) (xy 80.610919 -284.200188) (xy 80.65819 -284.21388)
			(xy 80.702652 -284.234978) (xy 80.743155 -284.262934) (xy 80.778648 -284.297026) (xy 80.808213 -284.33637)
			(xy 80.831084 -284.379947) (xy 80.846668 -284.426628) (xy 80.854563 -284.475205) (xy 80.855058 -284.499812)
			(xy 192.544204 -284.499812) (xy 192.548164 -284.450758) (xy 192.559941 -284.402974) (xy 192.579232 -284.357698)
			(xy 192.605535 -284.316102) (xy 192.63817 -284.279265) (xy 192.676291 -284.24814) (xy 192.718912 -284.223533)
			(xy 192.764928 -284.206081) (xy 192.813147 -284.196237) (xy 192.862322 -284.194256) (xy 192.911177 -284.200188)
			(xy 192.958448 -284.21388) (xy 193.00291 -284.234978) (xy 193.043413 -284.262934) (xy 193.078906 -284.297026)
			(xy 193.108471 -284.33637) (xy 193.131342 -284.379947) (xy 193.146926 -284.426628) (xy 193.154821 -284.475205)
			(xy 193.155316 -284.499812) (xy 193.494164 -284.499812) (xy 193.498124 -284.450758) (xy 193.509901 -284.402974)
			(xy 193.529192 -284.357698) (xy 193.555495 -284.316102) (xy 193.58813 -284.279265) (xy 193.626251 -284.24814)
			(xy 193.668872 -284.223533) (xy 193.714888 -284.206081) (xy 193.763107 -284.196237) (xy 193.812282 -284.194256)
			(xy 193.861137 -284.200188) (xy 193.908408 -284.21388) (xy 193.95287 -284.234978) (xy 193.993373 -284.262934)
			(xy 194.028866 -284.297026) (xy 194.058431 -284.33637) (xy 194.081302 -284.379947) (xy 194.096886 -284.426628)
			(xy 194.104781 -284.475205) (xy 194.105276 -284.499812) (xy 195.394084 -284.499812) (xy 195.398044 -284.450758)
			(xy 195.409821 -284.402974) (xy 195.429112 -284.357698) (xy 195.455415 -284.316102) (xy 195.48805 -284.279265)
			(xy 195.526171 -284.24814) (xy 195.568792 -284.223533) (xy 195.614808 -284.206081) (xy 195.663027 -284.196237)
			(xy 195.712202 -284.194256) (xy 195.761057 -284.200188) (xy 195.808328 -284.21388) (xy 195.85279 -284.234978)
			(xy 195.893293 -284.262934) (xy 195.928786 -284.297026) (xy 195.958351 -284.33637) (xy 195.981222 -284.379947)
			(xy 195.996806 -284.426628) (xy 196.004701 -284.475205) (xy 196.005196 -284.499812) (xy 196.344044 -284.499812)
			(xy 196.348004 -284.450758) (xy 196.359781 -284.402974) (xy 196.379072 -284.357698) (xy 196.405375 -284.316102)
			(xy 196.43801 -284.279265) (xy 196.476131 -284.24814) (xy 196.518752 -284.223533) (xy 196.564768 -284.206081)
			(xy 196.612987 -284.196237) (xy 196.662162 -284.194256) (xy 196.711017 -284.200188) (xy 196.758288 -284.21388)
			(xy 196.80275 -284.234978) (xy 196.843253 -284.262934) (xy 196.878746 -284.297026) (xy 196.908311 -284.33637)
			(xy 196.931182 -284.379947) (xy 196.946766 -284.426628) (xy 196.954661 -284.475205) (xy 196.955156 -284.499812)
			(xy 308.644048 -284.499812) (xy 308.648008 -284.450758) (xy 308.659785 -284.402974) (xy 308.679076 -284.357698)
			(xy 308.705379 -284.316102) (xy 308.738014 -284.279265) (xy 308.776135 -284.24814) (xy 308.818756 -284.223533)
			(xy 308.864772 -284.206081) (xy 308.912991 -284.196237) (xy 308.962166 -284.194256) (xy 309.011021 -284.200188)
			(xy 309.058292 -284.21388) (xy 309.102754 -284.234978) (xy 309.143257 -284.262934) (xy 309.17875 -284.297026)
			(xy 309.208315 -284.33637) (xy 309.231186 -284.379947) (xy 309.24677 -284.426628) (xy 309.254665 -284.475205)
			(xy 309.25516 -284.499812) (xy 309.594008 -284.499812) (xy 309.597968 -284.450758) (xy 309.609745 -284.402974)
			(xy 309.629036 -284.357698) (xy 309.655339 -284.316102) (xy 309.687974 -284.279265) (xy 309.726095 -284.24814)
			(xy 309.768716 -284.223533) (xy 309.814732 -284.206081) (xy 309.862951 -284.196237) (xy 309.912126 -284.194256)
			(xy 309.960981 -284.200188) (xy 310.008252 -284.21388) (xy 310.052714 -284.234978) (xy 310.093217 -284.262934)
			(xy 310.12871 -284.297026) (xy 310.158275 -284.33637) (xy 310.181146 -284.379947) (xy 310.19673 -284.426628)
			(xy 310.204625 -284.475205) (xy 310.20512 -284.499812) (xy 311.493928 -284.499812) (xy 311.497888 -284.450758)
			(xy 311.509665 -284.402974) (xy 311.528956 -284.357698) (xy 311.555259 -284.316102) (xy 311.587894 -284.279265)
			(xy 311.626015 -284.24814) (xy 311.668636 -284.223533) (xy 311.714652 -284.206081) (xy 311.762871 -284.196237)
			(xy 311.812046 -284.194256) (xy 311.860901 -284.200188) (xy 311.908172 -284.21388) (xy 311.952634 -284.234978)
			(xy 311.993137 -284.262934) (xy 312.02863 -284.297026) (xy 312.058195 -284.33637) (xy 312.081066 -284.379947)
			(xy 312.09665 -284.426628) (xy 312.104545 -284.475205) (xy 312.10504 -284.499812) (xy 312.443888 -284.499812)
			(xy 312.447848 -284.450758) (xy 312.459625 -284.402974) (xy 312.478916 -284.357698) (xy 312.505219 -284.316102)
			(xy 312.537854 -284.279265) (xy 312.575975 -284.24814) (xy 312.618596 -284.223533) (xy 312.664612 -284.206081)
			(xy 312.712831 -284.196237) (xy 312.762006 -284.194256) (xy 312.810861 -284.200188) (xy 312.858132 -284.21388)
			(xy 312.902594 -284.234978) (xy 312.943097 -284.262934) (xy 312.97859 -284.297026) (xy 313.008155 -284.33637)
			(xy 313.031026 -284.379947) (xy 313.04661 -284.426628) (xy 313.054505 -284.475205) (xy 313.055 -284.499812)
			(xy 424.744146 -284.499812) (xy 424.748106 -284.450758) (xy 424.759883 -284.402974) (xy 424.779174 -284.357698)
			(xy 424.805477 -284.316102) (xy 424.838112 -284.279265) (xy 424.876233 -284.24814) (xy 424.918854 -284.223533)
			(xy 424.96487 -284.206081) (xy 425.013089 -284.196237) (xy 425.062264 -284.194256) (xy 425.111119 -284.200188)
			(xy 425.15839 -284.21388) (xy 425.202852 -284.234978) (xy 425.243355 -284.262934) (xy 425.278848 -284.297026)
			(xy 425.308413 -284.33637) (xy 425.331284 -284.379947) (xy 425.346868 -284.426628) (xy 425.354763 -284.475205)
			(xy 425.355258 -284.499812) (xy 425.694106 -284.499812) (xy 425.698066 -284.450758) (xy 425.709843 -284.402974)
			(xy 425.729134 -284.357698) (xy 425.755437 -284.316102) (xy 425.788072 -284.279265) (xy 425.826193 -284.24814)
			(xy 425.868814 -284.223533) (xy 425.91483 -284.206081) (xy 425.963049 -284.196237) (xy 426.012224 -284.194256)
			(xy 426.061079 -284.200188) (xy 426.10835 -284.21388) (xy 426.152812 -284.234978) (xy 426.193315 -284.262934)
			(xy 426.228808 -284.297026) (xy 426.258373 -284.33637) (xy 426.281244 -284.379947) (xy 426.296828 -284.426628)
			(xy 426.304723 -284.475205) (xy 426.305218 -284.499812) (xy 427.594026 -284.499812) (xy 427.597986 -284.450758)
			(xy 427.609763 -284.402974) (xy 427.629054 -284.357698) (xy 427.655357 -284.316102) (xy 427.687992 -284.279265)
			(xy 427.726113 -284.24814) (xy 427.768734 -284.223533) (xy 427.81475 -284.206081) (xy 427.862969 -284.196237)
			(xy 427.912144 -284.194256) (xy 427.960999 -284.200188) (xy 428.00827 -284.21388) (xy 428.052732 -284.234978)
			(xy 428.093235 -284.262934) (xy 428.128728 -284.297026) (xy 428.158293 -284.33637) (xy 428.181164 -284.379947)
			(xy 428.196748 -284.426628) (xy 428.204643 -284.475205) (xy 428.205138 -284.499812) (xy 428.543986 -284.499812)
			(xy 428.547946 -284.450758) (xy 428.559723 -284.402974) (xy 428.579014 -284.357698) (xy 428.605317 -284.316102)
			(xy 428.637952 -284.279265) (xy 428.676073 -284.24814) (xy 428.718694 -284.223533) (xy 428.76471 -284.206081)
			(xy 428.812929 -284.196237) (xy 428.862104 -284.194256) (xy 428.910959 -284.200188) (xy 428.95823 -284.21388)
			(xy 429.002692 -284.234978) (xy 429.043195 -284.262934) (xy 429.078688 -284.297026) (xy 429.108253 -284.33637)
			(xy 429.131124 -284.379947) (xy 429.146708 -284.426628) (xy 429.154603 -284.475205) (xy 429.155098 -284.499812)
			(xy 429.154603 -284.524419) (xy 429.146708 -284.572996) (xy 429.131124 -284.619677) (xy 429.108253 -284.663254)
			(xy 429.078688 -284.702598) (xy 429.043195 -284.73669) (xy 429.002692 -284.764646) (xy 428.95823 -284.785744)
			(xy 428.910959 -284.799436) (xy 428.862104 -284.805368) (xy 428.812929 -284.803387) (xy 428.76471 -284.793543)
			(xy 428.718694 -284.776091) (xy 428.676073 -284.751484) (xy 428.637952 -284.720359) (xy 428.605317 -284.683522)
			(xy 428.579014 -284.641926) (xy 428.559723 -284.59665) (xy 428.547946 -284.548866) (xy 428.543986 -284.499812)
			(xy 428.205138 -284.499812) (xy 428.204643 -284.524419) (xy 428.196748 -284.572996) (xy 428.181164 -284.619677)
			(xy 428.158293 -284.663254) (xy 428.128728 -284.702598) (xy 428.093235 -284.73669) (xy 428.052732 -284.764646)
			(xy 428.00827 -284.785744) (xy 427.960999 -284.799436) (xy 427.912144 -284.805368) (xy 427.862969 -284.803387)
			(xy 427.81475 -284.793543) (xy 427.768734 -284.776091) (xy 427.726113 -284.751484) (xy 427.687992 -284.720359)
			(xy 427.655357 -284.683522) (xy 427.629054 -284.641926) (xy 427.609763 -284.59665) (xy 427.597986 -284.548866)
			(xy 427.594026 -284.499812) (xy 426.305218 -284.499812) (xy 426.304723 -284.524419) (xy 426.296828 -284.572996)
			(xy 426.281244 -284.619677) (xy 426.258373 -284.663254) (xy 426.228808 -284.702598) (xy 426.193315 -284.73669)
			(xy 426.152812 -284.764646) (xy 426.10835 -284.785744) (xy 426.061079 -284.799436) (xy 426.012224 -284.805368)
			(xy 425.963049 -284.803387) (xy 425.91483 -284.793543) (xy 425.868814 -284.776091) (xy 425.826193 -284.751484)
			(xy 425.788072 -284.720359) (xy 425.755437 -284.683522) (xy 425.729134 -284.641926) (xy 425.709843 -284.59665)
			(xy 425.698066 -284.548866) (xy 425.694106 -284.499812) (xy 425.355258 -284.499812) (xy 425.354763 -284.524419)
			(xy 425.346868 -284.572996) (xy 425.331284 -284.619677) (xy 425.308413 -284.663254) (xy 425.278848 -284.702598)
			(xy 425.243355 -284.73669) (xy 425.202852 -284.764646) (xy 425.15839 -284.785744) (xy 425.111119 -284.799436)
			(xy 425.062264 -284.805368) (xy 425.013089 -284.803387) (xy 424.96487 -284.793543) (xy 424.918854 -284.776091)
			(xy 424.876233 -284.751484) (xy 424.838112 -284.720359) (xy 424.805477 -284.683522) (xy 424.779174 -284.641926)
			(xy 424.759883 -284.59665) (xy 424.748106 -284.548866) (xy 424.744146 -284.499812) (xy 313.055 -284.499812)
			(xy 313.054505 -284.524419) (xy 313.04661 -284.572996) (xy 313.031026 -284.619677) (xy 313.008155 -284.663254)
			(xy 312.97859 -284.702598) (xy 312.943097 -284.73669) (xy 312.902594 -284.764646) (xy 312.858132 -284.785744)
			(xy 312.810861 -284.799436) (xy 312.762006 -284.805368) (xy 312.712831 -284.803387) (xy 312.664612 -284.793543)
			(xy 312.618596 -284.776091) (xy 312.575975 -284.751484) (xy 312.537854 -284.720359) (xy 312.505219 -284.683522)
			(xy 312.478916 -284.641926) (xy 312.459625 -284.59665) (xy 312.447848 -284.548866) (xy 312.443888 -284.499812)
			(xy 312.10504 -284.499812) (xy 312.104545 -284.524419) (xy 312.09665 -284.572996) (xy 312.081066 -284.619677)
			(xy 312.058195 -284.663254) (xy 312.02863 -284.702598) (xy 311.993137 -284.73669) (xy 311.952634 -284.764646)
			(xy 311.908172 -284.785744) (xy 311.860901 -284.799436) (xy 311.812046 -284.805368) (xy 311.762871 -284.803387)
			(xy 311.714652 -284.793543) (xy 311.668636 -284.776091) (xy 311.626015 -284.751484) (xy 311.587894 -284.720359)
			(xy 311.555259 -284.683522) (xy 311.528956 -284.641926) (xy 311.509665 -284.59665) (xy 311.497888 -284.548866)
			(xy 311.493928 -284.499812) (xy 310.20512 -284.499812) (xy 310.204625 -284.524419) (xy 310.19673 -284.572996)
			(xy 310.181146 -284.619677) (xy 310.158275 -284.663254) (xy 310.12871 -284.702598) (xy 310.093217 -284.73669)
			(xy 310.052714 -284.764646) (xy 310.008252 -284.785744) (xy 309.960981 -284.799436) (xy 309.912126 -284.805368)
			(xy 309.862951 -284.803387) (xy 309.814732 -284.793543) (xy 309.768716 -284.776091) (xy 309.726095 -284.751484)
			(xy 309.687974 -284.720359) (xy 309.655339 -284.683522) (xy 309.629036 -284.641926) (xy 309.609745 -284.59665)
			(xy 309.597968 -284.548866) (xy 309.594008 -284.499812) (xy 309.25516 -284.499812) (xy 309.254665 -284.524419)
			(xy 309.24677 -284.572996) (xy 309.231186 -284.619677) (xy 309.208315 -284.663254) (xy 309.17875 -284.702598)
			(xy 309.143257 -284.73669) (xy 309.102754 -284.764646) (xy 309.058292 -284.785744) (xy 309.011021 -284.799436)
			(xy 308.962166 -284.805368) (xy 308.912991 -284.803387) (xy 308.864772 -284.793543) (xy 308.818756 -284.776091)
			(xy 308.776135 -284.751484) (xy 308.738014 -284.720359) (xy 308.705379 -284.683522) (xy 308.679076 -284.641926)
			(xy 308.659785 -284.59665) (xy 308.648008 -284.548866) (xy 308.644048 -284.499812) (xy 196.955156 -284.499812)
			(xy 196.954661 -284.524419) (xy 196.946766 -284.572996) (xy 196.931182 -284.619677) (xy 196.908311 -284.663254)
			(xy 196.878746 -284.702598) (xy 196.843253 -284.73669) (xy 196.80275 -284.764646) (xy 196.758288 -284.785744)
			(xy 196.711017 -284.799436) (xy 196.662162 -284.805368) (xy 196.612987 -284.803387) (xy 196.564768 -284.793543)
			(xy 196.518752 -284.776091) (xy 196.476131 -284.751484) (xy 196.43801 -284.720359) (xy 196.405375 -284.683522)
			(xy 196.379072 -284.641926) (xy 196.359781 -284.59665) (xy 196.348004 -284.548866) (xy 196.344044 -284.499812)
			(xy 196.005196 -284.499812) (xy 196.004701 -284.524419) (xy 195.996806 -284.572996) (xy 195.981222 -284.619677)
			(xy 195.958351 -284.663254) (xy 195.928786 -284.702598) (xy 195.893293 -284.73669) (xy 195.85279 -284.764646)
			(xy 195.808328 -284.785744) (xy 195.761057 -284.799436) (xy 195.712202 -284.805368) (xy 195.663027 -284.803387)
			(xy 195.614808 -284.793543) (xy 195.568792 -284.776091) (xy 195.526171 -284.751484) (xy 195.48805 -284.720359)
			(xy 195.455415 -284.683522) (xy 195.429112 -284.641926) (xy 195.409821 -284.59665) (xy 195.398044 -284.548866)
			(xy 195.394084 -284.499812) (xy 194.105276 -284.499812) (xy 194.104781 -284.524419) (xy 194.096886 -284.572996)
			(xy 194.081302 -284.619677) (xy 194.058431 -284.663254) (xy 194.028866 -284.702598) (xy 193.993373 -284.73669)
			(xy 193.95287 -284.764646) (xy 193.908408 -284.785744) (xy 193.861137 -284.799436) (xy 193.812282 -284.805368)
			(xy 193.763107 -284.803387) (xy 193.714888 -284.793543) (xy 193.668872 -284.776091) (xy 193.626251 -284.751484)
			(xy 193.58813 -284.720359) (xy 193.555495 -284.683522) (xy 193.529192 -284.641926) (xy 193.509901 -284.59665)
			(xy 193.498124 -284.548866) (xy 193.494164 -284.499812) (xy 193.155316 -284.499812) (xy 193.154821 -284.524419)
			(xy 193.146926 -284.572996) (xy 193.131342 -284.619677) (xy 193.108471 -284.663254) (xy 193.078906 -284.702598)
			(xy 193.043413 -284.73669) (xy 193.00291 -284.764646) (xy 192.958448 -284.785744) (xy 192.911177 -284.799436)
			(xy 192.862322 -284.805368) (xy 192.813147 -284.803387) (xy 192.764928 -284.793543) (xy 192.718912 -284.776091)
			(xy 192.676291 -284.751484) (xy 192.63817 -284.720359) (xy 192.605535 -284.683522) (xy 192.579232 -284.641926)
			(xy 192.559941 -284.59665) (xy 192.548164 -284.548866) (xy 192.544204 -284.499812) (xy 80.855058 -284.499812)
			(xy 80.854563 -284.524419) (xy 80.846668 -284.572996) (xy 80.831084 -284.619677) (xy 80.808213 -284.663254)
			(xy 80.778648 -284.702598) (xy 80.743155 -284.73669) (xy 80.702652 -284.764646) (xy 80.65819 -284.785744)
			(xy 80.610919 -284.799436) (xy 80.562064 -284.805368) (xy 80.512889 -284.803387) (xy 80.46467 -284.793543)
			(xy 80.418654 -284.776091) (xy 80.376033 -284.751484) (xy 80.337912 -284.720359) (xy 80.305277 -284.683522)
			(xy 80.278974 -284.641926) (xy 80.259683 -284.59665) (xy 80.247906 -284.548866) (xy 80.243946 -284.499812)
			(xy 79.905098 -284.499812) (xy 79.904603 -284.524419) (xy 79.896708 -284.572996) (xy 79.881124 -284.619677)
			(xy 79.858253 -284.663254) (xy 79.828688 -284.702598) (xy 79.793195 -284.73669) (xy 79.752692 -284.764646)
			(xy 79.70823 -284.785744) (xy 79.660959 -284.799436) (xy 79.612104 -284.805368) (xy 79.562929 -284.803387)
			(xy 79.51471 -284.793543) (xy 79.468694 -284.776091) (xy 79.426073 -284.751484) (xy 79.387952 -284.720359)
			(xy 79.355317 -284.683522) (xy 79.329014 -284.641926) (xy 79.309723 -284.59665) (xy 79.297946 -284.548866)
			(xy 79.293986 -284.499812) (xy 78.005178 -284.499812) (xy 78.004683 -284.524419) (xy 77.996788 -284.572996)
			(xy 77.981204 -284.619677) (xy 77.958333 -284.663254) (xy 77.928768 -284.702598) (xy 77.893275 -284.73669)
			(xy 77.852772 -284.764646) (xy 77.80831 -284.785744) (xy 77.761039 -284.799436) (xy 77.712184 -284.805368)
			(xy 77.663009 -284.803387) (xy 77.61479 -284.793543) (xy 77.568774 -284.776091) (xy 77.526153 -284.751484)
			(xy 77.488032 -284.720359) (xy 77.455397 -284.683522) (xy 77.429094 -284.641926) (xy 77.409803 -284.59665)
			(xy 77.398026 -284.548866) (xy 77.394066 -284.499812) (xy 77.055218 -284.499812) (xy 77.054723 -284.524419)
			(xy 77.046828 -284.572996) (xy 77.031244 -284.619677) (xy 77.008373 -284.663254) (xy 76.978808 -284.702598)
			(xy 76.943315 -284.73669) (xy 76.902812 -284.764646) (xy 76.85835 -284.785744) (xy 76.811079 -284.799436)
			(xy 76.762224 -284.805368) (xy 76.713049 -284.803387) (xy 76.66483 -284.793543) (xy 76.618814 -284.776091)
			(xy 76.576193 -284.751484) (xy 76.538072 -284.720359) (xy 76.505437 -284.683522) (xy 76.479134 -284.641926)
			(xy 76.459843 -284.59665) (xy 76.448066 -284.548866) (xy 76.444106 -284.499812) (xy 0.509016 -284.499812)
			(xy 0.509016 -285.449772) (xy 74.543932 -285.449772) (xy 74.547892 -285.400718) (xy 74.559669 -285.352934)
			(xy 74.57896 -285.307658) (xy 74.605263 -285.266062) (xy 74.637898 -285.229225) (xy 74.676019 -285.1981)
			(xy 74.71864 -285.173493) (xy 74.764656 -285.156041) (xy 74.812875 -285.146197) (xy 74.86205 -285.144216)
			(xy 74.910905 -285.150148) (xy 74.958176 -285.16384) (xy 75.002638 -285.184938) (xy 75.043141 -285.212894)
			(xy 75.078634 -285.246986) (xy 75.108199 -285.28633) (xy 75.13107 -285.329907) (xy 75.146654 -285.376588)
			(xy 75.154549 -285.425165) (xy 75.155044 -285.449772) (xy 75.494146 -285.449772) (xy 75.498106 -285.400718)
			(xy 75.509883 -285.352934) (xy 75.529174 -285.307658) (xy 75.555477 -285.266062) (xy 75.588112 -285.229225)
			(xy 75.626233 -285.1981) (xy 75.668854 -285.173493) (xy 75.71487 -285.156041) (xy 75.763089 -285.146197)
			(xy 75.812264 -285.144216) (xy 75.861119 -285.150148) (xy 75.90839 -285.16384) (xy 75.952852 -285.184938)
			(xy 75.993355 -285.212894) (xy 76.028848 -285.246986) (xy 76.058413 -285.28633) (xy 76.081284 -285.329907)
			(xy 76.096868 -285.376588) (xy 76.104763 -285.425165) (xy 76.105258 -285.449772) (xy 81.19416 -285.449772)
			(xy 81.19812 -285.400718) (xy 81.209897 -285.352934) (xy 81.229188 -285.307658) (xy 81.255491 -285.266062)
			(xy 81.288126 -285.229225) (xy 81.326247 -285.1981) (xy 81.368868 -285.173493) (xy 81.414884 -285.156041)
			(xy 81.463103 -285.146197) (xy 81.512278 -285.144216) (xy 81.561133 -285.150148) (xy 81.608404 -285.16384)
			(xy 81.652866 -285.184938) (xy 81.693369 -285.212894) (xy 81.728862 -285.246986) (xy 81.758427 -285.28633)
			(xy 81.781298 -285.329907) (xy 81.796882 -285.376588) (xy 81.804777 -285.425165) (xy 81.805272 -285.449772)
			(xy 82.14412 -285.449772) (xy 82.14808 -285.400718) (xy 82.159857 -285.352934) (xy 82.179148 -285.307658)
			(xy 82.205451 -285.266062) (xy 82.238086 -285.229225) (xy 82.276207 -285.1981) (xy 82.318828 -285.173493)
			(xy 82.364844 -285.156041) (xy 82.413063 -285.146197) (xy 82.462238 -285.144216) (xy 82.511093 -285.150148)
			(xy 82.558364 -285.16384) (xy 82.602826 -285.184938) (xy 82.643329 -285.212894) (xy 82.678822 -285.246986)
			(xy 82.708387 -285.28633) (xy 82.731258 -285.329907) (xy 82.746842 -285.376588) (xy 82.754737 -285.425165)
			(xy 82.755232 -285.449772) (xy 190.64403 -285.449772) (xy 190.64799 -285.400718) (xy 190.659767 -285.352934)
			(xy 190.679058 -285.307658) (xy 190.705361 -285.266062) (xy 190.737996 -285.229225) (xy 190.776117 -285.1981)
			(xy 190.818738 -285.173493) (xy 190.864754 -285.156041) (xy 190.912973 -285.146197) (xy 190.962148 -285.144216)
			(xy 191.011003 -285.150148) (xy 191.058274 -285.16384) (xy 191.102736 -285.184938) (xy 191.143239 -285.212894)
			(xy 191.178732 -285.246986) (xy 191.208297 -285.28633) (xy 191.231168 -285.329907) (xy 191.246752 -285.376588)
			(xy 191.254647 -285.425165) (xy 191.255142 -285.449772) (xy 191.594244 -285.449772) (xy 191.598204 -285.400718)
			(xy 191.609981 -285.352934) (xy 191.629272 -285.307658) (xy 191.655575 -285.266062) (xy 191.68821 -285.229225)
			(xy 191.726331 -285.1981) (xy 191.768952 -285.173493) (xy 191.814968 -285.156041) (xy 191.863187 -285.146197)
			(xy 191.912362 -285.144216) (xy 191.961217 -285.150148) (xy 192.008488 -285.16384) (xy 192.05295 -285.184938)
			(xy 192.093453 -285.212894) (xy 192.128946 -285.246986) (xy 192.158511 -285.28633) (xy 192.181382 -285.329907)
			(xy 192.196966 -285.376588) (xy 192.204861 -285.425165) (xy 192.205356 -285.449772) (xy 197.294258 -285.449772)
			(xy 197.298218 -285.400718) (xy 197.309995 -285.352934) (xy 197.329286 -285.307658) (xy 197.355589 -285.266062)
			(xy 197.388224 -285.229225) (xy 197.426345 -285.1981) (xy 197.468966 -285.173493) (xy 197.514982 -285.156041)
			(xy 197.563201 -285.146197) (xy 197.612376 -285.144216) (xy 197.661231 -285.150148) (xy 197.708502 -285.16384)
			(xy 197.752964 -285.184938) (xy 197.793467 -285.212894) (xy 197.82896 -285.246986) (xy 197.858525 -285.28633)
			(xy 197.881396 -285.329907) (xy 197.89698 -285.376588) (xy 197.904875 -285.425165) (xy 197.90537 -285.449772)
			(xy 198.244218 -285.449772) (xy 198.248178 -285.400718) (xy 198.259955 -285.352934) (xy 198.279246 -285.307658)
			(xy 198.305549 -285.266062) (xy 198.338184 -285.229225) (xy 198.376305 -285.1981) (xy 198.418926 -285.173493)
			(xy 198.464942 -285.156041) (xy 198.513161 -285.146197) (xy 198.562336 -285.144216) (xy 198.611191 -285.150148)
			(xy 198.658462 -285.16384) (xy 198.702924 -285.184938) (xy 198.743427 -285.212894) (xy 198.77892 -285.246986)
			(xy 198.808485 -285.28633) (xy 198.831356 -285.329907) (xy 198.84694 -285.376588) (xy 198.854835 -285.425165)
			(xy 198.85533 -285.449772) (xy 306.744128 -285.449772) (xy 306.748088 -285.400718) (xy 306.759865 -285.352934)
			(xy 306.779156 -285.307658) (xy 306.805459 -285.266062) (xy 306.838094 -285.229225) (xy 306.876215 -285.1981)
			(xy 306.918836 -285.173493) (xy 306.964852 -285.156041) (xy 307.013071 -285.146197) (xy 307.062246 -285.144216)
			(xy 307.111101 -285.150148) (xy 307.158372 -285.16384) (xy 307.202834 -285.184938) (xy 307.243337 -285.212894)
			(xy 307.27883 -285.246986) (xy 307.308395 -285.28633) (xy 307.331266 -285.329907) (xy 307.34685 -285.376588)
			(xy 307.354745 -285.425165) (xy 307.35524 -285.449772) (xy 307.694088 -285.449772) (xy 307.698048 -285.400718)
			(xy 307.709825 -285.352934) (xy 307.729116 -285.307658) (xy 307.755419 -285.266062) (xy 307.788054 -285.229225)
			(xy 307.826175 -285.1981) (xy 307.868796 -285.173493) (xy 307.914812 -285.156041) (xy 307.963031 -285.146197)
			(xy 308.012206 -285.144216) (xy 308.061061 -285.150148) (xy 308.108332 -285.16384) (xy 308.152794 -285.184938)
			(xy 308.193297 -285.212894) (xy 308.22879 -285.246986) (xy 308.258355 -285.28633) (xy 308.281226 -285.329907)
			(xy 308.29681 -285.376588) (xy 308.304705 -285.425165) (xy 308.3052 -285.449772) (xy 313.394102 -285.449772)
			(xy 313.398062 -285.400718) (xy 313.409839 -285.352934) (xy 313.42913 -285.307658) (xy 313.455433 -285.266062)
			(xy 313.488068 -285.229225) (xy 313.526189 -285.1981) (xy 313.56881 -285.173493) (xy 313.614826 -285.156041)
			(xy 313.663045 -285.146197) (xy 313.71222 -285.144216) (xy 313.761075 -285.150148) (xy 313.808346 -285.16384)
			(xy 313.852808 -285.184938) (xy 313.893311 -285.212894) (xy 313.928804 -285.246986) (xy 313.958369 -285.28633)
			(xy 313.98124 -285.329907) (xy 313.996824 -285.376588) (xy 314.004719 -285.425165) (xy 314.005214 -285.449772)
			(xy 314.344062 -285.449772) (xy 314.348022 -285.400718) (xy 314.359799 -285.352934) (xy 314.37909 -285.307658)
			(xy 314.405393 -285.266062) (xy 314.438028 -285.229225) (xy 314.476149 -285.1981) (xy 314.51877 -285.173493)
			(xy 314.564786 -285.156041) (xy 314.613005 -285.146197) (xy 314.66218 -285.144216) (xy 314.711035 -285.150148)
			(xy 314.758306 -285.16384) (xy 314.802768 -285.184938) (xy 314.843271 -285.212894) (xy 314.878764 -285.246986)
			(xy 314.908329 -285.28633) (xy 314.9312 -285.329907) (xy 314.946784 -285.376588) (xy 314.954679 -285.425165)
			(xy 314.955174 -285.449772) (xy 422.844226 -285.449772) (xy 422.848186 -285.400718) (xy 422.859963 -285.352934)
			(xy 422.879254 -285.307658) (xy 422.905557 -285.266062) (xy 422.938192 -285.229225) (xy 422.976313 -285.1981)
			(xy 423.018934 -285.173493) (xy 423.06495 -285.156041) (xy 423.113169 -285.146197) (xy 423.162344 -285.144216)
			(xy 423.211199 -285.150148) (xy 423.25847 -285.16384) (xy 423.302932 -285.184938) (xy 423.343435 -285.212894)
			(xy 423.378928 -285.246986) (xy 423.408493 -285.28633) (xy 423.431364 -285.329907) (xy 423.446948 -285.376588)
			(xy 423.454843 -285.425165) (xy 423.455338 -285.449772) (xy 423.794186 -285.449772) (xy 423.798146 -285.400718)
			(xy 423.809923 -285.352934) (xy 423.829214 -285.307658) (xy 423.855517 -285.266062) (xy 423.888152 -285.229225)
			(xy 423.926273 -285.1981) (xy 423.968894 -285.173493) (xy 424.01491 -285.156041) (xy 424.063129 -285.146197)
			(xy 424.112304 -285.144216) (xy 424.161159 -285.150148) (xy 424.20843 -285.16384) (xy 424.252892 -285.184938)
			(xy 424.293395 -285.212894) (xy 424.328888 -285.246986) (xy 424.358453 -285.28633) (xy 424.381324 -285.329907)
			(xy 424.396908 -285.376588) (xy 424.404803 -285.425165) (xy 424.405298 -285.449772) (xy 429.4942 -285.449772)
			(xy 429.49816 -285.400718) (xy 429.509937 -285.352934) (xy 429.529228 -285.307658) (xy 429.555531 -285.266062)
			(xy 429.588166 -285.229225) (xy 429.626287 -285.1981) (xy 429.668908 -285.173493) (xy 429.714924 -285.156041)
			(xy 429.763143 -285.146197) (xy 429.812318 -285.144216) (xy 429.861173 -285.150148) (xy 429.908444 -285.16384)
			(xy 429.952906 -285.184938) (xy 429.993409 -285.212894) (xy 430.028902 -285.246986) (xy 430.058467 -285.28633)
			(xy 430.081338 -285.329907) (xy 430.096922 -285.376588) (xy 430.104817 -285.425165) (xy 430.105312 -285.449772)
			(xy 430.44416 -285.449772) (xy 430.44812 -285.400718) (xy 430.459897 -285.352934) (xy 430.479188 -285.307658)
			(xy 430.505491 -285.266062) (xy 430.538126 -285.229225) (xy 430.576247 -285.1981) (xy 430.618868 -285.173493)
			(xy 430.664884 -285.156041) (xy 430.713103 -285.146197) (xy 430.762278 -285.144216) (xy 430.811133 -285.150148)
			(xy 430.858404 -285.16384) (xy 430.902866 -285.184938) (xy 430.943369 -285.212894) (xy 430.978862 -285.246986)
			(xy 431.008427 -285.28633) (xy 431.031298 -285.329907) (xy 431.046882 -285.376588) (xy 431.054777 -285.425165)
			(xy 431.055272 -285.449772) (xy 431.054777 -285.474379) (xy 431.046882 -285.522956) (xy 431.031298 -285.569637)
			(xy 431.008427 -285.613214) (xy 430.978862 -285.652558) (xy 430.943369 -285.68665) (xy 430.902866 -285.714606)
			(xy 430.858404 -285.735704) (xy 430.811133 -285.749396) (xy 430.762278 -285.755328) (xy 430.713103 -285.753347)
			(xy 430.664884 -285.743503) (xy 430.618868 -285.726051) (xy 430.576247 -285.701444) (xy 430.538126 -285.670319)
			(xy 430.505491 -285.633482) (xy 430.479188 -285.591886) (xy 430.459897 -285.54661) (xy 430.44812 -285.498826)
			(xy 430.44416 -285.449772) (xy 430.105312 -285.449772) (xy 430.104817 -285.474379) (xy 430.096922 -285.522956)
			(xy 430.081338 -285.569637) (xy 430.058467 -285.613214) (xy 430.028902 -285.652558) (xy 429.993409 -285.68665)
			(xy 429.952906 -285.714606) (xy 429.908444 -285.735704) (xy 429.861173 -285.749396) (xy 429.812318 -285.755328)
			(xy 429.763143 -285.753347) (xy 429.714924 -285.743503) (xy 429.668908 -285.726051) (xy 429.626287 -285.701444)
			(xy 429.588166 -285.670319) (xy 429.555531 -285.633482) (xy 429.529228 -285.591886) (xy 429.509937 -285.54661)
			(xy 429.49816 -285.498826) (xy 429.4942 -285.449772) (xy 424.405298 -285.449772) (xy 424.404803 -285.474379)
			(xy 424.396908 -285.522956) (xy 424.381324 -285.569637) (xy 424.358453 -285.613214) (xy 424.328888 -285.652558)
			(xy 424.293395 -285.68665) (xy 424.252892 -285.714606) (xy 424.20843 -285.735704) (xy 424.161159 -285.749396)
			(xy 424.112304 -285.755328) (xy 424.063129 -285.753347) (xy 424.01491 -285.743503) (xy 423.968894 -285.726051)
			(xy 423.926273 -285.701444) (xy 423.888152 -285.670319) (xy 423.855517 -285.633482) (xy 423.829214 -285.591886)
			(xy 423.809923 -285.54661) (xy 423.798146 -285.498826) (xy 423.794186 -285.449772) (xy 423.455338 -285.449772)
			(xy 423.454843 -285.474379) (xy 423.446948 -285.522956) (xy 423.431364 -285.569637) (xy 423.408493 -285.613214)
			(xy 423.378928 -285.652558) (xy 423.343435 -285.68665) (xy 423.302932 -285.714606) (xy 423.25847 -285.735704)
			(xy 423.211199 -285.749396) (xy 423.162344 -285.755328) (xy 423.113169 -285.753347) (xy 423.06495 -285.743503)
			(xy 423.018934 -285.726051) (xy 422.976313 -285.701444) (xy 422.938192 -285.670319) (xy 422.905557 -285.633482)
			(xy 422.879254 -285.591886) (xy 422.859963 -285.54661) (xy 422.848186 -285.498826) (xy 422.844226 -285.449772)
			(xy 314.955174 -285.449772) (xy 314.954679 -285.474379) (xy 314.946784 -285.522956) (xy 314.9312 -285.569637)
			(xy 314.908329 -285.613214) (xy 314.878764 -285.652558) (xy 314.843271 -285.68665) (xy 314.802768 -285.714606)
			(xy 314.758306 -285.735704) (xy 314.711035 -285.749396) (xy 314.66218 -285.755328) (xy 314.613005 -285.753347)
			(xy 314.564786 -285.743503) (xy 314.51877 -285.726051) (xy 314.476149 -285.701444) (xy 314.438028 -285.670319)
			(xy 314.405393 -285.633482) (xy 314.37909 -285.591886) (xy 314.359799 -285.54661) (xy 314.348022 -285.498826)
			(xy 314.344062 -285.449772) (xy 314.005214 -285.449772) (xy 314.004719 -285.474379) (xy 313.996824 -285.522956)
			(xy 313.98124 -285.569637) (xy 313.958369 -285.613214) (xy 313.928804 -285.652558) (xy 313.893311 -285.68665)
			(xy 313.852808 -285.714606) (xy 313.808346 -285.735704) (xy 313.761075 -285.749396) (xy 313.71222 -285.755328)
			(xy 313.663045 -285.753347) (xy 313.614826 -285.743503) (xy 313.56881 -285.726051) (xy 313.526189 -285.701444)
			(xy 313.488068 -285.670319) (xy 313.455433 -285.633482) (xy 313.42913 -285.591886) (xy 313.409839 -285.54661)
			(xy 313.398062 -285.498826) (xy 313.394102 -285.449772) (xy 308.3052 -285.449772) (xy 308.304705 -285.474379)
			(xy 308.29681 -285.522956) (xy 308.281226 -285.569637) (xy 308.258355 -285.613214) (xy 308.22879 -285.652558)
			(xy 308.193297 -285.68665) (xy 308.152794 -285.714606) (xy 308.108332 -285.735704) (xy 308.061061 -285.749396)
			(xy 308.012206 -285.755328) (xy 307.963031 -285.753347) (xy 307.914812 -285.743503) (xy 307.868796 -285.726051)
			(xy 307.826175 -285.701444) (xy 307.788054 -285.670319) (xy 307.755419 -285.633482) (xy 307.729116 -285.591886)
			(xy 307.709825 -285.54661) (xy 307.698048 -285.498826) (xy 307.694088 -285.449772) (xy 307.35524 -285.449772)
			(xy 307.354745 -285.474379) (xy 307.34685 -285.522956) (xy 307.331266 -285.569637) (xy 307.308395 -285.613214)
			(xy 307.27883 -285.652558) (xy 307.243337 -285.68665) (xy 307.202834 -285.714606) (xy 307.158372 -285.735704)
			(xy 307.111101 -285.749396) (xy 307.062246 -285.755328) (xy 307.013071 -285.753347) (xy 306.964852 -285.743503)
			(xy 306.918836 -285.726051) (xy 306.876215 -285.701444) (xy 306.838094 -285.670319) (xy 306.805459 -285.633482)
			(xy 306.779156 -285.591886) (xy 306.759865 -285.54661) (xy 306.748088 -285.498826) (xy 306.744128 -285.449772)
			(xy 198.85533 -285.449772) (xy 198.854835 -285.474379) (xy 198.84694 -285.522956) (xy 198.831356 -285.569637)
			(xy 198.808485 -285.613214) (xy 198.77892 -285.652558) (xy 198.743427 -285.68665) (xy 198.702924 -285.714606)
			(xy 198.658462 -285.735704) (xy 198.611191 -285.749396) (xy 198.562336 -285.755328) (xy 198.513161 -285.753347)
			(xy 198.464942 -285.743503) (xy 198.418926 -285.726051) (xy 198.376305 -285.701444) (xy 198.338184 -285.670319)
			(xy 198.305549 -285.633482) (xy 198.279246 -285.591886) (xy 198.259955 -285.54661) (xy 198.248178 -285.498826)
			(xy 198.244218 -285.449772) (xy 197.90537 -285.449772) (xy 197.904875 -285.474379) (xy 197.89698 -285.522956)
			(xy 197.881396 -285.569637) (xy 197.858525 -285.613214) (xy 197.82896 -285.652558) (xy 197.793467 -285.68665)
			(xy 197.752964 -285.714606) (xy 197.708502 -285.735704) (xy 197.661231 -285.749396) (xy 197.612376 -285.755328)
			(xy 197.563201 -285.753347) (xy 197.514982 -285.743503) (xy 197.468966 -285.726051) (xy 197.426345 -285.701444)
			(xy 197.388224 -285.670319) (xy 197.355589 -285.633482) (xy 197.329286 -285.591886) (xy 197.309995 -285.54661)
			(xy 197.298218 -285.498826) (xy 197.294258 -285.449772) (xy 192.205356 -285.449772) (xy 192.204861 -285.474379)
			(xy 192.196966 -285.522956) (xy 192.181382 -285.569637) (xy 192.158511 -285.613214) (xy 192.128946 -285.652558)
			(xy 192.093453 -285.68665) (xy 192.05295 -285.714606) (xy 192.008488 -285.735704) (xy 191.961217 -285.749396)
			(xy 191.912362 -285.755328) (xy 191.863187 -285.753347) (xy 191.814968 -285.743503) (xy 191.768952 -285.726051)
			(xy 191.726331 -285.701444) (xy 191.68821 -285.670319) (xy 191.655575 -285.633482) (xy 191.629272 -285.591886)
			(xy 191.609981 -285.54661) (xy 191.598204 -285.498826) (xy 191.594244 -285.449772) (xy 191.255142 -285.449772)
			(xy 191.254647 -285.474379) (xy 191.246752 -285.522956) (xy 191.231168 -285.569637) (xy 191.208297 -285.613214)
			(xy 191.178732 -285.652558) (xy 191.143239 -285.68665) (xy 191.102736 -285.714606) (xy 191.058274 -285.735704)
			(xy 191.011003 -285.749396) (xy 190.962148 -285.755328) (xy 190.912973 -285.753347) (xy 190.864754 -285.743503)
			(xy 190.818738 -285.726051) (xy 190.776117 -285.701444) (xy 190.737996 -285.670319) (xy 190.705361 -285.633482)
			(xy 190.679058 -285.591886) (xy 190.659767 -285.54661) (xy 190.64799 -285.498826) (xy 190.64403 -285.449772)
			(xy 82.755232 -285.449772) (xy 82.754737 -285.474379) (xy 82.746842 -285.522956) (xy 82.731258 -285.569637)
			(xy 82.708387 -285.613214) (xy 82.678822 -285.652558) (xy 82.643329 -285.68665) (xy 82.602826 -285.714606)
			(xy 82.558364 -285.735704) (xy 82.511093 -285.749396) (xy 82.462238 -285.755328) (xy 82.413063 -285.753347)
			(xy 82.364844 -285.743503) (xy 82.318828 -285.726051) (xy 82.276207 -285.701444) (xy 82.238086 -285.670319)
			(xy 82.205451 -285.633482) (xy 82.179148 -285.591886) (xy 82.159857 -285.54661) (xy 82.14808 -285.498826)
			(xy 82.14412 -285.449772) (xy 81.805272 -285.449772) (xy 81.804777 -285.474379) (xy 81.796882 -285.522956)
			(xy 81.781298 -285.569637) (xy 81.758427 -285.613214) (xy 81.728862 -285.652558) (xy 81.693369 -285.68665)
			(xy 81.652866 -285.714606) (xy 81.608404 -285.735704) (xy 81.561133 -285.749396) (xy 81.512278 -285.755328)
			(xy 81.463103 -285.753347) (xy 81.414884 -285.743503) (xy 81.368868 -285.726051) (xy 81.326247 -285.701444)
			(xy 81.288126 -285.670319) (xy 81.255491 -285.633482) (xy 81.229188 -285.591886) (xy 81.209897 -285.54661)
			(xy 81.19812 -285.498826) (xy 81.19416 -285.449772) (xy 76.105258 -285.449772) (xy 76.104763 -285.474379)
			(xy 76.096868 -285.522956) (xy 76.081284 -285.569637) (xy 76.058413 -285.613214) (xy 76.028848 -285.652558)
			(xy 75.993355 -285.68665) (xy 75.952852 -285.714606) (xy 75.90839 -285.735704) (xy 75.861119 -285.749396)
			(xy 75.812264 -285.755328) (xy 75.763089 -285.753347) (xy 75.71487 -285.743503) (xy 75.668854 -285.726051)
			(xy 75.626233 -285.701444) (xy 75.588112 -285.670319) (xy 75.555477 -285.633482) (xy 75.529174 -285.591886)
			(xy 75.509883 -285.54661) (xy 75.498106 -285.498826) (xy 75.494146 -285.449772) (xy 75.155044 -285.449772)
			(xy 75.154549 -285.474379) (xy 75.146654 -285.522956) (xy 75.13107 -285.569637) (xy 75.108199 -285.613214)
			(xy 75.078634 -285.652558) (xy 75.043141 -285.68665) (xy 75.002638 -285.714606) (xy 74.958176 -285.735704)
			(xy 74.910905 -285.749396) (xy 74.86205 -285.755328) (xy 74.812875 -285.753347) (xy 74.764656 -285.743503)
			(xy 74.71864 -285.726051) (xy 74.676019 -285.701444) (xy 74.637898 -285.670319) (xy 74.605263 -285.633482)
			(xy 74.57896 -285.591886) (xy 74.559669 -285.54661) (xy 74.547892 -285.498826) (xy 74.543932 -285.449772)
			(xy 0.509016 -285.449772) (xy 0.509016 -286.399986) (xy 76.444106 -286.399986) (xy 76.448066 -286.350932)
			(xy 76.459843 -286.303148) (xy 76.479134 -286.257872) (xy 76.505437 -286.216276) (xy 76.538072 -286.179439)
			(xy 76.576193 -286.148314) (xy 76.618814 -286.123707) (xy 76.66483 -286.106255) (xy 76.713049 -286.096411)
			(xy 76.762224 -286.09443) (xy 76.811079 -286.100362) (xy 76.85835 -286.114054) (xy 76.902812 -286.135152)
			(xy 76.943315 -286.163108) (xy 76.978808 -286.1972) (xy 77.008373 -286.236544) (xy 77.031244 -286.280121)
			(xy 77.046828 -286.326802) (xy 77.054723 -286.375379) (xy 77.055218 -286.399986) (xy 77.394066 -286.399986)
			(xy 77.398026 -286.350932) (xy 77.409803 -286.303148) (xy 77.429094 -286.257872) (xy 77.455397 -286.216276)
			(xy 77.488032 -286.179439) (xy 77.526153 -286.148314) (xy 77.568774 -286.123707) (xy 77.61479 -286.106255)
			(xy 77.663009 -286.096411) (xy 77.712184 -286.09443) (xy 77.761039 -286.100362) (xy 77.80831 -286.114054)
			(xy 77.852772 -286.135152) (xy 77.893275 -286.163108) (xy 77.928768 -286.1972) (xy 77.958333 -286.236544)
			(xy 77.981204 -286.280121) (xy 77.996788 -286.326802) (xy 78.004683 -286.375379) (xy 78.005173 -286.399732)
			(xy 79.293986 -286.399732) (xy 79.297946 -286.350678) (xy 79.309723 -286.302894) (xy 79.329014 -286.257618)
			(xy 79.355317 -286.216022) (xy 79.387952 -286.179185) (xy 79.426073 -286.14806) (xy 79.468694 -286.123453)
			(xy 79.51471 -286.106001) (xy 79.562929 -286.096157) (xy 79.612104 -286.094176) (xy 79.660959 -286.100108)
			(xy 79.70823 -286.1138) (xy 79.752692 -286.134898) (xy 79.793195 -286.162854) (xy 79.828688 -286.196946)
			(xy 79.858253 -286.23629) (xy 79.881124 -286.279867) (xy 79.896708 -286.326548) (xy 79.904603 -286.375125)
			(xy 79.905098 -286.399732) (xy 80.243946 -286.399732) (xy 80.247906 -286.350678) (xy 80.259683 -286.302894)
			(xy 80.278974 -286.257618) (xy 80.305277 -286.216022) (xy 80.337912 -286.179185) (xy 80.376033 -286.14806)
			(xy 80.418654 -286.123453) (xy 80.46467 -286.106001) (xy 80.512889 -286.096157) (xy 80.562064 -286.094176)
			(xy 80.610919 -286.100108) (xy 80.65819 -286.1138) (xy 80.702652 -286.134898) (xy 80.743155 -286.162854)
			(xy 80.778648 -286.196946) (xy 80.808213 -286.23629) (xy 80.831084 -286.279867) (xy 80.846668 -286.326548)
			(xy 80.854563 -286.375125) (xy 80.855058 -286.399732) (xy 80.855053 -286.399986) (xy 192.544204 -286.399986)
			(xy 192.548164 -286.350932) (xy 192.559941 -286.303148) (xy 192.579232 -286.257872) (xy 192.605535 -286.216276)
			(xy 192.63817 -286.179439) (xy 192.676291 -286.148314) (xy 192.718912 -286.123707) (xy 192.764928 -286.106255)
			(xy 192.813147 -286.096411) (xy 192.862322 -286.09443) (xy 192.911177 -286.100362) (xy 192.958448 -286.114054)
			(xy 193.00291 -286.135152) (xy 193.043413 -286.163108) (xy 193.078906 -286.1972) (xy 193.108471 -286.236544)
			(xy 193.131342 -286.280121) (xy 193.146926 -286.326802) (xy 193.154821 -286.375379) (xy 193.155316 -286.399986)
			(xy 193.494164 -286.399986) (xy 193.498124 -286.350932) (xy 193.509901 -286.303148) (xy 193.529192 -286.257872)
			(xy 193.555495 -286.216276) (xy 193.58813 -286.179439) (xy 193.626251 -286.148314) (xy 193.668872 -286.123707)
			(xy 193.714888 -286.106255) (xy 193.763107 -286.096411) (xy 193.812282 -286.09443) (xy 193.861137 -286.100362)
			(xy 193.908408 -286.114054) (xy 193.95287 -286.135152) (xy 193.993373 -286.163108) (xy 194.028866 -286.1972)
			(xy 194.058431 -286.236544) (xy 194.081302 -286.280121) (xy 194.096886 -286.326802) (xy 194.104781 -286.375379)
			(xy 194.105271 -286.399732) (xy 195.394084 -286.399732) (xy 195.398044 -286.350678) (xy 195.409821 -286.302894)
			(xy 195.429112 -286.257618) (xy 195.455415 -286.216022) (xy 195.48805 -286.179185) (xy 195.526171 -286.14806)
			(xy 195.568792 -286.123453) (xy 195.614808 -286.106001) (xy 195.663027 -286.096157) (xy 195.712202 -286.094176)
			(xy 195.761057 -286.100108) (xy 195.808328 -286.1138) (xy 195.85279 -286.134898) (xy 195.893293 -286.162854)
			(xy 195.928786 -286.196946) (xy 195.958351 -286.23629) (xy 195.981222 -286.279867) (xy 195.996806 -286.326548)
			(xy 196.004701 -286.375125) (xy 196.005196 -286.399732) (xy 196.344044 -286.399732) (xy 196.348004 -286.350678)
			(xy 196.359781 -286.302894) (xy 196.379072 -286.257618) (xy 196.405375 -286.216022) (xy 196.43801 -286.179185)
			(xy 196.476131 -286.14806) (xy 196.518752 -286.123453) (xy 196.564768 -286.106001) (xy 196.612987 -286.096157)
			(xy 196.662162 -286.094176) (xy 196.711017 -286.100108) (xy 196.758288 -286.1138) (xy 196.80275 -286.134898)
			(xy 196.843253 -286.162854) (xy 196.878746 -286.196946) (xy 196.908311 -286.23629) (xy 196.931182 -286.279867)
			(xy 196.946766 -286.326548) (xy 196.954661 -286.375125) (xy 196.955156 -286.399732) (xy 196.955151 -286.399986)
			(xy 308.644048 -286.399986) (xy 308.648008 -286.350932) (xy 308.659785 -286.303148) (xy 308.679076 -286.257872)
			(xy 308.705379 -286.216276) (xy 308.738014 -286.179439) (xy 308.776135 -286.148314) (xy 308.818756 -286.123707)
			(xy 308.864772 -286.106255) (xy 308.912991 -286.096411) (xy 308.962166 -286.09443) (xy 309.011021 -286.100362)
			(xy 309.058292 -286.114054) (xy 309.102754 -286.135152) (xy 309.143257 -286.163108) (xy 309.17875 -286.1972)
			(xy 309.208315 -286.236544) (xy 309.231186 -286.280121) (xy 309.24677 -286.326802) (xy 309.254665 -286.375379)
			(xy 309.25516 -286.399986) (xy 309.594008 -286.399986) (xy 309.597968 -286.350932) (xy 309.609745 -286.303148)
			(xy 309.629036 -286.257872) (xy 309.655339 -286.216276) (xy 309.687974 -286.179439) (xy 309.726095 -286.148314)
			(xy 309.768716 -286.123707) (xy 309.814732 -286.106255) (xy 309.862951 -286.096411) (xy 309.912126 -286.09443)
			(xy 309.960981 -286.100362) (xy 310.008252 -286.114054) (xy 310.052714 -286.135152) (xy 310.093217 -286.163108)
			(xy 310.12871 -286.1972) (xy 310.158275 -286.236544) (xy 310.181146 -286.280121) (xy 310.19673 -286.326802)
			(xy 310.204625 -286.375379) (xy 310.205115 -286.399732) (xy 311.493928 -286.399732) (xy 311.497888 -286.350678)
			(xy 311.509665 -286.302894) (xy 311.528956 -286.257618) (xy 311.555259 -286.216022) (xy 311.587894 -286.179185)
			(xy 311.626015 -286.14806) (xy 311.668636 -286.123453) (xy 311.714652 -286.106001) (xy 311.762871 -286.096157)
			(xy 311.812046 -286.094176) (xy 311.860901 -286.100108) (xy 311.908172 -286.1138) (xy 311.952634 -286.134898)
			(xy 311.993137 -286.162854) (xy 312.02863 -286.196946) (xy 312.058195 -286.23629) (xy 312.081066 -286.279867)
			(xy 312.09665 -286.326548) (xy 312.104545 -286.375125) (xy 312.10504 -286.399732) (xy 312.443888 -286.399732)
			(xy 312.447848 -286.350678) (xy 312.459625 -286.302894) (xy 312.478916 -286.257618) (xy 312.505219 -286.216022)
			(xy 312.537854 -286.179185) (xy 312.575975 -286.14806) (xy 312.618596 -286.123453) (xy 312.664612 -286.106001)
			(xy 312.712831 -286.096157) (xy 312.762006 -286.094176) (xy 312.810861 -286.100108) (xy 312.858132 -286.1138)
			(xy 312.902594 -286.134898) (xy 312.943097 -286.162854) (xy 312.97859 -286.196946) (xy 313.008155 -286.23629)
			(xy 313.031026 -286.279867) (xy 313.04661 -286.326548) (xy 313.054505 -286.375125) (xy 313.055 -286.399732)
			(xy 313.054995 -286.399986) (xy 424.744146 -286.399986) (xy 424.748106 -286.350932) (xy 424.759883 -286.303148)
			(xy 424.779174 -286.257872) (xy 424.805477 -286.216276) (xy 424.838112 -286.179439) (xy 424.876233 -286.148314)
			(xy 424.918854 -286.123707) (xy 424.96487 -286.106255) (xy 425.013089 -286.096411) (xy 425.062264 -286.09443)
			(xy 425.111119 -286.100362) (xy 425.15839 -286.114054) (xy 425.202852 -286.135152) (xy 425.243355 -286.163108)
			(xy 425.278848 -286.1972) (xy 425.308413 -286.236544) (xy 425.331284 -286.280121) (xy 425.346868 -286.326802)
			(xy 425.354763 -286.375379) (xy 425.355258 -286.399986) (xy 425.694106 -286.399986) (xy 425.698066 -286.350932)
			(xy 425.709843 -286.303148) (xy 425.729134 -286.257872) (xy 425.755437 -286.216276) (xy 425.788072 -286.179439)
			(xy 425.826193 -286.148314) (xy 425.868814 -286.123707) (xy 425.91483 -286.106255) (xy 425.963049 -286.096411)
			(xy 426.012224 -286.09443) (xy 426.061079 -286.100362) (xy 426.10835 -286.114054) (xy 426.152812 -286.135152)
			(xy 426.193315 -286.163108) (xy 426.228808 -286.1972) (xy 426.258373 -286.236544) (xy 426.281244 -286.280121)
			(xy 426.296828 -286.326802) (xy 426.304723 -286.375379) (xy 426.305213 -286.399732) (xy 427.594026 -286.399732)
			(xy 427.597986 -286.350678) (xy 427.609763 -286.302894) (xy 427.629054 -286.257618) (xy 427.655357 -286.216022)
			(xy 427.687992 -286.179185) (xy 427.726113 -286.14806) (xy 427.768734 -286.123453) (xy 427.81475 -286.106001)
			(xy 427.862969 -286.096157) (xy 427.912144 -286.094176) (xy 427.960999 -286.100108) (xy 428.00827 -286.1138)
			(xy 428.052732 -286.134898) (xy 428.093235 -286.162854) (xy 428.128728 -286.196946) (xy 428.158293 -286.23629)
			(xy 428.181164 -286.279867) (xy 428.196748 -286.326548) (xy 428.204643 -286.375125) (xy 428.205138 -286.399732)
			(xy 428.543986 -286.399732) (xy 428.547946 -286.350678) (xy 428.559723 -286.302894) (xy 428.579014 -286.257618)
			(xy 428.605317 -286.216022) (xy 428.637952 -286.179185) (xy 428.676073 -286.14806) (xy 428.718694 -286.123453)
			(xy 428.76471 -286.106001) (xy 428.812929 -286.096157) (xy 428.862104 -286.094176) (xy 428.910959 -286.100108)
			(xy 428.95823 -286.1138) (xy 429.002692 -286.134898) (xy 429.043195 -286.162854) (xy 429.078688 -286.196946)
			(xy 429.108253 -286.23629) (xy 429.131124 -286.279867) (xy 429.146708 -286.326548) (xy 429.154603 -286.375125)
			(xy 429.155098 -286.399732) (xy 429.154603 -286.424339) (xy 429.146708 -286.472916) (xy 429.131124 -286.519597)
			(xy 429.108253 -286.563174) (xy 429.078688 -286.602518) (xy 429.043195 -286.63661) (xy 429.002692 -286.664566)
			(xy 428.95823 -286.685664) (xy 428.910959 -286.699356) (xy 428.862104 -286.705288) (xy 428.812929 -286.703307)
			(xy 428.76471 -286.693463) (xy 428.718694 -286.676011) (xy 428.676073 -286.651404) (xy 428.637952 -286.620279)
			(xy 428.605317 -286.583442) (xy 428.579014 -286.541846) (xy 428.559723 -286.49657) (xy 428.547946 -286.448786)
			(xy 428.543986 -286.399732) (xy 428.205138 -286.399732) (xy 428.204643 -286.424339) (xy 428.196748 -286.472916)
			(xy 428.181164 -286.519597) (xy 428.158293 -286.563174) (xy 428.128728 -286.602518) (xy 428.093235 -286.63661)
			(xy 428.052732 -286.664566) (xy 428.00827 -286.685664) (xy 427.960999 -286.699356) (xy 427.912144 -286.705288)
			(xy 427.862969 -286.703307) (xy 427.81475 -286.693463) (xy 427.768734 -286.676011) (xy 427.726113 -286.651404)
			(xy 427.687992 -286.620279) (xy 427.655357 -286.583442) (xy 427.629054 -286.541846) (xy 427.609763 -286.49657)
			(xy 427.597986 -286.448786) (xy 427.594026 -286.399732) (xy 426.305213 -286.399732) (xy 426.305218 -286.399986)
			(xy 426.304723 -286.424593) (xy 426.296828 -286.47317) (xy 426.281244 -286.519851) (xy 426.258373 -286.563428)
			(xy 426.228808 -286.602772) (xy 426.193315 -286.636864) (xy 426.152812 -286.66482) (xy 426.10835 -286.685918)
			(xy 426.061079 -286.69961) (xy 426.012224 -286.705542) (xy 425.963049 -286.703561) (xy 425.91483 -286.693717)
			(xy 425.868814 -286.676265) (xy 425.826193 -286.651658) (xy 425.788072 -286.620533) (xy 425.755437 -286.583696)
			(xy 425.729134 -286.5421) (xy 425.709843 -286.496824) (xy 425.698066 -286.44904) (xy 425.694106 -286.399986)
			(xy 425.355258 -286.399986) (xy 425.354763 -286.424593) (xy 425.346868 -286.47317) (xy 425.331284 -286.519851)
			(xy 425.308413 -286.563428) (xy 425.278848 -286.602772) (xy 425.243355 -286.636864) (xy 425.202852 -286.66482)
			(xy 425.15839 -286.685918) (xy 425.111119 -286.69961) (xy 425.062264 -286.705542) (xy 425.013089 -286.703561)
			(xy 424.96487 -286.693717) (xy 424.918854 -286.676265) (xy 424.876233 -286.651658) (xy 424.838112 -286.620533)
			(xy 424.805477 -286.583696) (xy 424.779174 -286.5421) (xy 424.759883 -286.496824) (xy 424.748106 -286.44904)
			(xy 424.744146 -286.399986) (xy 313.054995 -286.399986) (xy 313.054505 -286.424339) (xy 313.04661 -286.472916)
			(xy 313.031026 -286.519597) (xy 313.008155 -286.563174) (xy 312.97859 -286.602518) (xy 312.943097 -286.63661)
			(xy 312.902594 -286.664566) (xy 312.858132 -286.685664) (xy 312.810861 -286.699356) (xy 312.762006 -286.705288)
			(xy 312.712831 -286.703307) (xy 312.664612 -286.693463) (xy 312.618596 -286.676011) (xy 312.575975 -286.651404)
			(xy 312.537854 -286.620279) (xy 312.505219 -286.583442) (xy 312.478916 -286.541846) (xy 312.459625 -286.49657)
			(xy 312.447848 -286.448786) (xy 312.443888 -286.399732) (xy 312.10504 -286.399732) (xy 312.104545 -286.424339)
			(xy 312.09665 -286.472916) (xy 312.081066 -286.519597) (xy 312.058195 -286.563174) (xy 312.02863 -286.602518)
			(xy 311.993137 -286.63661) (xy 311.952634 -286.664566) (xy 311.908172 -286.685664) (xy 311.860901 -286.699356)
			(xy 311.812046 -286.705288) (xy 311.762871 -286.703307) (xy 311.714652 -286.693463) (xy 311.668636 -286.676011)
			(xy 311.626015 -286.651404) (xy 311.587894 -286.620279) (xy 311.555259 -286.583442) (xy 311.528956 -286.541846)
			(xy 311.509665 -286.49657) (xy 311.497888 -286.448786) (xy 311.493928 -286.399732) (xy 310.205115 -286.399732)
			(xy 310.20512 -286.399986) (xy 310.204625 -286.424593) (xy 310.19673 -286.47317) (xy 310.181146 -286.519851)
			(xy 310.158275 -286.563428) (xy 310.12871 -286.602772) (xy 310.093217 -286.636864) (xy 310.052714 -286.66482)
			(xy 310.008252 -286.685918) (xy 309.960981 -286.69961) (xy 309.912126 -286.705542) (xy 309.862951 -286.703561)
			(xy 309.814732 -286.693717) (xy 309.768716 -286.676265) (xy 309.726095 -286.651658) (xy 309.687974 -286.620533)
			(xy 309.655339 -286.583696) (xy 309.629036 -286.5421) (xy 309.609745 -286.496824) (xy 309.597968 -286.44904)
			(xy 309.594008 -286.399986) (xy 309.25516 -286.399986) (xy 309.254665 -286.424593) (xy 309.24677 -286.47317)
			(xy 309.231186 -286.519851) (xy 309.208315 -286.563428) (xy 309.17875 -286.602772) (xy 309.143257 -286.636864)
			(xy 309.102754 -286.66482) (xy 309.058292 -286.685918) (xy 309.011021 -286.69961) (xy 308.962166 -286.705542)
			(xy 308.912991 -286.703561) (xy 308.864772 -286.693717) (xy 308.818756 -286.676265) (xy 308.776135 -286.651658)
			(xy 308.738014 -286.620533) (xy 308.705379 -286.583696) (xy 308.679076 -286.5421) (xy 308.659785 -286.496824)
			(xy 308.648008 -286.44904) (xy 308.644048 -286.399986) (xy 196.955151 -286.399986) (xy 196.954661 -286.424339)
			(xy 196.946766 -286.472916) (xy 196.931182 -286.519597) (xy 196.908311 -286.563174) (xy 196.878746 -286.602518)
			(xy 196.843253 -286.63661) (xy 196.80275 -286.664566) (xy 196.758288 -286.685664) (xy 196.711017 -286.699356)
			(xy 196.662162 -286.705288) (xy 196.612987 -286.703307) (xy 196.564768 -286.693463) (xy 196.518752 -286.676011)
			(xy 196.476131 -286.651404) (xy 196.43801 -286.620279) (xy 196.405375 -286.583442) (xy 196.379072 -286.541846)
			(xy 196.359781 -286.49657) (xy 196.348004 -286.448786) (xy 196.344044 -286.399732) (xy 196.005196 -286.399732)
			(xy 196.004701 -286.424339) (xy 195.996806 -286.472916) (xy 195.981222 -286.519597) (xy 195.958351 -286.563174)
			(xy 195.928786 -286.602518) (xy 195.893293 -286.63661) (xy 195.85279 -286.664566) (xy 195.808328 -286.685664)
			(xy 195.761057 -286.699356) (xy 195.712202 -286.705288) (xy 195.663027 -286.703307) (xy 195.614808 -286.693463)
			(xy 195.568792 -286.676011) (xy 195.526171 -286.651404) (xy 195.48805 -286.620279) (xy 195.455415 -286.583442)
			(xy 195.429112 -286.541846) (xy 195.409821 -286.49657) (xy 195.398044 -286.448786) (xy 195.394084 -286.399732)
			(xy 194.105271 -286.399732) (xy 194.105276 -286.399986) (xy 194.104781 -286.424593) (xy 194.096886 -286.47317)
			(xy 194.081302 -286.519851) (xy 194.058431 -286.563428) (xy 194.028866 -286.602772) (xy 193.993373 -286.636864)
			(xy 193.95287 -286.66482) (xy 193.908408 -286.685918) (xy 193.861137 -286.69961) (xy 193.812282 -286.705542)
			(xy 193.763107 -286.703561) (xy 193.714888 -286.693717) (xy 193.668872 -286.676265) (xy 193.626251 -286.651658)
			(xy 193.58813 -286.620533) (xy 193.555495 -286.583696) (xy 193.529192 -286.5421) (xy 193.509901 -286.496824)
			(xy 193.498124 -286.44904) (xy 193.494164 -286.399986) (xy 193.155316 -286.399986) (xy 193.154821 -286.424593)
			(xy 193.146926 -286.47317) (xy 193.131342 -286.519851) (xy 193.108471 -286.563428) (xy 193.078906 -286.602772)
			(xy 193.043413 -286.636864) (xy 193.00291 -286.66482) (xy 192.958448 -286.685918) (xy 192.911177 -286.69961)
			(xy 192.862322 -286.705542) (xy 192.813147 -286.703561) (xy 192.764928 -286.693717) (xy 192.718912 -286.676265)
			(xy 192.676291 -286.651658) (xy 192.63817 -286.620533) (xy 192.605535 -286.583696) (xy 192.579232 -286.5421)
			(xy 192.559941 -286.496824) (xy 192.548164 -286.44904) (xy 192.544204 -286.399986) (xy 80.855053 -286.399986)
			(xy 80.854563 -286.424339) (xy 80.846668 -286.472916) (xy 80.831084 -286.519597) (xy 80.808213 -286.563174)
			(xy 80.778648 -286.602518) (xy 80.743155 -286.63661) (xy 80.702652 -286.664566) (xy 80.65819 -286.685664)
			(xy 80.610919 -286.699356) (xy 80.562064 -286.705288) (xy 80.512889 -286.703307) (xy 80.46467 -286.693463)
			(xy 80.418654 -286.676011) (xy 80.376033 -286.651404) (xy 80.337912 -286.620279) (xy 80.305277 -286.583442)
			(xy 80.278974 -286.541846) (xy 80.259683 -286.49657) (xy 80.247906 -286.448786) (xy 80.243946 -286.399732)
			(xy 79.905098 -286.399732) (xy 79.904603 -286.424339) (xy 79.896708 -286.472916) (xy 79.881124 -286.519597)
			(xy 79.858253 -286.563174) (xy 79.828688 -286.602518) (xy 79.793195 -286.63661) (xy 79.752692 -286.664566)
			(xy 79.70823 -286.685664) (xy 79.660959 -286.699356) (xy 79.612104 -286.705288) (xy 79.562929 -286.703307)
			(xy 79.51471 -286.693463) (xy 79.468694 -286.676011) (xy 79.426073 -286.651404) (xy 79.387952 -286.620279)
			(xy 79.355317 -286.583442) (xy 79.329014 -286.541846) (xy 79.309723 -286.49657) (xy 79.297946 -286.448786)
			(xy 79.293986 -286.399732) (xy 78.005173 -286.399732) (xy 78.005178 -286.399986) (xy 78.004683 -286.424593)
			(xy 77.996788 -286.47317) (xy 77.981204 -286.519851) (xy 77.958333 -286.563428) (xy 77.928768 -286.602772)
			(xy 77.893275 -286.636864) (xy 77.852772 -286.66482) (xy 77.80831 -286.685918) (xy 77.761039 -286.69961)
			(xy 77.712184 -286.705542) (xy 77.663009 -286.703561) (xy 77.61479 -286.693717) (xy 77.568774 -286.676265)
			(xy 77.526153 -286.651658) (xy 77.488032 -286.620533) (xy 77.455397 -286.583696) (xy 77.429094 -286.5421)
			(xy 77.409803 -286.496824) (xy 77.398026 -286.44904) (xy 77.394066 -286.399986) (xy 77.055218 -286.399986)
			(xy 77.054723 -286.424593) (xy 77.046828 -286.47317) (xy 77.031244 -286.519851) (xy 77.008373 -286.563428)
			(xy 76.978808 -286.602772) (xy 76.943315 -286.636864) (xy 76.902812 -286.66482) (xy 76.85835 -286.685918)
			(xy 76.811079 -286.69961) (xy 76.762224 -286.705542) (xy 76.713049 -286.703561) (xy 76.66483 -286.693717)
			(xy 76.618814 -286.676265) (xy 76.576193 -286.651658) (xy 76.538072 -286.620533) (xy 76.505437 -286.583696)
			(xy 76.479134 -286.5421) (xy 76.459843 -286.496824) (xy 76.448066 -286.44904) (xy 76.444106 -286.399986)
			(xy 0.509016 -286.399986) (xy 0.509016 -287.349946) (xy 74.543932 -287.349946) (xy 74.547892 -287.300892)
			(xy 74.559669 -287.253108) (xy 74.57896 -287.207832) (xy 74.605263 -287.166236) (xy 74.637898 -287.129399)
			(xy 74.676019 -287.098274) (xy 74.71864 -287.073667) (xy 74.764656 -287.056215) (xy 74.812875 -287.046371)
			(xy 74.86205 -287.04439) (xy 74.910905 -287.050322) (xy 74.958176 -287.064014) (xy 75.002638 -287.085112)
			(xy 75.043141 -287.113068) (xy 75.078634 -287.14716) (xy 75.108199 -287.186504) (xy 75.13107 -287.230081)
			(xy 75.146654 -287.276762) (xy 75.154549 -287.325339) (xy 75.155044 -287.349946) (xy 75.494146 -287.349946)
			(xy 75.498106 -287.300892) (xy 75.509883 -287.253108) (xy 75.529174 -287.207832) (xy 75.555477 -287.166236)
			(xy 75.588112 -287.129399) (xy 75.626233 -287.098274) (xy 75.668854 -287.073667) (xy 75.71487 -287.056215)
			(xy 75.763089 -287.046371) (xy 75.812264 -287.04439) (xy 75.861119 -287.050322) (xy 75.90839 -287.064014)
			(xy 75.952852 -287.085112) (xy 75.993355 -287.113068) (xy 76.028848 -287.14716) (xy 76.058413 -287.186504)
			(xy 76.081284 -287.230081) (xy 76.096868 -287.276762) (xy 76.104763 -287.325339) (xy 76.105258 -287.349946)
			(xy 81.19416 -287.349946) (xy 81.19812 -287.300892) (xy 81.209897 -287.253108) (xy 81.229188 -287.207832)
			(xy 81.255491 -287.166236) (xy 81.288126 -287.129399) (xy 81.326247 -287.098274) (xy 81.368868 -287.073667)
			(xy 81.414884 -287.056215) (xy 81.463103 -287.046371) (xy 81.512278 -287.04439) (xy 81.561133 -287.050322)
			(xy 81.608404 -287.064014) (xy 81.652866 -287.085112) (xy 81.693369 -287.113068) (xy 81.728862 -287.14716)
			(xy 81.758427 -287.186504) (xy 81.781298 -287.230081) (xy 81.796882 -287.276762) (xy 81.804777 -287.325339)
			(xy 81.805272 -287.349946) (xy 82.14412 -287.349946) (xy 82.14808 -287.300892) (xy 82.159857 -287.253108)
			(xy 82.179148 -287.207832) (xy 82.205451 -287.166236) (xy 82.238086 -287.129399) (xy 82.276207 -287.098274)
			(xy 82.318828 -287.073667) (xy 82.364844 -287.056215) (xy 82.413063 -287.046371) (xy 82.462238 -287.04439)
			(xy 82.511093 -287.050322) (xy 82.558364 -287.064014) (xy 82.602826 -287.085112) (xy 82.643329 -287.113068)
			(xy 82.678822 -287.14716) (xy 82.708387 -287.186504) (xy 82.731258 -287.230081) (xy 82.746842 -287.276762)
			(xy 82.754737 -287.325339) (xy 82.755232 -287.349946) (xy 190.64403 -287.349946) (xy 190.64799 -287.300892)
			(xy 190.659767 -287.253108) (xy 190.679058 -287.207832) (xy 190.705361 -287.166236) (xy 190.737996 -287.129399)
			(xy 190.776117 -287.098274) (xy 190.818738 -287.073667) (xy 190.864754 -287.056215) (xy 190.912973 -287.046371)
			(xy 190.962148 -287.04439) (xy 191.011003 -287.050322) (xy 191.058274 -287.064014) (xy 191.102736 -287.085112)
			(xy 191.143239 -287.113068) (xy 191.178732 -287.14716) (xy 191.208297 -287.186504) (xy 191.231168 -287.230081)
			(xy 191.246752 -287.276762) (xy 191.254647 -287.325339) (xy 191.255142 -287.349946) (xy 191.594244 -287.349946)
			(xy 191.598204 -287.300892) (xy 191.609981 -287.253108) (xy 191.629272 -287.207832) (xy 191.655575 -287.166236)
			(xy 191.68821 -287.129399) (xy 191.726331 -287.098274) (xy 191.768952 -287.073667) (xy 191.814968 -287.056215)
			(xy 191.863187 -287.046371) (xy 191.912362 -287.04439) (xy 191.961217 -287.050322) (xy 192.008488 -287.064014)
			(xy 192.05295 -287.085112) (xy 192.093453 -287.113068) (xy 192.128946 -287.14716) (xy 192.158511 -287.186504)
			(xy 192.181382 -287.230081) (xy 192.196966 -287.276762) (xy 192.204861 -287.325339) (xy 192.205356 -287.349946)
			(xy 197.294258 -287.349946) (xy 197.298218 -287.300892) (xy 197.309995 -287.253108) (xy 197.329286 -287.207832)
			(xy 197.355589 -287.166236) (xy 197.388224 -287.129399) (xy 197.426345 -287.098274) (xy 197.468966 -287.073667)
			(xy 197.514982 -287.056215) (xy 197.563201 -287.046371) (xy 197.612376 -287.04439) (xy 197.661231 -287.050322)
			(xy 197.708502 -287.064014) (xy 197.752964 -287.085112) (xy 197.793467 -287.113068) (xy 197.82896 -287.14716)
			(xy 197.858525 -287.186504) (xy 197.881396 -287.230081) (xy 197.89698 -287.276762) (xy 197.904875 -287.325339)
			(xy 197.90537 -287.349946) (xy 198.244218 -287.349946) (xy 198.248178 -287.300892) (xy 198.259955 -287.253108)
			(xy 198.279246 -287.207832) (xy 198.305549 -287.166236) (xy 198.338184 -287.129399) (xy 198.376305 -287.098274)
			(xy 198.418926 -287.073667) (xy 198.464942 -287.056215) (xy 198.513161 -287.046371) (xy 198.562336 -287.04439)
			(xy 198.611191 -287.050322) (xy 198.658462 -287.064014) (xy 198.702924 -287.085112) (xy 198.743427 -287.113068)
			(xy 198.77892 -287.14716) (xy 198.808485 -287.186504) (xy 198.831356 -287.230081) (xy 198.84694 -287.276762)
			(xy 198.854835 -287.325339) (xy 198.85533 -287.349946) (xy 306.744128 -287.349946) (xy 306.748088 -287.300892)
			(xy 306.759865 -287.253108) (xy 306.779156 -287.207832) (xy 306.805459 -287.166236) (xy 306.838094 -287.129399)
			(xy 306.876215 -287.098274) (xy 306.918836 -287.073667) (xy 306.964852 -287.056215) (xy 307.013071 -287.046371)
			(xy 307.062246 -287.04439) (xy 307.111101 -287.050322) (xy 307.158372 -287.064014) (xy 307.202834 -287.085112)
			(xy 307.243337 -287.113068) (xy 307.27883 -287.14716) (xy 307.308395 -287.186504) (xy 307.331266 -287.230081)
			(xy 307.34685 -287.276762) (xy 307.354745 -287.325339) (xy 307.35524 -287.349946) (xy 307.694088 -287.349946)
			(xy 307.698048 -287.300892) (xy 307.709825 -287.253108) (xy 307.729116 -287.207832) (xy 307.755419 -287.166236)
			(xy 307.788054 -287.129399) (xy 307.826175 -287.098274) (xy 307.868796 -287.073667) (xy 307.914812 -287.056215)
			(xy 307.963031 -287.046371) (xy 308.012206 -287.04439) (xy 308.061061 -287.050322) (xy 308.108332 -287.064014)
			(xy 308.152794 -287.085112) (xy 308.193297 -287.113068) (xy 308.22879 -287.14716) (xy 308.258355 -287.186504)
			(xy 308.281226 -287.230081) (xy 308.29681 -287.276762) (xy 308.304705 -287.325339) (xy 308.3052 -287.349946)
			(xy 313.394102 -287.349946) (xy 313.398062 -287.300892) (xy 313.409839 -287.253108) (xy 313.42913 -287.207832)
			(xy 313.455433 -287.166236) (xy 313.488068 -287.129399) (xy 313.526189 -287.098274) (xy 313.56881 -287.073667)
			(xy 313.614826 -287.056215) (xy 313.663045 -287.046371) (xy 313.71222 -287.04439) (xy 313.761075 -287.050322)
			(xy 313.808346 -287.064014) (xy 313.852808 -287.085112) (xy 313.893311 -287.113068) (xy 313.928804 -287.14716)
			(xy 313.958369 -287.186504) (xy 313.98124 -287.230081) (xy 313.996824 -287.276762) (xy 314.004719 -287.325339)
			(xy 314.005214 -287.349946) (xy 314.344062 -287.349946) (xy 314.348022 -287.300892) (xy 314.359799 -287.253108)
			(xy 314.37909 -287.207832) (xy 314.405393 -287.166236) (xy 314.438028 -287.129399) (xy 314.476149 -287.098274)
			(xy 314.51877 -287.073667) (xy 314.564786 -287.056215) (xy 314.613005 -287.046371) (xy 314.66218 -287.04439)
			(xy 314.711035 -287.050322) (xy 314.758306 -287.064014) (xy 314.802768 -287.085112) (xy 314.843271 -287.113068)
			(xy 314.878764 -287.14716) (xy 314.908329 -287.186504) (xy 314.9312 -287.230081) (xy 314.946784 -287.276762)
			(xy 314.954679 -287.325339) (xy 314.955174 -287.349946) (xy 422.844226 -287.349946) (xy 422.848186 -287.300892)
			(xy 422.859963 -287.253108) (xy 422.879254 -287.207832) (xy 422.905557 -287.166236) (xy 422.938192 -287.129399)
			(xy 422.976313 -287.098274) (xy 423.018934 -287.073667) (xy 423.06495 -287.056215) (xy 423.113169 -287.046371)
			(xy 423.162344 -287.04439) (xy 423.211199 -287.050322) (xy 423.25847 -287.064014) (xy 423.302932 -287.085112)
			(xy 423.343435 -287.113068) (xy 423.378928 -287.14716) (xy 423.408493 -287.186504) (xy 423.431364 -287.230081)
			(xy 423.446948 -287.276762) (xy 423.454843 -287.325339) (xy 423.455338 -287.349946) (xy 423.794186 -287.349946)
			(xy 423.798146 -287.300892) (xy 423.809923 -287.253108) (xy 423.829214 -287.207832) (xy 423.855517 -287.166236)
			(xy 423.888152 -287.129399) (xy 423.926273 -287.098274) (xy 423.968894 -287.073667) (xy 424.01491 -287.056215)
			(xy 424.063129 -287.046371) (xy 424.112304 -287.04439) (xy 424.161159 -287.050322) (xy 424.20843 -287.064014)
			(xy 424.252892 -287.085112) (xy 424.293395 -287.113068) (xy 424.328888 -287.14716) (xy 424.358453 -287.186504)
			(xy 424.381324 -287.230081) (xy 424.396908 -287.276762) (xy 424.404803 -287.325339) (xy 424.405298 -287.349946)
			(xy 429.4942 -287.349946) (xy 429.49816 -287.300892) (xy 429.509937 -287.253108) (xy 429.529228 -287.207832)
			(xy 429.555531 -287.166236) (xy 429.588166 -287.129399) (xy 429.626287 -287.098274) (xy 429.668908 -287.073667)
			(xy 429.714924 -287.056215) (xy 429.763143 -287.046371) (xy 429.812318 -287.04439) (xy 429.861173 -287.050322)
			(xy 429.908444 -287.064014) (xy 429.952906 -287.085112) (xy 429.993409 -287.113068) (xy 430.028902 -287.14716)
			(xy 430.058467 -287.186504) (xy 430.081338 -287.230081) (xy 430.096922 -287.276762) (xy 430.104817 -287.325339)
			(xy 430.105312 -287.349946) (xy 430.44416 -287.349946) (xy 430.44812 -287.300892) (xy 430.459897 -287.253108)
			(xy 430.479188 -287.207832) (xy 430.505491 -287.166236) (xy 430.538126 -287.129399) (xy 430.576247 -287.098274)
			(xy 430.618868 -287.073667) (xy 430.664884 -287.056215) (xy 430.713103 -287.046371) (xy 430.762278 -287.04439)
			(xy 430.811133 -287.050322) (xy 430.858404 -287.064014) (xy 430.902866 -287.085112) (xy 430.943369 -287.113068)
			(xy 430.978862 -287.14716) (xy 431.008427 -287.186504) (xy 431.031298 -287.230081) (xy 431.046882 -287.276762)
			(xy 431.054777 -287.325339) (xy 431.055272 -287.349946) (xy 431.054777 -287.374553) (xy 431.046882 -287.42313)
			(xy 431.031298 -287.469811) (xy 431.008427 -287.513388) (xy 430.978862 -287.552732) (xy 430.943369 -287.586824)
			(xy 430.902866 -287.61478) (xy 430.858404 -287.635878) (xy 430.811133 -287.64957) (xy 430.762278 -287.655502)
			(xy 430.713103 -287.653521) (xy 430.664884 -287.643677) (xy 430.618868 -287.626225) (xy 430.576247 -287.601618)
			(xy 430.538126 -287.570493) (xy 430.505491 -287.533656) (xy 430.479188 -287.49206) (xy 430.459897 -287.446784)
			(xy 430.44812 -287.399) (xy 430.44416 -287.349946) (xy 430.105312 -287.349946) (xy 430.104817 -287.374553)
			(xy 430.096922 -287.42313) (xy 430.081338 -287.469811) (xy 430.058467 -287.513388) (xy 430.028902 -287.552732)
			(xy 429.993409 -287.586824) (xy 429.952906 -287.61478) (xy 429.908444 -287.635878) (xy 429.861173 -287.64957)
			(xy 429.812318 -287.655502) (xy 429.763143 -287.653521) (xy 429.714924 -287.643677) (xy 429.668908 -287.626225)
			(xy 429.626287 -287.601618) (xy 429.588166 -287.570493) (xy 429.555531 -287.533656) (xy 429.529228 -287.49206)
			(xy 429.509937 -287.446784) (xy 429.49816 -287.399) (xy 429.4942 -287.349946) (xy 424.405298 -287.349946)
			(xy 424.404803 -287.374553) (xy 424.396908 -287.42313) (xy 424.381324 -287.469811) (xy 424.358453 -287.513388)
			(xy 424.328888 -287.552732) (xy 424.293395 -287.586824) (xy 424.252892 -287.61478) (xy 424.20843 -287.635878)
			(xy 424.161159 -287.64957) (xy 424.112304 -287.655502) (xy 424.063129 -287.653521) (xy 424.01491 -287.643677)
			(xy 423.968894 -287.626225) (xy 423.926273 -287.601618) (xy 423.888152 -287.570493) (xy 423.855517 -287.533656)
			(xy 423.829214 -287.49206) (xy 423.809923 -287.446784) (xy 423.798146 -287.399) (xy 423.794186 -287.349946)
			(xy 423.455338 -287.349946) (xy 423.454843 -287.374553) (xy 423.446948 -287.42313) (xy 423.431364 -287.469811)
			(xy 423.408493 -287.513388) (xy 423.378928 -287.552732) (xy 423.343435 -287.586824) (xy 423.302932 -287.61478)
			(xy 423.25847 -287.635878) (xy 423.211199 -287.64957) (xy 423.162344 -287.655502) (xy 423.113169 -287.653521)
			(xy 423.06495 -287.643677) (xy 423.018934 -287.626225) (xy 422.976313 -287.601618) (xy 422.938192 -287.570493)
			(xy 422.905557 -287.533656) (xy 422.879254 -287.49206) (xy 422.859963 -287.446784) (xy 422.848186 -287.399)
			(xy 422.844226 -287.349946) (xy 314.955174 -287.349946) (xy 314.954679 -287.374553) (xy 314.946784 -287.42313)
			(xy 314.9312 -287.469811) (xy 314.908329 -287.513388) (xy 314.878764 -287.552732) (xy 314.843271 -287.586824)
			(xy 314.802768 -287.61478) (xy 314.758306 -287.635878) (xy 314.711035 -287.64957) (xy 314.66218 -287.655502)
			(xy 314.613005 -287.653521) (xy 314.564786 -287.643677) (xy 314.51877 -287.626225) (xy 314.476149 -287.601618)
			(xy 314.438028 -287.570493) (xy 314.405393 -287.533656) (xy 314.37909 -287.49206) (xy 314.359799 -287.446784)
			(xy 314.348022 -287.399) (xy 314.344062 -287.349946) (xy 314.005214 -287.349946) (xy 314.004719 -287.374553)
			(xy 313.996824 -287.42313) (xy 313.98124 -287.469811) (xy 313.958369 -287.513388) (xy 313.928804 -287.552732)
			(xy 313.893311 -287.586824) (xy 313.852808 -287.61478) (xy 313.808346 -287.635878) (xy 313.761075 -287.64957)
			(xy 313.71222 -287.655502) (xy 313.663045 -287.653521) (xy 313.614826 -287.643677) (xy 313.56881 -287.626225)
			(xy 313.526189 -287.601618) (xy 313.488068 -287.570493) (xy 313.455433 -287.533656) (xy 313.42913 -287.49206)
			(xy 313.409839 -287.446784) (xy 313.398062 -287.399) (xy 313.394102 -287.349946) (xy 308.3052 -287.349946)
			(xy 308.304705 -287.374553) (xy 308.29681 -287.42313) (xy 308.281226 -287.469811) (xy 308.258355 -287.513388)
			(xy 308.22879 -287.552732) (xy 308.193297 -287.586824) (xy 308.152794 -287.61478) (xy 308.108332 -287.635878)
			(xy 308.061061 -287.64957) (xy 308.012206 -287.655502) (xy 307.963031 -287.653521) (xy 307.914812 -287.643677)
			(xy 307.868796 -287.626225) (xy 307.826175 -287.601618) (xy 307.788054 -287.570493) (xy 307.755419 -287.533656)
			(xy 307.729116 -287.49206) (xy 307.709825 -287.446784) (xy 307.698048 -287.399) (xy 307.694088 -287.349946)
			(xy 307.35524 -287.349946) (xy 307.354745 -287.374553) (xy 307.34685 -287.42313) (xy 307.331266 -287.469811)
			(xy 307.308395 -287.513388) (xy 307.27883 -287.552732) (xy 307.243337 -287.586824) (xy 307.202834 -287.61478)
			(xy 307.158372 -287.635878) (xy 307.111101 -287.64957) (xy 307.062246 -287.655502) (xy 307.013071 -287.653521)
			(xy 306.964852 -287.643677) (xy 306.918836 -287.626225) (xy 306.876215 -287.601618) (xy 306.838094 -287.570493)
			(xy 306.805459 -287.533656) (xy 306.779156 -287.49206) (xy 306.759865 -287.446784) (xy 306.748088 -287.399)
			(xy 306.744128 -287.349946) (xy 198.85533 -287.349946) (xy 198.854835 -287.374553) (xy 198.84694 -287.42313)
			(xy 198.831356 -287.469811) (xy 198.808485 -287.513388) (xy 198.77892 -287.552732) (xy 198.743427 -287.586824)
			(xy 198.702924 -287.61478) (xy 198.658462 -287.635878) (xy 198.611191 -287.64957) (xy 198.562336 -287.655502)
			(xy 198.513161 -287.653521) (xy 198.464942 -287.643677) (xy 198.418926 -287.626225) (xy 198.376305 -287.601618)
			(xy 198.338184 -287.570493) (xy 198.305549 -287.533656) (xy 198.279246 -287.49206) (xy 198.259955 -287.446784)
			(xy 198.248178 -287.399) (xy 198.244218 -287.349946) (xy 197.90537 -287.349946) (xy 197.904875 -287.374553)
			(xy 197.89698 -287.42313) (xy 197.881396 -287.469811) (xy 197.858525 -287.513388) (xy 197.82896 -287.552732)
			(xy 197.793467 -287.586824) (xy 197.752964 -287.61478) (xy 197.708502 -287.635878) (xy 197.661231 -287.64957)
			(xy 197.612376 -287.655502) (xy 197.563201 -287.653521) (xy 197.514982 -287.643677) (xy 197.468966 -287.626225)
			(xy 197.426345 -287.601618) (xy 197.388224 -287.570493) (xy 197.355589 -287.533656) (xy 197.329286 -287.49206)
			(xy 197.309995 -287.446784) (xy 197.298218 -287.399) (xy 197.294258 -287.349946) (xy 192.205356 -287.349946)
			(xy 192.204861 -287.374553) (xy 192.196966 -287.42313) (xy 192.181382 -287.469811) (xy 192.158511 -287.513388)
			(xy 192.128946 -287.552732) (xy 192.093453 -287.586824) (xy 192.05295 -287.61478) (xy 192.008488 -287.635878)
			(xy 191.961217 -287.64957) (xy 191.912362 -287.655502) (xy 191.863187 -287.653521) (xy 191.814968 -287.643677)
			(xy 191.768952 -287.626225) (xy 191.726331 -287.601618) (xy 191.68821 -287.570493) (xy 191.655575 -287.533656)
			(xy 191.629272 -287.49206) (xy 191.609981 -287.446784) (xy 191.598204 -287.399) (xy 191.594244 -287.349946)
			(xy 191.255142 -287.349946) (xy 191.254647 -287.374553) (xy 191.246752 -287.42313) (xy 191.231168 -287.469811)
			(xy 191.208297 -287.513388) (xy 191.178732 -287.552732) (xy 191.143239 -287.586824) (xy 191.102736 -287.61478)
			(xy 191.058274 -287.635878) (xy 191.011003 -287.64957) (xy 190.962148 -287.655502) (xy 190.912973 -287.653521)
			(xy 190.864754 -287.643677) (xy 190.818738 -287.626225) (xy 190.776117 -287.601618) (xy 190.737996 -287.570493)
			(xy 190.705361 -287.533656) (xy 190.679058 -287.49206) (xy 190.659767 -287.446784) (xy 190.64799 -287.399)
			(xy 190.64403 -287.349946) (xy 82.755232 -287.349946) (xy 82.754737 -287.374553) (xy 82.746842 -287.42313)
			(xy 82.731258 -287.469811) (xy 82.708387 -287.513388) (xy 82.678822 -287.552732) (xy 82.643329 -287.586824)
			(xy 82.602826 -287.61478) (xy 82.558364 -287.635878) (xy 82.511093 -287.64957) (xy 82.462238 -287.655502)
			(xy 82.413063 -287.653521) (xy 82.364844 -287.643677) (xy 82.318828 -287.626225) (xy 82.276207 -287.601618)
			(xy 82.238086 -287.570493) (xy 82.205451 -287.533656) (xy 82.179148 -287.49206) (xy 82.159857 -287.446784)
			(xy 82.14808 -287.399) (xy 82.14412 -287.349946) (xy 81.805272 -287.349946) (xy 81.804777 -287.374553)
			(xy 81.796882 -287.42313) (xy 81.781298 -287.469811) (xy 81.758427 -287.513388) (xy 81.728862 -287.552732)
			(xy 81.693369 -287.586824) (xy 81.652866 -287.61478) (xy 81.608404 -287.635878) (xy 81.561133 -287.64957)
			(xy 81.512278 -287.655502) (xy 81.463103 -287.653521) (xy 81.414884 -287.643677) (xy 81.368868 -287.626225)
			(xy 81.326247 -287.601618) (xy 81.288126 -287.570493) (xy 81.255491 -287.533656) (xy 81.229188 -287.49206)
			(xy 81.209897 -287.446784) (xy 81.19812 -287.399) (xy 81.19416 -287.349946) (xy 76.105258 -287.349946)
			(xy 76.104763 -287.374553) (xy 76.096868 -287.42313) (xy 76.081284 -287.469811) (xy 76.058413 -287.513388)
			(xy 76.028848 -287.552732) (xy 75.993355 -287.586824) (xy 75.952852 -287.61478) (xy 75.90839 -287.635878)
			(xy 75.861119 -287.64957) (xy 75.812264 -287.655502) (xy 75.763089 -287.653521) (xy 75.71487 -287.643677)
			(xy 75.668854 -287.626225) (xy 75.626233 -287.601618) (xy 75.588112 -287.570493) (xy 75.555477 -287.533656)
			(xy 75.529174 -287.49206) (xy 75.509883 -287.446784) (xy 75.498106 -287.399) (xy 75.494146 -287.349946)
			(xy 75.155044 -287.349946) (xy 75.154549 -287.374553) (xy 75.146654 -287.42313) (xy 75.13107 -287.469811)
			(xy 75.108199 -287.513388) (xy 75.078634 -287.552732) (xy 75.043141 -287.586824) (xy 75.002638 -287.61478)
			(xy 74.958176 -287.635878) (xy 74.910905 -287.64957) (xy 74.86205 -287.655502) (xy 74.812875 -287.653521)
			(xy 74.764656 -287.643677) (xy 74.71864 -287.626225) (xy 74.676019 -287.601618) (xy 74.637898 -287.570493)
			(xy 74.605263 -287.533656) (xy 74.57896 -287.49206) (xy 74.559669 -287.446784) (xy 74.547892 -287.399)
			(xy 74.543932 -287.349946) (xy 0.509016 -287.349946) (xy 0.509016 -287.850408) (xy 37.944539 -287.850408)
			(xy 37.944539 -287.798392) (xy 37.952677 -287.747016) (xy 37.968751 -287.697546) (xy 37.992366 -287.651199)
			(xy 38.02294 -287.609117) (xy 38.059722 -287.572337) (xy 38.101804 -287.541763) (xy 38.148151 -287.518148)
			(xy 38.197622 -287.502075) (xy 38.248998 -287.493939) (xy 38.275006 -287.493456) (xy 39.224966 -287.493456)
			(xy 39.250978 -287.493901) (xy 39.302363 -287.502035) (xy 39.351843 -287.518107) (xy 39.398199 -287.541722)
			(xy 39.44029 -287.572299) (xy 39.477079 -287.609084) (xy 39.50766 -287.651172) (xy 39.53128 -287.697525)
			(xy 39.547357 -287.747004) (xy 39.555496 -287.798388) (xy 39.555496 -287.850405) (xy 40.794466 -287.850405)
			(xy 40.794466 -287.798395) (xy 40.802602 -287.747025) (xy 40.818674 -287.697561) (xy 40.842285 -287.651219)
			(xy 40.872855 -287.609142) (xy 40.909631 -287.572364) (xy 40.951707 -287.541792) (xy 40.998048 -287.518179)
			(xy 41.047512 -287.502105) (xy 41.098881 -287.493967) (xy 41.124886 -287.493456) (xy 42.074846 -287.493456)
			(xy 42.100852 -287.493934) (xy 42.152223 -287.502077) (xy 42.201688 -287.518155) (xy 42.248029 -287.541773)
			(xy 42.290106 -287.572348) (xy 42.326882 -287.609129) (xy 42.357451 -287.65121) (xy 42.381063 -287.697554)
			(xy 42.397134 -287.747022) (xy 42.40527 -287.798394) (xy 42.40527 -287.850406) (xy 42.397134 -287.901778)
			(xy 42.381063 -287.951246) (xy 42.357451 -287.99759) (xy 42.326882 -288.039671) (xy 42.290106 -288.076452)
			(xy 42.248029 -288.107027) (xy 42.201688 -288.130645) (xy 42.152223 -288.146723) (xy 42.100852 -288.154866)
			(xy 42.074846 -288.15538) (xy 41.124886 -288.15538) (xy 41.098881 -288.154833) (xy 41.047512 -288.146695)
			(xy 40.998048 -288.130621) (xy 40.951707 -288.107008) (xy 40.909631 -288.076436) (xy 40.872855 -288.039658)
			(xy 40.842285 -287.997581) (xy 40.818674 -287.951239) (xy 40.802602 -287.901775) (xy 40.794466 -287.850405)
			(xy 39.555496 -287.850405) (xy 39.555496 -287.850412) (xy 39.547357 -287.901796) (xy 39.53128 -287.951275)
			(xy 39.50766 -287.997628) (xy 39.477079 -288.039716) (xy 39.44029 -288.076501) (xy 39.398199 -288.107078)
			(xy 39.351843 -288.130693) (xy 39.302363 -288.146765) (xy 39.250978 -288.154899) (xy 39.224966 -288.15538)
			(xy 38.275006 -288.15538) (xy 38.248998 -288.154861) (xy 38.197622 -288.146725) (xy 38.148151 -288.130652)
			(xy 38.101804 -288.107037) (xy 38.059722 -288.076463) (xy 38.02294 -288.039683) (xy 37.992366 -287.997601)
			(xy 37.968751 -287.951254) (xy 37.952677 -287.901784) (xy 37.944539 -287.850408) (xy 0.509016 -287.850408)
			(xy 0.509016 -288.299906) (xy 76.444106 -288.299906) (xy 76.448066 -288.250852) (xy 76.459843 -288.203068)
			(xy 76.479134 -288.157792) (xy 76.505437 -288.116196) (xy 76.538072 -288.079359) (xy 76.576193 -288.048234)
			(xy 76.618814 -288.023627) (xy 76.66483 -288.006175) (xy 76.713049 -287.996331) (xy 76.762224 -287.99435)
			(xy 76.811079 -288.000282) (xy 76.85835 -288.013974) (xy 76.902812 -288.035072) (xy 76.943315 -288.063028)
			(xy 76.978808 -288.09712) (xy 77.008373 -288.136464) (xy 77.031244 -288.180041) (xy 77.046828 -288.226722)
			(xy 77.054723 -288.275299) (xy 77.055218 -288.299906) (xy 77.394066 -288.299906) (xy 77.398026 -288.250852)
			(xy 77.409803 -288.203068) (xy 77.429094 -288.157792) (xy 77.455397 -288.116196) (xy 77.488032 -288.079359)
			(xy 77.526153 -288.048234) (xy 77.568774 -288.023627) (xy 77.61479 -288.006175) (xy 77.663009 -287.996331)
			(xy 77.712184 -287.99435) (xy 77.761039 -288.000282) (xy 77.80831 -288.013974) (xy 77.852772 -288.035072)
			(xy 77.893275 -288.063028) (xy 77.928768 -288.09712) (xy 77.958333 -288.136464) (xy 77.981204 -288.180041)
			(xy 77.996788 -288.226722) (xy 78.004683 -288.275299) (xy 78.005178 -288.299906) (xy 79.293986 -288.299906)
			(xy 79.297946 -288.250852) (xy 79.309723 -288.203068) (xy 79.329014 -288.157792) (xy 79.355317 -288.116196)
			(xy 79.387952 -288.079359) (xy 79.426073 -288.048234) (xy 79.468694 -288.023627) (xy 79.51471 -288.006175)
			(xy 79.562929 -287.996331) (xy 79.612104 -287.99435) (xy 79.660959 -288.000282) (xy 79.70823 -288.013974)
			(xy 79.752692 -288.035072) (xy 79.793195 -288.063028) (xy 79.828688 -288.09712) (xy 79.858253 -288.136464)
			(xy 79.881124 -288.180041) (xy 79.896708 -288.226722) (xy 79.904603 -288.275299) (xy 79.905098 -288.299906)
			(xy 80.243946 -288.299906) (xy 80.247906 -288.250852) (xy 80.259683 -288.203068) (xy 80.278974 -288.157792)
			(xy 80.305277 -288.116196) (xy 80.337912 -288.079359) (xy 80.376033 -288.048234) (xy 80.418654 -288.023627)
			(xy 80.46467 -288.006175) (xy 80.512889 -287.996331) (xy 80.562064 -287.99435) (xy 80.610919 -288.000282)
			(xy 80.65819 -288.013974) (xy 80.702652 -288.035072) (xy 80.743155 -288.063028) (xy 80.778648 -288.09712)
			(xy 80.808213 -288.136464) (xy 80.831084 -288.180041) (xy 80.846668 -288.226722) (xy 80.854563 -288.275299)
			(xy 80.855058 -288.299906) (xy 192.544204 -288.299906) (xy 192.548164 -288.250852) (xy 192.559941 -288.203068)
			(xy 192.579232 -288.157792) (xy 192.605535 -288.116196) (xy 192.63817 -288.079359) (xy 192.676291 -288.048234)
			(xy 192.718912 -288.023627) (xy 192.764928 -288.006175) (xy 192.813147 -287.996331) (xy 192.862322 -287.99435)
			(xy 192.911177 -288.000282) (xy 192.958448 -288.013974) (xy 193.00291 -288.035072) (xy 193.043413 -288.063028)
			(xy 193.078906 -288.09712) (xy 193.108471 -288.136464) (xy 193.131342 -288.180041) (xy 193.146926 -288.226722)
			(xy 193.154821 -288.275299) (xy 193.155316 -288.299906) (xy 193.494164 -288.299906) (xy 193.498124 -288.250852)
			(xy 193.509901 -288.203068) (xy 193.529192 -288.157792) (xy 193.555495 -288.116196) (xy 193.58813 -288.079359)
			(xy 193.626251 -288.048234) (xy 193.668872 -288.023627) (xy 193.714888 -288.006175) (xy 193.763107 -287.996331)
			(xy 193.812282 -287.99435) (xy 193.861137 -288.000282) (xy 193.908408 -288.013974) (xy 193.95287 -288.035072)
			(xy 193.993373 -288.063028) (xy 194.028866 -288.09712) (xy 194.058431 -288.136464) (xy 194.081302 -288.180041)
			(xy 194.096886 -288.226722) (xy 194.104781 -288.275299) (xy 194.105276 -288.299906) (xy 195.394084 -288.299906)
			(xy 195.398044 -288.250852) (xy 195.409821 -288.203068) (xy 195.429112 -288.157792) (xy 195.455415 -288.116196)
			(xy 195.48805 -288.079359) (xy 195.526171 -288.048234) (xy 195.568792 -288.023627) (xy 195.614808 -288.006175)
			(xy 195.663027 -287.996331) (xy 195.712202 -287.99435) (xy 195.761057 -288.000282) (xy 195.808328 -288.013974)
			(xy 195.85279 -288.035072) (xy 195.893293 -288.063028) (xy 195.928786 -288.09712) (xy 195.958351 -288.136464)
			(xy 195.981222 -288.180041) (xy 195.996806 -288.226722) (xy 196.004701 -288.275299) (xy 196.005196 -288.299906)
			(xy 196.344044 -288.299906) (xy 196.348004 -288.250852) (xy 196.359781 -288.203068) (xy 196.379072 -288.157792)
			(xy 196.405375 -288.116196) (xy 196.43801 -288.079359) (xy 196.476131 -288.048234) (xy 196.518752 -288.023627)
			(xy 196.564768 -288.006175) (xy 196.612987 -287.996331) (xy 196.662162 -287.99435) (xy 196.711017 -288.000282)
			(xy 196.758288 -288.013974) (xy 196.80275 -288.035072) (xy 196.843253 -288.063028) (xy 196.878746 -288.09712)
			(xy 196.908311 -288.136464) (xy 196.931182 -288.180041) (xy 196.946766 -288.226722) (xy 196.954661 -288.275299)
			(xy 196.955156 -288.299906) (xy 308.644048 -288.299906) (xy 308.648008 -288.250852) (xy 308.659785 -288.203068)
			(xy 308.679076 -288.157792) (xy 308.705379 -288.116196) (xy 308.738014 -288.079359) (xy 308.776135 -288.048234)
			(xy 308.818756 -288.023627) (xy 308.864772 -288.006175) (xy 308.912991 -287.996331) (xy 308.962166 -287.99435)
			(xy 309.011021 -288.000282) (xy 309.058292 -288.013974) (xy 309.102754 -288.035072) (xy 309.143257 -288.063028)
			(xy 309.17875 -288.09712) (xy 309.208315 -288.136464) (xy 309.231186 -288.180041) (xy 309.24677 -288.226722)
			(xy 309.254665 -288.275299) (xy 309.25516 -288.299906) (xy 309.594008 -288.299906) (xy 309.597968 -288.250852)
			(xy 309.609745 -288.203068) (xy 309.629036 -288.157792) (xy 309.655339 -288.116196) (xy 309.687974 -288.079359)
			(xy 309.726095 -288.048234) (xy 309.768716 -288.023627) (xy 309.814732 -288.006175) (xy 309.862951 -287.996331)
			(xy 309.912126 -287.99435) (xy 309.960981 -288.000282) (xy 310.008252 -288.013974) (xy 310.052714 -288.035072)
			(xy 310.093217 -288.063028) (xy 310.12871 -288.09712) (xy 310.158275 -288.136464) (xy 310.181146 -288.180041)
			(xy 310.19673 -288.226722) (xy 310.204625 -288.275299) (xy 310.20512 -288.299906) (xy 311.493928 -288.299906)
			(xy 311.497888 -288.250852) (xy 311.509665 -288.203068) (xy 311.528956 -288.157792) (xy 311.555259 -288.116196)
			(xy 311.587894 -288.079359) (xy 311.626015 -288.048234) (xy 311.668636 -288.023627) (xy 311.714652 -288.006175)
			(xy 311.762871 -287.996331) (xy 311.812046 -287.99435) (xy 311.860901 -288.000282) (xy 311.908172 -288.013974)
			(xy 311.952634 -288.035072) (xy 311.993137 -288.063028) (xy 312.02863 -288.09712) (xy 312.058195 -288.136464)
			(xy 312.081066 -288.180041) (xy 312.09665 -288.226722) (xy 312.104545 -288.275299) (xy 312.10504 -288.299906)
			(xy 312.443888 -288.299906) (xy 312.447848 -288.250852) (xy 312.459625 -288.203068) (xy 312.478916 -288.157792)
			(xy 312.505219 -288.116196) (xy 312.537854 -288.079359) (xy 312.575975 -288.048234) (xy 312.618596 -288.023627)
			(xy 312.664612 -288.006175) (xy 312.712831 -287.996331) (xy 312.762006 -287.99435) (xy 312.810861 -288.000282)
			(xy 312.858132 -288.013974) (xy 312.902594 -288.035072) (xy 312.943097 -288.063028) (xy 312.97859 -288.09712)
			(xy 313.008155 -288.136464) (xy 313.031026 -288.180041) (xy 313.04661 -288.226722) (xy 313.054505 -288.275299)
			(xy 313.055 -288.299906) (xy 424.744146 -288.299906) (xy 424.748106 -288.250852) (xy 424.759883 -288.203068)
			(xy 424.779174 -288.157792) (xy 424.805477 -288.116196) (xy 424.838112 -288.079359) (xy 424.876233 -288.048234)
			(xy 424.918854 -288.023627) (xy 424.96487 -288.006175) (xy 425.013089 -287.996331) (xy 425.062264 -287.99435)
			(xy 425.111119 -288.000282) (xy 425.15839 -288.013974) (xy 425.202852 -288.035072) (xy 425.243355 -288.063028)
			(xy 425.278848 -288.09712) (xy 425.308413 -288.136464) (xy 425.331284 -288.180041) (xy 425.346868 -288.226722)
			(xy 425.354763 -288.275299) (xy 425.355258 -288.299906) (xy 425.694106 -288.299906) (xy 425.698066 -288.250852)
			(xy 425.709843 -288.203068) (xy 425.729134 -288.157792) (xy 425.755437 -288.116196) (xy 425.788072 -288.079359)
			(xy 425.826193 -288.048234) (xy 425.868814 -288.023627) (xy 425.91483 -288.006175) (xy 425.963049 -287.996331)
			(xy 426.012224 -287.99435) (xy 426.061079 -288.000282) (xy 426.10835 -288.013974) (xy 426.152812 -288.035072)
			(xy 426.193315 -288.063028) (xy 426.228808 -288.09712) (xy 426.258373 -288.136464) (xy 426.281244 -288.180041)
			(xy 426.296828 -288.226722) (xy 426.304723 -288.275299) (xy 426.305218 -288.299906) (xy 427.594026 -288.299906)
			(xy 427.597986 -288.250852) (xy 427.609763 -288.203068) (xy 427.629054 -288.157792) (xy 427.655357 -288.116196)
			(xy 427.687992 -288.079359) (xy 427.726113 -288.048234) (xy 427.768734 -288.023627) (xy 427.81475 -288.006175)
			(xy 427.862969 -287.996331) (xy 427.912144 -287.99435) (xy 427.960999 -288.000282) (xy 428.00827 -288.013974)
			(xy 428.052732 -288.035072) (xy 428.093235 -288.063028) (xy 428.128728 -288.09712) (xy 428.158293 -288.136464)
			(xy 428.181164 -288.180041) (xy 428.196748 -288.226722) (xy 428.204643 -288.275299) (xy 428.205138 -288.299906)
			(xy 428.543986 -288.299906) (xy 428.547946 -288.250852) (xy 428.559723 -288.203068) (xy 428.579014 -288.157792)
			(xy 428.605317 -288.116196) (xy 428.637952 -288.079359) (xy 428.676073 -288.048234) (xy 428.718694 -288.023627)
			(xy 428.76471 -288.006175) (xy 428.812929 -287.996331) (xy 428.862104 -287.99435) (xy 428.910959 -288.000282)
			(xy 428.95823 -288.013974) (xy 429.002692 -288.035072) (xy 429.043195 -288.063028) (xy 429.078688 -288.09712)
			(xy 429.108253 -288.136464) (xy 429.131124 -288.180041) (xy 429.146708 -288.226722) (xy 429.154603 -288.275299)
			(xy 429.155098 -288.299906) (xy 429.154603 -288.324513) (xy 429.146708 -288.37309) (xy 429.131124 -288.419771)
			(xy 429.108253 -288.463348) (xy 429.078688 -288.502692) (xy 429.043195 -288.536784) (xy 429.002692 -288.56474)
			(xy 428.95823 -288.585838) (xy 428.910959 -288.59953) (xy 428.862104 -288.605462) (xy 428.812929 -288.603481)
			(xy 428.76471 -288.593637) (xy 428.718694 -288.576185) (xy 428.676073 -288.551578) (xy 428.637952 -288.520453)
			(xy 428.605317 -288.483616) (xy 428.579014 -288.44202) (xy 428.559723 -288.396744) (xy 428.547946 -288.34896)
			(xy 428.543986 -288.299906) (xy 428.205138 -288.299906) (xy 428.204643 -288.324513) (xy 428.196748 -288.37309)
			(xy 428.181164 -288.419771) (xy 428.158293 -288.463348) (xy 428.128728 -288.502692) (xy 428.093235 -288.536784)
			(xy 428.052732 -288.56474) (xy 428.00827 -288.585838) (xy 427.960999 -288.59953) (xy 427.912144 -288.605462)
			(xy 427.862969 -288.603481) (xy 427.81475 -288.593637) (xy 427.768734 -288.576185) (xy 427.726113 -288.551578)
			(xy 427.687992 -288.520453) (xy 427.655357 -288.483616) (xy 427.629054 -288.44202) (xy 427.609763 -288.396744)
			(xy 427.597986 -288.34896) (xy 427.594026 -288.299906) (xy 426.305218 -288.299906) (xy 426.304723 -288.324513)
			(xy 426.296828 -288.37309) (xy 426.281244 -288.419771) (xy 426.258373 -288.463348) (xy 426.228808 -288.502692)
			(xy 426.193315 -288.536784) (xy 426.152812 -288.56474) (xy 426.10835 -288.585838) (xy 426.061079 -288.59953)
			(xy 426.012224 -288.605462) (xy 425.963049 -288.603481) (xy 425.91483 -288.593637) (xy 425.868814 -288.576185)
			(xy 425.826193 -288.551578) (xy 425.788072 -288.520453) (xy 425.755437 -288.483616) (xy 425.729134 -288.44202)
			(xy 425.709843 -288.396744) (xy 425.698066 -288.34896) (xy 425.694106 -288.299906) (xy 425.355258 -288.299906)
			(xy 425.354763 -288.324513) (xy 425.346868 -288.37309) (xy 425.331284 -288.419771) (xy 425.308413 -288.463348)
			(xy 425.278848 -288.502692) (xy 425.243355 -288.536784) (xy 425.202852 -288.56474) (xy 425.15839 -288.585838)
			(xy 425.111119 -288.59953) (xy 425.062264 -288.605462) (xy 425.013089 -288.603481) (xy 424.96487 -288.593637)
			(xy 424.918854 -288.576185) (xy 424.876233 -288.551578) (xy 424.838112 -288.520453) (xy 424.805477 -288.483616)
			(xy 424.779174 -288.44202) (xy 424.759883 -288.396744) (xy 424.748106 -288.34896) (xy 424.744146 -288.299906)
			(xy 313.055 -288.299906) (xy 313.054505 -288.324513) (xy 313.04661 -288.37309) (xy 313.031026 -288.419771)
			(xy 313.008155 -288.463348) (xy 312.97859 -288.502692) (xy 312.943097 -288.536784) (xy 312.902594 -288.56474)
			(xy 312.858132 -288.585838) (xy 312.810861 -288.59953) (xy 312.762006 -288.605462) (xy 312.712831 -288.603481)
			(xy 312.664612 -288.593637) (xy 312.618596 -288.576185) (xy 312.575975 -288.551578) (xy 312.537854 -288.520453)
			(xy 312.505219 -288.483616) (xy 312.478916 -288.44202) (xy 312.459625 -288.396744) (xy 312.447848 -288.34896)
			(xy 312.443888 -288.299906) (xy 312.10504 -288.299906) (xy 312.104545 -288.324513) (xy 312.09665 -288.37309)
			(xy 312.081066 -288.419771) (xy 312.058195 -288.463348) (xy 312.02863 -288.502692) (xy 311.993137 -288.536784)
			(xy 311.952634 -288.56474) (xy 311.908172 -288.585838) (xy 311.860901 -288.59953) (xy 311.812046 -288.605462)
			(xy 311.762871 -288.603481) (xy 311.714652 -288.593637) (xy 311.668636 -288.576185) (xy 311.626015 -288.551578)
			(xy 311.587894 -288.520453) (xy 311.555259 -288.483616) (xy 311.528956 -288.44202) (xy 311.509665 -288.396744)
			(xy 311.497888 -288.34896) (xy 311.493928 -288.299906) (xy 310.20512 -288.299906) (xy 310.204625 -288.324513)
			(xy 310.19673 -288.37309) (xy 310.181146 -288.419771) (xy 310.158275 -288.463348) (xy 310.12871 -288.502692)
			(xy 310.093217 -288.536784) (xy 310.052714 -288.56474) (xy 310.008252 -288.585838) (xy 309.960981 -288.59953)
			(xy 309.912126 -288.605462) (xy 309.862951 -288.603481) (xy 309.814732 -288.593637) (xy 309.768716 -288.576185)
			(xy 309.726095 -288.551578) (xy 309.687974 -288.520453) (xy 309.655339 -288.483616) (xy 309.629036 -288.44202)
			(xy 309.609745 -288.396744) (xy 309.597968 -288.34896) (xy 309.594008 -288.299906) (xy 309.25516 -288.299906)
			(xy 309.254665 -288.324513) (xy 309.24677 -288.37309) (xy 309.231186 -288.419771) (xy 309.208315 -288.463348)
			(xy 309.17875 -288.502692) (xy 309.143257 -288.536784) (xy 309.102754 -288.56474) (xy 309.058292 -288.585838)
			(xy 309.011021 -288.59953) (xy 308.962166 -288.605462) (xy 308.912991 -288.603481) (xy 308.864772 -288.593637)
			(xy 308.818756 -288.576185) (xy 308.776135 -288.551578) (xy 308.738014 -288.520453) (xy 308.705379 -288.483616)
			(xy 308.679076 -288.44202) (xy 308.659785 -288.396744) (xy 308.648008 -288.34896) (xy 308.644048 -288.299906)
			(xy 196.955156 -288.299906) (xy 196.954661 -288.324513) (xy 196.946766 -288.37309) (xy 196.931182 -288.419771)
			(xy 196.908311 -288.463348) (xy 196.878746 -288.502692) (xy 196.843253 -288.536784) (xy 196.80275 -288.56474)
			(xy 196.758288 -288.585838) (xy 196.711017 -288.59953) (xy 196.662162 -288.605462) (xy 196.612987 -288.603481)
			(xy 196.564768 -288.593637) (xy 196.518752 -288.576185) (xy 196.476131 -288.551578) (xy 196.43801 -288.520453)
			(xy 196.405375 -288.483616) (xy 196.379072 -288.44202) (xy 196.359781 -288.396744) (xy 196.348004 -288.34896)
			(xy 196.344044 -288.299906) (xy 196.005196 -288.299906) (xy 196.004701 -288.324513) (xy 195.996806 -288.37309)
			(xy 195.981222 -288.419771) (xy 195.958351 -288.463348) (xy 195.928786 -288.502692) (xy 195.893293 -288.536784)
			(xy 195.85279 -288.56474) (xy 195.808328 -288.585838) (xy 195.761057 -288.59953) (xy 195.712202 -288.605462)
			(xy 195.663027 -288.603481) (xy 195.614808 -288.593637) (xy 195.568792 -288.576185) (xy 195.526171 -288.551578)
			(xy 195.48805 -288.520453) (xy 195.455415 -288.483616) (xy 195.429112 -288.44202) (xy 195.409821 -288.396744)
			(xy 195.398044 -288.34896) (xy 195.394084 -288.299906) (xy 194.105276 -288.299906) (xy 194.104781 -288.324513)
			(xy 194.096886 -288.37309) (xy 194.081302 -288.419771) (xy 194.058431 -288.463348) (xy 194.028866 -288.502692)
			(xy 193.993373 -288.536784) (xy 193.95287 -288.56474) (xy 193.908408 -288.585838) (xy 193.861137 -288.59953)
			(xy 193.812282 -288.605462) (xy 193.763107 -288.603481) (xy 193.714888 -288.593637) (xy 193.668872 -288.576185)
			(xy 193.626251 -288.551578) (xy 193.58813 -288.520453) (xy 193.555495 -288.483616) (xy 193.529192 -288.44202)
			(xy 193.509901 -288.396744) (xy 193.498124 -288.34896) (xy 193.494164 -288.299906) (xy 193.155316 -288.299906)
			(xy 193.154821 -288.324513) (xy 193.146926 -288.37309) (xy 193.131342 -288.419771) (xy 193.108471 -288.463348)
			(xy 193.078906 -288.502692) (xy 193.043413 -288.536784) (xy 193.00291 -288.56474) (xy 192.958448 -288.585838)
			(xy 192.911177 -288.59953) (xy 192.862322 -288.605462) (xy 192.813147 -288.603481) (xy 192.764928 -288.593637)
			(xy 192.718912 -288.576185) (xy 192.676291 -288.551578) (xy 192.63817 -288.520453) (xy 192.605535 -288.483616)
			(xy 192.579232 -288.44202) (xy 192.559941 -288.396744) (xy 192.548164 -288.34896) (xy 192.544204 -288.299906)
			(xy 80.855058 -288.299906) (xy 80.854563 -288.324513) (xy 80.846668 -288.37309) (xy 80.831084 -288.419771)
			(xy 80.808213 -288.463348) (xy 80.778648 -288.502692) (xy 80.743155 -288.536784) (xy 80.702652 -288.56474)
			(xy 80.65819 -288.585838) (xy 80.610919 -288.59953) (xy 80.562064 -288.605462) (xy 80.512889 -288.603481)
			(xy 80.46467 -288.593637) (xy 80.418654 -288.576185) (xy 80.376033 -288.551578) (xy 80.337912 -288.520453)
			(xy 80.305277 -288.483616) (xy 80.278974 -288.44202) (xy 80.259683 -288.396744) (xy 80.247906 -288.34896)
			(xy 80.243946 -288.299906) (xy 79.905098 -288.299906) (xy 79.904603 -288.324513) (xy 79.896708 -288.37309)
			(xy 79.881124 -288.419771) (xy 79.858253 -288.463348) (xy 79.828688 -288.502692) (xy 79.793195 -288.536784)
			(xy 79.752692 -288.56474) (xy 79.70823 -288.585838) (xy 79.660959 -288.59953) (xy 79.612104 -288.605462)
			(xy 79.562929 -288.603481) (xy 79.51471 -288.593637) (xy 79.468694 -288.576185) (xy 79.426073 -288.551578)
			(xy 79.387952 -288.520453) (xy 79.355317 -288.483616) (xy 79.329014 -288.44202) (xy 79.309723 -288.396744)
			(xy 79.297946 -288.34896) (xy 79.293986 -288.299906) (xy 78.005178 -288.299906) (xy 78.004683 -288.324513)
			(xy 77.996788 -288.37309) (xy 77.981204 -288.419771) (xy 77.958333 -288.463348) (xy 77.928768 -288.502692)
			(xy 77.893275 -288.536784) (xy 77.852772 -288.56474) (xy 77.80831 -288.585838) (xy 77.761039 -288.59953)
			(xy 77.712184 -288.605462) (xy 77.663009 -288.603481) (xy 77.61479 -288.593637) (xy 77.568774 -288.576185)
			(xy 77.526153 -288.551578) (xy 77.488032 -288.520453) (xy 77.455397 -288.483616) (xy 77.429094 -288.44202)
			(xy 77.409803 -288.396744) (xy 77.398026 -288.34896) (xy 77.394066 -288.299906) (xy 77.055218 -288.299906)
			(xy 77.054723 -288.324513) (xy 77.046828 -288.37309) (xy 77.031244 -288.419771) (xy 77.008373 -288.463348)
			(xy 76.978808 -288.502692) (xy 76.943315 -288.536784) (xy 76.902812 -288.56474) (xy 76.85835 -288.585838)
			(xy 76.811079 -288.59953) (xy 76.762224 -288.605462) (xy 76.713049 -288.603481) (xy 76.66483 -288.593637)
			(xy 76.618814 -288.576185) (xy 76.576193 -288.551578) (xy 76.538072 -288.520453) (xy 76.505437 -288.483616)
			(xy 76.479134 -288.44202) (xy 76.459843 -288.396744) (xy 76.448066 -288.34896) (xy 76.444106 -288.299906)
			(xy 0.509016 -288.299906) (xy 0.509016 -288.800413) (xy 36.0443 -288.800413) (xy 36.0443 -288.748387)
			(xy 36.052439 -288.697003) (xy 36.068516 -288.647524) (xy 36.092136 -288.60117) (xy 36.122718 -288.559082)
			(xy 36.159507 -288.522297) (xy 36.201598 -288.49172) (xy 36.247954 -288.468104) (xy 36.297434 -288.452031)
			(xy 36.348819 -288.443897) (xy 36.374832 -288.443416) (xy 37.324792 -288.443416) (xy 37.3508 -288.443943)
			(xy 37.402175 -288.452079) (xy 37.451646 -288.468151) (xy 37.497993 -288.491765) (xy 37.540075 -288.522339)
			(xy 37.576856 -288.559119) (xy 37.60743 -288.601201) (xy 37.631045 -288.647547) (xy 37.647119 -288.697017)
			(xy 37.655257 -288.748392) (xy 37.655257 -288.800408) (xy 37.655257 -288.800411) (xy 42.694299 -288.800411)
			(xy 42.694299 -288.748389) (xy 42.702438 -288.697007) (xy 42.718514 -288.64753) (xy 42.742132 -288.601178)
			(xy 42.77271 -288.559091) (xy 42.809496 -288.522306) (xy 42.851583 -288.491729) (xy 42.897936 -288.468111)
			(xy 42.947413 -288.452036) (xy 42.998795 -288.443899) (xy 43.024806 -288.443416) (xy 43.974766 -288.443416)
			(xy 44.000775 -288.443941) (xy 44.052154 -288.452074) (xy 44.101628 -288.468144) (xy 44.147978 -288.491757)
			(xy 44.190064 -288.52233) (xy 44.226848 -288.55911) (xy 44.257426 -288.601193) (xy 44.281043 -288.647541)
			(xy 44.297119 -288.697013) (xy 44.305257 -288.748391) (xy 44.305257 -288.800409) (xy 44.297119 -288.851787)
			(xy 44.281043 -288.901259) (xy 44.257426 -288.947607) (xy 44.226848 -288.98969) (xy 44.190064 -289.02647)
			(xy 44.147978 -289.057043) (xy 44.101628 -289.080656) (xy 44.052154 -289.096726) (xy 44.000775 -289.104859)
			(xy 43.974766 -289.10534) (xy 43.024806 -289.10534) (xy 42.998795 -289.104901) (xy 42.947413 -289.096764)
			(xy 42.897936 -289.080689) (xy 42.851583 -289.057071) (xy 42.809496 -289.026494) (xy 42.77271 -288.989709)
			(xy 42.742132 -288.947622) (xy 42.718514 -288.90127) (xy 42.702438 -288.851793) (xy 42.694299 -288.800411)
			(xy 37.655257 -288.800411) (xy 37.647119 -288.851783) (xy 37.631045 -288.901253) (xy 37.60743 -288.947599)
			(xy 37.576856 -288.989681) (xy 37.540075 -289.026461) (xy 37.497993 -289.057035) (xy 37.451646 -289.080649)
			(xy 37.402175 -289.096721) (xy 37.3508 -289.104857) (xy 37.324792 -289.10534) (xy 36.374832 -289.10534)
			(xy 36.348819 -289.104903) (xy 36.297434 -289.096769) (xy 36.247954 -289.080696) (xy 36.201598 -289.05708)
			(xy 36.159507 -289.026503) (xy 36.122718 -288.989718) (xy 36.092136 -288.94763) (xy 36.068516 -288.901276)
			(xy 36.052439 -288.851797) (xy 36.0443 -288.800413) (xy 0.509016 -288.800413) (xy 0.509016 -297.350788)
			(xy 36.044382 -297.350788) (xy 36.044382 -297.298812) (xy 36.052512 -297.247477) (xy 36.068572 -297.198045)
			(xy 36.092168 -297.151734) (xy 36.122717 -297.109685) (xy 36.159468 -297.072931) (xy 36.201516 -297.042379)
			(xy 36.247825 -297.018781) (xy 36.297255 -297.002717) (xy 36.34859 -296.994583) (xy 36.374578 -296.994072)
			(xy 37.324538 -296.994072) (xy 37.350522 -296.994624) (xy 37.401848 -297.002759) (xy 37.451271 -297.018822)
			(xy 37.497572 -297.042419) (xy 37.539613 -297.072968) (xy 37.576357 -297.109716) (xy 37.606901 -297.15176)
			(xy 37.630492 -297.198064) (xy 37.64655 -297.247489) (xy 37.654679 -297.298816) (xy 37.654679 -297.350784)
			(xy 37.654678 -297.350788) (xy 152.144482 -297.350788) (xy 152.144482 -297.298812) (xy 152.152612 -297.247477)
			(xy 152.168672 -297.198046) (xy 152.192268 -297.151735) (xy 152.222816 -297.109685) (xy 152.259567 -297.072932)
			(xy 152.301615 -297.04238) (xy 152.347923 -297.018782) (xy 152.397354 -297.002717) (xy 152.448688 -296.994583)
			(xy 152.474676 -296.994072) (xy 153.424636 -296.994072) (xy 153.45062 -296.994624) (xy 153.501947 -297.002759)
			(xy 153.55137 -297.018822) (xy 153.597671 -297.042418) (xy 153.639712 -297.072967) (xy 153.676457 -297.109715)
			(xy 153.707001 -297.151759) (xy 153.730592 -297.198064) (xy 153.74665 -297.247488) (xy 153.754779 -297.298816)
			(xy 153.754779 -297.350784) (xy 153.754778 -297.350792) (xy 268.244255 -297.350792) (xy 268.244255 -297.298808)
			(xy 268.252388 -297.247465) (xy 268.268452 -297.198025) (xy 268.292053 -297.151708) (xy 268.322609 -297.109653)
			(xy 268.359368 -297.072896) (xy 268.401425 -297.042342) (xy 268.447744 -297.018744) (xy 268.497184 -297.002683)
			(xy 268.548528 -296.994554) (xy 268.57452 -296.994072) (xy 269.52448 -296.994072) (xy 269.550469 -296.994594)
			(xy 269.601807 -297.002722) (xy 269.651241 -297.018781) (xy 269.697554 -297.042377) (xy 269.739606 -297.072927)
			(xy 269.77636 -297.109679) (xy 269.806913 -297.151729) (xy 269.830511 -297.198041) (xy 269.846573 -297.247474)
			(xy 269.854705 -297.298811) (xy 269.854705 -297.350789) (xy 269.854705 -297.350792) (xy 384.344355 -297.350792)
			(xy 384.344355 -297.298808) (xy 384.352488 -297.247465) (xy 384.368552 -297.198026) (xy 384.392153 -297.151709)
			(xy 384.422709 -297.109654) (xy 384.459467 -297.072897) (xy 384.501524 -297.042343) (xy 384.547842 -297.018745)
			(xy 384.597282 -297.002683) (xy 384.648626 -296.994554) (xy 384.674618 -296.994072) (xy 385.624578 -296.994072)
			(xy 385.650567 -296.994593) (xy 385.701905 -297.002721) (xy 385.751339 -297.018781) (xy 385.797653 -297.042376)
			(xy 385.839705 -297.072926) (xy 385.87646 -297.109678) (xy 385.907013 -297.151728) (xy 385.930611 -297.19804)
			(xy 385.946673 -297.247474) (xy 385.954805 -297.298811) (xy 385.954805 -297.350789) (xy 385.946673 -297.402126)
			(xy 385.930611 -297.45156) (xy 385.907013 -297.497872) (xy 385.87646 -297.539922) (xy 385.839705 -297.576674)
			(xy 385.797653 -297.607224) (xy 385.751339 -297.630819) (xy 385.701905 -297.646879) (xy 385.650567 -297.655007)
			(xy 385.624578 -297.655488) (xy 384.674618 -297.655488) (xy 384.648626 -297.655046) (xy 384.597282 -297.646917)
			(xy 384.547842 -297.630855) (xy 384.501524 -297.607257) (xy 384.459467 -297.576703) (xy 384.422709 -297.539946)
			(xy 384.392153 -297.497891) (xy 384.368552 -297.451574) (xy 384.352488 -297.402135) (xy 384.344355 -297.350792)
			(xy 269.854705 -297.350792) (xy 269.846573 -297.402126) (xy 269.830511 -297.451559) (xy 269.806913 -297.497871)
			(xy 269.77636 -297.539921) (xy 269.739606 -297.576673) (xy 269.697554 -297.607223) (xy 269.651241 -297.630819)
			(xy 269.601807 -297.646878) (xy 269.550469 -297.655006) (xy 269.52448 -297.655488) (xy 268.57452 -297.655488)
			(xy 268.548528 -297.655046) (xy 268.497184 -297.646917) (xy 268.447744 -297.630856) (xy 268.401425 -297.607258)
			(xy 268.359368 -297.576704) (xy 268.322609 -297.539947) (xy 268.292053 -297.497892) (xy 268.268452 -297.451575)
			(xy 268.252388 -297.402135) (xy 268.244255 -297.350792) (xy 153.754778 -297.350792) (xy 153.74665 -297.402112)
			(xy 153.730592 -297.451536) (xy 153.707001 -297.497841) (xy 153.676457 -297.539885) (xy 153.639712 -297.576633)
			(xy 153.597671 -297.607182) (xy 153.55137 -297.630778) (xy 153.501947 -297.646841) (xy 153.45062 -297.654976)
			(xy 153.424636 -297.655488) (xy 152.474676 -297.655488) (xy 152.448688 -297.655017) (xy 152.397354 -297.646883)
			(xy 152.347923 -297.630818) (xy 152.301615 -297.60722) (xy 152.259567 -297.576668) (xy 152.222816 -297.539915)
			(xy 152.192268 -297.497865) (xy 152.168672 -297.451554) (xy 152.152612 -297.402123) (xy 152.144482 -297.350788)
			(xy 37.654678 -297.350788) (xy 37.64655 -297.402111) (xy 37.630492 -297.451536) (xy 37.606901 -297.49784)
			(xy 37.576357 -297.539884) (xy 37.539613 -297.576632) (xy 37.497572 -297.607181) (xy 37.451271 -297.630778)
			(xy 37.401848 -297.646841) (xy 37.350522 -297.654976) (xy 37.324538 -297.655488) (xy 36.374578 -297.655488)
			(xy 36.34859 -297.655017) (xy 36.297255 -297.646883) (xy 36.247825 -297.630819) (xy 36.201516 -297.607221)
			(xy 36.159468 -297.576669) (xy 36.122717 -297.539915) (xy 36.092168 -297.497866) (xy 36.068572 -297.451555)
			(xy 36.052512 -297.402123) (xy 36.044382 -297.350788) (xy 0.509016 -297.350788) (xy 0.509016 -298.77569)
			(xy 39.369695 -298.77569) (xy 39.369695 -298.72371) (xy 39.377827 -298.67237) (xy 39.393891 -298.622935)
			(xy 39.417492 -298.576621) (xy 39.448047 -298.53457) (xy 39.484805 -298.497817) (xy 39.52686 -298.467268)
			(xy 39.573177 -298.443674) (xy 39.622615 -298.427617) (xy 39.673956 -298.419492) (xy 39.699946 -298.419012)
			(xy 40.649906 -298.419012) (xy 40.675894 -298.419482) (xy 40.727231 -298.427614) (xy 40.776664 -298.443676)
			(xy 40.822975 -298.467274) (xy 40.865025 -298.497826) (xy 40.901778 -298.534579) (xy 40.932329 -298.57663)
			(xy 40.955926 -298.622942) (xy 40.971988 -298.672375) (xy 40.980118 -298.723712) (xy 40.980118 -298.775685)
			(xy 387.669821 -298.775685) (xy 387.669821 -298.723715) (xy 387.677951 -298.672385) (xy 387.69401 -298.622959)
			(xy 387.717603 -298.576653) (xy 387.74815 -298.534608) (xy 387.784897 -298.497859) (xy 387.826941 -298.467311)
			(xy 387.873246 -298.443716) (xy 387.922671 -298.427654) (xy 387.974001 -298.419523) (xy 387.999986 -298.419012)
			(xy 388.949946 -298.419012) (xy 388.975932 -298.419485) (xy 389.027264 -298.427622) (xy 389.076692 -298.443688)
			(xy 389.122998 -298.467288) (xy 389.165042 -298.49784) (xy 389.20179 -298.534593) (xy 389.232337 -298.576642)
			(xy 389.25593 -298.622951) (xy 389.271989 -298.67238) (xy 389.280119 -298.723714) (xy 389.280119 -298.775686)
			(xy 389.271989 -298.82702) (xy 389.25593 -298.876449) (xy 389.232337 -298.922758) (xy 389.20179 -298.964807)
			(xy 389.165042 -299.00156) (xy 389.122998 -299.032112) (xy 389.076692 -299.055712) (xy 389.027264 -299.071778)
			(xy 388.975932 -299.079915) (xy 388.949946 -299.080428) (xy 387.999986 -299.080428) (xy 387.974001 -299.079877)
			(xy 387.922671 -299.071746) (xy 387.873246 -299.055684) (xy 387.826941 -299.032089) (xy 387.784897 -299.001541)
			(xy 387.74815 -298.964792) (xy 387.717603 -298.922747) (xy 387.69401 -298.876441) (xy 387.677951 -298.827015)
			(xy 387.669821 -298.775685) (xy 40.980118 -298.775685) (xy 40.980118 -298.775688) (xy 40.971988 -298.827025)
			(xy 40.955926 -298.876458) (xy 40.932329 -298.92277) (xy 40.901778 -298.964821) (xy 40.865025 -299.001574)
			(xy 40.822975 -299.032126) (xy 40.776664 -299.055724) (xy 40.727231 -299.071786) (xy 40.675894 -299.079918)
			(xy 40.649906 -299.080428) (xy 39.699946 -299.080428) (xy 39.673956 -299.079908) (xy 39.622615 -299.071783)
			(xy 39.573177 -299.055726) (xy 39.52686 -299.032132) (xy 39.484805 -299.001583) (xy 39.448047 -298.96483)
			(xy 39.417492 -298.922779) (xy 39.393891 -298.876465) (xy 39.377827 -298.82703) (xy 39.369695 -298.77569)
			(xy 0.509016 -298.77569) (xy 0.509016 -299.25101) (xy 36.044102 -299.25101) (xy 36.044102 -299.19899)
			(xy 36.052239 -299.147611) (xy 36.068313 -299.098138) (xy 36.091929 -299.051788) (xy 36.122504 -299.009703)
			(xy 36.159286 -298.972918) (xy 36.201369 -298.94234) (xy 36.247718 -298.918722) (xy 36.29719 -298.902644)
			(xy 36.348568 -298.894504) (xy 36.374578 -298.893992) (xy 37.324538 -298.893992) (xy 37.35054 -298.894597)
			(xy 37.401902 -298.902737) (xy 37.451358 -298.918812) (xy 37.497691 -298.942425) (xy 37.539761 -298.972994)
			(xy 37.576531 -299.009768) (xy 37.607095 -299.051841) (xy 37.630703 -299.098177) (xy 37.646771 -299.147635)
			(xy 37.654906 -299.198998) (xy 37.654906 -299.251002) (xy 37.654905 -299.25101) (xy 152.144202 -299.25101)
			(xy 152.144202 -299.19899) (xy 152.152339 -299.147612) (xy 152.168413 -299.098138) (xy 152.192028 -299.051788)
			(xy 152.222603 -299.009703) (xy 152.259385 -298.972919) (xy 152.301468 -298.942341) (xy 152.347816 -298.918722)
			(xy 152.397288 -298.902645) (xy 152.448666 -298.894504) (xy 152.474676 -298.893992) (xy 153.424636 -298.893992)
			(xy 153.450638 -298.894597) (xy 153.502 -298.902737) (xy 153.551457 -298.918811) (xy 153.59779 -298.942424)
			(xy 153.63986 -298.972993) (xy 153.67663 -299.009767) (xy 153.707195 -299.05184) (xy 153.730803 -299.098177)
			(xy 153.746871 -299.147635) (xy 153.755006 -299.198998) (xy 153.755006 -299.251002) (xy 153.755005 -299.251009)
			(xy 154.994602 -299.251009) (xy 154.994602 -299.198991) (xy 155.002739 -299.147613) (xy 155.018812 -299.098141)
			(xy 155.042426 -299.051792) (xy 155.073 -299.009707) (xy 155.10978 -298.972923) (xy 155.151861 -298.942345)
			(xy 155.198208 -298.918726) (xy 155.247678 -298.902647) (xy 155.299055 -298.894505) (xy 155.325064 -298.893992)
			(xy 156.275024 -298.893992) (xy 156.301026 -298.894596) (xy 156.35239 -298.902735) (xy 156.401848 -298.918808)
			(xy 156.448184 -298.94242) (xy 156.490255 -298.972989) (xy 156.527026 -299.009763) (xy 156.557593 -299.051837)
			(xy 156.581201 -299.098174) (xy 156.597271 -299.147633) (xy 156.605406 -299.198998) (xy 156.605406 -299.251002)
			(xy 156.605404 -299.251014) (xy 268.243976 -299.251014) (xy 268.243976 -299.198986) (xy 268.252115 -299.147599)
			(xy 268.268193 -299.098118) (xy 268.291814 -299.051761) (xy 268.322396 -299.009671) (xy 268.359186 -298.972883)
			(xy 268.401279 -298.942303) (xy 268.447637 -298.918685) (xy 268.497119 -298.90261) (xy 268.548506 -298.894474)
			(xy 268.57452 -298.893992) (xy 269.52448 -298.893992) (xy 269.550487 -298.894566) (xy 269.60186 -298.9027)
			(xy 269.651328 -298.91877) (xy 269.697673 -298.942382) (xy 269.739754 -298.972953) (xy 269.776534 -299.009731)
			(xy 269.807108 -299.05181) (xy 269.830722 -299.098153) (xy 269.846796 -299.147621) (xy 269.854933 -299.198993)
			(xy 269.854933 -299.251007) (xy 269.854932 -299.251013) (xy 271.094376 -299.251013) (xy 271.094376 -299.198987)
			(xy 271.102514 -299.147601) (xy 271.118592 -299.098121) (xy 271.142212 -299.051765) (xy 271.172792 -299.009675)
			(xy 271.209581 -298.972887) (xy 271.251672 -298.942307) (xy 271.298028 -298.918689) (xy 271.347509 -298.902613)
			(xy 271.398895 -298.894475) (xy 271.424908 -298.893992) (xy 272.374868 -298.893992) (xy 272.400875 -298.894565)
			(xy 272.45225 -298.902697) (xy 272.50172 -298.918767) (xy 272.548067 -298.942378) (xy 272.590149 -298.972949)
			(xy 272.626931 -299.009727) (xy 272.657506 -299.051806) (xy 272.681121 -299.09815) (xy 272.697195 -299.147619)
			(xy 272.705333 -299.198993) (xy 272.705333 -299.251007) (xy 272.705332 -299.251014) (xy 384.344076 -299.251014)
			(xy 384.344076 -299.198986) (xy 384.352215 -299.147599) (xy 384.368293 -299.098118) (xy 384.391913 -299.051762)
			(xy 384.422495 -299.009672) (xy 384.459285 -298.972884) (xy 384.501377 -298.942304) (xy 384.547735 -298.918686)
			(xy 384.597217 -298.902611) (xy 384.648604 -298.894474) (xy 384.674618 -298.893992) (xy 385.624578 -298.893992)
			(xy 385.650585 -298.894566) (xy 385.701958 -298.902699) (xy 385.751427 -298.91877) (xy 385.797772 -298.942381)
			(xy 385.839853 -298.972952) (xy 385.876634 -299.00973) (xy 385.907207 -299.051809) (xy 385.930822 -299.098153)
			(xy 385.946896 -299.14762) (xy 385.955033 -299.198993) (xy 385.955033 -299.251007) (xy 385.946896 -299.30238)
			(xy 385.930822 -299.351847) (xy 385.907207 -299.398191) (xy 385.876634 -299.44027) (xy 385.839853 -299.477048)
			(xy 385.797772 -299.507619) (xy 385.751427 -299.53123) (xy 385.701958 -299.547301) (xy 385.650585 -299.555434)
			(xy 385.624578 -299.555916) (xy 384.674618 -299.555916) (xy 384.648604 -299.555526) (xy 384.597217 -299.547389)
			(xy 384.547735 -299.531314) (xy 384.501377 -299.507696) (xy 384.459285 -299.477116) (xy 384.422495 -299.440328)
			(xy 384.391913 -299.398238) (xy 384.368293 -299.351882) (xy 384.352215 -299.302401) (xy 384.344076 -299.251014)
			(xy 272.705332 -299.251014) (xy 272.697195 -299.302381) (xy 272.681121 -299.35185) (xy 272.657506 -299.398194)
			(xy 272.626931 -299.440273) (xy 272.590149 -299.477051) (xy 272.548067 -299.507622) (xy 272.50172 -299.531233)
			(xy 272.45225 -299.547303) (xy 272.400875 -299.555435) (xy 272.374868 -299.555916) (xy 271.424908 -299.555916)
			(xy 271.398895 -299.555525) (xy 271.347509 -299.547387) (xy 271.298028 -299.531311) (xy 271.251672 -299.507693)
			(xy 271.209581 -299.477113) (xy 271.172792 -299.440325) (xy 271.142212 -299.398235) (xy 271.118592 -299.351879)
			(xy 271.102514 -299.302399) (xy 271.094376 -299.251013) (xy 269.854932 -299.251013) (xy 269.846796 -299.302379)
			(xy 269.830722 -299.351847) (xy 269.807108 -299.39819) (xy 269.776534 -299.440269) (xy 269.739754 -299.477047)
			(xy 269.697673 -299.507618) (xy 269.651328 -299.53123) (xy 269.60186 -299.5473) (xy 269.550487 -299.555434)
			(xy 269.52448 -299.555916) (xy 268.57452 -299.555916) (xy 268.548506 -299.555526) (xy 268.497119 -299.54739)
			(xy 268.447637 -299.531315) (xy 268.401279 -299.507697) (xy 268.359186 -299.477117) (xy 268.322396 -299.440329)
			(xy 268.291814 -299.398239) (xy 268.268193 -299.351882) (xy 268.252115 -299.302401) (xy 268.243976 -299.251014)
			(xy 156.605404 -299.251014) (xy 156.597271 -299.302367) (xy 156.581201 -299.351826) (xy 156.557593 -299.398163)
			(xy 156.527026 -299.440237) (xy 156.490255 -299.477011) (xy 156.448184 -299.50758) (xy 156.401848 -299.531192)
			(xy 156.35239 -299.547265) (xy 156.301026 -299.555404) (xy 156.275024 -299.555916) (xy 155.325064 -299.555916)
			(xy 155.299055 -299.555495) (xy 155.247678 -299.547353) (xy 155.198208 -299.531274) (xy 155.151861 -299.507655)
			(xy 155.10978 -299.477077) (xy 155.073 -299.440293) (xy 155.042426 -299.398208) (xy 155.018812 -299.351859)
			(xy 155.002739 -299.302387) (xy 154.994602 -299.251009) (xy 153.755005 -299.251009) (xy 153.746871 -299.302365)
			(xy 153.730803 -299.351823) (xy 153.707195 -299.39816) (xy 153.67663 -299.440233) (xy 153.63986 -299.477007)
			(xy 153.59779 -299.507576) (xy 153.551457 -299.531189) (xy 153.502 -299.547263) (xy 153.450638 -299.555403)
			(xy 153.424636 -299.555916) (xy 152.474676 -299.555916) (xy 152.448666 -299.555496) (xy 152.397288 -299.547355)
			(xy 152.347816 -299.531278) (xy 152.301468 -299.507659) (xy 152.259385 -299.477081) (xy 152.222603 -299.440297)
			(xy 152.192028 -299.398212) (xy 152.168413 -299.351862) (xy 152.152339 -299.302388) (xy 152.144202 -299.25101)
			(xy 37.654905 -299.25101) (xy 37.646771 -299.302365) (xy 37.630703 -299.351823) (xy 37.607095 -299.398159)
			(xy 37.576531 -299.440232) (xy 37.539761 -299.477006) (xy 37.497691 -299.507575) (xy 37.451358 -299.531188)
			(xy 37.401902 -299.547263) (xy 37.35054 -299.555403) (xy 37.324538 -299.555916) (xy 36.374578 -299.555916)
			(xy 36.348568 -299.555496) (xy 36.29719 -299.547356) (xy 36.247718 -299.531278) (xy 36.201369 -299.50766)
			(xy 36.159286 -299.477082) (xy 36.122504 -299.440297) (xy 36.091929 -299.398212) (xy 36.068313 -299.351862)
			(xy 36.052239 -299.302389) (xy 36.044102 -299.25101) (xy 0.509016 -299.25101) (xy 0.509016 -301.599854)
			(xy 38.444182 -301.599854) (xy 38.448142 -301.5508) (xy 38.459919 -301.503016) (xy 38.47921 -301.45774)
			(xy 38.505513 -301.416144) (xy 38.538148 -301.379307) (xy 38.576269 -301.348182) (xy 38.61889 -301.323575)
			(xy 38.664906 -301.306123) (xy 38.713125 -301.296279) (xy 38.7623 -301.294298) (xy 38.811155 -301.30023)
			(xy 38.858426 -301.313922) (xy 38.902888 -301.33502) (xy 38.943391 -301.362976) (xy 38.978884 -301.397068)
			(xy 39.008449 -301.436412) (xy 39.03132 -301.479989) (xy 39.046904 -301.52667) (xy 39.054799 -301.575247)
			(xy 39.055294 -301.599854) (xy 39.394142 -301.599854) (xy 39.398102 -301.5508) (xy 39.409879 -301.503016)
			(xy 39.42917 -301.45774) (xy 39.455473 -301.416144) (xy 39.488108 -301.379307) (xy 39.526229 -301.348182)
			(xy 39.56885 -301.323575) (xy 39.614866 -301.306123) (xy 39.663085 -301.296279) (xy 39.71226 -301.294298)
			(xy 39.761115 -301.30023) (xy 39.808386 -301.313922) (xy 39.852848 -301.33502) (xy 39.893351 -301.362976)
			(xy 39.928844 -301.397068) (xy 39.958409 -301.436412) (xy 39.98128 -301.479989) (xy 39.996864 -301.52667)
			(xy 40.004759 -301.575247) (xy 40.005254 -301.599854) (xy 41.294062 -301.599854) (xy 41.298022 -301.5508)
			(xy 41.309799 -301.503016) (xy 41.32909 -301.45774) (xy 41.355393 -301.416144) (xy 41.388028 -301.379307)
			(xy 41.426149 -301.348182) (xy 41.46877 -301.323575) (xy 41.514786 -301.306123) (xy 41.563005 -301.296279)
			(xy 41.61218 -301.294298) (xy 41.661035 -301.30023) (xy 41.708306 -301.313922) (xy 41.752768 -301.33502)
			(xy 41.793271 -301.362976) (xy 41.828764 -301.397068) (xy 41.858329 -301.436412) (xy 41.8812 -301.479989)
			(xy 41.896784 -301.52667) (xy 41.904679 -301.575247) (xy 41.905174 -301.599854) (xy 42.244022 -301.599854)
			(xy 42.247982 -301.5508) (xy 42.259759 -301.503016) (xy 42.27905 -301.45774) (xy 42.305353 -301.416144)
			(xy 42.337988 -301.379307) (xy 42.376109 -301.348182) (xy 42.41873 -301.323575) (xy 42.464746 -301.306123)
			(xy 42.512965 -301.296279) (xy 42.56214 -301.294298) (xy 42.610995 -301.30023) (xy 42.658266 -301.313922)
			(xy 42.702728 -301.33502) (xy 42.743231 -301.362976) (xy 42.778724 -301.397068) (xy 42.808289 -301.436412)
			(xy 42.83116 -301.479989) (xy 42.846744 -301.52667) (xy 42.854639 -301.575247) (xy 42.855134 -301.599854)
			(xy 154.54428 -301.599854) (xy 154.54824 -301.5508) (xy 154.560017 -301.503016) (xy 154.579308 -301.45774)
			(xy 154.605611 -301.416144) (xy 154.638246 -301.379307) (xy 154.676367 -301.348182) (xy 154.718988 -301.323575)
			(xy 154.765004 -301.306123) (xy 154.813223 -301.296279) (xy 154.862398 -301.294298) (xy 154.911253 -301.30023)
			(xy 154.958524 -301.313922) (xy 155.002986 -301.33502) (xy 155.043489 -301.362976) (xy 155.078982 -301.397068)
			(xy 155.108547 -301.436412) (xy 155.131418 -301.479989) (xy 155.147002 -301.52667) (xy 155.154897 -301.575247)
			(xy 155.155392 -301.599854) (xy 155.49424 -301.599854) (xy 155.4982 -301.5508) (xy 155.509977 -301.503016)
			(xy 155.529268 -301.45774) (xy 155.555571 -301.416144) (xy 155.588206 -301.379307) (xy 155.626327 -301.348182)
			(xy 155.668948 -301.323575) (xy 155.714964 -301.306123) (xy 155.763183 -301.296279) (xy 155.812358 -301.294298)
			(xy 155.861213 -301.30023) (xy 155.908484 -301.313922) (xy 155.952946 -301.33502) (xy 155.993449 -301.362976)
			(xy 156.028942 -301.397068) (xy 156.058507 -301.436412) (xy 156.081378 -301.479989) (xy 156.096962 -301.52667)
			(xy 156.104857 -301.575247) (xy 156.105352 -301.599854) (xy 157.39416 -301.599854) (xy 157.39812 -301.5508)
			(xy 157.409897 -301.503016) (xy 157.429188 -301.45774) (xy 157.455491 -301.416144) (xy 157.488126 -301.379307)
			(xy 157.526247 -301.348182) (xy 157.568868 -301.323575) (xy 157.614884 -301.306123) (xy 157.663103 -301.296279)
			(xy 157.712278 -301.294298) (xy 157.761133 -301.30023) (xy 157.808404 -301.313922) (xy 157.852866 -301.33502)
			(xy 157.893369 -301.362976) (xy 157.928862 -301.397068) (xy 157.958427 -301.436412) (xy 157.981298 -301.479989)
			(xy 157.996882 -301.52667) (xy 158.004777 -301.575247) (xy 158.005272 -301.599854) (xy 158.34412 -301.599854)
			(xy 158.34808 -301.5508) (xy 158.359857 -301.503016) (xy 158.379148 -301.45774) (xy 158.405451 -301.416144)
			(xy 158.438086 -301.379307) (xy 158.476207 -301.348182) (xy 158.518828 -301.323575) (xy 158.564844 -301.306123)
			(xy 158.613063 -301.296279) (xy 158.662238 -301.294298) (xy 158.711093 -301.30023) (xy 158.758364 -301.313922)
			(xy 158.802826 -301.33502) (xy 158.843329 -301.362976) (xy 158.878822 -301.397068) (xy 158.908387 -301.436412)
			(xy 158.931258 -301.479989) (xy 158.946842 -301.52667) (xy 158.954737 -301.575247) (xy 158.955232 -301.599854)
			(xy 270.644124 -301.599854) (xy 270.648084 -301.5508) (xy 270.659861 -301.503016) (xy 270.679152 -301.45774)
			(xy 270.705455 -301.416144) (xy 270.73809 -301.379307) (xy 270.776211 -301.348182) (xy 270.818832 -301.323575)
			(xy 270.864848 -301.306123) (xy 270.913067 -301.296279) (xy 270.962242 -301.294298) (xy 271.011097 -301.30023)
			(xy 271.058368 -301.313922) (xy 271.10283 -301.33502) (xy 271.143333 -301.362976) (xy 271.178826 -301.397068)
			(xy 271.208391 -301.436412) (xy 271.231262 -301.479989) (xy 271.246846 -301.52667) (xy 271.254741 -301.575247)
			(xy 271.255236 -301.599854) (xy 271.594084 -301.599854) (xy 271.598044 -301.5508) (xy 271.609821 -301.503016)
			(xy 271.629112 -301.45774) (xy 271.655415 -301.416144) (xy 271.68805 -301.379307) (xy 271.726171 -301.348182)
			(xy 271.768792 -301.323575) (xy 271.814808 -301.306123) (xy 271.863027 -301.296279) (xy 271.912202 -301.294298)
			(xy 271.961057 -301.30023) (xy 272.008328 -301.313922) (xy 272.05279 -301.33502) (xy 272.093293 -301.362976)
			(xy 272.128786 -301.397068) (xy 272.158351 -301.436412) (xy 272.181222 -301.479989) (xy 272.196806 -301.52667)
			(xy 272.204701 -301.575247) (xy 272.205196 -301.599854) (xy 273.494004 -301.599854) (xy 273.497964 -301.5508)
			(xy 273.509741 -301.503016) (xy 273.529032 -301.45774) (xy 273.555335 -301.416144) (xy 273.58797 -301.379307)
			(xy 273.626091 -301.348182) (xy 273.668712 -301.323575) (xy 273.714728 -301.306123) (xy 273.762947 -301.296279)
			(xy 273.812122 -301.294298) (xy 273.860977 -301.30023) (xy 273.908248 -301.313922) (xy 273.95271 -301.33502)
			(xy 273.993213 -301.362976) (xy 274.028706 -301.397068) (xy 274.058271 -301.436412) (xy 274.081142 -301.479989)
			(xy 274.096726 -301.52667) (xy 274.104621 -301.575247) (xy 274.105116 -301.599854) (xy 274.443964 -301.599854)
			(xy 274.447924 -301.5508) (xy 274.459701 -301.503016) (xy 274.478992 -301.45774) (xy 274.505295 -301.416144)
			(xy 274.53793 -301.379307) (xy 274.576051 -301.348182) (xy 274.618672 -301.323575) (xy 274.664688 -301.306123)
			(xy 274.712907 -301.296279) (xy 274.762082 -301.294298) (xy 274.810937 -301.30023) (xy 274.858208 -301.313922)
			(xy 274.90267 -301.33502) (xy 274.943173 -301.362976) (xy 274.978666 -301.397068) (xy 275.008231 -301.436412)
			(xy 275.031102 -301.479989) (xy 275.046686 -301.52667) (xy 275.054581 -301.575247) (xy 275.055076 -301.599854)
			(xy 386.744222 -301.599854) (xy 386.748182 -301.5508) (xy 386.759959 -301.503016) (xy 386.77925 -301.45774)
			(xy 386.805553 -301.416144) (xy 386.838188 -301.379307) (xy 386.876309 -301.348182) (xy 386.91893 -301.323575)
			(xy 386.964946 -301.306123) (xy 387.013165 -301.296279) (xy 387.06234 -301.294298) (xy 387.111195 -301.30023)
			(xy 387.158466 -301.313922) (xy 387.202928 -301.33502) (xy 387.243431 -301.362976) (xy 387.278924 -301.397068)
			(xy 387.308489 -301.436412) (xy 387.33136 -301.479989) (xy 387.346944 -301.52667) (xy 387.354839 -301.575247)
			(xy 387.355334 -301.599854) (xy 387.694182 -301.599854) (xy 387.698142 -301.5508) (xy 387.709919 -301.503016)
			(xy 387.72921 -301.45774) (xy 387.755513 -301.416144) (xy 387.788148 -301.379307) (xy 387.826269 -301.348182)
			(xy 387.86889 -301.323575) (xy 387.914906 -301.306123) (xy 387.963125 -301.296279) (xy 388.0123 -301.294298)
			(xy 388.061155 -301.30023) (xy 388.108426 -301.313922) (xy 388.152888 -301.33502) (xy 388.193391 -301.362976)
			(xy 388.228884 -301.397068) (xy 388.258449 -301.436412) (xy 388.28132 -301.479989) (xy 388.296904 -301.52667)
			(xy 388.304799 -301.575247) (xy 388.305294 -301.599854) (xy 389.594102 -301.599854) (xy 389.598062 -301.5508)
			(xy 389.609839 -301.503016) (xy 389.62913 -301.45774) (xy 389.655433 -301.416144) (xy 389.688068 -301.379307)
			(xy 389.726189 -301.348182) (xy 389.76881 -301.323575) (xy 389.814826 -301.306123) (xy 389.863045 -301.296279)
			(xy 389.91222 -301.294298) (xy 389.961075 -301.30023) (xy 390.008346 -301.313922) (xy 390.052808 -301.33502)
			(xy 390.093311 -301.362976) (xy 390.128804 -301.397068) (xy 390.158369 -301.436412) (xy 390.18124 -301.479989)
			(xy 390.196824 -301.52667) (xy 390.204719 -301.575247) (xy 390.205214 -301.599854) (xy 390.544062 -301.599854)
			(xy 390.548022 -301.5508) (xy 390.559799 -301.503016) (xy 390.57909 -301.45774) (xy 390.605393 -301.416144)
			(xy 390.638028 -301.379307) (xy 390.676149 -301.348182) (xy 390.71877 -301.323575) (xy 390.764786 -301.306123)
			(xy 390.813005 -301.296279) (xy 390.86218 -301.294298) (xy 390.911035 -301.30023) (xy 390.958306 -301.313922)
			(xy 391.002768 -301.33502) (xy 391.043271 -301.362976) (xy 391.078764 -301.397068) (xy 391.108329 -301.436412)
			(xy 391.1312 -301.479989) (xy 391.146784 -301.52667) (xy 391.154679 -301.575247) (xy 391.155174 -301.599854)
			(xy 391.154679 -301.624461) (xy 391.146784 -301.673038) (xy 391.1312 -301.719719) (xy 391.108329 -301.763296)
			(xy 391.078764 -301.80264) (xy 391.043271 -301.836732) (xy 391.002768 -301.864688) (xy 390.958306 -301.885786)
			(xy 390.911035 -301.899478) (xy 390.86218 -301.90541) (xy 390.813005 -301.903429) (xy 390.764786 -301.893585)
			(xy 390.71877 -301.876133) (xy 390.676149 -301.851526) (xy 390.638028 -301.820401) (xy 390.605393 -301.783564)
			(xy 390.57909 -301.741968) (xy 390.559799 -301.696692) (xy 390.548022 -301.648908) (xy 390.544062 -301.599854)
			(xy 390.205214 -301.599854) (xy 390.204719 -301.624461) (xy 390.196824 -301.673038) (xy 390.18124 -301.719719)
			(xy 390.158369 -301.763296) (xy 390.128804 -301.80264) (xy 390.093311 -301.836732) (xy 390.052808 -301.864688)
			(xy 390.008346 -301.885786) (xy 389.961075 -301.899478) (xy 389.91222 -301.90541) (xy 389.863045 -301.903429)
			(xy 389.814826 -301.893585) (xy 389.76881 -301.876133) (xy 389.726189 -301.851526) (xy 389.688068 -301.820401)
			(xy 389.655433 -301.783564) (xy 389.62913 -301.741968) (xy 389.609839 -301.696692) (xy 389.598062 -301.648908)
			(xy 389.594102 -301.599854) (xy 388.305294 -301.599854) (xy 388.304799 -301.624461) (xy 388.296904 -301.673038)
			(xy 388.28132 -301.719719) (xy 388.258449 -301.763296) (xy 388.228884 -301.80264) (xy 388.193391 -301.836732)
			(xy 388.152888 -301.864688) (xy 388.108426 -301.885786) (xy 388.061155 -301.899478) (xy 388.0123 -301.90541)
			(xy 387.963125 -301.903429) (xy 387.914906 -301.893585) (xy 387.86889 -301.876133) (xy 387.826269 -301.851526)
			(xy 387.788148 -301.820401) (xy 387.755513 -301.783564) (xy 387.72921 -301.741968) (xy 387.709919 -301.696692)
			(xy 387.698142 -301.648908) (xy 387.694182 -301.599854) (xy 387.355334 -301.599854) (xy 387.354839 -301.624461)
			(xy 387.346944 -301.673038) (xy 387.33136 -301.719719) (xy 387.308489 -301.763296) (xy 387.278924 -301.80264)
			(xy 387.243431 -301.836732) (xy 387.202928 -301.864688) (xy 387.158466 -301.885786) (xy 387.111195 -301.899478)
			(xy 387.06234 -301.90541) (xy 387.013165 -301.903429) (xy 386.964946 -301.893585) (xy 386.91893 -301.876133)
			(xy 386.876309 -301.851526) (xy 386.838188 -301.820401) (xy 386.805553 -301.783564) (xy 386.77925 -301.741968)
			(xy 386.759959 -301.696692) (xy 386.748182 -301.648908) (xy 386.744222 -301.599854) (xy 275.055076 -301.599854)
			(xy 275.054581 -301.624461) (xy 275.046686 -301.673038) (xy 275.031102 -301.719719) (xy 275.008231 -301.763296)
			(xy 274.978666 -301.80264) (xy 274.943173 -301.836732) (xy 274.90267 -301.864688) (xy 274.858208 -301.885786)
			(xy 274.810937 -301.899478) (xy 274.762082 -301.90541) (xy 274.712907 -301.903429) (xy 274.664688 -301.893585)
			(xy 274.618672 -301.876133) (xy 274.576051 -301.851526) (xy 274.53793 -301.820401) (xy 274.505295 -301.783564)
			(xy 274.478992 -301.741968) (xy 274.459701 -301.696692) (xy 274.447924 -301.648908) (xy 274.443964 -301.599854)
			(xy 274.105116 -301.599854) (xy 274.104621 -301.624461) (xy 274.096726 -301.673038) (xy 274.081142 -301.719719)
			(xy 274.058271 -301.763296) (xy 274.028706 -301.80264) (xy 273.993213 -301.836732) (xy 273.95271 -301.864688)
			(xy 273.908248 -301.885786) (xy 273.860977 -301.899478) (xy 273.812122 -301.90541) (xy 273.762947 -301.903429)
			(xy 273.714728 -301.893585) (xy 273.668712 -301.876133) (xy 273.626091 -301.851526) (xy 273.58797 -301.820401)
			(xy 273.555335 -301.783564) (xy 273.529032 -301.741968) (xy 273.509741 -301.696692) (xy 273.497964 -301.648908)
			(xy 273.494004 -301.599854) (xy 272.205196 -301.599854) (xy 272.204701 -301.624461) (xy 272.196806 -301.673038)
			(xy 272.181222 -301.719719) (xy 272.158351 -301.763296) (xy 272.128786 -301.80264) (xy 272.093293 -301.836732)
			(xy 272.05279 -301.864688) (xy 272.008328 -301.885786) (xy 271.961057 -301.899478) (xy 271.912202 -301.90541)
			(xy 271.863027 -301.903429) (xy 271.814808 -301.893585) (xy 271.768792 -301.876133) (xy 271.726171 -301.851526)
			(xy 271.68805 -301.820401) (xy 271.655415 -301.783564) (xy 271.629112 -301.741968) (xy 271.609821 -301.696692)
			(xy 271.598044 -301.648908) (xy 271.594084 -301.599854) (xy 271.255236 -301.599854) (xy 271.254741 -301.624461)
			(xy 271.246846 -301.673038) (xy 271.231262 -301.719719) (xy 271.208391 -301.763296) (xy 271.178826 -301.80264)
			(xy 271.143333 -301.836732) (xy 271.10283 -301.864688) (xy 271.058368 -301.885786) (xy 271.011097 -301.899478)
			(xy 270.962242 -301.90541) (xy 270.913067 -301.903429) (xy 270.864848 -301.893585) (xy 270.818832 -301.876133)
			(xy 270.776211 -301.851526) (xy 270.73809 -301.820401) (xy 270.705455 -301.783564) (xy 270.679152 -301.741968)
			(xy 270.659861 -301.696692) (xy 270.648084 -301.648908) (xy 270.644124 -301.599854) (xy 158.955232 -301.599854)
			(xy 158.954737 -301.624461) (xy 158.946842 -301.673038) (xy 158.931258 -301.719719) (xy 158.908387 -301.763296)
			(xy 158.878822 -301.80264) (xy 158.843329 -301.836732) (xy 158.802826 -301.864688) (xy 158.758364 -301.885786)
			(xy 158.711093 -301.899478) (xy 158.662238 -301.90541) (xy 158.613063 -301.903429) (xy 158.564844 -301.893585)
			(xy 158.518828 -301.876133) (xy 158.476207 -301.851526) (xy 158.438086 -301.820401) (xy 158.405451 -301.783564)
			(xy 158.379148 -301.741968) (xy 158.359857 -301.696692) (xy 158.34808 -301.648908) (xy 158.34412 -301.599854)
			(xy 158.005272 -301.599854) (xy 158.004777 -301.624461) (xy 157.996882 -301.673038) (xy 157.981298 -301.719719)
			(xy 157.958427 -301.763296) (xy 157.928862 -301.80264) (xy 157.893369 -301.836732) (xy 157.852866 -301.864688)
			(xy 157.808404 -301.885786) (xy 157.761133 -301.899478) (xy 157.712278 -301.90541) (xy 157.663103 -301.903429)
			(xy 157.614884 -301.893585) (xy 157.568868 -301.876133) (xy 157.526247 -301.851526) (xy 157.488126 -301.820401)
			(xy 157.455491 -301.783564) (xy 157.429188 -301.741968) (xy 157.409897 -301.696692) (xy 157.39812 -301.648908)
			(xy 157.39416 -301.599854) (xy 156.105352 -301.599854) (xy 156.104857 -301.624461) (xy 156.096962 -301.673038)
			(xy 156.081378 -301.719719) (xy 156.058507 -301.763296) (xy 156.028942 -301.80264) (xy 155.993449 -301.836732)
			(xy 155.952946 -301.864688) (xy 155.908484 -301.885786) (xy 155.861213 -301.899478) (xy 155.812358 -301.90541)
			(xy 155.763183 -301.903429) (xy 155.714964 -301.893585) (xy 155.668948 -301.876133) (xy 155.626327 -301.851526)
			(xy 155.588206 -301.820401) (xy 155.555571 -301.783564) (xy 155.529268 -301.741968) (xy 155.509977 -301.696692)
			(xy 155.4982 -301.648908) (xy 155.49424 -301.599854) (xy 155.155392 -301.599854) (xy 155.154897 -301.624461)
			(xy 155.147002 -301.673038) (xy 155.131418 -301.719719) (xy 155.108547 -301.763296) (xy 155.078982 -301.80264)
			(xy 155.043489 -301.836732) (xy 155.002986 -301.864688) (xy 154.958524 -301.885786) (xy 154.911253 -301.899478)
			(xy 154.862398 -301.90541) (xy 154.813223 -301.903429) (xy 154.765004 -301.893585) (xy 154.718988 -301.876133)
			(xy 154.676367 -301.851526) (xy 154.638246 -301.820401) (xy 154.605611 -301.783564) (xy 154.579308 -301.741968)
			(xy 154.560017 -301.696692) (xy 154.54824 -301.648908) (xy 154.54428 -301.599854) (xy 42.855134 -301.599854)
			(xy 42.854639 -301.624461) (xy 42.846744 -301.673038) (xy 42.83116 -301.719719) (xy 42.808289 -301.763296)
			(xy 42.778724 -301.80264) (xy 42.743231 -301.836732) (xy 42.702728 -301.864688) (xy 42.658266 -301.885786)
			(xy 42.610995 -301.899478) (xy 42.56214 -301.90541) (xy 42.512965 -301.903429) (xy 42.464746 -301.893585)
			(xy 42.41873 -301.876133) (xy 42.376109 -301.851526) (xy 42.337988 -301.820401) (xy 42.305353 -301.783564)
			(xy 42.27905 -301.741968) (xy 42.259759 -301.696692) (xy 42.247982 -301.648908) (xy 42.244022 -301.599854)
			(xy 41.905174 -301.599854) (xy 41.904679 -301.624461) (xy 41.896784 -301.673038) (xy 41.8812 -301.719719)
			(xy 41.858329 -301.763296) (xy 41.828764 -301.80264) (xy 41.793271 -301.836732) (xy 41.752768 -301.864688)
			(xy 41.708306 -301.885786) (xy 41.661035 -301.899478) (xy 41.61218 -301.90541) (xy 41.563005 -301.903429)
			(xy 41.514786 -301.893585) (xy 41.46877 -301.876133) (xy 41.426149 -301.851526) (xy 41.388028 -301.820401)
			(xy 41.355393 -301.783564) (xy 41.32909 -301.741968) (xy 41.309799 -301.696692) (xy 41.298022 -301.648908)
			(xy 41.294062 -301.599854) (xy 40.005254 -301.599854) (xy 40.004759 -301.624461) (xy 39.996864 -301.673038)
			(xy 39.98128 -301.719719) (xy 39.958409 -301.763296) (xy 39.928844 -301.80264) (xy 39.893351 -301.836732)
			(xy 39.852848 -301.864688) (xy 39.808386 -301.885786) (xy 39.761115 -301.899478) (xy 39.71226 -301.90541)
			(xy 39.663085 -301.903429) (xy 39.614866 -301.893585) (xy 39.56885 -301.876133) (xy 39.526229 -301.851526)
			(xy 39.488108 -301.820401) (xy 39.455473 -301.783564) (xy 39.42917 -301.741968) (xy 39.409879 -301.696692)
			(xy 39.398102 -301.648908) (xy 39.394142 -301.599854) (xy 39.055294 -301.599854) (xy 39.054799 -301.624461)
			(xy 39.046904 -301.673038) (xy 39.03132 -301.719719) (xy 39.008449 -301.763296) (xy 38.978884 -301.80264)
			(xy 38.943391 -301.836732) (xy 38.902888 -301.864688) (xy 38.858426 -301.885786) (xy 38.811155 -301.899478)
			(xy 38.7623 -301.90541) (xy 38.713125 -301.903429) (xy 38.664906 -301.893585) (xy 38.61889 -301.876133)
			(xy 38.576269 -301.851526) (xy 38.538148 -301.820401) (xy 38.505513 -301.783564) (xy 38.47921 -301.741968)
			(xy 38.459919 -301.696692) (xy 38.448142 -301.648908) (xy 38.444182 -301.599854) (xy 0.509016 -301.599854)
			(xy 0.509016 -302.549814) (xy 36.544008 -302.549814) (xy 36.547968 -302.50076) (xy 36.559745 -302.452976)
			(xy 36.579036 -302.4077) (xy 36.605339 -302.366104) (xy 36.637974 -302.329267) (xy 36.676095 -302.298142)
			(xy 36.718716 -302.273535) (xy 36.764732 -302.256083) (xy 36.812951 -302.246239) (xy 36.862126 -302.244258)
			(xy 36.910981 -302.25019) (xy 36.958252 -302.263882) (xy 37.002714 -302.28498) (xy 37.043217 -302.312936)
			(xy 37.07871 -302.347028) (xy 37.108275 -302.386372) (xy 37.131146 -302.429949) (xy 37.14673 -302.47663)
			(xy 37.154625 -302.525207) (xy 37.15512 -302.549814) (xy 37.493968 -302.549814) (xy 37.497928 -302.50076)
			(xy 37.509705 -302.452976) (xy 37.528996 -302.4077) (xy 37.555299 -302.366104) (xy 37.587934 -302.329267)
			(xy 37.626055 -302.298142) (xy 37.668676 -302.273535) (xy 37.714692 -302.256083) (xy 37.762911 -302.246239)
			(xy 37.812086 -302.244258) (xy 37.860941 -302.25019) (xy 37.908212 -302.263882) (xy 37.952674 -302.28498)
			(xy 37.993177 -302.312936) (xy 38.02867 -302.347028) (xy 38.058235 -302.386372) (xy 38.081106 -302.429949)
			(xy 38.09669 -302.47663) (xy 38.104585 -302.525207) (xy 38.10508 -302.549814) (xy 43.193982 -302.549814)
			(xy 43.197942 -302.50076) (xy 43.209719 -302.452976) (xy 43.22901 -302.4077) (xy 43.255313 -302.366104)
			(xy 43.287948 -302.329267) (xy 43.326069 -302.298142) (xy 43.36869 -302.273535) (xy 43.414706 -302.256083)
			(xy 43.462925 -302.246239) (xy 43.5121 -302.244258) (xy 43.560955 -302.25019) (xy 43.608226 -302.263882)
			(xy 43.652688 -302.28498) (xy 43.693191 -302.312936) (xy 43.728684 -302.347028) (xy 43.758249 -302.386372)
			(xy 43.78112 -302.429949) (xy 43.796704 -302.47663) (xy 43.804599 -302.525207) (xy 43.805094 -302.549814)
			(xy 44.143942 -302.549814) (xy 44.147902 -302.50076) (xy 44.159679 -302.452976) (xy 44.17897 -302.4077)
			(xy 44.205273 -302.366104) (xy 44.237908 -302.329267) (xy 44.276029 -302.298142) (xy 44.31865 -302.273535)
			(xy 44.364666 -302.256083) (xy 44.412885 -302.246239) (xy 44.46206 -302.244258) (xy 44.510915 -302.25019)
			(xy 44.558186 -302.263882) (xy 44.602648 -302.28498) (xy 44.643151 -302.312936) (xy 44.678644 -302.347028)
			(xy 44.708209 -302.386372) (xy 44.73108 -302.429949) (xy 44.746664 -302.47663) (xy 44.754559 -302.525207)
			(xy 44.755054 -302.549814) (xy 152.644106 -302.549814) (xy 152.648066 -302.50076) (xy 152.659843 -302.452976)
			(xy 152.679134 -302.4077) (xy 152.705437 -302.366104) (xy 152.738072 -302.329267) (xy 152.776193 -302.298142)
			(xy 152.818814 -302.273535) (xy 152.86483 -302.256083) (xy 152.913049 -302.246239) (xy 152.962224 -302.244258)
			(xy 153.011079 -302.25019) (xy 153.05835 -302.263882) (xy 153.102812 -302.28498) (xy 153.143315 -302.312936)
			(xy 153.178808 -302.347028) (xy 153.208373 -302.386372) (xy 153.231244 -302.429949) (xy 153.246828 -302.47663)
			(xy 153.254723 -302.525207) (xy 153.255218 -302.549814) (xy 153.594066 -302.549814) (xy 153.598026 -302.50076)
			(xy 153.609803 -302.452976) (xy 153.629094 -302.4077) (xy 153.655397 -302.366104) (xy 153.688032 -302.329267)
			(xy 153.726153 -302.298142) (xy 153.768774 -302.273535) (xy 153.81479 -302.256083) (xy 153.863009 -302.246239)
			(xy 153.912184 -302.244258) (xy 153.961039 -302.25019) (xy 154.00831 -302.263882) (xy 154.052772 -302.28498)
			(xy 154.093275 -302.312936) (xy 154.128768 -302.347028) (xy 154.158333 -302.386372) (xy 154.181204 -302.429949)
			(xy 154.196788 -302.47663) (xy 154.204683 -302.525207) (xy 154.205178 -302.549814) (xy 159.29408 -302.549814)
			(xy 159.29804 -302.50076) (xy 159.309817 -302.452976) (xy 159.329108 -302.4077) (xy 159.355411 -302.366104)
			(xy 159.388046 -302.329267) (xy 159.426167 -302.298142) (xy 159.468788 -302.273535) (xy 159.514804 -302.256083)
			(xy 159.563023 -302.246239) (xy 159.612198 -302.244258) (xy 159.661053 -302.25019) (xy 159.708324 -302.263882)
			(xy 159.752786 -302.28498) (xy 159.793289 -302.312936) (xy 159.828782 -302.347028) (xy 159.858347 -302.386372)
			(xy 159.881218 -302.429949) (xy 159.896802 -302.47663) (xy 159.904697 -302.525207) (xy 159.905192 -302.549814)
			(xy 160.24404 -302.549814) (xy 160.248 -302.50076) (xy 160.259777 -302.452976) (xy 160.279068 -302.4077)
			(xy 160.305371 -302.366104) (xy 160.338006 -302.329267) (xy 160.376127 -302.298142) (xy 160.418748 -302.273535)
			(xy 160.464764 -302.256083) (xy 160.512983 -302.246239) (xy 160.562158 -302.244258) (xy 160.611013 -302.25019)
			(xy 160.658284 -302.263882) (xy 160.702746 -302.28498) (xy 160.743249 -302.312936) (xy 160.778742 -302.347028)
			(xy 160.808307 -302.386372) (xy 160.831178 -302.429949) (xy 160.846762 -302.47663) (xy 160.854657 -302.525207)
			(xy 160.855152 -302.549814) (xy 268.74395 -302.549814) (xy 268.74791 -302.50076) (xy 268.759687 -302.452976)
			(xy 268.778978 -302.4077) (xy 268.805281 -302.366104) (xy 268.837916 -302.329267) (xy 268.876037 -302.298142)
			(xy 268.918658 -302.273535) (xy 268.964674 -302.256083) (xy 269.012893 -302.246239) (xy 269.062068 -302.244258)
			(xy 269.110923 -302.25019) (xy 269.158194 -302.263882) (xy 269.202656 -302.28498) (xy 269.243159 -302.312936)
			(xy 269.278652 -302.347028) (xy 269.308217 -302.386372) (xy 269.331088 -302.429949) (xy 269.346672 -302.47663)
			(xy 269.354567 -302.525207) (xy 269.355062 -302.549814) (xy 269.69391 -302.549814) (xy 269.69787 -302.50076)
			(xy 269.709647 -302.452976) (xy 269.728938 -302.4077) (xy 269.755241 -302.366104) (xy 269.787876 -302.329267)
			(xy 269.825997 -302.298142) (xy 269.868618 -302.273535) (xy 269.914634 -302.256083) (xy 269.962853 -302.246239)
			(xy 270.012028 -302.244258) (xy 270.060883 -302.25019) (xy 270.108154 -302.263882) (xy 270.152616 -302.28498)
			(xy 270.193119 -302.312936) (xy 270.228612 -302.347028) (xy 270.258177 -302.386372) (xy 270.281048 -302.429949)
			(xy 270.296632 -302.47663) (xy 270.304527 -302.525207) (xy 270.305022 -302.549814) (xy 275.393924 -302.549814)
			(xy 275.397884 -302.50076) (xy 275.409661 -302.452976) (xy 275.428952 -302.4077) (xy 275.455255 -302.366104)
			(xy 275.48789 -302.329267) (xy 275.526011 -302.298142) (xy 275.568632 -302.273535) (xy 275.614648 -302.256083)
			(xy 275.662867 -302.246239) (xy 275.712042 -302.244258) (xy 275.760897 -302.25019) (xy 275.808168 -302.263882)
			(xy 275.85263 -302.28498) (xy 275.893133 -302.312936) (xy 275.928626 -302.347028) (xy 275.958191 -302.386372)
			(xy 275.981062 -302.429949) (xy 275.996646 -302.47663) (xy 276.004541 -302.525207) (xy 276.005036 -302.549814)
			(xy 276.343884 -302.549814) (xy 276.347844 -302.50076) (xy 276.359621 -302.452976) (xy 276.378912 -302.4077)
			(xy 276.405215 -302.366104) (xy 276.43785 -302.329267) (xy 276.475971 -302.298142) (xy 276.518592 -302.273535)
			(xy 276.564608 -302.256083) (xy 276.612827 -302.246239) (xy 276.662002 -302.244258) (xy 276.710857 -302.25019)
			(xy 276.758128 -302.263882) (xy 276.80259 -302.28498) (xy 276.843093 -302.312936) (xy 276.878586 -302.347028)
			(xy 276.908151 -302.386372) (xy 276.931022 -302.429949) (xy 276.946606 -302.47663) (xy 276.954501 -302.525207)
			(xy 276.954996 -302.549814) (xy 384.844048 -302.549814) (xy 384.848008 -302.50076) (xy 384.859785 -302.452976)
			(xy 384.879076 -302.4077) (xy 384.905379 -302.366104) (xy 384.938014 -302.329267) (xy 384.976135 -302.298142)
			(xy 385.018756 -302.273535) (xy 385.064772 -302.256083) (xy 385.112991 -302.246239) (xy 385.162166 -302.244258)
			(xy 385.211021 -302.25019) (xy 385.258292 -302.263882) (xy 385.302754 -302.28498) (xy 385.343257 -302.312936)
			(xy 385.37875 -302.347028) (xy 385.408315 -302.386372) (xy 385.431186 -302.429949) (xy 385.44677 -302.47663)
			(xy 385.454665 -302.525207) (xy 385.45516 -302.549814) (xy 385.794008 -302.549814) (xy 385.797968 -302.50076)
			(xy 385.809745 -302.452976) (xy 385.829036 -302.4077) (xy 385.855339 -302.366104) (xy 385.887974 -302.329267)
			(xy 385.926095 -302.298142) (xy 385.968716 -302.273535) (xy 386.014732 -302.256083) (xy 386.062951 -302.246239)
			(xy 386.112126 -302.244258) (xy 386.160981 -302.25019) (xy 386.208252 -302.263882) (xy 386.252714 -302.28498)
			(xy 386.293217 -302.312936) (xy 386.32871 -302.347028) (xy 386.358275 -302.386372) (xy 386.381146 -302.429949)
			(xy 386.39673 -302.47663) (xy 386.404625 -302.525207) (xy 386.40512 -302.549814) (xy 391.494022 -302.549814)
			(xy 391.497982 -302.50076) (xy 391.509759 -302.452976) (xy 391.52905 -302.4077) (xy 391.555353 -302.366104)
			(xy 391.587988 -302.329267) (xy 391.626109 -302.298142) (xy 391.66873 -302.273535) (xy 391.714746 -302.256083)
			(xy 391.762965 -302.246239) (xy 391.81214 -302.244258) (xy 391.860995 -302.25019) (xy 391.908266 -302.263882)
			(xy 391.952728 -302.28498) (xy 391.993231 -302.312936) (xy 392.028724 -302.347028) (xy 392.058289 -302.386372)
			(xy 392.08116 -302.429949) (xy 392.096744 -302.47663) (xy 392.104639 -302.525207) (xy 392.105134 -302.549814)
			(xy 392.443982 -302.549814) (xy 392.447942 -302.50076) (xy 392.459719 -302.452976) (xy 392.47901 -302.4077)
			(xy 392.505313 -302.366104) (xy 392.537948 -302.329267) (xy 392.576069 -302.298142) (xy 392.61869 -302.273535)
			(xy 392.664706 -302.256083) (xy 392.712925 -302.246239) (xy 392.7621 -302.244258) (xy 392.810955 -302.25019)
			(xy 392.858226 -302.263882) (xy 392.902688 -302.28498) (xy 392.943191 -302.312936) (xy 392.978684 -302.347028)
			(xy 393.008249 -302.386372) (xy 393.03112 -302.429949) (xy 393.046704 -302.47663) (xy 393.054599 -302.525207)
			(xy 393.055094 -302.549814) (xy 393.054599 -302.574421) (xy 393.046704 -302.622998) (xy 393.03112 -302.669679)
			(xy 393.008249 -302.713256) (xy 392.978684 -302.7526) (xy 392.943191 -302.786692) (xy 392.902688 -302.814648)
			(xy 392.858226 -302.835746) (xy 392.810955 -302.849438) (xy 392.7621 -302.85537) (xy 392.712925 -302.853389)
			(xy 392.664706 -302.843545) (xy 392.61869 -302.826093) (xy 392.576069 -302.801486) (xy 392.537948 -302.770361)
			(xy 392.505313 -302.733524) (xy 392.47901 -302.691928) (xy 392.459719 -302.646652) (xy 392.447942 -302.598868)
			(xy 392.443982 -302.549814) (xy 392.105134 -302.549814) (xy 392.104639 -302.574421) (xy 392.096744 -302.622998)
			(xy 392.08116 -302.669679) (xy 392.058289 -302.713256) (xy 392.028724 -302.7526) (xy 391.993231 -302.786692)
			(xy 391.952728 -302.814648) (xy 391.908266 -302.835746) (xy 391.860995 -302.849438) (xy 391.81214 -302.85537)
			(xy 391.762965 -302.853389) (xy 391.714746 -302.843545) (xy 391.66873 -302.826093) (xy 391.626109 -302.801486)
			(xy 391.587988 -302.770361) (xy 391.555353 -302.733524) (xy 391.52905 -302.691928) (xy 391.509759 -302.646652)
			(xy 391.497982 -302.598868) (xy 391.494022 -302.549814) (xy 386.40512 -302.549814) (xy 386.404625 -302.574421)
			(xy 386.39673 -302.622998) (xy 386.381146 -302.669679) (xy 386.358275 -302.713256) (xy 386.32871 -302.7526)
			(xy 386.293217 -302.786692) (xy 386.252714 -302.814648) (xy 386.208252 -302.835746) (xy 386.160981 -302.849438)
			(xy 386.112126 -302.85537) (xy 386.062951 -302.853389) (xy 386.014732 -302.843545) (xy 385.968716 -302.826093)
			(xy 385.926095 -302.801486) (xy 385.887974 -302.770361) (xy 385.855339 -302.733524) (xy 385.829036 -302.691928)
			(xy 385.809745 -302.646652) (xy 385.797968 -302.598868) (xy 385.794008 -302.549814) (xy 385.45516 -302.549814)
			(xy 385.454665 -302.574421) (xy 385.44677 -302.622998) (xy 385.431186 -302.669679) (xy 385.408315 -302.713256)
			(xy 385.37875 -302.7526) (xy 385.343257 -302.786692) (xy 385.302754 -302.814648) (xy 385.258292 -302.835746)
			(xy 385.211021 -302.849438) (xy 385.162166 -302.85537) (xy 385.112991 -302.853389) (xy 385.064772 -302.843545)
			(xy 385.018756 -302.826093) (xy 384.976135 -302.801486) (xy 384.938014 -302.770361) (xy 384.905379 -302.733524)
			(xy 384.879076 -302.691928) (xy 384.859785 -302.646652) (xy 384.848008 -302.598868) (xy 384.844048 -302.549814)
			(xy 276.954996 -302.549814) (xy 276.954501 -302.574421) (xy 276.946606 -302.622998) (xy 276.931022 -302.669679)
			(xy 276.908151 -302.713256) (xy 276.878586 -302.7526) (xy 276.843093 -302.786692) (xy 276.80259 -302.814648)
			(xy 276.758128 -302.835746) (xy 276.710857 -302.849438) (xy 276.662002 -302.85537) (xy 276.612827 -302.853389)
			(xy 276.564608 -302.843545) (xy 276.518592 -302.826093) (xy 276.475971 -302.801486) (xy 276.43785 -302.770361)
			(xy 276.405215 -302.733524) (xy 276.378912 -302.691928) (xy 276.359621 -302.646652) (xy 276.347844 -302.598868)
			(xy 276.343884 -302.549814) (xy 276.005036 -302.549814) (xy 276.004541 -302.574421) (xy 275.996646 -302.622998)
			(xy 275.981062 -302.669679) (xy 275.958191 -302.713256) (xy 275.928626 -302.7526) (xy 275.893133 -302.786692)
			(xy 275.85263 -302.814648) (xy 275.808168 -302.835746) (xy 275.760897 -302.849438) (xy 275.712042 -302.85537)
			(xy 275.662867 -302.853389) (xy 275.614648 -302.843545) (xy 275.568632 -302.826093) (xy 275.526011 -302.801486)
			(xy 275.48789 -302.770361) (xy 275.455255 -302.733524) (xy 275.428952 -302.691928) (xy 275.409661 -302.646652)
			(xy 275.397884 -302.598868) (xy 275.393924 -302.549814) (xy 270.305022 -302.549814) (xy 270.304527 -302.574421)
			(xy 270.296632 -302.622998) (xy 270.281048 -302.669679) (xy 270.258177 -302.713256) (xy 270.228612 -302.7526)
			(xy 270.193119 -302.786692) (xy 270.152616 -302.814648) (xy 270.108154 -302.835746) (xy 270.060883 -302.849438)
			(xy 270.012028 -302.85537) (xy 269.962853 -302.853389) (xy 269.914634 -302.843545) (xy 269.868618 -302.826093)
			(xy 269.825997 -302.801486) (xy 269.787876 -302.770361) (xy 269.755241 -302.733524) (xy 269.728938 -302.691928)
			(xy 269.709647 -302.646652) (xy 269.69787 -302.598868) (xy 269.69391 -302.549814) (xy 269.355062 -302.549814)
			(xy 269.354567 -302.574421) (xy 269.346672 -302.622998) (xy 269.331088 -302.669679) (xy 269.308217 -302.713256)
			(xy 269.278652 -302.7526) (xy 269.243159 -302.786692) (xy 269.202656 -302.814648) (xy 269.158194 -302.835746)
			(xy 269.110923 -302.849438) (xy 269.062068 -302.85537) (xy 269.012893 -302.853389) (xy 268.964674 -302.843545)
			(xy 268.918658 -302.826093) (xy 268.876037 -302.801486) (xy 268.837916 -302.770361) (xy 268.805281 -302.733524)
			(xy 268.778978 -302.691928) (xy 268.759687 -302.646652) (xy 268.74791 -302.598868) (xy 268.74395 -302.549814)
			(xy 160.855152 -302.549814) (xy 160.854657 -302.574421) (xy 160.846762 -302.622998) (xy 160.831178 -302.669679)
			(xy 160.808307 -302.713256) (xy 160.778742 -302.7526) (xy 160.743249 -302.786692) (xy 160.702746 -302.814648)
			(xy 160.658284 -302.835746) (xy 160.611013 -302.849438) (xy 160.562158 -302.85537) (xy 160.512983 -302.853389)
			(xy 160.464764 -302.843545) (xy 160.418748 -302.826093) (xy 160.376127 -302.801486) (xy 160.338006 -302.770361)
			(xy 160.305371 -302.733524) (xy 160.279068 -302.691928) (xy 160.259777 -302.646652) (xy 160.248 -302.598868)
			(xy 160.24404 -302.549814) (xy 159.905192 -302.549814) (xy 159.904697 -302.574421) (xy 159.896802 -302.622998)
			(xy 159.881218 -302.669679) (xy 159.858347 -302.713256) (xy 159.828782 -302.7526) (xy 159.793289 -302.786692)
			(xy 159.752786 -302.814648) (xy 159.708324 -302.835746) (xy 159.661053 -302.849438) (xy 159.612198 -302.85537)
			(xy 159.563023 -302.853389) (xy 159.514804 -302.843545) (xy 159.468788 -302.826093) (xy 159.426167 -302.801486)
			(xy 159.388046 -302.770361) (xy 159.355411 -302.733524) (xy 159.329108 -302.691928) (xy 159.309817 -302.646652)
			(xy 159.29804 -302.598868) (xy 159.29408 -302.549814) (xy 154.205178 -302.549814) (xy 154.204683 -302.574421)
			(xy 154.196788 -302.622998) (xy 154.181204 -302.669679) (xy 154.158333 -302.713256) (xy 154.128768 -302.7526)
			(xy 154.093275 -302.786692) (xy 154.052772 -302.814648) (xy 154.00831 -302.835746) (xy 153.961039 -302.849438)
			(xy 153.912184 -302.85537) (xy 153.863009 -302.853389) (xy 153.81479 -302.843545) (xy 153.768774 -302.826093)
			(xy 153.726153 -302.801486) (xy 153.688032 -302.770361) (xy 153.655397 -302.733524) (xy 153.629094 -302.691928)
			(xy 153.609803 -302.646652) (xy 153.598026 -302.598868) (xy 153.594066 -302.549814) (xy 153.255218 -302.549814)
			(xy 153.254723 -302.574421) (xy 153.246828 -302.622998) (xy 153.231244 -302.669679) (xy 153.208373 -302.713256)
			(xy 153.178808 -302.7526) (xy 153.143315 -302.786692) (xy 153.102812 -302.814648) (xy 153.05835 -302.835746)
			(xy 153.011079 -302.849438) (xy 152.962224 -302.85537) (xy 152.913049 -302.853389) (xy 152.86483 -302.843545)
			(xy 152.818814 -302.826093) (xy 152.776193 -302.801486) (xy 152.738072 -302.770361) (xy 152.705437 -302.733524)
			(xy 152.679134 -302.691928) (xy 152.659843 -302.646652) (xy 152.648066 -302.598868) (xy 152.644106 -302.549814)
			(xy 44.755054 -302.549814) (xy 44.754559 -302.574421) (xy 44.746664 -302.622998) (xy 44.73108 -302.669679)
			(xy 44.708209 -302.713256) (xy 44.678644 -302.7526) (xy 44.643151 -302.786692) (xy 44.602648 -302.814648)
			(xy 44.558186 -302.835746) (xy 44.510915 -302.849438) (xy 44.46206 -302.85537) (xy 44.412885 -302.853389)
			(xy 44.364666 -302.843545) (xy 44.31865 -302.826093) (xy 44.276029 -302.801486) (xy 44.237908 -302.770361)
			(xy 44.205273 -302.733524) (xy 44.17897 -302.691928) (xy 44.159679 -302.646652) (xy 44.147902 -302.598868)
			(xy 44.143942 -302.549814) (xy 43.805094 -302.549814) (xy 43.804599 -302.574421) (xy 43.796704 -302.622998)
			(xy 43.78112 -302.669679) (xy 43.758249 -302.713256) (xy 43.728684 -302.7526) (xy 43.693191 -302.786692)
			(xy 43.652688 -302.814648) (xy 43.608226 -302.835746) (xy 43.560955 -302.849438) (xy 43.5121 -302.85537)
			(xy 43.462925 -302.853389) (xy 43.414706 -302.843545) (xy 43.36869 -302.826093) (xy 43.326069 -302.801486)
			(xy 43.287948 -302.770361) (xy 43.255313 -302.733524) (xy 43.22901 -302.691928) (xy 43.209719 -302.646652)
			(xy 43.197942 -302.598868) (xy 43.193982 -302.549814) (xy 38.10508 -302.549814) (xy 38.104585 -302.574421)
			(xy 38.09669 -302.622998) (xy 38.081106 -302.669679) (xy 38.058235 -302.713256) (xy 38.02867 -302.7526)
			(xy 37.993177 -302.786692) (xy 37.952674 -302.814648) (xy 37.908212 -302.835746) (xy 37.860941 -302.849438)
			(xy 37.812086 -302.85537) (xy 37.762911 -302.853389) (xy 37.714692 -302.843545) (xy 37.668676 -302.826093)
			(xy 37.626055 -302.801486) (xy 37.587934 -302.770361) (xy 37.555299 -302.733524) (xy 37.528996 -302.691928)
			(xy 37.509705 -302.646652) (xy 37.497928 -302.598868) (xy 37.493968 -302.549814) (xy 37.15512 -302.549814)
			(xy 37.154625 -302.574421) (xy 37.14673 -302.622998) (xy 37.131146 -302.669679) (xy 37.108275 -302.713256)
			(xy 37.07871 -302.7526) (xy 37.043217 -302.786692) (xy 37.002714 -302.814648) (xy 36.958252 -302.835746)
			(xy 36.910981 -302.849438) (xy 36.862126 -302.85537) (xy 36.812951 -302.853389) (xy 36.764732 -302.843545)
			(xy 36.718716 -302.826093) (xy 36.676095 -302.801486) (xy 36.637974 -302.770361) (xy 36.605339 -302.733524)
			(xy 36.579036 -302.691928) (xy 36.559745 -302.646652) (xy 36.547968 -302.598868) (xy 36.544008 -302.549814)
			(xy 0.509016 -302.549814) (xy 0.509016 -303.499774) (xy 38.444182 -303.499774) (xy 38.448142 -303.45072)
			(xy 38.459919 -303.402936) (xy 38.47921 -303.35766) (xy 38.505513 -303.316064) (xy 38.538148 -303.279227)
			(xy 38.576269 -303.248102) (xy 38.61889 -303.223495) (xy 38.664906 -303.206043) (xy 38.713125 -303.196199)
			(xy 38.7623 -303.194218) (xy 38.811155 -303.20015) (xy 38.858426 -303.213842) (xy 38.902888 -303.23494)
			(xy 38.943391 -303.262896) (xy 38.978884 -303.296988) (xy 39.008449 -303.336332) (xy 39.03132 -303.379909)
			(xy 39.046904 -303.42659) (xy 39.054799 -303.475167) (xy 39.055294 -303.499774) (xy 39.394142 -303.499774)
			(xy 39.398102 -303.45072) (xy 39.409879 -303.402936) (xy 39.42917 -303.35766) (xy 39.455473 -303.316064)
			(xy 39.488108 -303.279227) (xy 39.526229 -303.248102) (xy 39.56885 -303.223495) (xy 39.614866 -303.206043)
			(xy 39.663085 -303.196199) (xy 39.71226 -303.194218) (xy 39.761115 -303.20015) (xy 39.808386 -303.213842)
			(xy 39.852848 -303.23494) (xy 39.893351 -303.262896) (xy 39.928844 -303.296988) (xy 39.958409 -303.336332)
			(xy 39.98128 -303.379909) (xy 39.996864 -303.42659) (xy 40.004759 -303.475167) (xy 40.005254 -303.499774)
			(xy 41.294062 -303.499774) (xy 41.298022 -303.45072) (xy 41.309799 -303.402936) (xy 41.32909 -303.35766)
			(xy 41.355393 -303.316064) (xy 41.388028 -303.279227) (xy 41.426149 -303.248102) (xy 41.46877 -303.223495)
			(xy 41.514786 -303.206043) (xy 41.563005 -303.196199) (xy 41.61218 -303.194218) (xy 41.661035 -303.20015)
			(xy 41.708306 -303.213842) (xy 41.752768 -303.23494) (xy 41.793271 -303.262896) (xy 41.828764 -303.296988)
			(xy 41.858329 -303.336332) (xy 41.8812 -303.379909) (xy 41.896784 -303.42659) (xy 41.904679 -303.475167)
			(xy 41.905174 -303.499774) (xy 42.244022 -303.499774) (xy 42.247982 -303.45072) (xy 42.259759 -303.402936)
			(xy 42.27905 -303.35766) (xy 42.305353 -303.316064) (xy 42.337988 -303.279227) (xy 42.376109 -303.248102)
			(xy 42.41873 -303.223495) (xy 42.464746 -303.206043) (xy 42.512965 -303.196199) (xy 42.56214 -303.194218)
			(xy 42.610995 -303.20015) (xy 42.658266 -303.213842) (xy 42.702728 -303.23494) (xy 42.743231 -303.262896)
			(xy 42.778724 -303.296988) (xy 42.808289 -303.336332) (xy 42.83116 -303.379909) (xy 42.846744 -303.42659)
			(xy 42.854639 -303.475167) (xy 42.855134 -303.499774) (xy 154.54428 -303.499774) (xy 154.54824 -303.45072)
			(xy 154.560017 -303.402936) (xy 154.579308 -303.35766) (xy 154.605611 -303.316064) (xy 154.638246 -303.279227)
			(xy 154.676367 -303.248102) (xy 154.718988 -303.223495) (xy 154.765004 -303.206043) (xy 154.813223 -303.196199)
			(xy 154.862398 -303.194218) (xy 154.911253 -303.20015) (xy 154.958524 -303.213842) (xy 155.002986 -303.23494)
			(xy 155.043489 -303.262896) (xy 155.078982 -303.296988) (xy 155.108547 -303.336332) (xy 155.131418 -303.379909)
			(xy 155.147002 -303.42659) (xy 155.154897 -303.475167) (xy 155.155392 -303.499774) (xy 155.49424 -303.499774)
			(xy 155.4982 -303.45072) (xy 155.509977 -303.402936) (xy 155.529268 -303.35766) (xy 155.555571 -303.316064)
			(xy 155.588206 -303.279227) (xy 155.626327 -303.248102) (xy 155.668948 -303.223495) (xy 155.714964 -303.206043)
			(xy 155.763183 -303.196199) (xy 155.812358 -303.194218) (xy 155.861213 -303.20015) (xy 155.908484 -303.213842)
			(xy 155.952946 -303.23494) (xy 155.993449 -303.262896) (xy 156.028942 -303.296988) (xy 156.058507 -303.336332)
			(xy 156.081378 -303.379909) (xy 156.096962 -303.42659) (xy 156.104857 -303.475167) (xy 156.105352 -303.499774)
			(xy 157.39416 -303.499774) (xy 157.39812 -303.45072) (xy 157.409897 -303.402936) (xy 157.429188 -303.35766)
			(xy 157.455491 -303.316064) (xy 157.488126 -303.279227) (xy 157.526247 -303.248102) (xy 157.568868 -303.223495)
			(xy 157.614884 -303.206043) (xy 157.663103 -303.196199) (xy 157.712278 -303.194218) (xy 157.761133 -303.20015)
			(xy 157.808404 -303.213842) (xy 157.852866 -303.23494) (xy 157.893369 -303.262896) (xy 157.928862 -303.296988)
			(xy 157.958427 -303.336332) (xy 157.981298 -303.379909) (xy 157.996882 -303.42659) (xy 158.004777 -303.475167)
			(xy 158.005272 -303.499774) (xy 158.34412 -303.499774) (xy 158.34808 -303.45072) (xy 158.359857 -303.402936)
			(xy 158.379148 -303.35766) (xy 158.405451 -303.316064) (xy 158.438086 -303.279227) (xy 158.476207 -303.248102)
			(xy 158.518828 -303.223495) (xy 158.564844 -303.206043) (xy 158.613063 -303.196199) (xy 158.662238 -303.194218)
			(xy 158.711093 -303.20015) (xy 158.758364 -303.213842) (xy 158.802826 -303.23494) (xy 158.843329 -303.262896)
			(xy 158.878822 -303.296988) (xy 158.908387 -303.336332) (xy 158.931258 -303.379909) (xy 158.946842 -303.42659)
			(xy 158.954737 -303.475167) (xy 158.955232 -303.499774) (xy 270.644124 -303.499774) (xy 270.648084 -303.45072)
			(xy 270.659861 -303.402936) (xy 270.679152 -303.35766) (xy 270.705455 -303.316064) (xy 270.73809 -303.279227)
			(xy 270.776211 -303.248102) (xy 270.818832 -303.223495) (xy 270.864848 -303.206043) (xy 270.913067 -303.196199)
			(xy 270.962242 -303.194218) (xy 271.011097 -303.20015) (xy 271.058368 -303.213842) (xy 271.10283 -303.23494)
			(xy 271.143333 -303.262896) (xy 271.178826 -303.296988) (xy 271.208391 -303.336332) (xy 271.231262 -303.379909)
			(xy 271.246846 -303.42659) (xy 271.254741 -303.475167) (xy 271.255236 -303.499774) (xy 271.594084 -303.499774)
			(xy 271.598044 -303.45072) (xy 271.609821 -303.402936) (xy 271.629112 -303.35766) (xy 271.655415 -303.316064)
			(xy 271.68805 -303.279227) (xy 271.726171 -303.248102) (xy 271.768792 -303.223495) (xy 271.814808 -303.206043)
			(xy 271.863027 -303.196199) (xy 271.912202 -303.194218) (xy 271.961057 -303.20015) (xy 272.008328 -303.213842)
			(xy 272.05279 -303.23494) (xy 272.093293 -303.262896) (xy 272.128786 -303.296988) (xy 272.158351 -303.336332)
			(xy 272.181222 -303.379909) (xy 272.196806 -303.42659) (xy 272.204701 -303.475167) (xy 272.205196 -303.499774)
			(xy 273.494004 -303.499774) (xy 273.497964 -303.45072) (xy 273.509741 -303.402936) (xy 273.529032 -303.35766)
			(xy 273.555335 -303.316064) (xy 273.58797 -303.279227) (xy 273.626091 -303.248102) (xy 273.668712 -303.223495)
			(xy 273.714728 -303.206043) (xy 273.762947 -303.196199) (xy 273.812122 -303.194218) (xy 273.860977 -303.20015)
			(xy 273.908248 -303.213842) (xy 273.95271 -303.23494) (xy 273.993213 -303.262896) (xy 274.028706 -303.296988)
			(xy 274.058271 -303.336332) (xy 274.081142 -303.379909) (xy 274.096726 -303.42659) (xy 274.104621 -303.475167)
			(xy 274.105116 -303.499774) (xy 274.443964 -303.499774) (xy 274.447924 -303.45072) (xy 274.459701 -303.402936)
			(xy 274.478992 -303.35766) (xy 274.505295 -303.316064) (xy 274.53793 -303.279227) (xy 274.576051 -303.248102)
			(xy 274.618672 -303.223495) (xy 274.664688 -303.206043) (xy 274.712907 -303.196199) (xy 274.762082 -303.194218)
			(xy 274.810937 -303.20015) (xy 274.858208 -303.213842) (xy 274.90267 -303.23494) (xy 274.943173 -303.262896)
			(xy 274.978666 -303.296988) (xy 275.008231 -303.336332) (xy 275.031102 -303.379909) (xy 275.046686 -303.42659)
			(xy 275.054581 -303.475167) (xy 275.055076 -303.499774) (xy 386.744222 -303.499774) (xy 386.748182 -303.45072)
			(xy 386.759959 -303.402936) (xy 386.77925 -303.35766) (xy 386.805553 -303.316064) (xy 386.838188 -303.279227)
			(xy 386.876309 -303.248102) (xy 386.91893 -303.223495) (xy 386.964946 -303.206043) (xy 387.013165 -303.196199)
			(xy 387.06234 -303.194218) (xy 387.111195 -303.20015) (xy 387.158466 -303.213842) (xy 387.202928 -303.23494)
			(xy 387.243431 -303.262896) (xy 387.278924 -303.296988) (xy 387.308489 -303.336332) (xy 387.33136 -303.379909)
			(xy 387.346944 -303.42659) (xy 387.354839 -303.475167) (xy 387.355334 -303.499774) (xy 387.694182 -303.499774)
			(xy 387.698142 -303.45072) (xy 387.709919 -303.402936) (xy 387.72921 -303.35766) (xy 387.755513 -303.316064)
			(xy 387.788148 -303.279227) (xy 387.826269 -303.248102) (xy 387.86889 -303.223495) (xy 387.914906 -303.206043)
			(xy 387.963125 -303.196199) (xy 388.0123 -303.194218) (xy 388.061155 -303.20015) (xy 388.108426 -303.213842)
			(xy 388.152888 -303.23494) (xy 388.193391 -303.262896) (xy 388.228884 -303.296988) (xy 388.258449 -303.336332)
			(xy 388.28132 -303.379909) (xy 388.296904 -303.42659) (xy 388.304799 -303.475167) (xy 388.305294 -303.499774)
			(xy 389.594102 -303.499774) (xy 389.598062 -303.45072) (xy 389.609839 -303.402936) (xy 389.62913 -303.35766)
			(xy 389.655433 -303.316064) (xy 389.688068 -303.279227) (xy 389.726189 -303.248102) (xy 389.76881 -303.223495)
			(xy 389.814826 -303.206043) (xy 389.863045 -303.196199) (xy 389.91222 -303.194218) (xy 389.961075 -303.20015)
			(xy 390.008346 -303.213842) (xy 390.052808 -303.23494) (xy 390.093311 -303.262896) (xy 390.128804 -303.296988)
			(xy 390.158369 -303.336332) (xy 390.18124 -303.379909) (xy 390.196824 -303.42659) (xy 390.204719 -303.475167)
			(xy 390.205214 -303.499774) (xy 390.544062 -303.499774) (xy 390.548022 -303.45072) (xy 390.559799 -303.402936)
			(xy 390.57909 -303.35766) (xy 390.605393 -303.316064) (xy 390.638028 -303.279227) (xy 390.676149 -303.248102)
			(xy 390.71877 -303.223495) (xy 390.764786 -303.206043) (xy 390.813005 -303.196199) (xy 390.86218 -303.194218)
			(xy 390.911035 -303.20015) (xy 390.958306 -303.213842) (xy 391.002768 -303.23494) (xy 391.043271 -303.262896)
			(xy 391.078764 -303.296988) (xy 391.108329 -303.336332) (xy 391.1312 -303.379909) (xy 391.146784 -303.42659)
			(xy 391.154679 -303.475167) (xy 391.155174 -303.499774) (xy 391.154679 -303.524381) (xy 391.146784 -303.572958)
			(xy 391.1312 -303.619639) (xy 391.108329 -303.663216) (xy 391.078764 -303.70256) (xy 391.043271 -303.736652)
			(xy 391.002768 -303.764608) (xy 390.958306 -303.785706) (xy 390.911035 -303.799398) (xy 390.86218 -303.80533)
			(xy 390.813005 -303.803349) (xy 390.764786 -303.793505) (xy 390.71877 -303.776053) (xy 390.676149 -303.751446)
			(xy 390.638028 -303.720321) (xy 390.605393 -303.683484) (xy 390.57909 -303.641888) (xy 390.559799 -303.596612)
			(xy 390.548022 -303.548828) (xy 390.544062 -303.499774) (xy 390.205214 -303.499774) (xy 390.204719 -303.524381)
			(xy 390.196824 -303.572958) (xy 390.18124 -303.619639) (xy 390.158369 -303.663216) (xy 390.128804 -303.70256)
			(xy 390.093311 -303.736652) (xy 390.052808 -303.764608) (xy 390.008346 -303.785706) (xy 389.961075 -303.799398)
			(xy 389.91222 -303.80533) (xy 389.863045 -303.803349) (xy 389.814826 -303.793505) (xy 389.76881 -303.776053)
			(xy 389.726189 -303.751446) (xy 389.688068 -303.720321) (xy 389.655433 -303.683484) (xy 389.62913 -303.641888)
			(xy 389.609839 -303.596612) (xy 389.598062 -303.548828) (xy 389.594102 -303.499774) (xy 388.305294 -303.499774)
			(xy 388.304799 -303.524381) (xy 388.296904 -303.572958) (xy 388.28132 -303.619639) (xy 388.258449 -303.663216)
			(xy 388.228884 -303.70256) (xy 388.193391 -303.736652) (xy 388.152888 -303.764608) (xy 388.108426 -303.785706)
			(xy 388.061155 -303.799398) (xy 388.0123 -303.80533) (xy 387.963125 -303.803349) (xy 387.914906 -303.793505)
			(xy 387.86889 -303.776053) (xy 387.826269 -303.751446) (xy 387.788148 -303.720321) (xy 387.755513 -303.683484)
			(xy 387.72921 -303.641888) (xy 387.709919 -303.596612) (xy 387.698142 -303.548828) (xy 387.694182 -303.499774)
			(xy 387.355334 -303.499774) (xy 387.354839 -303.524381) (xy 387.346944 -303.572958) (xy 387.33136 -303.619639)
			(xy 387.308489 -303.663216) (xy 387.278924 -303.70256) (xy 387.243431 -303.736652) (xy 387.202928 -303.764608)
			(xy 387.158466 -303.785706) (xy 387.111195 -303.799398) (xy 387.06234 -303.80533) (xy 387.013165 -303.803349)
			(xy 386.964946 -303.793505) (xy 386.91893 -303.776053) (xy 386.876309 -303.751446) (xy 386.838188 -303.720321)
			(xy 386.805553 -303.683484) (xy 386.77925 -303.641888) (xy 386.759959 -303.596612) (xy 386.748182 -303.548828)
			(xy 386.744222 -303.499774) (xy 275.055076 -303.499774) (xy 275.054581 -303.524381) (xy 275.046686 -303.572958)
			(xy 275.031102 -303.619639) (xy 275.008231 -303.663216) (xy 274.978666 -303.70256) (xy 274.943173 -303.736652)
			(xy 274.90267 -303.764608) (xy 274.858208 -303.785706) (xy 274.810937 -303.799398) (xy 274.762082 -303.80533)
			(xy 274.712907 -303.803349) (xy 274.664688 -303.793505) (xy 274.618672 -303.776053) (xy 274.576051 -303.751446)
			(xy 274.53793 -303.720321) (xy 274.505295 -303.683484) (xy 274.478992 -303.641888) (xy 274.459701 -303.596612)
			(xy 274.447924 -303.548828) (xy 274.443964 -303.499774) (xy 274.105116 -303.499774) (xy 274.104621 -303.524381)
			(xy 274.096726 -303.572958) (xy 274.081142 -303.619639) (xy 274.058271 -303.663216) (xy 274.028706 -303.70256)
			(xy 273.993213 -303.736652) (xy 273.95271 -303.764608) (xy 273.908248 -303.785706) (xy 273.860977 -303.799398)
			(xy 273.812122 -303.80533) (xy 273.762947 -303.803349) (xy 273.714728 -303.793505) (xy 273.668712 -303.776053)
			(xy 273.626091 -303.751446) (xy 273.58797 -303.720321) (xy 273.555335 -303.683484) (xy 273.529032 -303.641888)
			(xy 273.509741 -303.596612) (xy 273.497964 -303.548828) (xy 273.494004 -303.499774) (xy 272.205196 -303.499774)
			(xy 272.204701 -303.524381) (xy 272.196806 -303.572958) (xy 272.181222 -303.619639) (xy 272.158351 -303.663216)
			(xy 272.128786 -303.70256) (xy 272.093293 -303.736652) (xy 272.05279 -303.764608) (xy 272.008328 -303.785706)
			(xy 271.961057 -303.799398) (xy 271.912202 -303.80533) (xy 271.863027 -303.803349) (xy 271.814808 -303.793505)
			(xy 271.768792 -303.776053) (xy 271.726171 -303.751446) (xy 271.68805 -303.720321) (xy 271.655415 -303.683484)
			(xy 271.629112 -303.641888) (xy 271.609821 -303.596612) (xy 271.598044 -303.548828) (xy 271.594084 -303.499774)
			(xy 271.255236 -303.499774) (xy 271.254741 -303.524381) (xy 271.246846 -303.572958) (xy 271.231262 -303.619639)
			(xy 271.208391 -303.663216) (xy 271.178826 -303.70256) (xy 271.143333 -303.736652) (xy 271.10283 -303.764608)
			(xy 271.058368 -303.785706) (xy 271.011097 -303.799398) (xy 270.962242 -303.80533) (xy 270.913067 -303.803349)
			(xy 270.864848 -303.793505) (xy 270.818832 -303.776053) (xy 270.776211 -303.751446) (xy 270.73809 -303.720321)
			(xy 270.705455 -303.683484) (xy 270.679152 -303.641888) (xy 270.659861 -303.596612) (xy 270.648084 -303.548828)
			(xy 270.644124 -303.499774) (xy 158.955232 -303.499774) (xy 158.954737 -303.524381) (xy 158.946842 -303.572958)
			(xy 158.931258 -303.619639) (xy 158.908387 -303.663216) (xy 158.878822 -303.70256) (xy 158.843329 -303.736652)
			(xy 158.802826 -303.764608) (xy 158.758364 -303.785706) (xy 158.711093 -303.799398) (xy 158.662238 -303.80533)
			(xy 158.613063 -303.803349) (xy 158.564844 -303.793505) (xy 158.518828 -303.776053) (xy 158.476207 -303.751446)
			(xy 158.438086 -303.720321) (xy 158.405451 -303.683484) (xy 158.379148 -303.641888) (xy 158.359857 -303.596612)
			(xy 158.34808 -303.548828) (xy 158.34412 -303.499774) (xy 158.005272 -303.499774) (xy 158.004777 -303.524381)
			(xy 157.996882 -303.572958) (xy 157.981298 -303.619639) (xy 157.958427 -303.663216) (xy 157.928862 -303.70256)
			(xy 157.893369 -303.736652) (xy 157.852866 -303.764608) (xy 157.808404 -303.785706) (xy 157.761133 -303.799398)
			(xy 157.712278 -303.80533) (xy 157.663103 -303.803349) (xy 157.614884 -303.793505) (xy 157.568868 -303.776053)
			(xy 157.526247 -303.751446) (xy 157.488126 -303.720321) (xy 157.455491 -303.683484) (xy 157.429188 -303.641888)
			(xy 157.409897 -303.596612) (xy 157.39812 -303.548828) (xy 157.39416 -303.499774) (xy 156.105352 -303.499774)
			(xy 156.104857 -303.524381) (xy 156.096962 -303.572958) (xy 156.081378 -303.619639) (xy 156.058507 -303.663216)
			(xy 156.028942 -303.70256) (xy 155.993449 -303.736652) (xy 155.952946 -303.764608) (xy 155.908484 -303.785706)
			(xy 155.861213 -303.799398) (xy 155.812358 -303.80533) (xy 155.763183 -303.803349) (xy 155.714964 -303.793505)
			(xy 155.668948 -303.776053) (xy 155.626327 -303.751446) (xy 155.588206 -303.720321) (xy 155.555571 -303.683484)
			(xy 155.529268 -303.641888) (xy 155.509977 -303.596612) (xy 155.4982 -303.548828) (xy 155.49424 -303.499774)
			(xy 155.155392 -303.499774) (xy 155.154897 -303.524381) (xy 155.147002 -303.572958) (xy 155.131418 -303.619639)
			(xy 155.108547 -303.663216) (xy 155.078982 -303.70256) (xy 155.043489 -303.736652) (xy 155.002986 -303.764608)
			(xy 154.958524 -303.785706) (xy 154.911253 -303.799398) (xy 154.862398 -303.80533) (xy 154.813223 -303.803349)
			(xy 154.765004 -303.793505) (xy 154.718988 -303.776053) (xy 154.676367 -303.751446) (xy 154.638246 -303.720321)
			(xy 154.605611 -303.683484) (xy 154.579308 -303.641888) (xy 154.560017 -303.596612) (xy 154.54824 -303.548828)
			(xy 154.54428 -303.499774) (xy 42.855134 -303.499774) (xy 42.854639 -303.524381) (xy 42.846744 -303.572958)
			(xy 42.83116 -303.619639) (xy 42.808289 -303.663216) (xy 42.778724 -303.70256) (xy 42.743231 -303.736652)
			(xy 42.702728 -303.764608) (xy 42.658266 -303.785706) (xy 42.610995 -303.799398) (xy 42.56214 -303.80533)
			(xy 42.512965 -303.803349) (xy 42.464746 -303.793505) (xy 42.41873 -303.776053) (xy 42.376109 -303.751446)
			(xy 42.337988 -303.720321) (xy 42.305353 -303.683484) (xy 42.27905 -303.641888) (xy 42.259759 -303.596612)
			(xy 42.247982 -303.548828) (xy 42.244022 -303.499774) (xy 41.905174 -303.499774) (xy 41.904679 -303.524381)
			(xy 41.896784 -303.572958) (xy 41.8812 -303.619639) (xy 41.858329 -303.663216) (xy 41.828764 -303.70256)
			(xy 41.793271 -303.736652) (xy 41.752768 -303.764608) (xy 41.708306 -303.785706) (xy 41.661035 -303.799398)
			(xy 41.61218 -303.80533) (xy 41.563005 -303.803349) (xy 41.514786 -303.793505) (xy 41.46877 -303.776053)
			(xy 41.426149 -303.751446) (xy 41.388028 -303.720321) (xy 41.355393 -303.683484) (xy 41.32909 -303.641888)
			(xy 41.309799 -303.596612) (xy 41.298022 -303.548828) (xy 41.294062 -303.499774) (xy 40.005254 -303.499774)
			(xy 40.004759 -303.524381) (xy 39.996864 -303.572958) (xy 39.98128 -303.619639) (xy 39.958409 -303.663216)
			(xy 39.928844 -303.70256) (xy 39.893351 -303.736652) (xy 39.852848 -303.764608) (xy 39.808386 -303.785706)
			(xy 39.761115 -303.799398) (xy 39.71226 -303.80533) (xy 39.663085 -303.803349) (xy 39.614866 -303.793505)
			(xy 39.56885 -303.776053) (xy 39.526229 -303.751446) (xy 39.488108 -303.720321) (xy 39.455473 -303.683484)
			(xy 39.42917 -303.641888) (xy 39.409879 -303.596612) (xy 39.398102 -303.548828) (xy 39.394142 -303.499774)
			(xy 39.055294 -303.499774) (xy 39.054799 -303.524381) (xy 39.046904 -303.572958) (xy 39.03132 -303.619639)
			(xy 39.008449 -303.663216) (xy 38.978884 -303.70256) (xy 38.943391 -303.736652) (xy 38.902888 -303.764608)
			(xy 38.858426 -303.785706) (xy 38.811155 -303.799398) (xy 38.7623 -303.80533) (xy 38.713125 -303.803349)
			(xy 38.664906 -303.793505) (xy 38.61889 -303.776053) (xy 38.576269 -303.751446) (xy 38.538148 -303.720321)
			(xy 38.505513 -303.683484) (xy 38.47921 -303.641888) (xy 38.459919 -303.596612) (xy 38.448142 -303.548828)
			(xy 38.444182 -303.499774) (xy 0.509016 -303.499774) (xy 0.509016 -304.449734) (xy 36.544008 -304.449734)
			(xy 36.547968 -304.40068) (xy 36.559745 -304.352896) (xy 36.579036 -304.30762) (xy 36.605339 -304.266024)
			(xy 36.637974 -304.229187) (xy 36.676095 -304.198062) (xy 36.718716 -304.173455) (xy 36.764732 -304.156003)
			(xy 36.812951 -304.146159) (xy 36.862126 -304.144178) (xy 36.910981 -304.15011) (xy 36.958252 -304.163802)
			(xy 37.002714 -304.1849) (xy 37.043217 -304.212856) (xy 37.07871 -304.246948) (xy 37.108275 -304.286292)
			(xy 37.131146 -304.329869) (xy 37.14673 -304.37655) (xy 37.154625 -304.425127) (xy 37.15512 -304.449734)
			(xy 37.493968 -304.449734) (xy 37.497928 -304.40068) (xy 37.509705 -304.352896) (xy 37.528996 -304.30762)
			(xy 37.555299 -304.266024) (xy 37.587934 -304.229187) (xy 37.626055 -304.198062) (xy 37.668676 -304.173455)
			(xy 37.714692 -304.156003) (xy 37.762911 -304.146159) (xy 37.812086 -304.144178) (xy 37.860941 -304.15011)
			(xy 37.908212 -304.163802) (xy 37.952674 -304.1849) (xy 37.993177 -304.212856) (xy 38.02867 -304.246948)
			(xy 38.058235 -304.286292) (xy 38.081106 -304.329869) (xy 38.09669 -304.37655) (xy 38.104585 -304.425127)
			(xy 38.10508 -304.449734) (xy 43.193982 -304.449734) (xy 43.197942 -304.40068) (xy 43.209719 -304.352896)
			(xy 43.22901 -304.30762) (xy 43.255313 -304.266024) (xy 43.287948 -304.229187) (xy 43.326069 -304.198062)
			(xy 43.36869 -304.173455) (xy 43.414706 -304.156003) (xy 43.462925 -304.146159) (xy 43.5121 -304.144178)
			(xy 43.560955 -304.15011) (xy 43.608226 -304.163802) (xy 43.652688 -304.1849) (xy 43.693191 -304.212856)
			(xy 43.728684 -304.246948) (xy 43.758249 -304.286292) (xy 43.78112 -304.329869) (xy 43.796704 -304.37655)
			(xy 43.804599 -304.425127) (xy 43.805094 -304.449734) (xy 44.143942 -304.449734) (xy 44.147902 -304.40068)
			(xy 44.159679 -304.352896) (xy 44.17897 -304.30762) (xy 44.205273 -304.266024) (xy 44.237908 -304.229187)
			(xy 44.276029 -304.198062) (xy 44.31865 -304.173455) (xy 44.364666 -304.156003) (xy 44.412885 -304.146159)
			(xy 44.46206 -304.144178) (xy 44.510915 -304.15011) (xy 44.558186 -304.163802) (xy 44.602648 -304.1849)
			(xy 44.643151 -304.212856) (xy 44.678644 -304.246948) (xy 44.708209 -304.286292) (xy 44.73108 -304.329869)
			(xy 44.746664 -304.37655) (xy 44.754559 -304.425127) (xy 44.755054 -304.449734) (xy 74.544186 -304.449734)
			(xy 74.548146 -304.40068) (xy 74.559923 -304.352896) (xy 74.579214 -304.30762) (xy 74.605517 -304.266024)
			(xy 74.638152 -304.229187) (xy 74.676273 -304.198062) (xy 74.718894 -304.173455) (xy 74.76491 -304.156003)
			(xy 74.813129 -304.146159) (xy 74.862304 -304.144178) (xy 74.911159 -304.15011) (xy 74.95843 -304.163802)
			(xy 75.002892 -304.1849) (xy 75.043395 -304.212856) (xy 75.078888 -304.246948) (xy 75.108453 -304.286292)
			(xy 75.131324 -304.329869) (xy 75.146908 -304.37655) (xy 75.154803 -304.425127) (xy 75.155298 -304.449734)
			(xy 75.494146 -304.449734) (xy 75.498106 -304.40068) (xy 75.509883 -304.352896) (xy 75.529174 -304.30762)
			(xy 75.555477 -304.266024) (xy 75.588112 -304.229187) (xy 75.626233 -304.198062) (xy 75.668854 -304.173455)
			(xy 75.71487 -304.156003) (xy 75.763089 -304.146159) (xy 75.812264 -304.144178) (xy 75.861119 -304.15011)
			(xy 75.90839 -304.163802) (xy 75.952852 -304.1849) (xy 75.993355 -304.212856) (xy 76.028848 -304.246948)
			(xy 76.058413 -304.286292) (xy 76.081284 -304.329869) (xy 76.096868 -304.37655) (xy 76.104763 -304.425127)
			(xy 76.105258 -304.449734) (xy 81.19416 -304.449734) (xy 81.19812 -304.40068) (xy 81.209897 -304.352896)
			(xy 81.229188 -304.30762) (xy 81.255491 -304.266024) (xy 81.288126 -304.229187) (xy 81.326247 -304.198062)
			(xy 81.368868 -304.173455) (xy 81.414884 -304.156003) (xy 81.463103 -304.146159) (xy 81.512278 -304.144178)
			(xy 81.561133 -304.15011) (xy 81.608404 -304.163802) (xy 81.652866 -304.1849) (xy 81.693369 -304.212856)
			(xy 81.728862 -304.246948) (xy 81.758427 -304.286292) (xy 81.781298 -304.329869) (xy 81.796882 -304.37655)
			(xy 81.804777 -304.425127) (xy 81.805272 -304.449734) (xy 82.14412 -304.449734) (xy 82.14808 -304.40068)
			(xy 82.159857 -304.352896) (xy 82.179148 -304.30762) (xy 82.205451 -304.266024) (xy 82.238086 -304.229187)
			(xy 82.276207 -304.198062) (xy 82.318828 -304.173455) (xy 82.364844 -304.156003) (xy 82.413063 -304.146159)
			(xy 82.462238 -304.144178) (xy 82.511093 -304.15011) (xy 82.558364 -304.163802) (xy 82.602826 -304.1849)
			(xy 82.643329 -304.212856) (xy 82.678822 -304.246948) (xy 82.708387 -304.286292) (xy 82.731258 -304.329869)
			(xy 82.746842 -304.37655) (xy 82.754737 -304.425127) (xy 82.755232 -304.449734) (xy 152.644106 -304.449734)
			(xy 152.648066 -304.40068) (xy 152.659843 -304.352896) (xy 152.679134 -304.30762) (xy 152.705437 -304.266024)
			(xy 152.738072 -304.229187) (xy 152.776193 -304.198062) (xy 152.818814 -304.173455) (xy 152.86483 -304.156003)
			(xy 152.913049 -304.146159) (xy 152.962224 -304.144178) (xy 153.011079 -304.15011) (xy 153.05835 -304.163802)
			(xy 153.102812 -304.1849) (xy 153.143315 -304.212856) (xy 153.178808 -304.246948) (xy 153.208373 -304.286292)
			(xy 153.231244 -304.329869) (xy 153.246828 -304.37655) (xy 153.254723 -304.425127) (xy 153.255218 -304.449734)
			(xy 153.594066 -304.449734) (xy 153.598026 -304.40068) (xy 153.609803 -304.352896) (xy 153.629094 -304.30762)
			(xy 153.655397 -304.266024) (xy 153.688032 -304.229187) (xy 153.726153 -304.198062) (xy 153.768774 -304.173455)
			(xy 153.81479 -304.156003) (xy 153.863009 -304.146159) (xy 153.912184 -304.144178) (xy 153.961039 -304.15011)
			(xy 154.00831 -304.163802) (xy 154.052772 -304.1849) (xy 154.093275 -304.212856) (xy 154.128768 -304.246948)
			(xy 154.158333 -304.286292) (xy 154.181204 -304.329869) (xy 154.196788 -304.37655) (xy 154.204683 -304.425127)
			(xy 154.205178 -304.449734) (xy 159.29408 -304.449734) (xy 159.29804 -304.40068) (xy 159.309817 -304.352896)
			(xy 159.329108 -304.30762) (xy 159.355411 -304.266024) (xy 159.388046 -304.229187) (xy 159.426167 -304.198062)
			(xy 159.468788 -304.173455) (xy 159.514804 -304.156003) (xy 159.563023 -304.146159) (xy 159.612198 -304.144178)
			(xy 159.661053 -304.15011) (xy 159.708324 -304.163802) (xy 159.752786 -304.1849) (xy 159.793289 -304.212856)
			(xy 159.828782 -304.246948) (xy 159.858347 -304.286292) (xy 159.881218 -304.329869) (xy 159.896802 -304.37655)
			(xy 159.904697 -304.425127) (xy 159.905192 -304.449734) (xy 160.24404 -304.449734) (xy 160.248 -304.40068)
			(xy 160.259777 -304.352896) (xy 160.279068 -304.30762) (xy 160.305371 -304.266024) (xy 160.338006 -304.229187)
			(xy 160.376127 -304.198062) (xy 160.418748 -304.173455) (xy 160.464764 -304.156003) (xy 160.512983 -304.146159)
			(xy 160.562158 -304.144178) (xy 160.611013 -304.15011) (xy 160.658284 -304.163802) (xy 160.702746 -304.1849)
			(xy 160.743249 -304.212856) (xy 160.778742 -304.246948) (xy 160.808307 -304.286292) (xy 160.831178 -304.329869)
			(xy 160.846762 -304.37655) (xy 160.854657 -304.425127) (xy 160.855152 -304.449734) (xy 190.644284 -304.449734)
			(xy 190.648244 -304.40068) (xy 190.660021 -304.352896) (xy 190.679312 -304.30762) (xy 190.705615 -304.266024)
			(xy 190.73825 -304.229187) (xy 190.776371 -304.198062) (xy 190.818992 -304.173455) (xy 190.865008 -304.156003)
			(xy 190.913227 -304.146159) (xy 190.962402 -304.144178) (xy 191.011257 -304.15011) (xy 191.058528 -304.163802)
			(xy 191.10299 -304.1849) (xy 191.143493 -304.212856) (xy 191.178986 -304.246948) (xy 191.208551 -304.286292)
			(xy 191.231422 -304.329869) (xy 191.247006 -304.37655) (xy 191.254901 -304.425127) (xy 191.255396 -304.449734)
			(xy 191.594244 -304.449734) (xy 191.598204 -304.40068) (xy 191.609981 -304.352896) (xy 191.629272 -304.30762)
			(xy 191.655575 -304.266024) (xy 191.68821 -304.229187) (xy 191.726331 -304.198062) (xy 191.768952 -304.173455)
			(xy 191.814968 -304.156003) (xy 191.863187 -304.146159) (xy 191.912362 -304.144178) (xy 191.961217 -304.15011)
			(xy 192.008488 -304.163802) (xy 192.05295 -304.1849) (xy 192.093453 -304.212856) (xy 192.128946 -304.246948)
			(xy 192.158511 -304.286292) (xy 192.181382 -304.329869) (xy 192.196966 -304.37655) (xy 192.204861 -304.425127)
			(xy 192.205356 -304.449734) (xy 197.294258 -304.449734) (xy 197.298218 -304.40068) (xy 197.309995 -304.352896)
			(xy 197.329286 -304.30762) (xy 197.355589 -304.266024) (xy 197.388224 -304.229187) (xy 197.426345 -304.198062)
			(xy 197.468966 -304.173455) (xy 197.514982 -304.156003) (xy 197.563201 -304.146159) (xy 197.612376 -304.144178)
			(xy 197.661231 -304.15011) (xy 197.708502 -304.163802) (xy 197.752964 -304.1849) (xy 197.793467 -304.212856)
			(xy 197.82896 -304.246948) (xy 197.858525 -304.286292) (xy 197.881396 -304.329869) (xy 197.89698 -304.37655)
			(xy 197.904875 -304.425127) (xy 197.90537 -304.449734) (xy 198.244218 -304.449734) (xy 198.248178 -304.40068)
			(xy 198.259955 -304.352896) (xy 198.279246 -304.30762) (xy 198.305549 -304.266024) (xy 198.338184 -304.229187)
			(xy 198.376305 -304.198062) (xy 198.418926 -304.173455) (xy 198.464942 -304.156003) (xy 198.513161 -304.146159)
			(xy 198.562336 -304.144178) (xy 198.611191 -304.15011) (xy 198.658462 -304.163802) (xy 198.702924 -304.1849)
			(xy 198.743427 -304.212856) (xy 198.77892 -304.246948) (xy 198.808485 -304.286292) (xy 198.831356 -304.329869)
			(xy 198.84694 -304.37655) (xy 198.854835 -304.425127) (xy 198.85533 -304.449734) (xy 268.74395 -304.449734)
			(xy 268.74791 -304.40068) (xy 268.759687 -304.352896) (xy 268.778978 -304.30762) (xy 268.805281 -304.266024)
			(xy 268.837916 -304.229187) (xy 268.876037 -304.198062) (xy 268.918658 -304.173455) (xy 268.964674 -304.156003)
			(xy 269.012893 -304.146159) (xy 269.062068 -304.144178) (xy 269.110923 -304.15011) (xy 269.158194 -304.163802)
			(xy 269.202656 -304.1849) (xy 269.243159 -304.212856) (xy 269.278652 -304.246948) (xy 269.308217 -304.286292)
			(xy 269.331088 -304.329869) (xy 269.346672 -304.37655) (xy 269.354567 -304.425127) (xy 269.355062 -304.449734)
			(xy 269.69391 -304.449734) (xy 269.69787 -304.40068) (xy 269.709647 -304.352896) (xy 269.728938 -304.30762)
			(xy 269.755241 -304.266024) (xy 269.787876 -304.229187) (xy 269.825997 -304.198062) (xy 269.868618 -304.173455)
			(xy 269.914634 -304.156003) (xy 269.962853 -304.146159) (xy 270.012028 -304.144178) (xy 270.060883 -304.15011)
			(xy 270.108154 -304.163802) (xy 270.152616 -304.1849) (xy 270.193119 -304.212856) (xy 270.228612 -304.246948)
			(xy 270.258177 -304.286292) (xy 270.281048 -304.329869) (xy 270.296632 -304.37655) (xy 270.304527 -304.425127)
			(xy 270.305022 -304.449734) (xy 275.393924 -304.449734) (xy 275.397884 -304.40068) (xy 275.409661 -304.352896)
			(xy 275.428952 -304.30762) (xy 275.455255 -304.266024) (xy 275.48789 -304.229187) (xy 275.526011 -304.198062)
			(xy 275.568632 -304.173455) (xy 275.614648 -304.156003) (xy 275.662867 -304.146159) (xy 275.712042 -304.144178)
			(xy 275.760897 -304.15011) (xy 275.808168 -304.163802) (xy 275.85263 -304.1849) (xy 275.893133 -304.212856)
			(xy 275.928626 -304.246948) (xy 275.958191 -304.286292) (xy 275.981062 -304.329869) (xy 275.996646 -304.37655)
			(xy 276.004541 -304.425127) (xy 276.005036 -304.449734) (xy 276.343884 -304.449734) (xy 276.347844 -304.40068)
			(xy 276.359621 -304.352896) (xy 276.378912 -304.30762) (xy 276.405215 -304.266024) (xy 276.43785 -304.229187)
			(xy 276.475971 -304.198062) (xy 276.518592 -304.173455) (xy 276.564608 -304.156003) (xy 276.612827 -304.146159)
			(xy 276.662002 -304.144178) (xy 276.710857 -304.15011) (xy 276.758128 -304.163802) (xy 276.80259 -304.1849)
			(xy 276.843093 -304.212856) (xy 276.878586 -304.246948) (xy 276.908151 -304.286292) (xy 276.931022 -304.329869)
			(xy 276.946606 -304.37655) (xy 276.954501 -304.425127) (xy 276.954996 -304.449734) (xy 306.744128 -304.449734)
			(xy 306.748088 -304.40068) (xy 306.759865 -304.352896) (xy 306.779156 -304.30762) (xy 306.805459 -304.266024)
			(xy 306.838094 -304.229187) (xy 306.876215 -304.198062) (xy 306.918836 -304.173455) (xy 306.964852 -304.156003)
			(xy 307.013071 -304.146159) (xy 307.062246 -304.144178) (xy 307.111101 -304.15011) (xy 307.158372 -304.163802)
			(xy 307.202834 -304.1849) (xy 307.243337 -304.212856) (xy 307.27883 -304.246948) (xy 307.308395 -304.286292)
			(xy 307.331266 -304.329869) (xy 307.34685 -304.37655) (xy 307.354745 -304.425127) (xy 307.35524 -304.449734)
			(xy 307.694088 -304.449734) (xy 307.698048 -304.40068) (xy 307.709825 -304.352896) (xy 307.729116 -304.30762)
			(xy 307.755419 -304.266024) (xy 307.788054 -304.229187) (xy 307.826175 -304.198062) (xy 307.868796 -304.173455)
			(xy 307.914812 -304.156003) (xy 307.963031 -304.146159) (xy 308.012206 -304.144178) (xy 308.061061 -304.15011)
			(xy 308.108332 -304.163802) (xy 308.152794 -304.1849) (xy 308.193297 -304.212856) (xy 308.22879 -304.246948)
			(xy 308.258355 -304.286292) (xy 308.281226 -304.329869) (xy 308.29681 -304.37655) (xy 308.304705 -304.425127)
			(xy 308.3052 -304.449734) (xy 313.394102 -304.449734) (xy 313.398062 -304.40068) (xy 313.409839 -304.352896)
			(xy 313.42913 -304.30762) (xy 313.455433 -304.266024) (xy 313.488068 -304.229187) (xy 313.526189 -304.198062)
			(xy 313.56881 -304.173455) (xy 313.614826 -304.156003) (xy 313.663045 -304.146159) (xy 313.71222 -304.144178)
			(xy 313.761075 -304.15011) (xy 313.808346 -304.163802) (xy 313.852808 -304.1849) (xy 313.893311 -304.212856)
			(xy 313.928804 -304.246948) (xy 313.958369 -304.286292) (xy 313.98124 -304.329869) (xy 313.996824 -304.37655)
			(xy 314.004719 -304.425127) (xy 314.005214 -304.449734) (xy 314.344062 -304.449734) (xy 314.348022 -304.40068)
			(xy 314.359799 -304.352896) (xy 314.37909 -304.30762) (xy 314.405393 -304.266024) (xy 314.438028 -304.229187)
			(xy 314.476149 -304.198062) (xy 314.51877 -304.173455) (xy 314.564786 -304.156003) (xy 314.613005 -304.146159)
			(xy 314.66218 -304.144178) (xy 314.711035 -304.15011) (xy 314.758306 -304.163802) (xy 314.802768 -304.1849)
			(xy 314.843271 -304.212856) (xy 314.878764 -304.246948) (xy 314.908329 -304.286292) (xy 314.9312 -304.329869)
			(xy 314.946784 -304.37655) (xy 314.954679 -304.425127) (xy 314.955174 -304.449734) (xy 384.844048 -304.449734)
			(xy 384.848008 -304.40068) (xy 384.859785 -304.352896) (xy 384.879076 -304.30762) (xy 384.905379 -304.266024)
			(xy 384.938014 -304.229187) (xy 384.976135 -304.198062) (xy 385.018756 -304.173455) (xy 385.064772 -304.156003)
			(xy 385.112991 -304.146159) (xy 385.162166 -304.144178) (xy 385.211021 -304.15011) (xy 385.258292 -304.163802)
			(xy 385.302754 -304.1849) (xy 385.343257 -304.212856) (xy 385.37875 -304.246948) (xy 385.408315 -304.286292)
			(xy 385.431186 -304.329869) (xy 385.44677 -304.37655) (xy 385.454665 -304.425127) (xy 385.45516 -304.449734)
			(xy 385.794008 -304.449734) (xy 385.797968 -304.40068) (xy 385.809745 -304.352896) (xy 385.829036 -304.30762)
			(xy 385.855339 -304.266024) (xy 385.887974 -304.229187) (xy 385.926095 -304.198062) (xy 385.968716 -304.173455)
			(xy 386.014732 -304.156003) (xy 386.062951 -304.146159) (xy 386.112126 -304.144178) (xy 386.160981 -304.15011)
			(xy 386.208252 -304.163802) (xy 386.252714 -304.1849) (xy 386.293217 -304.212856) (xy 386.32871 -304.246948)
			(xy 386.358275 -304.286292) (xy 386.381146 -304.329869) (xy 386.39673 -304.37655) (xy 386.404625 -304.425127)
			(xy 386.40512 -304.449734) (xy 391.494022 -304.449734) (xy 391.497982 -304.40068) (xy 391.509759 -304.352896)
			(xy 391.52905 -304.30762) (xy 391.555353 -304.266024) (xy 391.587988 -304.229187) (xy 391.626109 -304.198062)
			(xy 391.66873 -304.173455) (xy 391.714746 -304.156003) (xy 391.762965 -304.146159) (xy 391.81214 -304.144178)
			(xy 391.860995 -304.15011) (xy 391.908266 -304.163802) (xy 391.952728 -304.1849) (xy 391.993231 -304.212856)
			(xy 392.028724 -304.246948) (xy 392.058289 -304.286292) (xy 392.08116 -304.329869) (xy 392.096744 -304.37655)
			(xy 392.104639 -304.425127) (xy 392.105134 -304.449734) (xy 392.443982 -304.449734) (xy 392.447942 -304.40068)
			(xy 392.459719 -304.352896) (xy 392.47901 -304.30762) (xy 392.505313 -304.266024) (xy 392.537948 -304.229187)
			(xy 392.576069 -304.198062) (xy 392.61869 -304.173455) (xy 392.664706 -304.156003) (xy 392.712925 -304.146159)
			(xy 392.7621 -304.144178) (xy 392.810955 -304.15011) (xy 392.858226 -304.163802) (xy 392.902688 -304.1849)
			(xy 392.943191 -304.212856) (xy 392.978684 -304.246948) (xy 393.008249 -304.286292) (xy 393.03112 -304.329869)
			(xy 393.046704 -304.37655) (xy 393.054599 -304.425127) (xy 393.055094 -304.449734) (xy 422.844226 -304.449734)
			(xy 422.848186 -304.40068) (xy 422.859963 -304.352896) (xy 422.879254 -304.30762) (xy 422.905557 -304.266024)
			(xy 422.938192 -304.229187) (xy 422.976313 -304.198062) (xy 423.018934 -304.173455) (xy 423.06495 -304.156003)
			(xy 423.113169 -304.146159) (xy 423.162344 -304.144178) (xy 423.211199 -304.15011) (xy 423.25847 -304.163802)
			(xy 423.302932 -304.1849) (xy 423.343435 -304.212856) (xy 423.378928 -304.246948) (xy 423.408493 -304.286292)
			(xy 423.431364 -304.329869) (xy 423.446948 -304.37655) (xy 423.454843 -304.425127) (xy 423.455338 -304.449734)
			(xy 423.794186 -304.449734) (xy 423.798146 -304.40068) (xy 423.809923 -304.352896) (xy 423.829214 -304.30762)
			(xy 423.855517 -304.266024) (xy 423.888152 -304.229187) (xy 423.926273 -304.198062) (xy 423.968894 -304.173455)
			(xy 424.01491 -304.156003) (xy 424.063129 -304.146159) (xy 424.112304 -304.144178) (xy 424.161159 -304.15011)
			(xy 424.20843 -304.163802) (xy 424.252892 -304.1849) (xy 424.293395 -304.212856) (xy 424.328888 -304.246948)
			(xy 424.358453 -304.286292) (xy 424.381324 -304.329869) (xy 424.396908 -304.37655) (xy 424.404803 -304.425127)
			(xy 424.405298 -304.449734) (xy 429.4942 -304.449734) (xy 429.49816 -304.40068) (xy 429.509937 -304.352896)
			(xy 429.529228 -304.30762) (xy 429.555531 -304.266024) (xy 429.588166 -304.229187) (xy 429.626287 -304.198062)
			(xy 429.668908 -304.173455) (xy 429.714924 -304.156003) (xy 429.763143 -304.146159) (xy 429.812318 -304.144178)
			(xy 429.861173 -304.15011) (xy 429.908444 -304.163802) (xy 429.952906 -304.1849) (xy 429.993409 -304.212856)
			(xy 430.028902 -304.246948) (xy 430.058467 -304.286292) (xy 430.081338 -304.329869) (xy 430.096922 -304.37655)
			(xy 430.104817 -304.425127) (xy 430.105312 -304.449734) (xy 430.44416 -304.449734) (xy 430.44812 -304.40068)
			(xy 430.459897 -304.352896) (xy 430.479188 -304.30762) (xy 430.505491 -304.266024) (xy 430.538126 -304.229187)
			(xy 430.576247 -304.198062) (xy 430.618868 -304.173455) (xy 430.664884 -304.156003) (xy 430.713103 -304.146159)
			(xy 430.762278 -304.144178) (xy 430.811133 -304.15011) (xy 430.858404 -304.163802) (xy 430.902866 -304.1849)
			(xy 430.943369 -304.212856) (xy 430.978862 -304.246948) (xy 431.008427 -304.286292) (xy 431.031298 -304.329869)
			(xy 431.046882 -304.37655) (xy 431.054777 -304.425127) (xy 431.055272 -304.449734) (xy 431.054777 -304.474341)
			(xy 431.046882 -304.522918) (xy 431.031298 -304.569599) (xy 431.008427 -304.613176) (xy 430.978862 -304.65252)
			(xy 430.943369 -304.686612) (xy 430.902866 -304.714568) (xy 430.858404 -304.735666) (xy 430.811133 -304.749358)
			(xy 430.762278 -304.75529) (xy 430.713103 -304.753309) (xy 430.664884 -304.743465) (xy 430.618868 -304.726013)
			(xy 430.576247 -304.701406) (xy 430.538126 -304.670281) (xy 430.505491 -304.633444) (xy 430.479188 -304.591848)
			(xy 430.459897 -304.546572) (xy 430.44812 -304.498788) (xy 430.44416 -304.449734) (xy 430.105312 -304.449734)
			(xy 430.104817 -304.474341) (xy 430.096922 -304.522918) (xy 430.081338 -304.569599) (xy 430.058467 -304.613176)
			(xy 430.028902 -304.65252) (xy 429.993409 -304.686612) (xy 429.952906 -304.714568) (xy 429.908444 -304.735666)
			(xy 429.861173 -304.749358) (xy 429.812318 -304.75529) (xy 429.763143 -304.753309) (xy 429.714924 -304.743465)
			(xy 429.668908 -304.726013) (xy 429.626287 -304.701406) (xy 429.588166 -304.670281) (xy 429.555531 -304.633444)
			(xy 429.529228 -304.591848) (xy 429.509937 -304.546572) (xy 429.49816 -304.498788) (xy 429.4942 -304.449734)
			(xy 424.405298 -304.449734) (xy 424.404803 -304.474341) (xy 424.396908 -304.522918) (xy 424.381324 -304.569599)
			(xy 424.358453 -304.613176) (xy 424.328888 -304.65252) (xy 424.293395 -304.686612) (xy 424.252892 -304.714568)
			(xy 424.20843 -304.735666) (xy 424.161159 -304.749358) (xy 424.112304 -304.75529) (xy 424.063129 -304.753309)
			(xy 424.01491 -304.743465) (xy 423.968894 -304.726013) (xy 423.926273 -304.701406) (xy 423.888152 -304.670281)
			(xy 423.855517 -304.633444) (xy 423.829214 -304.591848) (xy 423.809923 -304.546572) (xy 423.798146 -304.498788)
			(xy 423.794186 -304.449734) (xy 423.455338 -304.449734) (xy 423.454843 -304.474341) (xy 423.446948 -304.522918)
			(xy 423.431364 -304.569599) (xy 423.408493 -304.613176) (xy 423.378928 -304.65252) (xy 423.343435 -304.686612)
			(xy 423.302932 -304.714568) (xy 423.25847 -304.735666) (xy 423.211199 -304.749358) (xy 423.162344 -304.75529)
			(xy 423.113169 -304.753309) (xy 423.06495 -304.743465) (xy 423.018934 -304.726013) (xy 422.976313 -304.701406)
			(xy 422.938192 -304.670281) (xy 422.905557 -304.633444) (xy 422.879254 -304.591848) (xy 422.859963 -304.546572)
			(xy 422.848186 -304.498788) (xy 422.844226 -304.449734) (xy 393.055094 -304.449734) (xy 393.054599 -304.474341)
			(xy 393.046704 -304.522918) (xy 393.03112 -304.569599) (xy 393.008249 -304.613176) (xy 392.978684 -304.65252)
			(xy 392.943191 -304.686612) (xy 392.902688 -304.714568) (xy 392.858226 -304.735666) (xy 392.810955 -304.749358)
			(xy 392.7621 -304.75529) (xy 392.712925 -304.753309) (xy 392.664706 -304.743465) (xy 392.61869 -304.726013)
			(xy 392.576069 -304.701406) (xy 392.537948 -304.670281) (xy 392.505313 -304.633444) (xy 392.47901 -304.591848)
			(xy 392.459719 -304.546572) (xy 392.447942 -304.498788) (xy 392.443982 -304.449734) (xy 392.105134 -304.449734)
			(xy 392.104639 -304.474341) (xy 392.096744 -304.522918) (xy 392.08116 -304.569599) (xy 392.058289 -304.613176)
			(xy 392.028724 -304.65252) (xy 391.993231 -304.686612) (xy 391.952728 -304.714568) (xy 391.908266 -304.735666)
			(xy 391.860995 -304.749358) (xy 391.81214 -304.75529) (xy 391.762965 -304.753309) (xy 391.714746 -304.743465)
			(xy 391.66873 -304.726013) (xy 391.626109 -304.701406) (xy 391.587988 -304.670281) (xy 391.555353 -304.633444)
			(xy 391.52905 -304.591848) (xy 391.509759 -304.546572) (xy 391.497982 -304.498788) (xy 391.494022 -304.449734)
			(xy 386.40512 -304.449734) (xy 386.404625 -304.474341) (xy 386.39673 -304.522918) (xy 386.381146 -304.569599)
			(xy 386.358275 -304.613176) (xy 386.32871 -304.65252) (xy 386.293217 -304.686612) (xy 386.252714 -304.714568)
			(xy 386.208252 -304.735666) (xy 386.160981 -304.749358) (xy 386.112126 -304.75529) (xy 386.062951 -304.753309)
			(xy 386.014732 -304.743465) (xy 385.968716 -304.726013) (xy 385.926095 -304.701406) (xy 385.887974 -304.670281)
			(xy 385.855339 -304.633444) (xy 385.829036 -304.591848) (xy 385.809745 -304.546572) (xy 385.797968 -304.498788)
			(xy 385.794008 -304.449734) (xy 385.45516 -304.449734) (xy 385.454665 -304.474341) (xy 385.44677 -304.522918)
			(xy 385.431186 -304.569599) (xy 385.408315 -304.613176) (xy 385.37875 -304.65252) (xy 385.343257 -304.686612)
			(xy 385.302754 -304.714568) (xy 385.258292 -304.735666) (xy 385.211021 -304.749358) (xy 385.162166 -304.75529)
			(xy 385.112991 -304.753309) (xy 385.064772 -304.743465) (xy 385.018756 -304.726013) (xy 384.976135 -304.701406)
			(xy 384.938014 -304.670281) (xy 384.905379 -304.633444) (xy 384.879076 -304.591848) (xy 384.859785 -304.546572)
			(xy 384.848008 -304.498788) (xy 384.844048 -304.449734) (xy 314.955174 -304.449734) (xy 314.954679 -304.474341)
			(xy 314.946784 -304.522918) (xy 314.9312 -304.569599) (xy 314.908329 -304.613176) (xy 314.878764 -304.65252)
			(xy 314.843271 -304.686612) (xy 314.802768 -304.714568) (xy 314.758306 -304.735666) (xy 314.711035 -304.749358)
			(xy 314.66218 -304.75529) (xy 314.613005 -304.753309) (xy 314.564786 -304.743465) (xy 314.51877 -304.726013)
			(xy 314.476149 -304.701406) (xy 314.438028 -304.670281) (xy 314.405393 -304.633444) (xy 314.37909 -304.591848)
			(xy 314.359799 -304.546572) (xy 314.348022 -304.498788) (xy 314.344062 -304.449734) (xy 314.005214 -304.449734)
			(xy 314.004719 -304.474341) (xy 313.996824 -304.522918) (xy 313.98124 -304.569599) (xy 313.958369 -304.613176)
			(xy 313.928804 -304.65252) (xy 313.893311 -304.686612) (xy 313.852808 -304.714568) (xy 313.808346 -304.735666)
			(xy 313.761075 -304.749358) (xy 313.71222 -304.75529) (xy 313.663045 -304.753309) (xy 313.614826 -304.743465)
			(xy 313.56881 -304.726013) (xy 313.526189 -304.701406) (xy 313.488068 -304.670281) (xy 313.455433 -304.633444)
			(xy 313.42913 -304.591848) (xy 313.409839 -304.546572) (xy 313.398062 -304.498788) (xy 313.394102 -304.449734)
			(xy 308.3052 -304.449734) (xy 308.304705 -304.474341) (xy 308.29681 -304.522918) (xy 308.281226 -304.569599)
			(xy 308.258355 -304.613176) (xy 308.22879 -304.65252) (xy 308.193297 -304.686612) (xy 308.152794 -304.714568)
			(xy 308.108332 -304.735666) (xy 308.061061 -304.749358) (xy 308.012206 -304.75529) (xy 307.963031 -304.753309)
			(xy 307.914812 -304.743465) (xy 307.868796 -304.726013) (xy 307.826175 -304.701406) (xy 307.788054 -304.670281)
			(xy 307.755419 -304.633444) (xy 307.729116 -304.591848) (xy 307.709825 -304.546572) (xy 307.698048 -304.498788)
			(xy 307.694088 -304.449734) (xy 307.35524 -304.449734) (xy 307.354745 -304.474341) (xy 307.34685 -304.522918)
			(xy 307.331266 -304.569599) (xy 307.308395 -304.613176) (xy 307.27883 -304.65252) (xy 307.243337 -304.686612)
			(xy 307.202834 -304.714568) (xy 307.158372 -304.735666) (xy 307.111101 -304.749358) (xy 307.062246 -304.75529)
			(xy 307.013071 -304.753309) (xy 306.964852 -304.743465) (xy 306.918836 -304.726013) (xy 306.876215 -304.701406)
			(xy 306.838094 -304.670281) (xy 306.805459 -304.633444) (xy 306.779156 -304.591848) (xy 306.759865 -304.546572)
			(xy 306.748088 -304.498788) (xy 306.744128 -304.449734) (xy 276.954996 -304.449734) (xy 276.954501 -304.474341)
			(xy 276.946606 -304.522918) (xy 276.931022 -304.569599) (xy 276.908151 -304.613176) (xy 276.878586 -304.65252)
			(xy 276.843093 -304.686612) (xy 276.80259 -304.714568) (xy 276.758128 -304.735666) (xy 276.710857 -304.749358)
			(xy 276.662002 -304.75529) (xy 276.612827 -304.753309) (xy 276.564608 -304.743465) (xy 276.518592 -304.726013)
			(xy 276.475971 -304.701406) (xy 276.43785 -304.670281) (xy 276.405215 -304.633444) (xy 276.378912 -304.591848)
			(xy 276.359621 -304.546572) (xy 276.347844 -304.498788) (xy 276.343884 -304.449734) (xy 276.005036 -304.449734)
			(xy 276.004541 -304.474341) (xy 275.996646 -304.522918) (xy 275.981062 -304.569599) (xy 275.958191 -304.613176)
			(xy 275.928626 -304.65252) (xy 275.893133 -304.686612) (xy 275.85263 -304.714568) (xy 275.808168 -304.735666)
			(xy 275.760897 -304.749358) (xy 275.712042 -304.75529) (xy 275.662867 -304.753309) (xy 275.614648 -304.743465)
			(xy 275.568632 -304.726013) (xy 275.526011 -304.701406) (xy 275.48789 -304.670281) (xy 275.455255 -304.633444)
			(xy 275.428952 -304.591848) (xy 275.409661 -304.546572) (xy 275.397884 -304.498788) (xy 275.393924 -304.449734)
			(xy 270.305022 -304.449734) (xy 270.304527 -304.474341) (xy 270.296632 -304.522918) (xy 270.281048 -304.569599)
			(xy 270.258177 -304.613176) (xy 270.228612 -304.65252) (xy 270.193119 -304.686612) (xy 270.152616 -304.714568)
			(xy 270.108154 -304.735666) (xy 270.060883 -304.749358) (xy 270.012028 -304.75529) (xy 269.962853 -304.753309)
			(xy 269.914634 -304.743465) (xy 269.868618 -304.726013) (xy 269.825997 -304.701406) (xy 269.787876 -304.670281)
			(xy 269.755241 -304.633444) (xy 269.728938 -304.591848) (xy 269.709647 -304.546572) (xy 269.69787 -304.498788)
			(xy 269.69391 -304.449734) (xy 269.355062 -304.449734) (xy 269.354567 -304.474341) (xy 269.346672 -304.522918)
			(xy 269.331088 -304.569599) (xy 269.308217 -304.613176) (xy 269.278652 -304.65252) (xy 269.243159 -304.686612)
			(xy 269.202656 -304.714568) (xy 269.158194 -304.735666) (xy 269.110923 -304.749358) (xy 269.062068 -304.75529)
			(xy 269.012893 -304.753309) (xy 268.964674 -304.743465) (xy 268.918658 -304.726013) (xy 268.876037 -304.701406)
			(xy 268.837916 -304.670281) (xy 268.805281 -304.633444) (xy 268.778978 -304.591848) (xy 268.759687 -304.546572)
			(xy 268.74791 -304.498788) (xy 268.74395 -304.449734) (xy 198.85533 -304.449734) (xy 198.854835 -304.474341)
			(xy 198.84694 -304.522918) (xy 198.831356 -304.569599) (xy 198.808485 -304.613176) (xy 198.77892 -304.65252)
			(xy 198.743427 -304.686612) (xy 198.702924 -304.714568) (xy 198.658462 -304.735666) (xy 198.611191 -304.749358)
			(xy 198.562336 -304.75529) (xy 198.513161 -304.753309) (xy 198.464942 -304.743465) (xy 198.418926 -304.726013)
			(xy 198.376305 -304.701406) (xy 198.338184 -304.670281) (xy 198.305549 -304.633444) (xy 198.279246 -304.591848)
			(xy 198.259955 -304.546572) (xy 198.248178 -304.498788) (xy 198.244218 -304.449734) (xy 197.90537 -304.449734)
			(xy 197.904875 -304.474341) (xy 197.89698 -304.522918) (xy 197.881396 -304.569599) (xy 197.858525 -304.613176)
			(xy 197.82896 -304.65252) (xy 197.793467 -304.686612) (xy 197.752964 -304.714568) (xy 197.708502 -304.735666)
			(xy 197.661231 -304.749358) (xy 197.612376 -304.75529) (xy 197.563201 -304.753309) (xy 197.514982 -304.743465)
			(xy 197.468966 -304.726013) (xy 197.426345 -304.701406) (xy 197.388224 -304.670281) (xy 197.355589 -304.633444)
			(xy 197.329286 -304.591848) (xy 197.309995 -304.546572) (xy 197.298218 -304.498788) (xy 197.294258 -304.449734)
			(xy 192.205356 -304.449734) (xy 192.204861 -304.474341) (xy 192.196966 -304.522918) (xy 192.181382 -304.569599)
			(xy 192.158511 -304.613176) (xy 192.128946 -304.65252) (xy 192.093453 -304.686612) (xy 192.05295 -304.714568)
			(xy 192.008488 -304.735666) (xy 191.961217 -304.749358) (xy 191.912362 -304.75529) (xy 191.863187 -304.753309)
			(xy 191.814968 -304.743465) (xy 191.768952 -304.726013) (xy 191.726331 -304.701406) (xy 191.68821 -304.670281)
			(xy 191.655575 -304.633444) (xy 191.629272 -304.591848) (xy 191.609981 -304.546572) (xy 191.598204 -304.498788)
			(xy 191.594244 -304.449734) (xy 191.255396 -304.449734) (xy 191.254901 -304.474341) (xy 191.247006 -304.522918)
			(xy 191.231422 -304.569599) (xy 191.208551 -304.613176) (xy 191.178986 -304.65252) (xy 191.143493 -304.686612)
			(xy 191.10299 -304.714568) (xy 191.058528 -304.735666) (xy 191.011257 -304.749358) (xy 190.962402 -304.75529)
			(xy 190.913227 -304.753309) (xy 190.865008 -304.743465) (xy 190.818992 -304.726013) (xy 190.776371 -304.701406)
			(xy 190.73825 -304.670281) (xy 190.705615 -304.633444) (xy 190.679312 -304.591848) (xy 190.660021 -304.546572)
			(xy 190.648244 -304.498788) (xy 190.644284 -304.449734) (xy 160.855152 -304.449734) (xy 160.854657 -304.474341)
			(xy 160.846762 -304.522918) (xy 160.831178 -304.569599) (xy 160.808307 -304.613176) (xy 160.778742 -304.65252)
			(xy 160.743249 -304.686612) (xy 160.702746 -304.714568) (xy 160.658284 -304.735666) (xy 160.611013 -304.749358)
			(xy 160.562158 -304.75529) (xy 160.512983 -304.753309) (xy 160.464764 -304.743465) (xy 160.418748 -304.726013)
			(xy 160.376127 -304.701406) (xy 160.338006 -304.670281) (xy 160.305371 -304.633444) (xy 160.279068 -304.591848)
			(xy 160.259777 -304.546572) (xy 160.248 -304.498788) (xy 160.24404 -304.449734) (xy 159.905192 -304.449734)
			(xy 159.904697 -304.474341) (xy 159.896802 -304.522918) (xy 159.881218 -304.569599) (xy 159.858347 -304.613176)
			(xy 159.828782 -304.65252) (xy 159.793289 -304.686612) (xy 159.752786 -304.714568) (xy 159.708324 -304.735666)
			(xy 159.661053 -304.749358) (xy 159.612198 -304.75529) (xy 159.563023 -304.753309) (xy 159.514804 -304.743465)
			(xy 159.468788 -304.726013) (xy 159.426167 -304.701406) (xy 159.388046 -304.670281) (xy 159.355411 -304.633444)
			(xy 159.329108 -304.591848) (xy 159.309817 -304.546572) (xy 159.29804 -304.498788) (xy 159.29408 -304.449734)
			(xy 154.205178 -304.449734) (xy 154.204683 -304.474341) (xy 154.196788 -304.522918) (xy 154.181204 -304.569599)
			(xy 154.158333 -304.613176) (xy 154.128768 -304.65252) (xy 154.093275 -304.686612) (xy 154.052772 -304.714568)
			(xy 154.00831 -304.735666) (xy 153.961039 -304.749358) (xy 153.912184 -304.75529) (xy 153.863009 -304.753309)
			(xy 153.81479 -304.743465) (xy 153.768774 -304.726013) (xy 153.726153 -304.701406) (xy 153.688032 -304.670281)
			(xy 153.655397 -304.633444) (xy 153.629094 -304.591848) (xy 153.609803 -304.546572) (xy 153.598026 -304.498788)
			(xy 153.594066 -304.449734) (xy 153.255218 -304.449734) (xy 153.254723 -304.474341) (xy 153.246828 -304.522918)
			(xy 153.231244 -304.569599) (xy 153.208373 -304.613176) (xy 153.178808 -304.65252) (xy 153.143315 -304.686612)
			(xy 153.102812 -304.714568) (xy 153.05835 -304.735666) (xy 153.011079 -304.749358) (xy 152.962224 -304.75529)
			(xy 152.913049 -304.753309) (xy 152.86483 -304.743465) (xy 152.818814 -304.726013) (xy 152.776193 -304.701406)
			(xy 152.738072 -304.670281) (xy 152.705437 -304.633444) (xy 152.679134 -304.591848) (xy 152.659843 -304.546572)
			(xy 152.648066 -304.498788) (xy 152.644106 -304.449734) (xy 82.755232 -304.449734) (xy 82.754737 -304.474341)
			(xy 82.746842 -304.522918) (xy 82.731258 -304.569599) (xy 82.708387 -304.613176) (xy 82.678822 -304.65252)
			(xy 82.643329 -304.686612) (xy 82.602826 -304.714568) (xy 82.558364 -304.735666) (xy 82.511093 -304.749358)
			(xy 82.462238 -304.75529) (xy 82.413063 -304.753309) (xy 82.364844 -304.743465) (xy 82.318828 -304.726013)
			(xy 82.276207 -304.701406) (xy 82.238086 -304.670281) (xy 82.205451 -304.633444) (xy 82.179148 -304.591848)
			(xy 82.159857 -304.546572) (xy 82.14808 -304.498788) (xy 82.14412 -304.449734) (xy 81.805272 -304.449734)
			(xy 81.804777 -304.474341) (xy 81.796882 -304.522918) (xy 81.781298 -304.569599) (xy 81.758427 -304.613176)
			(xy 81.728862 -304.65252) (xy 81.693369 -304.686612) (xy 81.652866 -304.714568) (xy 81.608404 -304.735666)
			(xy 81.561133 -304.749358) (xy 81.512278 -304.75529) (xy 81.463103 -304.753309) (xy 81.414884 -304.743465)
			(xy 81.368868 -304.726013) (xy 81.326247 -304.701406) (xy 81.288126 -304.670281) (xy 81.255491 -304.633444)
			(xy 81.229188 -304.591848) (xy 81.209897 -304.546572) (xy 81.19812 -304.498788) (xy 81.19416 -304.449734)
			(xy 76.105258 -304.449734) (xy 76.104763 -304.474341) (xy 76.096868 -304.522918) (xy 76.081284 -304.569599)
			(xy 76.058413 -304.613176) (xy 76.028848 -304.65252) (xy 75.993355 -304.686612) (xy 75.952852 -304.714568)
			(xy 75.90839 -304.735666) (xy 75.861119 -304.749358) (xy 75.812264 -304.75529) (xy 75.763089 -304.753309)
			(xy 75.71487 -304.743465) (xy 75.668854 -304.726013) (xy 75.626233 -304.701406) (xy 75.588112 -304.670281)
			(xy 75.555477 -304.633444) (xy 75.529174 -304.591848) (xy 75.509883 -304.546572) (xy 75.498106 -304.498788)
			(xy 75.494146 -304.449734) (xy 75.155298 -304.449734) (xy 75.154803 -304.474341) (xy 75.146908 -304.522918)
			(xy 75.131324 -304.569599) (xy 75.108453 -304.613176) (xy 75.078888 -304.65252) (xy 75.043395 -304.686612)
			(xy 75.002892 -304.714568) (xy 74.95843 -304.735666) (xy 74.911159 -304.749358) (xy 74.862304 -304.75529)
			(xy 74.813129 -304.753309) (xy 74.76491 -304.743465) (xy 74.718894 -304.726013) (xy 74.676273 -304.701406)
			(xy 74.638152 -304.670281) (xy 74.605517 -304.633444) (xy 74.579214 -304.591848) (xy 74.559923 -304.546572)
			(xy 74.548146 -304.498788) (xy 74.544186 -304.449734) (xy 44.755054 -304.449734) (xy 44.754559 -304.474341)
			(xy 44.746664 -304.522918) (xy 44.73108 -304.569599) (xy 44.708209 -304.613176) (xy 44.678644 -304.65252)
			(xy 44.643151 -304.686612) (xy 44.602648 -304.714568) (xy 44.558186 -304.735666) (xy 44.510915 -304.749358)
			(xy 44.46206 -304.75529) (xy 44.412885 -304.753309) (xy 44.364666 -304.743465) (xy 44.31865 -304.726013)
			(xy 44.276029 -304.701406) (xy 44.237908 -304.670281) (xy 44.205273 -304.633444) (xy 44.17897 -304.591848)
			(xy 44.159679 -304.546572) (xy 44.147902 -304.498788) (xy 44.143942 -304.449734) (xy 43.805094 -304.449734)
			(xy 43.804599 -304.474341) (xy 43.796704 -304.522918) (xy 43.78112 -304.569599) (xy 43.758249 -304.613176)
			(xy 43.728684 -304.65252) (xy 43.693191 -304.686612) (xy 43.652688 -304.714568) (xy 43.608226 -304.735666)
			(xy 43.560955 -304.749358) (xy 43.5121 -304.75529) (xy 43.462925 -304.753309) (xy 43.414706 -304.743465)
			(xy 43.36869 -304.726013) (xy 43.326069 -304.701406) (xy 43.287948 -304.670281) (xy 43.255313 -304.633444)
			(xy 43.22901 -304.591848) (xy 43.209719 -304.546572) (xy 43.197942 -304.498788) (xy 43.193982 -304.449734)
			(xy 38.10508 -304.449734) (xy 38.104585 -304.474341) (xy 38.09669 -304.522918) (xy 38.081106 -304.569599)
			(xy 38.058235 -304.613176) (xy 38.02867 -304.65252) (xy 37.993177 -304.686612) (xy 37.952674 -304.714568)
			(xy 37.908212 -304.735666) (xy 37.860941 -304.749358) (xy 37.812086 -304.75529) (xy 37.762911 -304.753309)
			(xy 37.714692 -304.743465) (xy 37.668676 -304.726013) (xy 37.626055 -304.701406) (xy 37.587934 -304.670281)
			(xy 37.555299 -304.633444) (xy 37.528996 -304.591848) (xy 37.509705 -304.546572) (xy 37.497928 -304.498788)
			(xy 37.493968 -304.449734) (xy 37.15512 -304.449734) (xy 37.154625 -304.474341) (xy 37.14673 -304.522918)
			(xy 37.131146 -304.569599) (xy 37.108275 -304.613176) (xy 37.07871 -304.65252) (xy 37.043217 -304.686612)
			(xy 37.002714 -304.714568) (xy 36.958252 -304.735666) (xy 36.910981 -304.749358) (xy 36.862126 -304.75529)
			(xy 36.812951 -304.753309) (xy 36.764732 -304.743465) (xy 36.718716 -304.726013) (xy 36.676095 -304.701406)
			(xy 36.637974 -304.670281) (xy 36.605339 -304.633444) (xy 36.579036 -304.591848) (xy 36.559745 -304.546572)
			(xy 36.547968 -304.498788) (xy 36.544008 -304.449734) (xy 0.509016 -304.449734) (xy 0.509016 -305.19751)
			(xy 17.638266 -305.19751) (xy 17.642339 -305.141851) (xy 17.654474 -305.087378) (xy 17.67441 -305.035252)
			(xy 17.701724 -304.986584) (xy 17.735832 -304.942412) (xy 17.776009 -304.903677) (xy 17.821397 -304.871205)
			(xy 17.871029 -304.845687) (xy 17.923849 -304.827668) (xy 17.978728 -304.817531) (xy 18.034499 -304.815493)
			(xy 18.089973 -304.821596) (xy 18.143966 -304.835712) (xy 18.195329 -304.857539) (xy 18.242967 -304.886612)
			(xy 18.285863 -304.922311) (xy 18.323105 -304.963875) (xy 18.353899 -305.010419) (xy 18.377587 -305.06095)
			(xy 18.393665 -305.114392) (xy 18.401791 -305.169606) (xy 18.4023 -305.19751) (xy 18.401791 -305.225414)
			(xy 18.393665 -305.280628) (xy 18.377587 -305.33407) (xy 18.353899 -305.384601) (xy 18.343745 -305.399948)
			(xy 38.444182 -305.399948) (xy 38.448142 -305.350894) (xy 38.459919 -305.30311) (xy 38.47921 -305.257834)
			(xy 38.505513 -305.216238) (xy 38.538148 -305.179401) (xy 38.576269 -305.148276) (xy 38.61889 -305.123669)
			(xy 38.664906 -305.106217) (xy 38.713125 -305.096373) (xy 38.7623 -305.094392) (xy 38.811155 -305.100324)
			(xy 38.858426 -305.114016) (xy 38.902888 -305.135114) (xy 38.943391 -305.16307) (xy 38.978884 -305.197162)
			(xy 39.008449 -305.236506) (xy 39.03132 -305.280083) (xy 39.046904 -305.326764) (xy 39.054799 -305.375341)
			(xy 39.055294 -305.399948) (xy 39.394142 -305.399948) (xy 39.398102 -305.350894) (xy 39.409879 -305.30311)
			(xy 39.42917 -305.257834) (xy 39.455473 -305.216238) (xy 39.488108 -305.179401) (xy 39.526229 -305.148276)
			(xy 39.56885 -305.123669) (xy 39.614866 -305.106217) (xy 39.663085 -305.096373) (xy 39.71226 -305.094392)
			(xy 39.761115 -305.100324) (xy 39.808386 -305.114016) (xy 39.852848 -305.135114) (xy 39.893351 -305.16307)
			(xy 39.928844 -305.197162) (xy 39.958409 -305.236506) (xy 39.98128 -305.280083) (xy 39.996864 -305.326764)
			(xy 40.004759 -305.375341) (xy 40.005254 -305.399948) (xy 41.294062 -305.399948) (xy 41.298022 -305.350894)
			(xy 41.309799 -305.30311) (xy 41.32909 -305.257834) (xy 41.355393 -305.216238) (xy 41.388028 -305.179401)
			(xy 41.426149 -305.148276) (xy 41.46877 -305.123669) (xy 41.514786 -305.106217) (xy 41.563005 -305.096373)
			(xy 41.61218 -305.094392) (xy 41.661035 -305.100324) (xy 41.708306 -305.114016) (xy 41.752768 -305.135114)
			(xy 41.793271 -305.16307) (xy 41.828764 -305.197162) (xy 41.858329 -305.236506) (xy 41.8812 -305.280083)
			(xy 41.896784 -305.326764) (xy 41.904679 -305.375341) (xy 41.905174 -305.399948) (xy 42.244022 -305.399948)
			(xy 42.247982 -305.350894) (xy 42.259759 -305.30311) (xy 42.27905 -305.257834) (xy 42.305353 -305.216238)
			(xy 42.337988 -305.179401) (xy 42.376109 -305.148276) (xy 42.41873 -305.123669) (xy 42.464746 -305.106217)
			(xy 42.512965 -305.096373) (xy 42.56214 -305.094392) (xy 42.610995 -305.100324) (xy 42.658266 -305.114016)
			(xy 42.702728 -305.135114) (xy 42.743231 -305.16307) (xy 42.778724 -305.197162) (xy 42.808289 -305.236506)
			(xy 42.83116 -305.280083) (xy 42.846744 -305.326764) (xy 42.854639 -305.375341) (xy 42.855134 -305.399948)
			(xy 76.444106 -305.399948) (xy 76.448066 -305.350894) (xy 76.459843 -305.30311) (xy 76.479134 -305.257834)
			(xy 76.505437 -305.216238) (xy 76.538072 -305.179401) (xy 76.576193 -305.148276) (xy 76.618814 -305.123669)
			(xy 76.66483 -305.106217) (xy 76.713049 -305.096373) (xy 76.762224 -305.094392) (xy 76.811079 -305.100324)
			(xy 76.85835 -305.114016) (xy 76.902812 -305.135114) (xy 76.943315 -305.16307) (xy 76.978808 -305.197162)
			(xy 77.008373 -305.236506) (xy 77.031244 -305.280083) (xy 77.046828 -305.326764) (xy 77.054723 -305.375341)
			(xy 77.055218 -305.399948) (xy 77.394066 -305.399948) (xy 77.398026 -305.350894) (xy 77.409803 -305.30311)
			(xy 77.429094 -305.257834) (xy 77.455397 -305.216238) (xy 77.488032 -305.179401) (xy 77.526153 -305.148276)
			(xy 77.568774 -305.123669) (xy 77.61479 -305.106217) (xy 77.663009 -305.096373) (xy 77.712184 -305.094392)
			(xy 77.761039 -305.100324) (xy 77.80831 -305.114016) (xy 77.852772 -305.135114) (xy 77.893275 -305.16307)
			(xy 77.928768 -305.197162) (xy 77.958333 -305.236506) (xy 77.981204 -305.280083) (xy 77.996788 -305.326764)
			(xy 78.004683 -305.375341) (xy 78.005178 -305.399948) (xy 79.293986 -305.399948) (xy 79.297946 -305.350894)
			(xy 79.309723 -305.30311) (xy 79.329014 -305.257834) (xy 79.355317 -305.216238) (xy 79.387952 -305.179401)
			(xy 79.426073 -305.148276) (xy 79.468694 -305.123669) (xy 79.51471 -305.106217) (xy 79.562929 -305.096373)
			(xy 79.612104 -305.094392) (xy 79.660959 -305.100324) (xy 79.70823 -305.114016) (xy 79.752692 -305.135114)
			(xy 79.793195 -305.16307) (xy 79.828688 -305.197162) (xy 79.858253 -305.236506) (xy 79.881124 -305.280083)
			(xy 79.896708 -305.326764) (xy 79.904603 -305.375341) (xy 79.905098 -305.399948) (xy 80.243946 -305.399948)
			(xy 80.247906 -305.350894) (xy 80.259683 -305.30311) (xy 80.278974 -305.257834) (xy 80.305277 -305.216238)
			(xy 80.337912 -305.179401) (xy 80.376033 -305.148276) (xy 80.418654 -305.123669) (xy 80.46467 -305.106217)
			(xy 80.512889 -305.096373) (xy 80.562064 -305.094392) (xy 80.610919 -305.100324) (xy 80.65819 -305.114016)
			(xy 80.702652 -305.135114) (xy 80.743155 -305.16307) (xy 80.778648 -305.197162) (xy 80.808213 -305.236506)
			(xy 80.831084 -305.280083) (xy 80.846668 -305.326764) (xy 80.854563 -305.375341) (xy 80.855058 -305.399948)
			(xy 154.54428 -305.399948) (xy 154.54824 -305.350894) (xy 154.560017 -305.30311) (xy 154.579308 -305.257834)
			(xy 154.605611 -305.216238) (xy 154.638246 -305.179401) (xy 154.676367 -305.148276) (xy 154.718988 -305.123669)
			(xy 154.765004 -305.106217) (xy 154.813223 -305.096373) (xy 154.862398 -305.094392) (xy 154.911253 -305.100324)
			(xy 154.958524 -305.114016) (xy 155.002986 -305.135114) (xy 155.043489 -305.16307) (xy 155.078982 -305.197162)
			(xy 155.108547 -305.236506) (xy 155.131418 -305.280083) (xy 155.147002 -305.326764) (xy 155.154897 -305.375341)
			(xy 155.155392 -305.399948) (xy 155.49424 -305.399948) (xy 155.4982 -305.350894) (xy 155.509977 -305.30311)
			(xy 155.529268 -305.257834) (xy 155.555571 -305.216238) (xy 155.588206 -305.179401) (xy 155.626327 -305.148276)
			(xy 155.668948 -305.123669) (xy 155.714964 -305.106217) (xy 155.763183 -305.096373) (xy 155.812358 -305.094392)
			(xy 155.861213 -305.100324) (xy 155.908484 -305.114016) (xy 155.952946 -305.135114) (xy 155.993449 -305.16307)
			(xy 156.028942 -305.197162) (xy 156.058507 -305.236506) (xy 156.081378 -305.280083) (xy 156.096962 -305.326764)
			(xy 156.104857 -305.375341) (xy 156.105352 -305.399948) (xy 157.39416 -305.399948) (xy 157.39812 -305.350894)
			(xy 157.409897 -305.30311) (xy 157.429188 -305.257834) (xy 157.455491 -305.216238) (xy 157.488126 -305.179401)
			(xy 157.526247 -305.148276) (xy 157.568868 -305.123669) (xy 157.614884 -305.106217) (xy 157.663103 -305.096373)
			(xy 157.712278 -305.094392) (xy 157.761133 -305.100324) (xy 157.808404 -305.114016) (xy 157.852866 -305.135114)
			(xy 157.893369 -305.16307) (xy 157.928862 -305.197162) (xy 157.958427 -305.236506) (xy 157.981298 -305.280083)
			(xy 157.996882 -305.326764) (xy 158.004777 -305.375341) (xy 158.005272 -305.399948) (xy 158.34412 -305.399948)
			(xy 158.34808 -305.350894) (xy 158.359857 -305.30311) (xy 158.379148 -305.257834) (xy 158.405451 -305.216238)
			(xy 158.438086 -305.179401) (xy 158.476207 -305.148276) (xy 158.518828 -305.123669) (xy 158.564844 -305.106217)
			(xy 158.613063 -305.096373) (xy 158.662238 -305.094392) (xy 158.711093 -305.100324) (xy 158.758364 -305.114016)
			(xy 158.802826 -305.135114) (xy 158.843329 -305.16307) (xy 158.878822 -305.197162) (xy 158.908387 -305.236506)
			(xy 158.931258 -305.280083) (xy 158.946842 -305.326764) (xy 158.954737 -305.375341) (xy 158.955232 -305.399948)
			(xy 192.544204 -305.399948) (xy 192.548164 -305.350894) (xy 192.559941 -305.30311) (xy 192.579232 -305.257834)
			(xy 192.605535 -305.216238) (xy 192.63817 -305.179401) (xy 192.676291 -305.148276) (xy 192.718912 -305.123669)
			(xy 192.764928 -305.106217) (xy 192.813147 -305.096373) (xy 192.862322 -305.094392) (xy 192.911177 -305.100324)
			(xy 192.958448 -305.114016) (xy 193.00291 -305.135114) (xy 193.043413 -305.16307) (xy 193.078906 -305.197162)
			(xy 193.108471 -305.236506) (xy 193.131342 -305.280083) (xy 193.146926 -305.326764) (xy 193.154821 -305.375341)
			(xy 193.155316 -305.399948) (xy 193.494164 -305.399948) (xy 193.498124 -305.350894) (xy 193.509901 -305.30311)
			(xy 193.529192 -305.257834) (xy 193.555495 -305.216238) (xy 193.58813 -305.179401) (xy 193.626251 -305.148276)
			(xy 193.668872 -305.123669) (xy 193.714888 -305.106217) (xy 193.763107 -305.096373) (xy 193.812282 -305.094392)
			(xy 193.861137 -305.100324) (xy 193.908408 -305.114016) (xy 193.95287 -305.135114) (xy 193.993373 -305.16307)
			(xy 194.028866 -305.197162) (xy 194.058431 -305.236506) (xy 194.081302 -305.280083) (xy 194.096886 -305.326764)
			(xy 194.104781 -305.375341) (xy 194.105276 -305.399948) (xy 195.394084 -305.399948) (xy 195.398044 -305.350894)
			(xy 195.409821 -305.30311) (xy 195.429112 -305.257834) (xy 195.455415 -305.216238) (xy 195.48805 -305.179401)
			(xy 195.526171 -305.148276) (xy 195.568792 -305.123669) (xy 195.614808 -305.106217) (xy 195.663027 -305.096373)
			(xy 195.712202 -305.094392) (xy 195.761057 -305.100324) (xy 195.808328 -305.114016) (xy 195.85279 -305.135114)
			(xy 195.893293 -305.16307) (xy 195.928786 -305.197162) (xy 195.958351 -305.236506) (xy 195.981222 -305.280083)
			(xy 195.996806 -305.326764) (xy 196.004701 -305.375341) (xy 196.005196 -305.399948) (xy 196.344044 -305.399948)
			(xy 196.348004 -305.350894) (xy 196.359781 -305.30311) (xy 196.379072 -305.257834) (xy 196.405375 -305.216238)
			(xy 196.43801 -305.179401) (xy 196.476131 -305.148276) (xy 196.518752 -305.123669) (xy 196.564768 -305.106217)
			(xy 196.612987 -305.096373) (xy 196.662162 -305.094392) (xy 196.711017 -305.100324) (xy 196.758288 -305.114016)
			(xy 196.80275 -305.135114) (xy 196.843253 -305.16307) (xy 196.878746 -305.197162) (xy 196.908311 -305.236506)
			(xy 196.931182 -305.280083) (xy 196.946766 -305.326764) (xy 196.954661 -305.375341) (xy 196.955156 -305.399948)
			(xy 270.644124 -305.399948) (xy 270.648084 -305.350894) (xy 270.659861 -305.30311) (xy 270.679152 -305.257834)
			(xy 270.705455 -305.216238) (xy 270.73809 -305.179401) (xy 270.776211 -305.148276) (xy 270.818832 -305.123669)
			(xy 270.864848 -305.106217) (xy 270.913067 -305.096373) (xy 270.962242 -305.094392) (xy 271.011097 -305.100324)
			(xy 271.058368 -305.114016) (xy 271.10283 -305.135114) (xy 271.143333 -305.16307) (xy 271.178826 -305.197162)
			(xy 271.208391 -305.236506) (xy 271.231262 -305.280083) (xy 271.246846 -305.326764) (xy 271.254741 -305.375341)
			(xy 271.255236 -305.399948) (xy 271.594084 -305.399948) (xy 271.598044 -305.350894) (xy 271.609821 -305.30311)
			(xy 271.629112 -305.257834) (xy 271.655415 -305.216238) (xy 271.68805 -305.179401) (xy 271.726171 -305.148276)
			(xy 271.768792 -305.123669) (xy 271.814808 -305.106217) (xy 271.863027 -305.096373) (xy 271.912202 -305.094392)
			(xy 271.961057 -305.100324) (xy 272.008328 -305.114016) (xy 272.05279 -305.135114) (xy 272.093293 -305.16307)
			(xy 272.128786 -305.197162) (xy 272.158351 -305.236506) (xy 272.181222 -305.280083) (xy 272.196806 -305.326764)
			(xy 272.204701 -305.375341) (xy 272.205196 -305.399948) (xy 273.494004 -305.399948) (xy 273.497964 -305.350894)
			(xy 273.509741 -305.30311) (xy 273.529032 -305.257834) (xy 273.555335 -305.216238) (xy 273.58797 -305.179401)
			(xy 273.626091 -305.148276) (xy 273.668712 -305.123669) (xy 273.714728 -305.106217) (xy 273.762947 -305.096373)
			(xy 273.812122 -305.094392) (xy 273.860977 -305.100324) (xy 273.908248 -305.114016) (xy 273.95271 -305.135114)
			(xy 273.993213 -305.16307) (xy 274.028706 -305.197162) (xy 274.058271 -305.236506) (xy 274.081142 -305.280083)
			(xy 274.096726 -305.326764) (xy 274.104621 -305.375341) (xy 274.105116 -305.399948) (xy 274.443964 -305.399948)
			(xy 274.447924 -305.350894) (xy 274.459701 -305.30311) (xy 274.478992 -305.257834) (xy 274.505295 -305.216238)
			(xy 274.53793 -305.179401) (xy 274.576051 -305.148276) (xy 274.618672 -305.123669) (xy 274.664688 -305.106217)
			(xy 274.712907 -305.096373) (xy 274.762082 -305.094392) (xy 274.810937 -305.100324) (xy 274.858208 -305.114016)
			(xy 274.90267 -305.135114) (xy 274.943173 -305.16307) (xy 274.978666 -305.197162) (xy 275.008231 -305.236506)
			(xy 275.031102 -305.280083) (xy 275.046686 -305.326764) (xy 275.054581 -305.375341) (xy 275.055076 -305.399948)
			(xy 308.644048 -305.399948) (xy 308.648008 -305.350894) (xy 308.659785 -305.30311) (xy 308.679076 -305.257834)
			(xy 308.705379 -305.216238) (xy 308.738014 -305.179401) (xy 308.776135 -305.148276) (xy 308.818756 -305.123669)
			(xy 308.864772 -305.106217) (xy 308.912991 -305.096373) (xy 308.962166 -305.094392) (xy 309.011021 -305.100324)
			(xy 309.058292 -305.114016) (xy 309.102754 -305.135114) (xy 309.143257 -305.16307) (xy 309.17875 -305.197162)
			(xy 309.208315 -305.236506) (xy 309.231186 -305.280083) (xy 309.24677 -305.326764) (xy 309.254665 -305.375341)
			(xy 309.25516 -305.399948) (xy 309.594008 -305.399948) (xy 309.597968 -305.350894) (xy 309.609745 -305.30311)
			(xy 309.629036 -305.257834) (xy 309.655339 -305.216238) (xy 309.687974 -305.179401) (xy 309.726095 -305.148276)
			(xy 309.768716 -305.123669) (xy 309.814732 -305.106217) (xy 309.862951 -305.096373) (xy 309.912126 -305.094392)
			(xy 309.960981 -305.100324) (xy 310.008252 -305.114016) (xy 310.052714 -305.135114) (xy 310.093217 -305.16307)
			(xy 310.12871 -305.197162) (xy 310.158275 -305.236506) (xy 310.181146 -305.280083) (xy 310.19673 -305.326764)
			(xy 310.204625 -305.375341) (xy 310.20512 -305.399948) (xy 311.493928 -305.399948) (xy 311.497888 -305.350894)
			(xy 311.509665 -305.30311) (xy 311.528956 -305.257834) (xy 311.555259 -305.216238) (xy 311.587894 -305.179401)
			(xy 311.626015 -305.148276) (xy 311.668636 -305.123669) (xy 311.714652 -305.106217) (xy 311.762871 -305.096373)
			(xy 311.812046 -305.094392) (xy 311.860901 -305.100324) (xy 311.908172 -305.114016) (xy 311.952634 -305.135114)
			(xy 311.993137 -305.16307) (xy 312.02863 -305.197162) (xy 312.058195 -305.236506) (xy 312.081066 -305.280083)
			(xy 312.09665 -305.326764) (xy 312.104545 -305.375341) (xy 312.10504 -305.399948) (xy 312.443888 -305.399948)
			(xy 312.447848 -305.350894) (xy 312.459625 -305.30311) (xy 312.478916 -305.257834) (xy 312.505219 -305.216238)
			(xy 312.537854 -305.179401) (xy 312.575975 -305.148276) (xy 312.618596 -305.123669) (xy 312.664612 -305.106217)
			(xy 312.712831 -305.096373) (xy 312.762006 -305.094392) (xy 312.810861 -305.100324) (xy 312.858132 -305.114016)
			(xy 312.902594 -305.135114) (xy 312.943097 -305.16307) (xy 312.97859 -305.197162) (xy 313.008155 -305.236506)
			(xy 313.031026 -305.280083) (xy 313.04661 -305.326764) (xy 313.054505 -305.375341) (xy 313.055 -305.399948)
			(xy 386.744222 -305.399948) (xy 386.748182 -305.350894) (xy 386.759959 -305.30311) (xy 386.77925 -305.257834)
			(xy 386.805553 -305.216238) (xy 386.838188 -305.179401) (xy 386.876309 -305.148276) (xy 386.91893 -305.123669)
			(xy 386.964946 -305.106217) (xy 387.013165 -305.096373) (xy 387.06234 -305.094392) (xy 387.111195 -305.100324)
			(xy 387.158466 -305.114016) (xy 387.202928 -305.135114) (xy 387.243431 -305.16307) (xy 387.278924 -305.197162)
			(xy 387.308489 -305.236506) (xy 387.33136 -305.280083) (xy 387.346944 -305.326764) (xy 387.354839 -305.375341)
			(xy 387.355334 -305.399948) (xy 387.694182 -305.399948) (xy 387.698142 -305.350894) (xy 387.709919 -305.30311)
			(xy 387.72921 -305.257834) (xy 387.755513 -305.216238) (xy 387.788148 -305.179401) (xy 387.826269 -305.148276)
			(xy 387.86889 -305.123669) (xy 387.914906 -305.106217) (xy 387.963125 -305.096373) (xy 388.0123 -305.094392)
			(xy 388.061155 -305.100324) (xy 388.108426 -305.114016) (xy 388.152888 -305.135114) (xy 388.193391 -305.16307)
			(xy 388.228884 -305.197162) (xy 388.258449 -305.236506) (xy 388.28132 -305.280083) (xy 388.296904 -305.326764)
			(xy 388.304799 -305.375341) (xy 388.305294 -305.399948) (xy 389.594102 -305.399948) (xy 389.598062 -305.350894)
			(xy 389.609839 -305.30311) (xy 389.62913 -305.257834) (xy 389.655433 -305.216238) (xy 389.688068 -305.179401)
			(xy 389.726189 -305.148276) (xy 389.76881 -305.123669) (xy 389.814826 -305.106217) (xy 389.863045 -305.096373)
			(xy 389.91222 -305.094392) (xy 389.961075 -305.100324) (xy 390.008346 -305.114016) (xy 390.052808 -305.135114)
			(xy 390.093311 -305.16307) (xy 390.128804 -305.197162) (xy 390.158369 -305.236506) (xy 390.18124 -305.280083)
			(xy 390.196824 -305.326764) (xy 390.204719 -305.375341) (xy 390.205214 -305.399948) (xy 390.544062 -305.399948)
			(xy 390.548022 -305.350894) (xy 390.559799 -305.30311) (xy 390.57909 -305.257834) (xy 390.605393 -305.216238)
			(xy 390.638028 -305.179401) (xy 390.676149 -305.148276) (xy 390.71877 -305.123669) (xy 390.764786 -305.106217)
			(xy 390.813005 -305.096373) (xy 390.86218 -305.094392) (xy 390.911035 -305.100324) (xy 390.958306 -305.114016)
			(xy 391.002768 -305.135114) (xy 391.043271 -305.16307) (xy 391.078764 -305.197162) (xy 391.108329 -305.236506)
			(xy 391.1312 -305.280083) (xy 391.146784 -305.326764) (xy 391.154679 -305.375341) (xy 391.155174 -305.399948)
			(xy 424.744146 -305.399948) (xy 424.748106 -305.350894) (xy 424.759883 -305.30311) (xy 424.779174 -305.257834)
			(xy 424.805477 -305.216238) (xy 424.838112 -305.179401) (xy 424.876233 -305.148276) (xy 424.918854 -305.123669)
			(xy 424.96487 -305.106217) (xy 425.013089 -305.096373) (xy 425.062264 -305.094392) (xy 425.111119 -305.100324)
			(xy 425.15839 -305.114016) (xy 425.202852 -305.135114) (xy 425.243355 -305.16307) (xy 425.278848 -305.197162)
			(xy 425.308413 -305.236506) (xy 425.331284 -305.280083) (xy 425.346868 -305.326764) (xy 425.354763 -305.375341)
			(xy 425.355258 -305.399948) (xy 425.694106 -305.399948) (xy 425.698066 -305.350894) (xy 425.709843 -305.30311)
			(xy 425.729134 -305.257834) (xy 425.755437 -305.216238) (xy 425.788072 -305.179401) (xy 425.826193 -305.148276)
			(xy 425.868814 -305.123669) (xy 425.91483 -305.106217) (xy 425.963049 -305.096373) (xy 426.012224 -305.094392)
			(xy 426.061079 -305.100324) (xy 426.10835 -305.114016) (xy 426.152812 -305.135114) (xy 426.193315 -305.16307)
			(xy 426.228808 -305.197162) (xy 426.258373 -305.236506) (xy 426.281244 -305.280083) (xy 426.296828 -305.326764)
			(xy 426.304723 -305.375341) (xy 426.305218 -305.399948) (xy 427.594026 -305.399948) (xy 427.597986 -305.350894)
			(xy 427.609763 -305.30311) (xy 427.629054 -305.257834) (xy 427.655357 -305.216238) (xy 427.687992 -305.179401)
			(xy 427.726113 -305.148276) (xy 427.768734 -305.123669) (xy 427.81475 -305.106217) (xy 427.862969 -305.096373)
			(xy 427.912144 -305.094392) (xy 427.960999 -305.100324) (xy 428.00827 -305.114016) (xy 428.052732 -305.135114)
			(xy 428.093235 -305.16307) (xy 428.128728 -305.197162) (xy 428.158293 -305.236506) (xy 428.181164 -305.280083)
			(xy 428.196748 -305.326764) (xy 428.204643 -305.375341) (xy 428.205138 -305.399948) (xy 428.543986 -305.399948)
			(xy 428.547946 -305.350894) (xy 428.559723 -305.30311) (xy 428.579014 -305.257834) (xy 428.605317 -305.216238)
			(xy 428.637952 -305.179401) (xy 428.676073 -305.148276) (xy 428.718694 -305.123669) (xy 428.76471 -305.106217)
			(xy 428.812929 -305.096373) (xy 428.862104 -305.094392) (xy 428.910959 -305.100324) (xy 428.95823 -305.114016)
			(xy 429.002692 -305.135114) (xy 429.043195 -305.16307) (xy 429.078688 -305.197162) (xy 429.108253 -305.236506)
			(xy 429.131124 -305.280083) (xy 429.146708 -305.326764) (xy 429.154603 -305.375341) (xy 429.155098 -305.399948)
			(xy 429.154603 -305.424555) (xy 429.146708 -305.473132) (xy 429.131124 -305.519813) (xy 429.108253 -305.56339)
			(xy 429.078688 -305.602734) (xy 429.043195 -305.636826) (xy 429.002692 -305.664782) (xy 428.95823 -305.68588)
			(xy 428.910959 -305.699572) (xy 428.862104 -305.705504) (xy 428.812929 -305.703523) (xy 428.76471 -305.693679)
			(xy 428.718694 -305.676227) (xy 428.676073 -305.65162) (xy 428.637952 -305.620495) (xy 428.605317 -305.583658)
			(xy 428.579014 -305.542062) (xy 428.559723 -305.496786) (xy 428.547946 -305.449002) (xy 428.543986 -305.399948)
			(xy 428.205138 -305.399948) (xy 428.204643 -305.424555) (xy 428.196748 -305.473132) (xy 428.181164 -305.519813)
			(xy 428.158293 -305.56339) (xy 428.128728 -305.602734) (xy 428.093235 -305.636826) (xy 428.052732 -305.664782)
			(xy 428.00827 -305.68588) (xy 427.960999 -305.699572) (xy 427.912144 -305.705504) (xy 427.862969 -305.703523)
			(xy 427.81475 -305.693679) (xy 427.768734 -305.676227) (xy 427.726113 -305.65162) (xy 427.687992 -305.620495)
			(xy 427.655357 -305.583658) (xy 427.629054 -305.542062) (xy 427.609763 -305.496786) (xy 427.597986 -305.449002)
			(xy 427.594026 -305.399948) (xy 426.305218 -305.399948) (xy 426.304723 -305.424555) (xy 426.296828 -305.473132)
			(xy 426.281244 -305.519813) (xy 426.258373 -305.56339) (xy 426.228808 -305.602734) (xy 426.193315 -305.636826)
			(xy 426.152812 -305.664782) (xy 426.10835 -305.68588) (xy 426.061079 -305.699572) (xy 426.012224 -305.705504)
			(xy 425.963049 -305.703523) (xy 425.91483 -305.693679) (xy 425.868814 -305.676227) (xy 425.826193 -305.65162)
			(xy 425.788072 -305.620495) (xy 425.755437 -305.583658) (xy 425.729134 -305.542062) (xy 425.709843 -305.496786)
			(xy 425.698066 -305.449002) (xy 425.694106 -305.399948) (xy 425.355258 -305.399948) (xy 425.354763 -305.424555)
			(xy 425.346868 -305.473132) (xy 425.331284 -305.519813) (xy 425.308413 -305.56339) (xy 425.278848 -305.602734)
			(xy 425.243355 -305.636826) (xy 425.202852 -305.664782) (xy 425.15839 -305.68588) (xy 425.111119 -305.699572)
			(xy 425.062264 -305.705504) (xy 425.013089 -305.703523) (xy 424.96487 -305.693679) (xy 424.918854 -305.676227)
			(xy 424.876233 -305.65162) (xy 424.838112 -305.620495) (xy 424.805477 -305.583658) (xy 424.779174 -305.542062)
			(xy 424.759883 -305.496786) (xy 424.748106 -305.449002) (xy 424.744146 -305.399948) (xy 391.155174 -305.399948)
			(xy 391.154679 -305.424555) (xy 391.146784 -305.473132) (xy 391.1312 -305.519813) (xy 391.108329 -305.56339)
			(xy 391.078764 -305.602734) (xy 391.043271 -305.636826) (xy 391.002768 -305.664782) (xy 390.958306 -305.68588)
			(xy 390.911035 -305.699572) (xy 390.86218 -305.705504) (xy 390.813005 -305.703523) (xy 390.764786 -305.693679)
			(xy 390.71877 -305.676227) (xy 390.676149 -305.65162) (xy 390.638028 -305.620495) (xy 390.605393 -305.583658)
			(xy 390.57909 -305.542062) (xy 390.559799 -305.496786) (xy 390.548022 -305.449002) (xy 390.544062 -305.399948)
			(xy 390.205214 -305.399948) (xy 390.204719 -305.424555) (xy 390.196824 -305.473132) (xy 390.18124 -305.519813)
			(xy 390.158369 -305.56339) (xy 390.128804 -305.602734) (xy 390.093311 -305.636826) (xy 390.052808 -305.664782)
			(xy 390.008346 -305.68588) (xy 389.961075 -305.699572) (xy 389.91222 -305.705504) (xy 389.863045 -305.703523)
			(xy 389.814826 -305.693679) (xy 389.76881 -305.676227) (xy 389.726189 -305.65162) (xy 389.688068 -305.620495)
			(xy 389.655433 -305.583658) (xy 389.62913 -305.542062) (xy 389.609839 -305.496786) (xy 389.598062 -305.449002)
			(xy 389.594102 -305.399948) (xy 388.305294 -305.399948) (xy 388.304799 -305.424555) (xy 388.296904 -305.473132)
			(xy 388.28132 -305.519813) (xy 388.258449 -305.56339) (xy 388.228884 -305.602734) (xy 388.193391 -305.636826)
			(xy 388.152888 -305.664782) (xy 388.108426 -305.68588) (xy 388.061155 -305.699572) (xy 388.0123 -305.705504)
			(xy 387.963125 -305.703523) (xy 387.914906 -305.693679) (xy 387.86889 -305.676227) (xy 387.826269 -305.65162)
			(xy 387.788148 -305.620495) (xy 387.755513 -305.583658) (xy 387.72921 -305.542062) (xy 387.709919 -305.496786)
			(xy 387.698142 -305.449002) (xy 387.694182 -305.399948) (xy 387.355334 -305.399948) (xy 387.354839 -305.424555)
			(xy 387.346944 -305.473132) (xy 387.33136 -305.519813) (xy 387.308489 -305.56339) (xy 387.278924 -305.602734)
			(xy 387.243431 -305.636826) (xy 387.202928 -305.664782) (xy 387.158466 -305.68588) (xy 387.111195 -305.699572)
			(xy 387.06234 -305.705504) (xy 387.013165 -305.703523) (xy 386.964946 -305.693679) (xy 386.91893 -305.676227)
			(xy 386.876309 -305.65162) (xy 386.838188 -305.620495) (xy 386.805553 -305.583658) (xy 386.77925 -305.542062)
			(xy 386.759959 -305.496786) (xy 386.748182 -305.449002) (xy 386.744222 -305.399948) (xy 313.055 -305.399948)
			(xy 313.054505 -305.424555) (xy 313.04661 -305.473132) (xy 313.031026 -305.519813) (xy 313.008155 -305.56339)
			(xy 312.97859 -305.602734) (xy 312.943097 -305.636826) (xy 312.902594 -305.664782) (xy 312.858132 -305.68588)
			(xy 312.810861 -305.699572) (xy 312.762006 -305.705504) (xy 312.712831 -305.703523) (xy 312.664612 -305.693679)
			(xy 312.618596 -305.676227) (xy 312.575975 -305.65162) (xy 312.537854 -305.620495) (xy 312.505219 -305.583658)
			(xy 312.478916 -305.542062) (xy 312.459625 -305.496786) (xy 312.447848 -305.449002) (xy 312.443888 -305.399948)
			(xy 312.10504 -305.399948) (xy 312.104545 -305.424555) (xy 312.09665 -305.473132) (xy 312.081066 -305.519813)
			(xy 312.058195 -305.56339) (xy 312.02863 -305.602734) (xy 311.993137 -305.636826) (xy 311.952634 -305.664782)
			(xy 311.908172 -305.68588) (xy 311.860901 -305.699572) (xy 311.812046 -305.705504) (xy 311.762871 -305.703523)
			(xy 311.714652 -305.693679) (xy 311.668636 -305.676227) (xy 311.626015 -305.65162) (xy 311.587894 -305.620495)
			(xy 311.555259 -305.583658) (xy 311.528956 -305.542062) (xy 311.509665 -305.496786) (xy 311.497888 -305.449002)
			(xy 311.493928 -305.399948) (xy 310.20512 -305.399948) (xy 310.204625 -305.424555) (xy 310.19673 -305.473132)
			(xy 310.181146 -305.519813) (xy 310.158275 -305.56339) (xy 310.12871 -305.602734) (xy 310.093217 -305.636826)
			(xy 310.052714 -305.664782) (xy 310.008252 -305.68588) (xy 309.960981 -305.699572) (xy 309.912126 -305.705504)
			(xy 309.862951 -305.703523) (xy 309.814732 -305.693679) (xy 309.768716 -305.676227) (xy 309.726095 -305.65162)
			(xy 309.687974 -305.620495) (xy 309.655339 -305.583658) (xy 309.629036 -305.542062) (xy 309.609745 -305.496786)
			(xy 309.597968 -305.449002) (xy 309.594008 -305.399948) (xy 309.25516 -305.399948) (xy 309.254665 -305.424555)
			(xy 309.24677 -305.473132) (xy 309.231186 -305.519813) (xy 309.208315 -305.56339) (xy 309.17875 -305.602734)
			(xy 309.143257 -305.636826) (xy 309.102754 -305.664782) (xy 309.058292 -305.68588) (xy 309.011021 -305.699572)
			(xy 308.962166 -305.705504) (xy 308.912991 -305.703523) (xy 308.864772 -305.693679) (xy 308.818756 -305.676227)
			(xy 308.776135 -305.65162) (xy 308.738014 -305.620495) (xy 308.705379 -305.583658) (xy 308.679076 -305.542062)
			(xy 308.659785 -305.496786) (xy 308.648008 -305.449002) (xy 308.644048 -305.399948) (xy 275.055076 -305.399948)
			(xy 275.054581 -305.424555) (xy 275.046686 -305.473132) (xy 275.031102 -305.519813) (xy 275.008231 -305.56339)
			(xy 274.978666 -305.602734) (xy 274.943173 -305.636826) (xy 274.90267 -305.664782) (xy 274.858208 -305.68588)
			(xy 274.810937 -305.699572) (xy 274.762082 -305.705504) (xy 274.712907 -305.703523) (xy 274.664688 -305.693679)
			(xy 274.618672 -305.676227) (xy 274.576051 -305.65162) (xy 274.53793 -305.620495) (xy 274.505295 -305.583658)
			(xy 274.478992 -305.542062) (xy 274.459701 -305.496786) (xy 274.447924 -305.449002) (xy 274.443964 -305.399948)
			(xy 274.105116 -305.399948) (xy 274.104621 -305.424555) (xy 274.096726 -305.473132) (xy 274.081142 -305.519813)
			(xy 274.058271 -305.56339) (xy 274.028706 -305.602734) (xy 273.993213 -305.636826) (xy 273.95271 -305.664782)
			(xy 273.908248 -305.68588) (xy 273.860977 -305.699572) (xy 273.812122 -305.705504) (xy 273.762947 -305.703523)
			(xy 273.714728 -305.693679) (xy 273.668712 -305.676227) (xy 273.626091 -305.65162) (xy 273.58797 -305.620495)
			(xy 273.555335 -305.583658) (xy 273.529032 -305.542062) (xy 273.509741 -305.496786) (xy 273.497964 -305.449002)
			(xy 273.494004 -305.399948) (xy 272.205196 -305.399948) (xy 272.204701 -305.424555) (xy 272.196806 -305.473132)
			(xy 272.181222 -305.519813) (xy 272.158351 -305.56339) (xy 272.128786 -305.602734) (xy 272.093293 -305.636826)
			(xy 272.05279 -305.664782) (xy 272.008328 -305.68588) (xy 271.961057 -305.699572) (xy 271.912202 -305.705504)
			(xy 271.863027 -305.703523) (xy 271.814808 -305.693679) (xy 271.768792 -305.676227) (xy 271.726171 -305.65162)
			(xy 271.68805 -305.620495) (xy 271.655415 -305.583658) (xy 271.629112 -305.542062) (xy 271.609821 -305.496786)
			(xy 271.598044 -305.449002) (xy 271.594084 -305.399948) (xy 271.255236 -305.399948) (xy 271.254741 -305.424555)
			(xy 271.246846 -305.473132) (xy 271.231262 -305.519813) (xy 271.208391 -305.56339) (xy 271.178826 -305.602734)
			(xy 271.143333 -305.636826) (xy 271.10283 -305.664782) (xy 271.058368 -305.68588) (xy 271.011097 -305.699572)
			(xy 270.962242 -305.705504) (xy 270.913067 -305.703523) (xy 270.864848 -305.693679) (xy 270.818832 -305.676227)
			(xy 270.776211 -305.65162) (xy 270.73809 -305.620495) (xy 270.705455 -305.583658) (xy 270.679152 -305.542062)
			(xy 270.659861 -305.496786) (xy 270.648084 -305.449002) (xy 270.644124 -305.399948) (xy 196.955156 -305.399948)
			(xy 196.954661 -305.424555) (xy 196.946766 -305.473132) (xy 196.931182 -305.519813) (xy 196.908311 -305.56339)
			(xy 196.878746 -305.602734) (xy 196.843253 -305.636826) (xy 196.80275 -305.664782) (xy 196.758288 -305.68588)
			(xy 196.711017 -305.699572) (xy 196.662162 -305.705504) (xy 196.612987 -305.703523) (xy 196.564768 -305.693679)
			(xy 196.518752 -305.676227) (xy 196.476131 -305.65162) (xy 196.43801 -305.620495) (xy 196.405375 -305.583658)
			(xy 196.379072 -305.542062) (xy 196.359781 -305.496786) (xy 196.348004 -305.449002) (xy 196.344044 -305.399948)
			(xy 196.005196 -305.399948) (xy 196.004701 -305.424555) (xy 195.996806 -305.473132) (xy 195.981222 -305.519813)
			(xy 195.958351 -305.56339) (xy 195.928786 -305.602734) (xy 195.893293 -305.636826) (xy 195.85279 -305.664782)
			(xy 195.808328 -305.68588) (xy 195.761057 -305.699572) (xy 195.712202 -305.705504) (xy 195.663027 -305.703523)
			(xy 195.614808 -305.693679) (xy 195.568792 -305.676227) (xy 195.526171 -305.65162) (xy 195.48805 -305.620495)
			(xy 195.455415 -305.583658) (xy 195.429112 -305.542062) (xy 195.409821 -305.496786) (xy 195.398044 -305.449002)
			(xy 195.394084 -305.399948) (xy 194.105276 -305.399948) (xy 194.104781 -305.424555) (xy 194.096886 -305.473132)
			(xy 194.081302 -305.519813) (xy 194.058431 -305.56339) (xy 194.028866 -305.602734) (xy 193.993373 -305.636826)
			(xy 193.95287 -305.664782) (xy 193.908408 -305.68588) (xy 193.861137 -305.699572) (xy 193.812282 -305.705504)
			(xy 193.763107 -305.703523) (xy 193.714888 -305.693679) (xy 193.668872 -305.676227) (xy 193.626251 -305.65162)
			(xy 193.58813 -305.620495) (xy 193.555495 -305.583658) (xy 193.529192 -305.542062) (xy 193.509901 -305.496786)
			(xy 193.498124 -305.449002) (xy 193.494164 -305.399948) (xy 193.155316 -305.399948) (xy 193.154821 -305.424555)
			(xy 193.146926 -305.473132) (xy 193.131342 -305.519813) (xy 193.108471 -305.56339) (xy 193.078906 -305.602734)
			(xy 193.043413 -305.636826) (xy 193.00291 -305.664782) (xy 192.958448 -305.68588) (xy 192.911177 -305.699572)
			(xy 192.862322 -305.705504) (xy 192.813147 -305.703523) (xy 192.764928 -305.693679) (xy 192.718912 -305.676227)
			(xy 192.676291 -305.65162) (xy 192.63817 -305.620495) (xy 192.605535 -305.583658) (xy 192.579232 -305.542062)
			(xy 192.559941 -305.496786) (xy 192.548164 -305.449002) (xy 192.544204 -305.399948) (xy 158.955232 -305.399948)
			(xy 158.954737 -305.424555) (xy 158.946842 -305.473132) (xy 158.931258 -305.519813) (xy 158.908387 -305.56339)
			(xy 158.878822 -305.602734) (xy 158.843329 -305.636826) (xy 158.802826 -305.664782) (xy 158.758364 -305.68588)
			(xy 158.711093 -305.699572) (xy 158.662238 -305.705504) (xy 158.613063 -305.703523) (xy 158.564844 -305.693679)
			(xy 158.518828 -305.676227) (xy 158.476207 -305.65162) (xy 158.438086 -305.620495) (xy 158.405451 -305.583658)
			(xy 158.379148 -305.542062) (xy 158.359857 -305.496786) (xy 158.34808 -305.449002) (xy 158.34412 -305.399948)
			(xy 158.005272 -305.399948) (xy 158.004777 -305.424555) (xy 157.996882 -305.473132) (xy 157.981298 -305.519813)
			(xy 157.958427 -305.56339) (xy 157.928862 -305.602734) (xy 157.893369 -305.636826) (xy 157.852866 -305.664782)
			(xy 157.808404 -305.68588) (xy 157.761133 -305.699572) (xy 157.712278 -305.705504) (xy 157.663103 -305.703523)
			(xy 157.614884 -305.693679) (xy 157.568868 -305.676227) (xy 157.526247 -305.65162) (xy 157.488126 -305.620495)
			(xy 157.455491 -305.583658) (xy 157.429188 -305.542062) (xy 157.409897 -305.496786) (xy 157.39812 -305.449002)
			(xy 157.39416 -305.399948) (xy 156.105352 -305.399948) (xy 156.104857 -305.424555) (xy 156.096962 -305.473132)
			(xy 156.081378 -305.519813) (xy 156.058507 -305.56339) (xy 156.028942 -305.602734) (xy 155.993449 -305.636826)
			(xy 155.952946 -305.664782) (xy 155.908484 -305.68588) (xy 155.861213 -305.699572) (xy 155.812358 -305.705504)
			(xy 155.763183 -305.703523) (xy 155.714964 -305.693679) (xy 155.668948 -305.676227) (xy 155.626327 -305.65162)
			(xy 155.588206 -305.620495) (xy 155.555571 -305.583658) (xy 155.529268 -305.542062) (xy 155.509977 -305.496786)
			(xy 155.4982 -305.449002) (xy 155.49424 -305.399948) (xy 155.155392 -305.399948) (xy 155.154897 -305.424555)
			(xy 155.147002 -305.473132) (xy 155.131418 -305.519813) (xy 155.108547 -305.56339) (xy 155.078982 -305.602734)
			(xy 155.043489 -305.636826) (xy 155.002986 -305.664782) (xy 154.958524 -305.68588) (xy 154.911253 -305.699572)
			(xy 154.862398 -305.705504) (xy 154.813223 -305.703523) (xy 154.765004 -305.693679) (xy 154.718988 -305.676227)
			(xy 154.676367 -305.65162) (xy 154.638246 -305.620495) (xy 154.605611 -305.583658) (xy 154.579308 -305.542062)
			(xy 154.560017 -305.496786) (xy 154.54824 -305.449002) (xy 154.54428 -305.399948) (xy 80.855058 -305.399948)
			(xy 80.854563 -305.424555) (xy 80.846668 -305.473132) (xy 80.831084 -305.519813) (xy 80.808213 -305.56339)
			(xy 80.778648 -305.602734) (xy 80.743155 -305.636826) (xy 80.702652 -305.664782) (xy 80.65819 -305.68588)
			(xy 80.610919 -305.699572) (xy 80.562064 -305.705504) (xy 80.512889 -305.703523) (xy 80.46467 -305.693679)
			(xy 80.418654 -305.676227) (xy 80.376033 -305.65162) (xy 80.337912 -305.620495) (xy 80.305277 -305.583658)
			(xy 80.278974 -305.542062) (xy 80.259683 -305.496786) (xy 80.247906 -305.449002) (xy 80.243946 -305.399948)
			(xy 79.905098 -305.399948) (xy 79.904603 -305.424555) (xy 79.896708 -305.473132) (xy 79.881124 -305.519813)
			(xy 79.858253 -305.56339) (xy 79.828688 -305.602734) (xy 79.793195 -305.636826) (xy 79.752692 -305.664782)
			(xy 79.70823 -305.68588) (xy 79.660959 -305.699572) (xy 79.612104 -305.705504) (xy 79.562929 -305.703523)
			(xy 79.51471 -305.693679) (xy 79.468694 -305.676227) (xy 79.426073 -305.65162) (xy 79.387952 -305.620495)
			(xy 79.355317 -305.583658) (xy 79.329014 -305.542062) (xy 79.309723 -305.496786) (xy 79.297946 -305.449002)
			(xy 79.293986 -305.399948) (xy 78.005178 -305.399948) (xy 78.004683 -305.424555) (xy 77.996788 -305.473132)
			(xy 77.981204 -305.519813) (xy 77.958333 -305.56339) (xy 77.928768 -305.602734) (xy 77.893275 -305.636826)
			(xy 77.852772 -305.664782) (xy 77.80831 -305.68588) (xy 77.761039 -305.699572) (xy 77.712184 -305.705504)
			(xy 77.663009 -305.703523) (xy 77.61479 -305.693679) (xy 77.568774 -305.676227) (xy 77.526153 -305.65162)
			(xy 77.488032 -305.620495) (xy 77.455397 -305.583658) (xy 77.429094 -305.542062) (xy 77.409803 -305.496786)
			(xy 77.398026 -305.449002) (xy 77.394066 -305.399948) (xy 77.055218 -305.399948) (xy 77.054723 -305.424555)
			(xy 77.046828 -305.473132) (xy 77.031244 -305.519813) (xy 77.008373 -305.56339) (xy 76.978808 -305.602734)
			(xy 76.943315 -305.636826) (xy 76.902812 -305.664782) (xy 76.85835 -305.68588) (xy 76.811079 -305.699572)
			(xy 76.762224 -305.705504) (xy 76.713049 -305.703523) (xy 76.66483 -305.693679) (xy 76.618814 -305.676227)
			(xy 76.576193 -305.65162) (xy 76.538072 -305.620495) (xy 76.505437 -305.583658) (xy 76.479134 -305.542062)
			(xy 76.459843 -305.496786) (xy 76.448066 -305.449002) (xy 76.444106 -305.399948) (xy 42.855134 -305.399948)
			(xy 42.854639 -305.424555) (xy 42.846744 -305.473132) (xy 42.83116 -305.519813) (xy 42.808289 -305.56339)
			(xy 42.778724 -305.602734) (xy 42.743231 -305.636826) (xy 42.702728 -305.664782) (xy 42.658266 -305.68588)
			(xy 42.610995 -305.699572) (xy 42.56214 -305.705504) (xy 42.512965 -305.703523) (xy 42.464746 -305.693679)
			(xy 42.41873 -305.676227) (xy 42.376109 -305.65162) (xy 42.337988 -305.620495) (xy 42.305353 -305.583658)
			(xy 42.27905 -305.542062) (xy 42.259759 -305.496786) (xy 42.247982 -305.449002) (xy 42.244022 -305.399948)
			(xy 41.905174 -305.399948) (xy 41.904679 -305.424555) (xy 41.896784 -305.473132) (xy 41.8812 -305.519813)
			(xy 41.858329 -305.56339) (xy 41.828764 -305.602734) (xy 41.793271 -305.636826) (xy 41.752768 -305.664782)
			(xy 41.708306 -305.68588) (xy 41.661035 -305.699572) (xy 41.61218 -305.705504) (xy 41.563005 -305.703523)
			(xy 41.514786 -305.693679) (xy 41.46877 -305.676227) (xy 41.426149 -305.65162) (xy 41.388028 -305.620495)
			(xy 41.355393 -305.583658) (xy 41.32909 -305.542062) (xy 41.309799 -305.496786) (xy 41.298022 -305.449002)
			(xy 41.294062 -305.399948) (xy 40.005254 -305.399948) (xy 40.004759 -305.424555) (xy 39.996864 -305.473132)
			(xy 39.98128 -305.519813) (xy 39.958409 -305.56339) (xy 39.928844 -305.602734) (xy 39.893351 -305.636826)
			(xy 39.852848 -305.664782) (xy 39.808386 -305.68588) (xy 39.761115 -305.699572) (xy 39.71226 -305.705504)
			(xy 39.663085 -305.703523) (xy 39.614866 -305.693679) (xy 39.56885 -305.676227) (xy 39.526229 -305.65162)
			(xy 39.488108 -305.620495) (xy 39.455473 -305.583658) (xy 39.42917 -305.542062) (xy 39.409879 -305.496786)
			(xy 39.398102 -305.449002) (xy 39.394142 -305.399948) (xy 39.055294 -305.399948) (xy 39.054799 -305.424555)
			(xy 39.046904 -305.473132) (xy 39.03132 -305.519813) (xy 39.008449 -305.56339) (xy 38.978884 -305.602734)
			(xy 38.943391 -305.636826) (xy 38.902888 -305.664782) (xy 38.858426 -305.68588) (xy 38.811155 -305.699572)
			(xy 38.7623 -305.705504) (xy 38.713125 -305.703523) (xy 38.664906 -305.693679) (xy 38.61889 -305.676227)
			(xy 38.576269 -305.65162) (xy 38.538148 -305.620495) (xy 38.505513 -305.583658) (xy 38.47921 -305.542062)
			(xy 38.459919 -305.496786) (xy 38.448142 -305.449002) (xy 38.444182 -305.399948) (xy 18.343745 -305.399948)
			(xy 18.323105 -305.431145) (xy 18.285863 -305.472709) (xy 18.242967 -305.508408) (xy 18.195329 -305.537481)
			(xy 18.143966 -305.559308) (xy 18.089973 -305.573424) (xy 18.034499 -305.579527) (xy 17.978728 -305.577489)
			(xy 17.923849 -305.567352) (xy 17.871029 -305.549333) (xy 17.821397 -305.523815) (xy 17.776009 -305.491343)
			(xy 17.735832 -305.452608) (xy 17.701724 -305.408436) (xy 17.67441 -305.359768) (xy 17.654474 -305.307642)
			(xy 17.642339 -305.253169) (xy 17.638266 -305.19751) (xy 0.509016 -305.19751) (xy 0.509016 -306.28209)
			(xy 17.638266 -306.28209) (xy 17.642339 -306.226431) (xy 17.654474 -306.171958) (xy 17.67441 -306.119832)
			(xy 17.701724 -306.071164) (xy 17.735832 -306.026992) (xy 17.776009 -305.988257) (xy 17.821397 -305.955785)
			(xy 17.871029 -305.930267) (xy 17.923849 -305.912248) (xy 17.978728 -305.902111) (xy 18.034499 -305.900073)
			(xy 18.089973 -305.906176) (xy 18.143966 -305.920292) (xy 18.195329 -305.942119) (xy 18.242967 -305.971192)
			(xy 18.285863 -306.006891) (xy 18.323105 -306.048455) (xy 18.353899 -306.094999) (xy 18.377587 -306.14553)
			(xy 18.393665 -306.198972) (xy 18.401791 -306.254186) (xy 18.4023 -306.28209) (xy 18.401791 -306.309994)
			(xy 18.395917 -306.349908) (xy 36.544008 -306.349908) (xy 36.547968 -306.300854) (xy 36.559745 -306.25307)
			(xy 36.579036 -306.207794) (xy 36.605339 -306.166198) (xy 36.637974 -306.129361) (xy 36.676095 -306.098236)
			(xy 36.718716 -306.073629) (xy 36.764732 -306.056177) (xy 36.812951 -306.046333) (xy 36.862126 -306.044352)
			(xy 36.910981 -306.050284) (xy 36.958252 -306.063976) (xy 37.002714 -306.085074) (xy 37.043217 -306.11303)
			(xy 37.07871 -306.147122) (xy 37.108275 -306.186466) (xy 37.131146 -306.230043) (xy 37.14673 -306.276724)
			(xy 37.154625 -306.325301) (xy 37.15512 -306.349908) (xy 37.493968 -306.349908) (xy 37.497928 -306.300854)
			(xy 37.509705 -306.25307) (xy 37.528996 -306.207794) (xy 37.555299 -306.166198) (xy 37.587934 -306.129361)
			(xy 37.626055 -306.098236) (xy 37.668676 -306.073629) (xy 37.714692 -306.056177) (xy 37.762911 -306.046333)
			(xy 37.812086 -306.044352) (xy 37.860941 -306.050284) (xy 37.908212 -306.063976) (xy 37.952674 -306.085074)
			(xy 37.993177 -306.11303) (xy 38.02867 -306.147122) (xy 38.058235 -306.186466) (xy 38.081106 -306.230043)
			(xy 38.09669 -306.276724) (xy 38.104585 -306.325301) (xy 38.10508 -306.349908) (xy 43.193982 -306.349908)
			(xy 43.197942 -306.300854) (xy 43.209719 -306.25307) (xy 43.22901 -306.207794) (xy 43.255313 -306.166198)
			(xy 43.287948 -306.129361) (xy 43.326069 -306.098236) (xy 43.36869 -306.073629) (xy 43.414706 -306.056177)
			(xy 43.462925 -306.046333) (xy 43.5121 -306.044352) (xy 43.560955 -306.050284) (xy 43.608226 -306.063976)
			(xy 43.652688 -306.085074) (xy 43.693191 -306.11303) (xy 43.728684 -306.147122) (xy 43.758249 -306.186466)
			(xy 43.78112 -306.230043) (xy 43.796704 -306.276724) (xy 43.804599 -306.325301) (xy 43.805094 -306.349908)
			(xy 44.143942 -306.349908) (xy 44.147902 -306.300854) (xy 44.159679 -306.25307) (xy 44.17897 -306.207794)
			(xy 44.205273 -306.166198) (xy 44.237908 -306.129361) (xy 44.276029 -306.098236) (xy 44.31865 -306.073629)
			(xy 44.364666 -306.056177) (xy 44.412885 -306.046333) (xy 44.46206 -306.044352) (xy 44.510915 -306.050284)
			(xy 44.558186 -306.063976) (xy 44.602648 -306.085074) (xy 44.643151 -306.11303) (xy 44.678644 -306.147122)
			(xy 44.708209 -306.186466) (xy 44.73108 -306.230043) (xy 44.746664 -306.276724) (xy 44.754559 -306.325301)
			(xy 44.755054 -306.349908) (xy 74.544186 -306.349908) (xy 74.548146 -306.300854) (xy 74.559923 -306.25307)
			(xy 74.579214 -306.207794) (xy 74.605517 -306.166198) (xy 74.638152 -306.129361) (xy 74.676273 -306.098236)
			(xy 74.718894 -306.073629) (xy 74.76491 -306.056177) (xy 74.813129 -306.046333) (xy 74.862304 -306.044352)
			(xy 74.911159 -306.050284) (xy 74.95843 -306.063976) (xy 75.002892 -306.085074) (xy 75.043395 -306.11303)
			(xy 75.078888 -306.147122) (xy 75.108453 -306.186466) (xy 75.131324 -306.230043) (xy 75.146908 -306.276724)
			(xy 75.154803 -306.325301) (xy 75.155298 -306.349908) (xy 75.494146 -306.349908) (xy 75.498106 -306.300854)
			(xy 75.509883 -306.25307) (xy 75.529174 -306.207794) (xy 75.555477 -306.166198) (xy 75.588112 -306.129361)
			(xy 75.626233 -306.098236) (xy 75.668854 -306.073629) (xy 75.71487 -306.056177) (xy 75.763089 -306.046333)
			(xy 75.812264 -306.044352) (xy 75.861119 -306.050284) (xy 75.90839 -306.063976) (xy 75.952852 -306.085074)
			(xy 75.993355 -306.11303) (xy 76.028848 -306.147122) (xy 76.058413 -306.186466) (xy 76.081284 -306.230043)
			(xy 76.096868 -306.276724) (xy 76.104763 -306.325301) (xy 76.105258 -306.349908) (xy 81.19416 -306.349908)
			(xy 81.19812 -306.300854) (xy 81.209897 -306.25307) (xy 81.229188 -306.207794) (xy 81.255491 -306.166198)
			(xy 81.288126 -306.129361) (xy 81.326247 -306.098236) (xy 81.368868 -306.073629) (xy 81.414884 -306.056177)
			(xy 81.463103 -306.046333) (xy 81.512278 -306.044352) (xy 81.561133 -306.050284) (xy 81.608404 -306.063976)
			(xy 81.652866 -306.085074) (xy 81.693369 -306.11303) (xy 81.728862 -306.147122) (xy 81.758427 -306.186466)
			(xy 81.781298 -306.230043) (xy 81.796882 -306.276724) (xy 81.804777 -306.325301) (xy 81.805272 -306.349908)
			(xy 82.14412 -306.349908) (xy 82.14808 -306.300854) (xy 82.159857 -306.25307) (xy 82.179148 -306.207794)
			(xy 82.205451 -306.166198) (xy 82.238086 -306.129361) (xy 82.276207 -306.098236) (xy 82.318828 -306.073629)
			(xy 82.364844 -306.056177) (xy 82.413063 -306.046333) (xy 82.462238 -306.044352) (xy 82.511093 -306.050284)
			(xy 82.558364 -306.063976) (xy 82.602826 -306.085074) (xy 82.643329 -306.11303) (xy 82.678822 -306.147122)
			(xy 82.708387 -306.186466) (xy 82.731258 -306.230043) (xy 82.746842 -306.276724) (xy 82.754737 -306.325301)
			(xy 82.755232 -306.349908) (xy 152.644106 -306.349908) (xy 152.648066 -306.300854) (xy 152.659843 -306.25307)
			(xy 152.679134 -306.207794) (xy 152.705437 -306.166198) (xy 152.738072 -306.129361) (xy 152.776193 -306.098236)
			(xy 152.818814 -306.073629) (xy 152.86483 -306.056177) (xy 152.913049 -306.046333) (xy 152.962224 -306.044352)
			(xy 153.011079 -306.050284) (xy 153.05835 -306.063976) (xy 153.102812 -306.085074) (xy 153.143315 -306.11303)
			(xy 153.178808 -306.147122) (xy 153.208373 -306.186466) (xy 153.231244 -306.230043) (xy 153.246828 -306.276724)
			(xy 153.254723 -306.325301) (xy 153.255218 -306.349908) (xy 153.594066 -306.349908) (xy 153.598026 -306.300854)
			(xy 153.609803 -306.25307) (xy 153.629094 -306.207794) (xy 153.655397 -306.166198) (xy 153.688032 -306.129361)
			(xy 153.726153 -306.098236) (xy 153.768774 -306.073629) (xy 153.81479 -306.056177) (xy 153.863009 -306.046333)
			(xy 153.912184 -306.044352) (xy 153.961039 -306.050284) (xy 154.00831 -306.063976) (xy 154.052772 -306.085074)
			(xy 154.093275 -306.11303) (xy 154.128768 -306.147122) (xy 154.158333 -306.186466) (xy 154.181204 -306.230043)
			(xy 154.196788 -306.276724) (xy 154.204683 -306.325301) (xy 154.205178 -306.349908) (xy 159.29408 -306.349908)
			(xy 159.29804 -306.300854) (xy 159.309817 -306.25307) (xy 159.329108 -306.207794) (xy 159.355411 -306.166198)
			(xy 159.388046 -306.129361) (xy 159.426167 -306.098236) (xy 159.468788 -306.073629) (xy 159.514804 -306.056177)
			(xy 159.563023 -306.046333) (xy 159.612198 -306.044352) (xy 159.661053 -306.050284) (xy 159.708324 -306.063976)
			(xy 159.752786 -306.085074) (xy 159.793289 -306.11303) (xy 159.828782 -306.147122) (xy 159.858347 -306.186466)
			(xy 159.881218 -306.230043) (xy 159.896802 -306.276724) (xy 159.904697 -306.325301) (xy 159.905192 -306.349908)
			(xy 160.24404 -306.349908) (xy 160.248 -306.300854) (xy 160.259777 -306.25307) (xy 160.279068 -306.207794)
			(xy 160.305371 -306.166198) (xy 160.338006 -306.129361) (xy 160.376127 -306.098236) (xy 160.418748 -306.073629)
			(xy 160.464764 -306.056177) (xy 160.512983 -306.046333) (xy 160.562158 -306.044352) (xy 160.611013 -306.050284)
			(xy 160.658284 -306.063976) (xy 160.702746 -306.085074) (xy 160.743249 -306.11303) (xy 160.778742 -306.147122)
			(xy 160.808307 -306.186466) (xy 160.831178 -306.230043) (xy 160.846762 -306.276724) (xy 160.854657 -306.325301)
			(xy 160.855152 -306.349908) (xy 190.644284 -306.349908) (xy 190.648244 -306.300854) (xy 190.660021 -306.25307)
			(xy 190.679312 -306.207794) (xy 190.705615 -306.166198) (xy 190.73825 -306.129361) (xy 190.776371 -306.098236)
			(xy 190.818992 -306.073629) (xy 190.865008 -306.056177) (xy 190.913227 -306.046333) (xy 190.962402 -306.044352)
			(xy 191.011257 -306.050284) (xy 191.058528 -306.063976) (xy 191.10299 -306.085074) (xy 191.143493 -306.11303)
			(xy 191.178986 -306.147122) (xy 191.208551 -306.186466) (xy 191.231422 -306.230043) (xy 191.247006 -306.276724)
			(xy 191.254901 -306.325301) (xy 191.255396 -306.349908) (xy 191.594244 -306.349908) (xy 191.598204 -306.300854)
			(xy 191.609981 -306.25307) (xy 191.629272 -306.207794) (xy 191.655575 -306.166198) (xy 191.68821 -306.129361)
			(xy 191.726331 -306.098236) (xy 191.768952 -306.073629) (xy 191.814968 -306.056177) (xy 191.863187 -306.046333)
			(xy 191.912362 -306.044352) (xy 191.961217 -306.050284) (xy 192.008488 -306.063976) (xy 192.05295 -306.085074)
			(xy 192.093453 -306.11303) (xy 192.128946 -306.147122) (xy 192.158511 -306.186466) (xy 192.181382 -306.230043)
			(xy 192.196966 -306.276724) (xy 192.204861 -306.325301) (xy 192.205356 -306.349908) (xy 197.294258 -306.349908)
			(xy 197.298218 -306.300854) (xy 197.309995 -306.25307) (xy 197.329286 -306.207794) (xy 197.355589 -306.166198)
			(xy 197.388224 -306.129361) (xy 197.426345 -306.098236) (xy 197.468966 -306.073629) (xy 197.514982 -306.056177)
			(xy 197.563201 -306.046333) (xy 197.612376 -306.044352) (xy 197.661231 -306.050284) (xy 197.708502 -306.063976)
			(xy 197.752964 -306.085074) (xy 197.793467 -306.11303) (xy 197.82896 -306.147122) (xy 197.858525 -306.186466)
			(xy 197.881396 -306.230043) (xy 197.89698 -306.276724) (xy 197.904875 -306.325301) (xy 197.90537 -306.349908)
			(xy 198.244218 -306.349908) (xy 198.248178 -306.300854) (xy 198.259955 -306.25307) (xy 198.279246 -306.207794)
			(xy 198.305549 -306.166198) (xy 198.338184 -306.129361) (xy 198.376305 -306.098236) (xy 198.418926 -306.073629)
			(xy 198.464942 -306.056177) (xy 198.513161 -306.046333) (xy 198.562336 -306.044352) (xy 198.611191 -306.050284)
			(xy 198.658462 -306.063976) (xy 198.702924 -306.085074) (xy 198.743427 -306.11303) (xy 198.77892 -306.147122)
			(xy 198.808485 -306.186466) (xy 198.831356 -306.230043) (xy 198.84694 -306.276724) (xy 198.854835 -306.325301)
			(xy 198.85533 -306.349908) (xy 268.74395 -306.349908) (xy 268.74791 -306.300854) (xy 268.759687 -306.25307)
			(xy 268.778978 -306.207794) (xy 268.805281 -306.166198) (xy 268.837916 -306.129361) (xy 268.876037 -306.098236)
			(xy 268.918658 -306.073629) (xy 268.964674 -306.056177) (xy 269.012893 -306.046333) (xy 269.062068 -306.044352)
			(xy 269.110923 -306.050284) (xy 269.158194 -306.063976) (xy 269.202656 -306.085074) (xy 269.243159 -306.11303)
			(xy 269.278652 -306.147122) (xy 269.308217 -306.186466) (xy 269.331088 -306.230043) (xy 269.346672 -306.276724)
			(xy 269.354567 -306.325301) (xy 269.355062 -306.349908) (xy 269.69391 -306.349908) (xy 269.69787 -306.300854)
			(xy 269.709647 -306.25307) (xy 269.728938 -306.207794) (xy 269.755241 -306.166198) (xy 269.787876 -306.129361)
			(xy 269.825997 -306.098236) (xy 269.868618 -306.073629) (xy 269.914634 -306.056177) (xy 269.962853 -306.046333)
			(xy 270.012028 -306.044352) (xy 270.060883 -306.050284) (xy 270.108154 -306.063976) (xy 270.152616 -306.085074)
			(xy 270.193119 -306.11303) (xy 270.228612 -306.147122) (xy 270.258177 -306.186466) (xy 270.281048 -306.230043)
			(xy 270.296632 -306.276724) (xy 270.304527 -306.325301) (xy 270.305022 -306.349908) (xy 275.393924 -306.349908)
			(xy 275.397884 -306.300854) (xy 275.409661 -306.25307) (xy 275.428952 -306.207794) (xy 275.455255 -306.166198)
			(xy 275.48789 -306.129361) (xy 275.526011 -306.098236) (xy 275.568632 -306.073629) (xy 275.614648 -306.056177)
			(xy 275.662867 -306.046333) (xy 275.712042 -306.044352) (xy 275.760897 -306.050284) (xy 275.808168 -306.063976)
			(xy 275.85263 -306.085074) (xy 275.893133 -306.11303) (xy 275.928626 -306.147122) (xy 275.958191 -306.186466)
			(xy 275.981062 -306.230043) (xy 275.996646 -306.276724) (xy 276.004541 -306.325301) (xy 276.005036 -306.349908)
			(xy 276.343884 -306.349908) (xy 276.347844 -306.300854) (xy 276.359621 -306.25307) (xy 276.378912 -306.207794)
			(xy 276.405215 -306.166198) (xy 276.43785 -306.129361) (xy 276.475971 -306.098236) (xy 276.518592 -306.073629)
			(xy 276.564608 -306.056177) (xy 276.612827 -306.046333) (xy 276.662002 -306.044352) (xy 276.710857 -306.050284)
			(xy 276.758128 -306.063976) (xy 276.80259 -306.085074) (xy 276.843093 -306.11303) (xy 276.878586 -306.147122)
			(xy 276.908151 -306.186466) (xy 276.931022 -306.230043) (xy 276.946606 -306.276724) (xy 276.954501 -306.325301)
			(xy 276.954996 -306.349908) (xy 306.744128 -306.349908) (xy 306.748088 -306.300854) (xy 306.759865 -306.25307)
			(xy 306.779156 -306.207794) (xy 306.805459 -306.166198) (xy 306.838094 -306.129361) (xy 306.876215 -306.098236)
			(xy 306.918836 -306.073629) (xy 306.964852 -306.056177) (xy 307.013071 -306.046333) (xy 307.062246 -306.044352)
			(xy 307.111101 -306.050284) (xy 307.158372 -306.063976) (xy 307.202834 -306.085074) (xy 307.243337 -306.11303)
			(xy 307.27883 -306.147122) (xy 307.308395 -306.186466) (xy 307.331266 -306.230043) (xy 307.34685 -306.276724)
			(xy 307.354745 -306.325301) (xy 307.35524 -306.349908) (xy 307.694088 -306.349908) (xy 307.698048 -306.300854)
			(xy 307.709825 -306.25307) (xy 307.729116 -306.207794) (xy 307.755419 -306.166198) (xy 307.788054 -306.129361)
			(xy 307.826175 -306.098236) (xy 307.868796 -306.073629) (xy 307.914812 -306.056177) (xy 307.963031 -306.046333)
			(xy 308.012206 -306.044352) (xy 308.061061 -306.050284) (xy 308.108332 -306.063976) (xy 308.152794 -306.085074)
			(xy 308.193297 -306.11303) (xy 308.22879 -306.147122) (xy 308.258355 -306.186466) (xy 308.281226 -306.230043)
			(xy 308.29681 -306.276724) (xy 308.304705 -306.325301) (xy 308.3052 -306.349908) (xy 313.394102 -306.349908)
			(xy 313.398062 -306.300854) (xy 313.409839 -306.25307) (xy 313.42913 -306.207794) (xy 313.455433 -306.166198)
			(xy 313.488068 -306.129361) (xy 313.526189 -306.098236) (xy 313.56881 -306.073629) (xy 313.614826 -306.056177)
			(xy 313.663045 -306.046333) (xy 313.71222 -306.044352) (xy 313.761075 -306.050284) (xy 313.808346 -306.063976)
			(xy 313.852808 -306.085074) (xy 313.893311 -306.11303) (xy 313.928804 -306.147122) (xy 313.958369 -306.186466)
			(xy 313.98124 -306.230043) (xy 313.996824 -306.276724) (xy 314.004719 -306.325301) (xy 314.005214 -306.349908)
			(xy 314.344062 -306.349908) (xy 314.348022 -306.300854) (xy 314.359799 -306.25307) (xy 314.37909 -306.207794)
			(xy 314.405393 -306.166198) (xy 314.438028 -306.129361) (xy 314.476149 -306.098236) (xy 314.51877 -306.073629)
			(xy 314.564786 -306.056177) (xy 314.613005 -306.046333) (xy 314.66218 -306.044352) (xy 314.711035 -306.050284)
			(xy 314.758306 -306.063976) (xy 314.802768 -306.085074) (xy 314.843271 -306.11303) (xy 314.878764 -306.147122)
			(xy 314.908329 -306.186466) (xy 314.9312 -306.230043) (xy 314.946784 -306.276724) (xy 314.954679 -306.325301)
			(xy 314.955174 -306.349908) (xy 384.844048 -306.349908) (xy 384.848008 -306.300854) (xy 384.859785 -306.25307)
			(xy 384.879076 -306.207794) (xy 384.905379 -306.166198) (xy 384.938014 -306.129361) (xy 384.976135 -306.098236)
			(xy 385.018756 -306.073629) (xy 385.064772 -306.056177) (xy 385.112991 -306.046333) (xy 385.162166 -306.044352)
			(xy 385.211021 -306.050284) (xy 385.258292 -306.063976) (xy 385.302754 -306.085074) (xy 385.343257 -306.11303)
			(xy 385.37875 -306.147122) (xy 385.408315 -306.186466) (xy 385.431186 -306.230043) (xy 385.44677 -306.276724)
			(xy 385.454665 -306.325301) (xy 385.45516 -306.349908) (xy 385.794008 -306.349908) (xy 385.797968 -306.300854)
			(xy 385.809745 -306.25307) (xy 385.829036 -306.207794) (xy 385.855339 -306.166198) (xy 385.887974 -306.129361)
			(xy 385.926095 -306.098236) (xy 385.968716 -306.073629) (xy 386.014732 -306.056177) (xy 386.062951 -306.046333)
			(xy 386.112126 -306.044352) (xy 386.160981 -306.050284) (xy 386.208252 -306.063976) (xy 386.252714 -306.085074)
			(xy 386.293217 -306.11303) (xy 386.32871 -306.147122) (xy 386.358275 -306.186466) (xy 386.381146 -306.230043)
			(xy 386.39673 -306.276724) (xy 386.404625 -306.325301) (xy 386.40512 -306.349908) (xy 391.494022 -306.349908)
			(xy 391.497982 -306.300854) (xy 391.509759 -306.25307) (xy 391.52905 -306.207794) (xy 391.555353 -306.166198)
			(xy 391.587988 -306.129361) (xy 391.626109 -306.098236) (xy 391.66873 -306.073629) (xy 391.714746 -306.056177)
			(xy 391.762965 -306.046333) (xy 391.81214 -306.044352) (xy 391.860995 -306.050284) (xy 391.908266 -306.063976)
			(xy 391.952728 -306.085074) (xy 391.993231 -306.11303) (xy 392.028724 -306.147122) (xy 392.058289 -306.186466)
			(xy 392.08116 -306.230043) (xy 392.096744 -306.276724) (xy 392.104639 -306.325301) (xy 392.105134 -306.349908)
			(xy 392.443982 -306.349908) (xy 392.447942 -306.300854) (xy 392.459719 -306.25307) (xy 392.47901 -306.207794)
			(xy 392.505313 -306.166198) (xy 392.537948 -306.129361) (xy 392.576069 -306.098236) (xy 392.61869 -306.073629)
			(xy 392.664706 -306.056177) (xy 392.712925 -306.046333) (xy 392.7621 -306.044352) (xy 392.810955 -306.050284)
			(xy 392.858226 -306.063976) (xy 392.902688 -306.085074) (xy 392.943191 -306.11303) (xy 392.978684 -306.147122)
			(xy 393.008249 -306.186466) (xy 393.03112 -306.230043) (xy 393.046704 -306.276724) (xy 393.054599 -306.325301)
			(xy 393.055094 -306.349908) (xy 422.844226 -306.349908) (xy 422.848186 -306.300854) (xy 422.859963 -306.25307)
			(xy 422.879254 -306.207794) (xy 422.905557 -306.166198) (xy 422.938192 -306.129361) (xy 422.976313 -306.098236)
			(xy 423.018934 -306.073629) (xy 423.06495 -306.056177) (xy 423.113169 -306.046333) (xy 423.162344 -306.044352)
			(xy 423.211199 -306.050284) (xy 423.25847 -306.063976) (xy 423.302932 -306.085074) (xy 423.343435 -306.11303)
			(xy 423.378928 -306.147122) (xy 423.408493 -306.186466) (xy 423.431364 -306.230043) (xy 423.446948 -306.276724)
			(xy 423.454843 -306.325301) (xy 423.455338 -306.349908) (xy 423.794186 -306.349908) (xy 423.798146 -306.300854)
			(xy 423.809923 -306.25307) (xy 423.829214 -306.207794) (xy 423.855517 -306.166198) (xy 423.888152 -306.129361)
			(xy 423.926273 -306.098236) (xy 423.968894 -306.073629) (xy 424.01491 -306.056177) (xy 424.063129 -306.046333)
			(xy 424.112304 -306.044352) (xy 424.161159 -306.050284) (xy 424.20843 -306.063976) (xy 424.252892 -306.085074)
			(xy 424.293395 -306.11303) (xy 424.328888 -306.147122) (xy 424.358453 -306.186466) (xy 424.381324 -306.230043)
			(xy 424.396908 -306.276724) (xy 424.404803 -306.325301) (xy 424.405298 -306.349908) (xy 429.4942 -306.349908)
			(xy 429.49816 -306.300854) (xy 429.509937 -306.25307) (xy 429.529228 -306.207794) (xy 429.555531 -306.166198)
			(xy 429.588166 -306.129361) (xy 429.626287 -306.098236) (xy 429.668908 -306.073629) (xy 429.714924 -306.056177)
			(xy 429.763143 -306.046333) (xy 429.812318 -306.044352) (xy 429.861173 -306.050284) (xy 429.908444 -306.063976)
			(xy 429.952906 -306.085074) (xy 429.993409 -306.11303) (xy 430.028902 -306.147122) (xy 430.058467 -306.186466)
			(xy 430.081338 -306.230043) (xy 430.096922 -306.276724) (xy 430.104817 -306.325301) (xy 430.105312 -306.349908)
			(xy 430.44416 -306.349908) (xy 430.44812 -306.300854) (xy 430.459897 -306.25307) (xy 430.479188 -306.207794)
			(xy 430.505491 -306.166198) (xy 430.538126 -306.129361) (xy 430.576247 -306.098236) (xy 430.618868 -306.073629)
			(xy 430.664884 -306.056177) (xy 430.713103 -306.046333) (xy 430.762278 -306.044352) (xy 430.811133 -306.050284)
			(xy 430.858404 -306.063976) (xy 430.902866 -306.085074) (xy 430.943369 -306.11303) (xy 430.978862 -306.147122)
			(xy 431.008427 -306.186466) (xy 431.031298 -306.230043) (xy 431.046882 -306.276724) (xy 431.054777 -306.325301)
			(xy 431.055272 -306.349908) (xy 431.054777 -306.374515) (xy 431.046882 -306.423092) (xy 431.031298 -306.469773)
			(xy 431.008427 -306.51335) (xy 430.978862 -306.552694) (xy 430.943369 -306.586786) (xy 430.902866 -306.614742)
			(xy 430.858404 -306.63584) (xy 430.811133 -306.649532) (xy 430.762278 -306.655464) (xy 430.713103 -306.653483)
			(xy 430.664884 -306.643639) (xy 430.618868 -306.626187) (xy 430.576247 -306.60158) (xy 430.538126 -306.570455)
			(xy 430.505491 -306.533618) (xy 430.479188 -306.492022) (xy 430.459897 -306.446746) (xy 430.44812 -306.398962)
			(xy 430.44416 -306.349908) (xy 430.105312 -306.349908) (xy 430.104817 -306.374515) (xy 430.096922 -306.423092)
			(xy 430.081338 -306.469773) (xy 430.058467 -306.51335) (xy 430.028902 -306.552694) (xy 429.993409 -306.586786)
			(xy 429.952906 -306.614742) (xy 429.908444 -306.63584) (xy 429.861173 -306.649532) (xy 429.812318 -306.655464)
			(xy 429.763143 -306.653483) (xy 429.714924 -306.643639) (xy 429.668908 -306.626187) (xy 429.626287 -306.60158)
			(xy 429.588166 -306.570455) (xy 429.555531 -306.533618) (xy 429.529228 -306.492022) (xy 429.509937 -306.446746)
			(xy 429.49816 -306.398962) (xy 429.4942 -306.349908) (xy 424.405298 -306.349908) (xy 424.404803 -306.374515)
			(xy 424.396908 -306.423092) (xy 424.381324 -306.469773) (xy 424.358453 -306.51335) (xy 424.328888 -306.552694)
			(xy 424.293395 -306.586786) (xy 424.252892 -306.614742) (xy 424.20843 -306.63584) (xy 424.161159 -306.649532)
			(xy 424.112304 -306.655464) (xy 424.063129 -306.653483) (xy 424.01491 -306.643639) (xy 423.968894 -306.626187)
			(xy 423.926273 -306.60158) (xy 423.888152 -306.570455) (xy 423.855517 -306.533618) (xy 423.829214 -306.492022)
			(xy 423.809923 -306.446746) (xy 423.798146 -306.398962) (xy 423.794186 -306.349908) (xy 423.455338 -306.349908)
			(xy 423.454843 -306.374515) (xy 423.446948 -306.423092) (xy 423.431364 -306.469773) (xy 423.408493 -306.51335)
			(xy 423.378928 -306.552694) (xy 423.343435 -306.586786) (xy 423.302932 -306.614742) (xy 423.25847 -306.63584)
			(xy 423.211199 -306.649532) (xy 423.162344 -306.655464) (xy 423.113169 -306.653483) (xy 423.06495 -306.643639)
			(xy 423.018934 -306.626187) (xy 422.976313 -306.60158) (xy 422.938192 -306.570455) (xy 422.905557 -306.533618)
			(xy 422.879254 -306.492022) (xy 422.859963 -306.446746) (xy 422.848186 -306.398962) (xy 422.844226 -306.349908)
			(xy 393.055094 -306.349908) (xy 393.054599 -306.374515) (xy 393.046704 -306.423092) (xy 393.03112 -306.469773)
			(xy 393.008249 -306.51335) (xy 392.978684 -306.552694) (xy 392.943191 -306.586786) (xy 392.902688 -306.614742)
			(xy 392.858226 -306.63584) (xy 392.810955 -306.649532) (xy 392.7621 -306.655464) (xy 392.712925 -306.653483)
			(xy 392.664706 -306.643639) (xy 392.61869 -306.626187) (xy 392.576069 -306.60158) (xy 392.537948 -306.570455)
			(xy 392.505313 -306.533618) (xy 392.47901 -306.492022) (xy 392.459719 -306.446746) (xy 392.447942 -306.398962)
			(xy 392.443982 -306.349908) (xy 392.105134 -306.349908) (xy 392.104639 -306.374515) (xy 392.096744 -306.423092)
			(xy 392.08116 -306.469773) (xy 392.058289 -306.51335) (xy 392.028724 -306.552694) (xy 391.993231 -306.586786)
			(xy 391.952728 -306.614742) (xy 391.908266 -306.63584) (xy 391.860995 -306.649532) (xy 391.81214 -306.655464)
			(xy 391.762965 -306.653483) (xy 391.714746 -306.643639) (xy 391.66873 -306.626187) (xy 391.626109 -306.60158)
			(xy 391.587988 -306.570455) (xy 391.555353 -306.533618) (xy 391.52905 -306.492022) (xy 391.509759 -306.446746)
			(xy 391.497982 -306.398962) (xy 391.494022 -306.349908) (xy 386.40512 -306.349908) (xy 386.404625 -306.374515)
			(xy 386.39673 -306.423092) (xy 386.381146 -306.469773) (xy 386.358275 -306.51335) (xy 386.32871 -306.552694)
			(xy 386.293217 -306.586786) (xy 386.252714 -306.614742) (xy 386.208252 -306.63584) (xy 386.160981 -306.649532)
			(xy 386.112126 -306.655464) (xy 386.062951 -306.653483) (xy 386.014732 -306.643639) (xy 385.968716 -306.626187)
			(xy 385.926095 -306.60158) (xy 385.887974 -306.570455) (xy 385.855339 -306.533618) (xy 385.829036 -306.492022)
			(xy 385.809745 -306.446746) (xy 385.797968 -306.398962) (xy 385.794008 -306.349908) (xy 385.45516 -306.349908)
			(xy 385.454665 -306.374515) (xy 385.44677 -306.423092) (xy 385.431186 -306.469773) (xy 385.408315 -306.51335)
			(xy 385.37875 -306.552694) (xy 385.343257 -306.586786) (xy 385.302754 -306.614742) (xy 385.258292 -306.63584)
			(xy 385.211021 -306.649532) (xy 385.162166 -306.655464) (xy 385.112991 -306.653483) (xy 385.064772 -306.643639)
			(xy 385.018756 -306.626187) (xy 384.976135 -306.60158) (xy 384.938014 -306.570455) (xy 384.905379 -306.533618)
			(xy 384.879076 -306.492022) (xy 384.859785 -306.446746) (xy 384.848008 -306.398962) (xy 384.844048 -306.349908)
			(xy 314.955174 -306.349908) (xy 314.954679 -306.374515) (xy 314.946784 -306.423092) (xy 314.9312 -306.469773)
			(xy 314.908329 -306.51335) (xy 314.878764 -306.552694) (xy 314.843271 -306.586786) (xy 314.802768 -306.614742)
			(xy 314.758306 -306.63584) (xy 314.711035 -306.649532) (xy 314.66218 -306.655464) (xy 314.613005 -306.653483)
			(xy 314.564786 -306.643639) (xy 314.51877 -306.626187) (xy 314.476149 -306.60158) (xy 314.438028 -306.570455)
			(xy 314.405393 -306.533618) (xy 314.37909 -306.492022) (xy 314.359799 -306.446746) (xy 314.348022 -306.398962)
			(xy 314.344062 -306.349908) (xy 314.005214 -306.349908) (xy 314.004719 -306.374515) (xy 313.996824 -306.423092)
			(xy 313.98124 -306.469773) (xy 313.958369 -306.51335) (xy 313.928804 -306.552694) (xy 313.893311 -306.586786)
			(xy 313.852808 -306.614742) (xy 313.808346 -306.63584) (xy 313.761075 -306.649532) (xy 313.71222 -306.655464)
			(xy 313.663045 -306.653483) (xy 313.614826 -306.643639) (xy 313.56881 -306.626187) (xy 313.526189 -306.60158)
			(xy 313.488068 -306.570455) (xy 313.455433 -306.533618) (xy 313.42913 -306.492022) (xy 313.409839 -306.446746)
			(xy 313.398062 -306.398962) (xy 313.394102 -306.349908) (xy 308.3052 -306.349908) (xy 308.304705 -306.374515)
			(xy 308.29681 -306.423092) (xy 308.281226 -306.469773) (xy 308.258355 -306.51335) (xy 308.22879 -306.552694)
			(xy 308.193297 -306.586786) (xy 308.152794 -306.614742) (xy 308.108332 -306.63584) (xy 308.061061 -306.649532)
			(xy 308.012206 -306.655464) (xy 307.963031 -306.653483) (xy 307.914812 -306.643639) (xy 307.868796 -306.626187)
			(xy 307.826175 -306.60158) (xy 307.788054 -306.570455) (xy 307.755419 -306.533618) (xy 307.729116 -306.492022)
			(xy 307.709825 -306.446746) (xy 307.698048 -306.398962) (xy 307.694088 -306.349908) (xy 307.35524 -306.349908)
			(xy 307.354745 -306.374515) (xy 307.34685 -306.423092) (xy 307.331266 -306.469773) (xy 307.308395 -306.51335)
			(xy 307.27883 -306.552694) (xy 307.243337 -306.586786) (xy 307.202834 -306.614742) (xy 307.158372 -306.63584)
			(xy 307.111101 -306.649532) (xy 307.062246 -306.655464) (xy 307.013071 -306.653483) (xy 306.964852 -306.643639)
			(xy 306.918836 -306.626187) (xy 306.876215 -306.60158) (xy 306.838094 -306.570455) (xy 306.805459 -306.533618)
			(xy 306.779156 -306.492022) (xy 306.759865 -306.446746) (xy 306.748088 -306.398962) (xy 306.744128 -306.349908)
			(xy 276.954996 -306.349908) (xy 276.954501 -306.374515) (xy 276.946606 -306.423092) (xy 276.931022 -306.469773)
			(xy 276.908151 -306.51335) (xy 276.878586 -306.552694) (xy 276.843093 -306.586786) (xy 276.80259 -306.614742)
			(xy 276.758128 -306.63584) (xy 276.710857 -306.649532) (xy 276.662002 -306.655464) (xy 276.612827 -306.653483)
			(xy 276.564608 -306.643639) (xy 276.518592 -306.626187) (xy 276.475971 -306.60158) (xy 276.43785 -306.570455)
			(xy 276.405215 -306.533618) (xy 276.378912 -306.492022) (xy 276.359621 -306.446746) (xy 276.347844 -306.398962)
			(xy 276.343884 -306.349908) (xy 276.005036 -306.349908) (xy 276.004541 -306.374515) (xy 275.996646 -306.423092)
			(xy 275.981062 -306.469773) (xy 275.958191 -306.51335) (xy 275.928626 -306.552694) (xy 275.893133 -306.586786)
			(xy 275.85263 -306.614742) (xy 275.808168 -306.63584) (xy 275.760897 -306.649532) (xy 275.712042 -306.655464)
			(xy 275.662867 -306.653483) (xy 275.614648 -306.643639) (xy 275.568632 -306.626187) (xy 275.526011 -306.60158)
			(xy 275.48789 -306.570455) (xy 275.455255 -306.533618) (xy 275.428952 -306.492022) (xy 275.409661 -306.446746)
			(xy 275.397884 -306.398962) (xy 275.393924 -306.349908) (xy 270.305022 -306.349908) (xy 270.304527 -306.374515)
			(xy 270.296632 -306.423092) (xy 270.281048 -306.469773) (xy 270.258177 -306.51335) (xy 270.228612 -306.552694)
			(xy 270.193119 -306.586786) (xy 270.152616 -306.614742) (xy 270.108154 -306.63584) (xy 270.060883 -306.649532)
			(xy 270.012028 -306.655464) (xy 269.962853 -306.653483) (xy 269.914634 -306.643639) (xy 269.868618 -306.626187)
			(xy 269.825997 -306.60158) (xy 269.787876 -306.570455) (xy 269.755241 -306.533618) (xy 269.728938 -306.492022)
			(xy 269.709647 -306.446746) (xy 269.69787 -306.398962) (xy 269.69391 -306.349908) (xy 269.355062 -306.349908)
			(xy 269.354567 -306.374515) (xy 269.346672 -306.423092) (xy 269.331088 -306.469773) (xy 269.308217 -306.51335)
			(xy 269.278652 -306.552694) (xy 269.243159 -306.586786) (xy 269.202656 -306.614742) (xy 269.158194 -306.63584)
			(xy 269.110923 -306.649532) (xy 269.062068 -306.655464) (xy 269.012893 -306.653483) (xy 268.964674 -306.643639)
			(xy 268.918658 -306.626187) (xy 268.876037 -306.60158) (xy 268.837916 -306.570455) (xy 268.805281 -306.533618)
			(xy 268.778978 -306.492022) (xy 268.759687 -306.446746) (xy 268.74791 -306.398962) (xy 268.74395 -306.349908)
			(xy 198.85533 -306.349908) (xy 198.854835 -306.374515) (xy 198.84694 -306.423092) (xy 198.831356 -306.469773)
			(xy 198.808485 -306.51335) (xy 198.77892 -306.552694) (xy 198.743427 -306.586786) (xy 198.702924 -306.614742)
			(xy 198.658462 -306.63584) (xy 198.611191 -306.649532) (xy 198.562336 -306.655464) (xy 198.513161 -306.653483)
			(xy 198.464942 -306.643639) (xy 198.418926 -306.626187) (xy 198.376305 -306.60158) (xy 198.338184 -306.570455)
			(xy 198.305549 -306.533618) (xy 198.279246 -306.492022) (xy 198.259955 -306.446746) (xy 198.248178 -306.398962)
			(xy 198.244218 -306.349908) (xy 197.90537 -306.349908) (xy 197.904875 -306.374515) (xy 197.89698 -306.423092)
			(xy 197.881396 -306.469773) (xy 197.858525 -306.51335) (xy 197.82896 -306.552694) (xy 197.793467 -306.586786)
			(xy 197.752964 -306.614742) (xy 197.708502 -306.63584) (xy 197.661231 -306.649532) (xy 197.612376 -306.655464)
			(xy 197.563201 -306.653483) (xy 197.514982 -306.643639) (xy 197.468966 -306.626187) (xy 197.426345 -306.60158)
			(xy 197.388224 -306.570455) (xy 197.355589 -306.533618) (xy 197.329286 -306.492022) (xy 197.309995 -306.446746)
			(xy 197.298218 -306.398962) (xy 197.294258 -306.349908) (xy 192.205356 -306.349908) (xy 192.204861 -306.374515)
			(xy 192.196966 -306.423092) (xy 192.181382 -306.469773) (xy 192.158511 -306.51335) (xy 192.128946 -306.552694)
			(xy 192.093453 -306.586786) (xy 192.05295 -306.614742) (xy 192.008488 -306.63584) (xy 191.961217 -306.649532)
			(xy 191.912362 -306.655464) (xy 191.863187 -306.653483) (xy 191.814968 -306.643639) (xy 191.768952 -306.626187)
			(xy 191.726331 -306.60158) (xy 191.68821 -306.570455) (xy 191.655575 -306.533618) (xy 191.629272 -306.492022)
			(xy 191.609981 -306.446746) (xy 191.598204 -306.398962) (xy 191.594244 -306.349908) (xy 191.255396 -306.349908)
			(xy 191.254901 -306.374515) (xy 191.247006 -306.423092) (xy 191.231422 -306.469773) (xy 191.208551 -306.51335)
			(xy 191.178986 -306.552694) (xy 191.143493 -306.586786) (xy 191.10299 -306.614742) (xy 191.058528 -306.63584)
			(xy 191.011257 -306.649532) (xy 190.962402 -306.655464) (xy 190.913227 -306.653483) (xy 190.865008 -306.643639)
			(xy 190.818992 -306.626187) (xy 190.776371 -306.60158) (xy 190.73825 -306.570455) (xy 190.705615 -306.533618)
			(xy 190.679312 -306.492022) (xy 190.660021 -306.446746) (xy 190.648244 -306.398962) (xy 190.644284 -306.349908)
			(xy 160.855152 -306.349908) (xy 160.854657 -306.374515) (xy 160.846762 -306.423092) (xy 160.831178 -306.469773)
			(xy 160.808307 -306.51335) (xy 160.778742 -306.552694) (xy 160.743249 -306.586786) (xy 160.702746 -306.614742)
			(xy 160.658284 -306.63584) (xy 160.611013 -306.649532) (xy 160.562158 -306.655464) (xy 160.512983 -306.653483)
			(xy 160.464764 -306.643639) (xy 160.418748 -306.626187) (xy 160.376127 -306.60158) (xy 160.338006 -306.570455)
			(xy 160.305371 -306.533618) (xy 160.279068 -306.492022) (xy 160.259777 -306.446746) (xy 160.248 -306.398962)
			(xy 160.24404 -306.349908) (xy 159.905192 -306.349908) (xy 159.904697 -306.374515) (xy 159.896802 -306.423092)
			(xy 159.881218 -306.469773) (xy 159.858347 -306.51335) (xy 159.828782 -306.552694) (xy 159.793289 -306.586786)
			(xy 159.752786 -306.614742) (xy 159.708324 -306.63584) (xy 159.661053 -306.649532) (xy 159.612198 -306.655464)
			(xy 159.563023 -306.653483) (xy 159.514804 -306.643639) (xy 159.468788 -306.626187) (xy 159.426167 -306.60158)
			(xy 159.388046 -306.570455) (xy 159.355411 -306.533618) (xy 159.329108 -306.492022) (xy 159.309817 -306.446746)
			(xy 159.29804 -306.398962) (xy 159.29408 -306.349908) (xy 154.205178 -306.349908) (xy 154.204683 -306.374515)
			(xy 154.196788 -306.423092) (xy 154.181204 -306.469773) (xy 154.158333 -306.51335) (xy 154.128768 -306.552694)
			(xy 154.093275 -306.586786) (xy 154.052772 -306.614742) (xy 154.00831 -306.63584) (xy 153.961039 -306.649532)
			(xy 153.912184 -306.655464) (xy 153.863009 -306.653483) (xy 153.81479 -306.643639) (xy 153.768774 -306.626187)
			(xy 153.726153 -306.60158) (xy 153.688032 -306.570455) (xy 153.655397 -306.533618) (xy 153.629094 -306.492022)
			(xy 153.609803 -306.446746) (xy 153.598026 -306.398962) (xy 153.594066 -306.349908) (xy 153.255218 -306.349908)
			(xy 153.254723 -306.374515) (xy 153.246828 -306.423092) (xy 153.231244 -306.469773) (xy 153.208373 -306.51335)
			(xy 153.178808 -306.552694) (xy 153.143315 -306.586786) (xy 153.102812 -306.614742) (xy 153.05835 -306.63584)
			(xy 153.011079 -306.649532) (xy 152.962224 -306.655464) (xy 152.913049 -306.653483) (xy 152.86483 -306.643639)
			(xy 152.818814 -306.626187) (xy 152.776193 -306.60158) (xy 152.738072 -306.570455) (xy 152.705437 -306.533618)
			(xy 152.679134 -306.492022) (xy 152.659843 -306.446746) (xy 152.648066 -306.398962) (xy 152.644106 -306.349908)
			(xy 82.755232 -306.349908) (xy 82.754737 -306.374515) (xy 82.746842 -306.423092) (xy 82.731258 -306.469773)
			(xy 82.708387 -306.51335) (xy 82.678822 -306.552694) (xy 82.643329 -306.586786) (xy 82.602826 -306.614742)
			(xy 82.558364 -306.63584) (xy 82.511093 -306.649532) (xy 82.462238 -306.655464) (xy 82.413063 -306.653483)
			(xy 82.364844 -306.643639) (xy 82.318828 -306.626187) (xy 82.276207 -306.60158) (xy 82.238086 -306.570455)
			(xy 82.205451 -306.533618) (xy 82.179148 -306.492022) (xy 82.159857 -306.446746) (xy 82.14808 -306.398962)
			(xy 82.14412 -306.349908) (xy 81.805272 -306.349908) (xy 81.804777 -306.374515) (xy 81.796882 -306.423092)
			(xy 81.781298 -306.469773) (xy 81.758427 -306.51335) (xy 81.728862 -306.552694) (xy 81.693369 -306.586786)
			(xy 81.652866 -306.614742) (xy 81.608404 -306.63584) (xy 81.561133 -306.649532) (xy 81.512278 -306.655464)
			(xy 81.463103 -306.653483) (xy 81.414884 -306.643639) (xy 81.368868 -306.626187) (xy 81.326247 -306.60158)
			(xy 81.288126 -306.570455) (xy 81.255491 -306.533618) (xy 81.229188 -306.492022) (xy 81.209897 -306.446746)
			(xy 81.19812 -306.398962) (xy 81.19416 -306.349908) (xy 76.105258 -306.349908) (xy 76.104763 -306.374515)
			(xy 76.096868 -306.423092) (xy 76.081284 -306.469773) (xy 76.058413 -306.51335) (xy 76.028848 -306.552694)
			(xy 75.993355 -306.586786) (xy 75.952852 -306.614742) (xy 75.90839 -306.63584) (xy 75.861119 -306.649532)
			(xy 75.812264 -306.655464) (xy 75.763089 -306.653483) (xy 75.71487 -306.643639) (xy 75.668854 -306.626187)
			(xy 75.626233 -306.60158) (xy 75.588112 -306.570455) (xy 75.555477 -306.533618) (xy 75.529174 -306.492022)
			(xy 75.509883 -306.446746) (xy 75.498106 -306.398962) (xy 75.494146 -306.349908) (xy 75.155298 -306.349908)
			(xy 75.154803 -306.374515) (xy 75.146908 -306.423092) (xy 75.131324 -306.469773) (xy 75.108453 -306.51335)
			(xy 75.078888 -306.552694) (xy 75.043395 -306.586786) (xy 75.002892 -306.614742) (xy 74.95843 -306.63584)
			(xy 74.911159 -306.649532) (xy 74.862304 -306.655464) (xy 74.813129 -306.653483) (xy 74.76491 -306.643639)
			(xy 74.718894 -306.626187) (xy 74.676273 -306.60158) (xy 74.638152 -306.570455) (xy 74.605517 -306.533618)
			(xy 74.579214 -306.492022) (xy 74.559923 -306.446746) (xy 74.548146 -306.398962) (xy 74.544186 -306.349908)
			(xy 44.755054 -306.349908) (xy 44.754559 -306.374515) (xy 44.746664 -306.423092) (xy 44.73108 -306.469773)
			(xy 44.708209 -306.51335) (xy 44.678644 -306.552694) (xy 44.643151 -306.586786) (xy 44.602648 -306.614742)
			(xy 44.558186 -306.63584) (xy 44.510915 -306.649532) (xy 44.46206 -306.655464) (xy 44.412885 -306.653483)
			(xy 44.364666 -306.643639) (xy 44.31865 -306.626187) (xy 44.276029 -306.60158) (xy 44.237908 -306.570455)
			(xy 44.205273 -306.533618) (xy 44.17897 -306.492022) (xy 44.159679 -306.446746) (xy 44.147902 -306.398962)
			(xy 44.143942 -306.349908) (xy 43.805094 -306.349908) (xy 43.804599 -306.374515) (xy 43.796704 -306.423092)
			(xy 43.78112 -306.469773) (xy 43.758249 -306.51335) (xy 43.728684 -306.552694) (xy 43.693191 -306.586786)
			(xy 43.652688 -306.614742) (xy 43.608226 -306.63584) (xy 43.560955 -306.649532) (xy 43.5121 -306.655464)
			(xy 43.462925 -306.653483) (xy 43.414706 -306.643639) (xy 43.36869 -306.626187) (xy 43.326069 -306.60158)
			(xy 43.287948 -306.570455) (xy 43.255313 -306.533618) (xy 43.22901 -306.492022) (xy 43.209719 -306.446746)
			(xy 43.197942 -306.398962) (xy 43.193982 -306.349908) (xy 38.10508 -306.349908) (xy 38.104585 -306.374515)
			(xy 38.09669 -306.423092) (xy 38.081106 -306.469773) (xy 38.058235 -306.51335) (xy 38.02867 -306.552694)
			(xy 37.993177 -306.586786) (xy 37.952674 -306.614742) (xy 37.908212 -306.63584) (xy 37.860941 -306.649532)
			(xy 37.812086 -306.655464) (xy 37.762911 -306.653483) (xy 37.714692 -306.643639) (xy 37.668676 -306.626187)
			(xy 37.626055 -306.60158) (xy 37.587934 -306.570455) (xy 37.555299 -306.533618) (xy 37.528996 -306.492022)
			(xy 37.509705 -306.446746) (xy 37.497928 -306.398962) (xy 37.493968 -306.349908) (xy 37.15512 -306.349908)
			(xy 37.154625 -306.374515) (xy 37.14673 -306.423092) (xy 37.131146 -306.469773) (xy 37.108275 -306.51335)
			(xy 37.07871 -306.552694) (xy 37.043217 -306.586786) (xy 37.002714 -306.614742) (xy 36.958252 -306.63584)
			(xy 36.910981 -306.649532) (xy 36.862126 -306.655464) (xy 36.812951 -306.653483) (xy 36.764732 -306.643639)
			(xy 36.718716 -306.626187) (xy 36.676095 -306.60158) (xy 36.637974 -306.570455) (xy 36.605339 -306.533618)
			(xy 36.579036 -306.492022) (xy 36.559745 -306.446746) (xy 36.547968 -306.398962) (xy 36.544008 -306.349908)
			(xy 18.395917 -306.349908) (xy 18.393665 -306.365208) (xy 18.377587 -306.41865) (xy 18.353899 -306.469181)
			(xy 18.323105 -306.515725) (xy 18.285863 -306.557289) (xy 18.242967 -306.592988) (xy 18.195329 -306.622061)
			(xy 18.143966 -306.643888) (xy 18.089973 -306.658004) (xy 18.034499 -306.664107) (xy 17.978728 -306.662069)
			(xy 17.923849 -306.651932) (xy 17.871029 -306.633913) (xy 17.821397 -306.608395) (xy 17.776009 -306.575923)
			(xy 17.735832 -306.537188) (xy 17.701724 -306.493016) (xy 17.67441 -306.444348) (xy 17.654474 -306.392222)
			(xy 17.642339 -306.337749) (xy 17.638266 -306.28209) (xy 0.509016 -306.28209) (xy 0.509016 -307.299868)
			(xy 38.444182 -307.299868) (xy 38.448142 -307.250814) (xy 38.459919 -307.20303) (xy 38.47921 -307.157754)
			(xy 38.505513 -307.116158) (xy 38.538148 -307.079321) (xy 38.576269 -307.048196) (xy 38.61889 -307.023589)
			(xy 38.664906 -307.006137) (xy 38.713125 -306.996293) (xy 38.7623 -306.994312) (xy 38.811155 -307.000244)
			(xy 38.858426 -307.013936) (xy 38.902888 -307.035034) (xy 38.943391 -307.06299) (xy 38.978884 -307.097082)
			(xy 39.008449 -307.136426) (xy 39.03132 -307.180003) (xy 39.046904 -307.226684) (xy 39.054799 -307.275261)
			(xy 39.055294 -307.299868) (xy 39.394142 -307.299868) (xy 39.398102 -307.250814) (xy 39.409879 -307.20303)
			(xy 39.42917 -307.157754) (xy 39.455473 -307.116158) (xy 39.488108 -307.079321) (xy 39.526229 -307.048196)
			(xy 39.56885 -307.023589) (xy 39.614866 -307.006137) (xy 39.663085 -306.996293) (xy 39.71226 -306.994312)
			(xy 39.761115 -307.000244) (xy 39.808386 -307.013936) (xy 39.852848 -307.035034) (xy 39.893351 -307.06299)
			(xy 39.928844 -307.097082) (xy 39.958409 -307.136426) (xy 39.98128 -307.180003) (xy 39.996864 -307.226684)
			(xy 40.004759 -307.275261) (xy 40.005254 -307.299868) (xy 41.294062 -307.299868) (xy 41.298022 -307.250814)
			(xy 41.309799 -307.20303) (xy 41.32909 -307.157754) (xy 41.355393 -307.116158) (xy 41.388028 -307.079321)
			(xy 41.426149 -307.048196) (xy 41.46877 -307.023589) (xy 41.514786 -307.006137) (xy 41.563005 -306.996293)
			(xy 41.61218 -306.994312) (xy 41.661035 -307.000244) (xy 41.708306 -307.013936) (xy 41.752768 -307.035034)
			(xy 41.793271 -307.06299) (xy 41.828764 -307.097082) (xy 41.858329 -307.136426) (xy 41.8812 -307.180003)
			(xy 41.896784 -307.226684) (xy 41.904679 -307.275261) (xy 41.905174 -307.299868) (xy 42.244022 -307.299868)
			(xy 42.247982 -307.250814) (xy 42.259759 -307.20303) (xy 42.27905 -307.157754) (xy 42.305353 -307.116158)
			(xy 42.337988 -307.079321) (xy 42.376109 -307.048196) (xy 42.41873 -307.023589) (xy 42.464746 -307.006137)
			(xy 42.512965 -306.996293) (xy 42.56214 -306.994312) (xy 42.610995 -307.000244) (xy 42.658266 -307.013936)
			(xy 42.702728 -307.035034) (xy 42.743231 -307.06299) (xy 42.778724 -307.097082) (xy 42.808289 -307.136426)
			(xy 42.83116 -307.180003) (xy 42.846744 -307.226684) (xy 42.854639 -307.275261) (xy 42.855134 -307.299868)
			(xy 76.444106 -307.299868) (xy 76.448066 -307.250814) (xy 76.459843 -307.20303) (xy 76.479134 -307.157754)
			(xy 76.505437 -307.116158) (xy 76.538072 -307.079321) (xy 76.576193 -307.048196) (xy 76.618814 -307.023589)
			(xy 76.66483 -307.006137) (xy 76.713049 -306.996293) (xy 76.762224 -306.994312) (xy 76.811079 -307.000244)
			(xy 76.85835 -307.013936) (xy 76.902812 -307.035034) (xy 76.943315 -307.06299) (xy 76.978808 -307.097082)
			(xy 77.008373 -307.136426) (xy 77.031244 -307.180003) (xy 77.046828 -307.226684) (xy 77.054723 -307.275261)
			(xy 77.055218 -307.299868) (xy 77.394066 -307.299868) (xy 77.398026 -307.250814) (xy 77.409803 -307.20303)
			(xy 77.429094 -307.157754) (xy 77.455397 -307.116158) (xy 77.488032 -307.079321) (xy 77.526153 -307.048196)
			(xy 77.568774 -307.023589) (xy 77.61479 -307.006137) (xy 77.663009 -306.996293) (xy 77.712184 -306.994312)
			(xy 77.761039 -307.000244) (xy 77.80831 -307.013936) (xy 77.852772 -307.035034) (xy 77.893275 -307.06299)
			(xy 77.928768 -307.097082) (xy 77.958333 -307.136426) (xy 77.981204 -307.180003) (xy 77.996788 -307.226684)
			(xy 78.004683 -307.275261) (xy 78.005178 -307.299868) (xy 79.293986 -307.299868) (xy 79.297946 -307.250814)
			(xy 79.309723 -307.20303) (xy 79.329014 -307.157754) (xy 79.355317 -307.116158) (xy 79.387952 -307.079321)
			(xy 79.426073 -307.048196) (xy 79.468694 -307.023589) (xy 79.51471 -307.006137) (xy 79.562929 -306.996293)
			(xy 79.612104 -306.994312) (xy 79.660959 -307.000244) (xy 79.70823 -307.013936) (xy 79.752692 -307.035034)
			(xy 79.793195 -307.06299) (xy 79.828688 -307.097082) (xy 79.858253 -307.136426) (xy 79.881124 -307.180003)
			(xy 79.896708 -307.226684) (xy 79.904603 -307.275261) (xy 79.905098 -307.299868) (xy 80.243946 -307.299868)
			(xy 80.247906 -307.250814) (xy 80.259683 -307.20303) (xy 80.278974 -307.157754) (xy 80.305277 -307.116158)
			(xy 80.337912 -307.079321) (xy 80.376033 -307.048196) (xy 80.418654 -307.023589) (xy 80.46467 -307.006137)
			(xy 80.512889 -306.996293) (xy 80.562064 -306.994312) (xy 80.610919 -307.000244) (xy 80.65819 -307.013936)
			(xy 80.702652 -307.035034) (xy 80.743155 -307.06299) (xy 80.778648 -307.097082) (xy 80.808213 -307.136426)
			(xy 80.831084 -307.180003) (xy 80.846668 -307.226684) (xy 80.854563 -307.275261) (xy 80.855058 -307.299868)
			(xy 154.54428 -307.299868) (xy 154.54824 -307.250814) (xy 154.560017 -307.20303) (xy 154.579308 -307.157754)
			(xy 154.605611 -307.116158) (xy 154.638246 -307.079321) (xy 154.676367 -307.048196) (xy 154.718988 -307.023589)
			(xy 154.765004 -307.006137) (xy 154.813223 -306.996293) (xy 154.862398 -306.994312) (xy 154.911253 -307.000244)
			(xy 154.958524 -307.013936) (xy 155.002986 -307.035034) (xy 155.043489 -307.06299) (xy 155.078982 -307.097082)
			(xy 155.108547 -307.136426) (xy 155.131418 -307.180003) (xy 155.147002 -307.226684) (xy 155.154897 -307.275261)
			(xy 155.155392 -307.299868) (xy 155.49424 -307.299868) (xy 155.4982 -307.250814) (xy 155.509977 -307.20303)
			(xy 155.529268 -307.157754) (xy 155.555571 -307.116158) (xy 155.588206 -307.079321) (xy 155.626327 -307.048196)
			(xy 155.668948 -307.023589) (xy 155.714964 -307.006137) (xy 155.763183 -306.996293) (xy 155.812358 -306.994312)
			(xy 155.861213 -307.000244) (xy 155.908484 -307.013936) (xy 155.952946 -307.035034) (xy 155.993449 -307.06299)
			(xy 156.028942 -307.097082) (xy 156.058507 -307.136426) (xy 156.081378 -307.180003) (xy 156.096962 -307.226684)
			(xy 156.104857 -307.275261) (xy 156.105352 -307.299868) (xy 157.39416 -307.299868) (xy 157.39812 -307.250814)
			(xy 157.409897 -307.20303) (xy 157.429188 -307.157754) (xy 157.455491 -307.116158) (xy 157.488126 -307.079321)
			(xy 157.526247 -307.048196) (xy 157.568868 -307.023589) (xy 157.614884 -307.006137) (xy 157.663103 -306.996293)
			(xy 157.712278 -306.994312) (xy 157.761133 -307.000244) (xy 157.808404 -307.013936) (xy 157.852866 -307.035034)
			(xy 157.893369 -307.06299) (xy 157.928862 -307.097082) (xy 157.958427 -307.136426) (xy 157.981298 -307.180003)
			(xy 157.996882 -307.226684) (xy 158.004777 -307.275261) (xy 158.005272 -307.299868) (xy 158.34412 -307.299868)
			(xy 158.34808 -307.250814) (xy 158.359857 -307.20303) (xy 158.379148 -307.157754) (xy 158.405451 -307.116158)
			(xy 158.438086 -307.079321) (xy 158.476207 -307.048196) (xy 158.518828 -307.023589) (xy 158.564844 -307.006137)
			(xy 158.613063 -306.996293) (xy 158.662238 -306.994312) (xy 158.711093 -307.000244) (xy 158.758364 -307.013936)
			(xy 158.802826 -307.035034) (xy 158.843329 -307.06299) (xy 158.878822 -307.097082) (xy 158.908387 -307.136426)
			(xy 158.931258 -307.180003) (xy 158.946842 -307.226684) (xy 158.954737 -307.275261) (xy 158.955232 -307.299868)
			(xy 192.544204 -307.299868) (xy 192.548164 -307.250814) (xy 192.559941 -307.20303) (xy 192.579232 -307.157754)
			(xy 192.605535 -307.116158) (xy 192.63817 -307.079321) (xy 192.676291 -307.048196) (xy 192.718912 -307.023589)
			(xy 192.764928 -307.006137) (xy 192.813147 -306.996293) (xy 192.862322 -306.994312) (xy 192.911177 -307.000244)
			(xy 192.958448 -307.013936) (xy 193.00291 -307.035034) (xy 193.043413 -307.06299) (xy 193.078906 -307.097082)
			(xy 193.108471 -307.136426) (xy 193.131342 -307.180003) (xy 193.146926 -307.226684) (xy 193.154821 -307.275261)
			(xy 193.155316 -307.299868) (xy 193.494164 -307.299868) (xy 193.498124 -307.250814) (xy 193.509901 -307.20303)
			(xy 193.529192 -307.157754) (xy 193.555495 -307.116158) (xy 193.58813 -307.079321) (xy 193.626251 -307.048196)
			(xy 193.668872 -307.023589) (xy 193.714888 -307.006137) (xy 193.763107 -306.996293) (xy 193.812282 -306.994312)
			(xy 193.861137 -307.000244) (xy 193.908408 -307.013936) (xy 193.95287 -307.035034) (xy 193.993373 -307.06299)
			(xy 194.028866 -307.097082) (xy 194.058431 -307.136426) (xy 194.081302 -307.180003) (xy 194.096886 -307.226684)
			(xy 194.104781 -307.275261) (xy 194.105276 -307.299868) (xy 195.394084 -307.299868) (xy 195.398044 -307.250814)
			(xy 195.409821 -307.20303) (xy 195.429112 -307.157754) (xy 195.455415 -307.116158) (xy 195.48805 -307.079321)
			(xy 195.526171 -307.048196) (xy 195.568792 -307.023589) (xy 195.614808 -307.006137) (xy 195.663027 -306.996293)
			(xy 195.712202 -306.994312) (xy 195.761057 -307.000244) (xy 195.808328 -307.013936) (xy 195.85279 -307.035034)
			(xy 195.893293 -307.06299) (xy 195.928786 -307.097082) (xy 195.958351 -307.136426) (xy 195.981222 -307.180003)
			(xy 195.996806 -307.226684) (xy 196.004701 -307.275261) (xy 196.005196 -307.299868) (xy 196.344044 -307.299868)
			(xy 196.348004 -307.250814) (xy 196.359781 -307.20303) (xy 196.379072 -307.157754) (xy 196.405375 -307.116158)
			(xy 196.43801 -307.079321) (xy 196.476131 -307.048196) (xy 196.518752 -307.023589) (xy 196.564768 -307.006137)
			(xy 196.612987 -306.996293) (xy 196.662162 -306.994312) (xy 196.711017 -307.000244) (xy 196.758288 -307.013936)
			(xy 196.80275 -307.035034) (xy 196.843253 -307.06299) (xy 196.878746 -307.097082) (xy 196.908311 -307.136426)
			(xy 196.931182 -307.180003) (xy 196.946766 -307.226684) (xy 196.954661 -307.275261) (xy 196.955156 -307.299868)
			(xy 196.954661 -307.324475) (xy 196.946766 -307.373052) (xy 196.931182 -307.419733) (xy 196.908311 -307.46331)
			(xy 196.892559 -307.484272) (xy 231.935526 -307.484272) (xy 231.939599 -307.428613) (xy 231.951734 -307.37414)
			(xy 231.97167 -307.322014) (xy 231.998984 -307.273346) (xy 232.033092 -307.229174) (xy 232.073269 -307.190439)
			(xy 232.118657 -307.157967) (xy 232.168289 -307.132449) (xy 232.221109 -307.11443) (xy 232.275988 -307.104293)
			(xy 232.331759 -307.102255) (xy 232.387233 -307.108358) (xy 232.441226 -307.122474) (xy 232.492589 -307.144301)
			(xy 232.540227 -307.173374) (xy 232.583123 -307.209073) (xy 232.620365 -307.250637) (xy 232.651159 -307.297181)
			(xy 232.674847 -307.347712) (xy 232.690925 -307.401154) (xy 232.699051 -307.456368) (xy 232.69956 -307.484272)
			(xy 248.185684 -307.484272) (xy 248.189757 -307.428613) (xy 248.201892 -307.37414) (xy 248.221828 -307.322014)
			(xy 248.249142 -307.273346) (xy 248.28325 -307.229174) (xy 248.323427 -307.190439) (xy 248.368815 -307.157967)
			(xy 248.418447 -307.132449) (xy 248.471267 -307.11443) (xy 248.526146 -307.104293) (xy 248.581917 -307.102255)
			(xy 248.637391 -307.108358) (xy 248.691384 -307.122474) (xy 248.742747 -307.144301) (xy 248.790385 -307.173374)
			(xy 248.833281 -307.209073) (xy 248.870523 -307.250637) (xy 248.901317 -307.297181) (xy 248.902577 -307.299868)
			(xy 270.644124 -307.299868) (xy 270.648084 -307.250814) (xy 270.659861 -307.20303) (xy 270.679152 -307.157754)
			(xy 270.705455 -307.116158) (xy 270.73809 -307.079321) (xy 270.776211 -307.048196) (xy 270.818832 -307.023589)
			(xy 270.864848 -307.006137) (xy 270.913067 -306.996293) (xy 270.962242 -306.994312) (xy 271.011097 -307.000244)
			(xy 271.058368 -307.013936) (xy 271.10283 -307.035034) (xy 271.143333 -307.06299) (xy 271.178826 -307.097082)
			(xy 271.208391 -307.136426) (xy 271.231262 -307.180003) (xy 271.246846 -307.226684) (xy 271.254741 -307.275261)
			(xy 271.255236 -307.299868) (xy 271.594084 -307.299868) (xy 271.598044 -307.250814) (xy 271.609821 -307.20303)
			(xy 271.629112 -307.157754) (xy 271.655415 -307.116158) (xy 271.68805 -307.079321) (xy 271.726171 -307.048196)
			(xy 271.768792 -307.023589) (xy 271.814808 -307.006137) (xy 271.863027 -306.996293) (xy 271.912202 -306.994312)
			(xy 271.961057 -307.000244) (xy 272.008328 -307.013936) (xy 272.05279 -307.035034) (xy 272.093293 -307.06299)
			(xy 272.128786 -307.097082) (xy 272.158351 -307.136426) (xy 272.181222 -307.180003) (xy 272.196806 -307.226684)
			(xy 272.204701 -307.275261) (xy 272.205196 -307.299868) (xy 273.494004 -307.299868) (xy 273.497964 -307.250814)
			(xy 273.509741 -307.20303) (xy 273.529032 -307.157754) (xy 273.555335 -307.116158) (xy 273.58797 -307.079321)
			(xy 273.626091 -307.048196) (xy 273.668712 -307.023589) (xy 273.714728 -307.006137) (xy 273.762947 -306.996293)
			(xy 273.812122 -306.994312) (xy 273.860977 -307.000244) (xy 273.908248 -307.013936) (xy 273.95271 -307.035034)
			(xy 273.993213 -307.06299) (xy 274.028706 -307.097082) (xy 274.058271 -307.136426) (xy 274.081142 -307.180003)
			(xy 274.096726 -307.226684) (xy 274.104621 -307.275261) (xy 274.105116 -307.299868) (xy 274.443964 -307.299868)
			(xy 274.447924 -307.250814) (xy 274.459701 -307.20303) (xy 274.478992 -307.157754) (xy 274.505295 -307.116158)
			(xy 274.53793 -307.079321) (xy 274.576051 -307.048196) (xy 274.618672 -307.023589) (xy 274.664688 -307.006137)
			(xy 274.712907 -306.996293) (xy 274.762082 -306.994312) (xy 274.810937 -307.000244) (xy 274.858208 -307.013936)
			(xy 274.90267 -307.035034) (xy 274.943173 -307.06299) (xy 274.978666 -307.097082) (xy 275.008231 -307.136426)
			(xy 275.031102 -307.180003) (xy 275.046686 -307.226684) (xy 275.054581 -307.275261) (xy 275.055076 -307.299868)
			(xy 308.644048 -307.299868) (xy 308.648008 -307.250814) (xy 308.659785 -307.20303) (xy 308.679076 -307.157754)
			(xy 308.705379 -307.116158) (xy 308.738014 -307.079321) (xy 308.776135 -307.048196) (xy 308.818756 -307.023589)
			(xy 308.864772 -307.006137) (xy 308.912991 -306.996293) (xy 308.962166 -306.994312) (xy 309.011021 -307.000244)
			(xy 309.058292 -307.013936) (xy 309.102754 -307.035034) (xy 309.143257 -307.06299) (xy 309.17875 -307.097082)
			(xy 309.208315 -307.136426) (xy 309.231186 -307.180003) (xy 309.24677 -307.226684) (xy 309.254665 -307.275261)
			(xy 309.25516 -307.299868) (xy 309.594008 -307.299868) (xy 309.597968 -307.250814) (xy 309.609745 -307.20303)
			(xy 309.629036 -307.157754) (xy 309.655339 -307.116158) (xy 309.687974 -307.079321) (xy 309.726095 -307.048196)
			(xy 309.768716 -307.023589) (xy 309.814732 -307.006137) (xy 309.862951 -306.996293) (xy 309.912126 -306.994312)
			(xy 309.960981 -307.000244) (xy 310.008252 -307.013936) (xy 310.052714 -307.035034) (xy 310.093217 -307.06299)
			(xy 310.12871 -307.097082) (xy 310.158275 -307.136426) (xy 310.181146 -307.180003) (xy 310.19673 -307.226684)
			(xy 310.204625 -307.275261) (xy 310.20512 -307.299868) (xy 311.493928 -307.299868) (xy 311.497888 -307.250814)
			(xy 311.509665 -307.20303) (xy 311.528956 -307.157754) (xy 311.555259 -307.116158) (xy 311.587894 -307.079321)
			(xy 311.626015 -307.048196) (xy 311.668636 -307.023589) (xy 311.714652 -307.006137) (xy 311.762871 -306.996293)
			(xy 311.812046 -306.994312) (xy 311.860901 -307.000244) (xy 311.908172 -307.013936) (xy 311.952634 -307.035034)
			(xy 311.993137 -307.06299) (xy 312.02863 -307.097082) (xy 312.058195 -307.136426) (xy 312.081066 -307.180003)
			(xy 312.09665 -307.226684) (xy 312.104545 -307.275261) (xy 312.10504 -307.299868) (xy 312.443888 -307.299868)
			(xy 312.447848 -307.250814) (xy 312.459625 -307.20303) (xy 312.478916 -307.157754) (xy 312.505219 -307.116158)
			(xy 312.537854 -307.079321) (xy 312.575975 -307.048196) (xy 312.618596 -307.023589) (xy 312.664612 -307.006137)
			(xy 312.712831 -306.996293) (xy 312.762006 -306.994312) (xy 312.810861 -307.000244) (xy 312.858132 -307.013936)
			(xy 312.902594 -307.035034) (xy 312.943097 -307.06299) (xy 312.97859 -307.097082) (xy 313.008155 -307.136426)
			(xy 313.031026 -307.180003) (xy 313.04661 -307.226684) (xy 313.054505 -307.275261) (xy 313.055 -307.299868)
			(xy 386.744222 -307.299868) (xy 386.748182 -307.250814) (xy 386.759959 -307.20303) (xy 386.77925 -307.157754)
			(xy 386.805553 -307.116158) (xy 386.838188 -307.079321) (xy 386.876309 -307.048196) (xy 386.91893 -307.023589)
			(xy 386.964946 -307.006137) (xy 387.013165 -306.996293) (xy 387.06234 -306.994312) (xy 387.111195 -307.000244)
			(xy 387.158466 -307.013936) (xy 387.202928 -307.035034) (xy 387.243431 -307.06299) (xy 387.278924 -307.097082)
			(xy 387.308489 -307.136426) (xy 387.33136 -307.180003) (xy 387.346944 -307.226684) (xy 387.354839 -307.275261)
			(xy 387.355334 -307.299868) (xy 387.694182 -307.299868) (xy 387.698142 -307.250814) (xy 387.709919 -307.20303)
			(xy 387.72921 -307.157754) (xy 387.755513 -307.116158) (xy 387.788148 -307.079321) (xy 387.826269 -307.048196)
			(xy 387.86889 -307.023589) (xy 387.914906 -307.006137) (xy 387.963125 -306.996293) (xy 388.0123 -306.994312)
			(xy 388.061155 -307.000244) (xy 388.108426 -307.013936) (xy 388.152888 -307.035034) (xy 388.193391 -307.06299)
			(xy 388.228884 -307.097082) (xy 388.258449 -307.136426) (xy 388.28132 -307.180003) (xy 388.296904 -307.226684)
			(xy 388.304799 -307.275261) (xy 388.305294 -307.299868) (xy 389.594102 -307.299868) (xy 389.598062 -307.250814)
			(xy 389.609839 -307.20303) (xy 389.62913 -307.157754) (xy 389.655433 -307.116158) (xy 389.688068 -307.079321)
			(xy 389.726189 -307.048196) (xy 389.76881 -307.023589) (xy 389.814826 -307.006137) (xy 389.863045 -306.996293)
			(xy 389.91222 -306.994312) (xy 389.961075 -307.000244) (xy 390.008346 -307.013936) (xy 390.052808 -307.035034)
			(xy 390.093311 -307.06299) (xy 390.128804 -307.097082) (xy 390.158369 -307.136426) (xy 390.18124 -307.180003)
			(xy 390.196824 -307.226684) (xy 390.204719 -307.275261) (xy 390.205214 -307.299868) (xy 390.544062 -307.299868)
			(xy 390.548022 -307.250814) (xy 390.559799 -307.20303) (xy 390.57909 -307.157754) (xy 390.605393 -307.116158)
			(xy 390.638028 -307.079321) (xy 390.676149 -307.048196) (xy 390.71877 -307.023589) (xy 390.764786 -307.006137)
			(xy 390.813005 -306.996293) (xy 390.86218 -306.994312) (xy 390.911035 -307.000244) (xy 390.958306 -307.013936)
			(xy 391.002768 -307.035034) (xy 391.043271 -307.06299) (xy 391.078764 -307.097082) (xy 391.108329 -307.136426)
			(xy 391.1312 -307.180003) (xy 391.146784 -307.226684) (xy 391.154679 -307.275261) (xy 391.155174 -307.299868)
			(xy 424.744146 -307.299868) (xy 424.748106 -307.250814) (xy 424.759883 -307.20303) (xy 424.779174 -307.157754)
			(xy 424.805477 -307.116158) (xy 424.838112 -307.079321) (xy 424.876233 -307.048196) (xy 424.918854 -307.023589)
			(xy 424.96487 -307.006137) (xy 425.013089 -306.996293) (xy 425.062264 -306.994312) (xy 425.111119 -307.000244)
			(xy 425.15839 -307.013936) (xy 425.202852 -307.035034) (xy 425.243355 -307.06299) (xy 425.278848 -307.097082)
			(xy 425.308413 -307.136426) (xy 425.331284 -307.180003) (xy 425.346868 -307.226684) (xy 425.354763 -307.275261)
			(xy 425.355258 -307.299868) (xy 425.694106 -307.299868) (xy 425.698066 -307.250814) (xy 425.709843 -307.20303)
			(xy 425.729134 -307.157754) (xy 425.755437 -307.116158) (xy 425.788072 -307.079321) (xy 425.826193 -307.048196)
			(xy 425.868814 -307.023589) (xy 425.91483 -307.006137) (xy 425.963049 -306.996293) (xy 426.012224 -306.994312)
			(xy 426.061079 -307.000244) (xy 426.10835 -307.013936) (xy 426.152812 -307.035034) (xy 426.193315 -307.06299)
			(xy 426.228808 -307.097082) (xy 426.258373 -307.136426) (xy 426.281244 -307.180003) (xy 426.296828 -307.226684)
			(xy 426.304723 -307.275261) (xy 426.305218 -307.299868) (xy 427.594026 -307.299868) (xy 427.597986 -307.250814)
			(xy 427.609763 -307.20303) (xy 427.629054 -307.157754) (xy 427.655357 -307.116158) (xy 427.687992 -307.079321)
			(xy 427.726113 -307.048196) (xy 427.768734 -307.023589) (xy 427.81475 -307.006137) (xy 427.862969 -306.996293)
			(xy 427.912144 -306.994312) (xy 427.960999 -307.000244) (xy 428.00827 -307.013936) (xy 428.052732 -307.035034)
			(xy 428.093235 -307.06299) (xy 428.128728 -307.097082) (xy 428.158293 -307.136426) (xy 428.181164 -307.180003)
			(xy 428.196748 -307.226684) (xy 428.204643 -307.275261) (xy 428.205138 -307.299868) (xy 428.543986 -307.299868)
			(xy 428.547946 -307.250814) (xy 428.559723 -307.20303) (xy 428.579014 -307.157754) (xy 428.605317 -307.116158)
			(xy 428.637952 -307.079321) (xy 428.676073 -307.048196) (xy 428.718694 -307.023589) (xy 428.76471 -307.006137)
			(xy 428.812929 -306.996293) (xy 428.862104 -306.994312) (xy 428.910959 -307.000244) (xy 428.95823 -307.013936)
			(xy 429.002692 -307.035034) (xy 429.043195 -307.06299) (xy 429.078688 -307.097082) (xy 429.108253 -307.136426)
			(xy 429.131124 -307.180003) (xy 429.146708 -307.226684) (xy 429.154603 -307.275261) (xy 429.155098 -307.299868)
			(xy 429.154603 -307.324475) (xy 429.146708 -307.373052) (xy 429.131124 -307.419733) (xy 429.108253 -307.46331)
			(xy 429.078688 -307.502654) (xy 429.043195 -307.536746) (xy 429.002692 -307.564702) (xy 428.95823 -307.5858)
			(xy 428.910959 -307.599492) (xy 428.862104 -307.605424) (xy 428.812929 -307.603443) (xy 428.76471 -307.593599)
			(xy 428.718694 -307.576147) (xy 428.676073 -307.55154) (xy 428.637952 -307.520415) (xy 428.605317 -307.483578)
			(xy 428.579014 -307.441982) (xy 428.559723 -307.396706) (xy 428.547946 -307.348922) (xy 428.543986 -307.299868)
			(xy 428.205138 -307.299868) (xy 428.204643 -307.324475) (xy 428.196748 -307.373052) (xy 428.181164 -307.419733)
			(xy 428.158293 -307.46331) (xy 428.128728 -307.502654) (xy 428.093235 -307.536746) (xy 428.052732 -307.564702)
			(xy 428.00827 -307.5858) (xy 427.960999 -307.599492) (xy 427.912144 -307.605424) (xy 427.862969 -307.603443)
			(xy 427.81475 -307.593599) (xy 427.768734 -307.576147) (xy 427.726113 -307.55154) (xy 427.687992 -307.520415)
			(xy 427.655357 -307.483578) (xy 427.629054 -307.441982) (xy 427.609763 -307.396706) (xy 427.597986 -307.348922)
			(xy 427.594026 -307.299868) (xy 426.305218 -307.299868) (xy 426.304723 -307.324475) (xy 426.296828 -307.373052)
			(xy 426.281244 -307.419733) (xy 426.258373 -307.46331) (xy 426.228808 -307.502654) (xy 426.193315 -307.536746)
			(xy 426.152812 -307.564702) (xy 426.10835 -307.5858) (xy 426.061079 -307.599492) (xy 426.012224 -307.605424)
			(xy 425.963049 -307.603443) (xy 425.91483 -307.593599) (xy 425.868814 -307.576147) (xy 425.826193 -307.55154)
			(xy 425.788072 -307.520415) (xy 425.755437 -307.483578) (xy 425.729134 -307.441982) (xy 425.709843 -307.396706)
			(xy 425.698066 -307.348922) (xy 425.694106 -307.299868) (xy 425.355258 -307.299868) (xy 425.354763 -307.324475)
			(xy 425.346868 -307.373052) (xy 425.331284 -307.419733) (xy 425.308413 -307.46331) (xy 425.278848 -307.502654)
			(xy 425.243355 -307.536746) (xy 425.202852 -307.564702) (xy 425.15839 -307.5858) (xy 425.111119 -307.599492)
			(xy 425.062264 -307.605424) (xy 425.013089 -307.603443) (xy 424.96487 -307.593599) (xy 424.918854 -307.576147)
			(xy 424.876233 -307.55154) (xy 424.838112 -307.520415) (xy 424.805477 -307.483578) (xy 424.779174 -307.441982)
			(xy 424.759883 -307.396706) (xy 424.748106 -307.348922) (xy 424.744146 -307.299868) (xy 391.155174 -307.299868)
			(xy 391.154679 -307.324475) (xy 391.146784 -307.373052) (xy 391.1312 -307.419733) (xy 391.108329 -307.46331)
			(xy 391.078764 -307.502654) (xy 391.043271 -307.536746) (xy 391.002768 -307.564702) (xy 390.958306 -307.5858)
			(xy 390.911035 -307.599492) (xy 390.86218 -307.605424) (xy 390.813005 -307.603443) (xy 390.764786 -307.593599)
			(xy 390.71877 -307.576147) (xy 390.676149 -307.55154) (xy 390.638028 -307.520415) (xy 390.605393 -307.483578)
			(xy 390.57909 -307.441982) (xy 390.559799 -307.396706) (xy 390.548022 -307.348922) (xy 390.544062 -307.299868)
			(xy 390.205214 -307.299868) (xy 390.204719 -307.324475) (xy 390.196824 -307.373052) (xy 390.18124 -307.419733)
			(xy 390.158369 -307.46331) (xy 390.128804 -307.502654) (xy 390.093311 -307.536746) (xy 390.052808 -307.564702)
			(xy 390.008346 -307.5858) (xy 389.961075 -307.599492) (xy 389.91222 -307.605424) (xy 389.863045 -307.603443)
			(xy 389.814826 -307.593599) (xy 389.76881 -307.576147) (xy 389.726189 -307.55154) (xy 389.688068 -307.520415)
			(xy 389.655433 -307.483578) (xy 389.62913 -307.441982) (xy 389.609839 -307.396706) (xy 389.598062 -307.348922)
			(xy 389.594102 -307.299868) (xy 388.305294 -307.299868) (xy 388.304799 -307.324475) (xy 388.296904 -307.373052)
			(xy 388.28132 -307.419733) (xy 388.258449 -307.46331) (xy 388.228884 -307.502654) (xy 388.193391 -307.536746)
			(xy 388.152888 -307.564702) (xy 388.108426 -307.5858) (xy 388.061155 -307.599492) (xy 388.0123 -307.605424)
			(xy 387.963125 -307.603443) (xy 387.914906 -307.593599) (xy 387.86889 -307.576147) (xy 387.826269 -307.55154)
			(xy 387.788148 -307.520415) (xy 387.755513 -307.483578) (xy 387.72921 -307.441982) (xy 387.709919 -307.396706)
			(xy 387.698142 -307.348922) (xy 387.694182 -307.299868) (xy 387.355334 -307.299868) (xy 387.354839 -307.324475)
			(xy 387.346944 -307.373052) (xy 387.33136 -307.419733) (xy 387.308489 -307.46331) (xy 387.278924 -307.502654)
			(xy 387.243431 -307.536746) (xy 387.202928 -307.564702) (xy 387.158466 -307.5858) (xy 387.111195 -307.599492)
			(xy 387.06234 -307.605424) (xy 387.013165 -307.603443) (xy 386.964946 -307.593599) (xy 386.91893 -307.576147)
			(xy 386.876309 -307.55154) (xy 386.838188 -307.520415) (xy 386.805553 -307.483578) (xy 386.77925 -307.441982)
			(xy 386.759959 -307.396706) (xy 386.748182 -307.348922) (xy 386.744222 -307.299868) (xy 313.055 -307.299868)
			(xy 313.054505 -307.324475) (xy 313.04661 -307.373052) (xy 313.031026 -307.419733) (xy 313.008155 -307.46331)
			(xy 312.97859 -307.502654) (xy 312.943097 -307.536746) (xy 312.902594 -307.564702) (xy 312.858132 -307.5858)
			(xy 312.810861 -307.599492) (xy 312.762006 -307.605424) (xy 312.712831 -307.603443) (xy 312.664612 -307.593599)
			(xy 312.618596 -307.576147) (xy 312.575975 -307.55154) (xy 312.537854 -307.520415) (xy 312.505219 -307.483578)
			(xy 312.478916 -307.441982) (xy 312.459625 -307.396706) (xy 312.447848 -307.348922) (xy 312.443888 -307.299868)
			(xy 312.10504 -307.299868) (xy 312.104545 -307.324475) (xy 312.09665 -307.373052) (xy 312.081066 -307.419733)
			(xy 312.058195 -307.46331) (xy 312.02863 -307.502654) (xy 311.993137 -307.536746) (xy 311.952634 -307.564702)
			(xy 311.908172 -307.5858) (xy 311.860901 -307.599492) (xy 311.812046 -307.605424) (xy 311.762871 -307.603443)
			(xy 311.714652 -307.593599) (xy 311.668636 -307.576147) (xy 311.626015 -307.55154) (xy 311.587894 -307.520415)
			(xy 311.555259 -307.483578) (xy 311.528956 -307.441982) (xy 311.509665 -307.396706) (xy 311.497888 -307.348922)
			(xy 311.493928 -307.299868) (xy 310.20512 -307.299868) (xy 310.204625 -307.324475) (xy 310.19673 -307.373052)
			(xy 310.181146 -307.419733) (xy 310.158275 -307.46331) (xy 310.12871 -307.502654) (xy 310.093217 -307.536746)
			(xy 310.052714 -307.564702) (xy 310.008252 -307.5858) (xy 309.960981 -307.599492) (xy 309.912126 -307.605424)
			(xy 309.862951 -307.603443) (xy 309.814732 -307.593599) (xy 309.768716 -307.576147) (xy 309.726095 -307.55154)
			(xy 309.687974 -307.520415) (xy 309.655339 -307.483578) (xy 309.629036 -307.441982) (xy 309.609745 -307.396706)
			(xy 309.597968 -307.348922) (xy 309.594008 -307.299868) (xy 309.25516 -307.299868) (xy 309.254665 -307.324475)
			(xy 309.24677 -307.373052) (xy 309.231186 -307.419733) (xy 309.208315 -307.46331) (xy 309.17875 -307.502654)
			(xy 309.143257 -307.536746) (xy 309.102754 -307.564702) (xy 309.058292 -307.5858) (xy 309.011021 -307.599492)
			(xy 308.962166 -307.605424) (xy 308.912991 -307.603443) (xy 308.864772 -307.593599) (xy 308.818756 -307.576147)
			(xy 308.776135 -307.55154) (xy 308.738014 -307.520415) (xy 308.705379 -307.483578) (xy 308.679076 -307.441982)
			(xy 308.659785 -307.396706) (xy 308.648008 -307.348922) (xy 308.644048 -307.299868) (xy 275.055076 -307.299868)
			(xy 275.054581 -307.324475) (xy 275.046686 -307.373052) (xy 275.031102 -307.419733) (xy 275.008231 -307.46331)
			(xy 274.978666 -307.502654) (xy 274.943173 -307.536746) (xy 274.90267 -307.564702) (xy 274.858208 -307.5858)
			(xy 274.810937 -307.599492) (xy 274.762082 -307.605424) (xy 274.712907 -307.603443) (xy 274.664688 -307.593599)
			(xy 274.618672 -307.576147) (xy 274.576051 -307.55154) (xy 274.53793 -307.520415) (xy 274.505295 -307.483578)
			(xy 274.478992 -307.441982) (xy 274.459701 -307.396706) (xy 274.447924 -307.348922) (xy 274.443964 -307.299868)
			(xy 274.105116 -307.299868) (xy 274.104621 -307.324475) (xy 274.096726 -307.373052) (xy 274.081142 -307.419733)
			(xy 274.058271 -307.46331) (xy 274.028706 -307.502654) (xy 273.993213 -307.536746) (xy 273.95271 -307.564702)
			(xy 273.908248 -307.5858) (xy 273.860977 -307.599492) (xy 273.812122 -307.605424) (xy 273.762947 -307.603443)
			(xy 273.714728 -307.593599) (xy 273.668712 -307.576147) (xy 273.626091 -307.55154) (xy 273.58797 -307.520415)
			(xy 273.555335 -307.483578) (xy 273.529032 -307.441982) (xy 273.509741 -307.396706) (xy 273.497964 -307.348922)
			(xy 273.494004 -307.299868) (xy 272.205196 -307.299868) (xy 272.204701 -307.324475) (xy 272.196806 -307.373052)
			(xy 272.181222 -307.419733) (xy 272.158351 -307.46331) (xy 272.128786 -307.502654) (xy 272.093293 -307.536746)
			(xy 272.05279 -307.564702) (xy 272.008328 -307.5858) (xy 271.961057 -307.599492) (xy 271.912202 -307.605424)
			(xy 271.863027 -307.603443) (xy 271.814808 -307.593599) (xy 271.768792 -307.576147) (xy 271.726171 -307.55154)
			(xy 271.68805 -307.520415) (xy 271.655415 -307.483578) (xy 271.629112 -307.441982) (xy 271.609821 -307.396706)
			(xy 271.598044 -307.348922) (xy 271.594084 -307.299868) (xy 271.255236 -307.299868) (xy 271.254741 -307.324475)
			(xy 271.246846 -307.373052) (xy 271.231262 -307.419733) (xy 271.208391 -307.46331) (xy 271.178826 -307.502654)
			(xy 271.143333 -307.536746) (xy 271.10283 -307.564702) (xy 271.058368 -307.5858) (xy 271.011097 -307.599492)
			(xy 270.962242 -307.605424) (xy 270.913067 -307.603443) (xy 270.864848 -307.593599) (xy 270.818832 -307.576147)
			(xy 270.776211 -307.55154) (xy 270.73809 -307.520415) (xy 270.705455 -307.483578) (xy 270.679152 -307.441982)
			(xy 270.659861 -307.396706) (xy 270.648084 -307.348922) (xy 270.644124 -307.299868) (xy 248.902577 -307.299868)
			(xy 248.925005 -307.347712) (xy 248.941083 -307.401154) (xy 248.949209 -307.456368) (xy 248.949718 -307.484272)
			(xy 248.949209 -307.512176) (xy 248.941083 -307.56739) (xy 248.928951 -307.607716) (xy 462.556604 -307.607716)
			(xy 462.560677 -307.552057) (xy 462.572812 -307.497584) (xy 462.592748 -307.445458) (xy 462.620062 -307.39679)
			(xy 462.65417 -307.352618) (xy 462.694347 -307.313883) (xy 462.739735 -307.281411) (xy 462.789367 -307.255893)
			(xy 462.842187 -307.237874) (xy 462.897066 -307.227737) (xy 462.952837 -307.225699) (xy 463.008311 -307.231802)
			(xy 463.062304 -307.245918) (xy 463.113667 -307.267745) (xy 463.161305 -307.296818) (xy 463.204201 -307.332517)
			(xy 463.241443 -307.374081) (xy 463.272237 -307.420625) (xy 463.295925 -307.471156) (xy 463.312003 -307.524598)
			(xy 463.320129 -307.579812) (xy 463.320638 -307.607716) (xy 463.320129 -307.63562) (xy 463.312003 -307.690834)
			(xy 463.295925 -307.744276) (xy 463.272237 -307.794807) (xy 463.241443 -307.841351) (xy 463.204201 -307.882915)
			(xy 463.161305 -307.918614) (xy 463.113667 -307.947687) (xy 463.062304 -307.969514) (xy 463.008311 -307.98363)
			(xy 462.952837 -307.989733) (xy 462.897066 -307.987695) (xy 462.842187 -307.977558) (xy 462.789367 -307.959539)
			(xy 462.739735 -307.934021) (xy 462.694347 -307.901549) (xy 462.65417 -307.862814) (xy 462.620062 -307.818642)
			(xy 462.592748 -307.769974) (xy 462.572812 -307.717848) (xy 462.560677 -307.663375) (xy 462.556604 -307.607716)
			(xy 248.928951 -307.607716) (xy 248.925005 -307.620832) (xy 248.901317 -307.671363) (xy 248.870523 -307.717907)
			(xy 248.833281 -307.759471) (xy 248.790385 -307.79517) (xy 248.742747 -307.824243) (xy 248.691384 -307.84607)
			(xy 248.637391 -307.860186) (xy 248.581917 -307.866289) (xy 248.526146 -307.864251) (xy 248.471267 -307.854114)
			(xy 248.418447 -307.836095) (xy 248.368815 -307.810577) (xy 248.323427 -307.778105) (xy 248.28325 -307.73937)
			(xy 248.249142 -307.695198) (xy 248.221828 -307.64653) (xy 248.201892 -307.594404) (xy 248.189757 -307.539931)
			(xy 248.185684 -307.484272) (xy 232.69956 -307.484272) (xy 232.699051 -307.512176) (xy 232.690925 -307.56739)
			(xy 232.674847 -307.620832) (xy 232.651159 -307.671363) (xy 232.620365 -307.717907) (xy 232.583123 -307.759471)
			(xy 232.540227 -307.79517) (xy 232.492589 -307.824243) (xy 232.441226 -307.84607) (xy 232.387233 -307.860186)
			(xy 232.331759 -307.866289) (xy 232.275988 -307.864251) (xy 232.221109 -307.854114) (xy 232.168289 -307.836095)
			(xy 232.118657 -307.810577) (xy 232.073269 -307.778105) (xy 232.033092 -307.73937) (xy 231.998984 -307.695198)
			(xy 231.97167 -307.64653) (xy 231.951734 -307.594404) (xy 231.939599 -307.539931) (xy 231.935526 -307.484272)
			(xy 196.892559 -307.484272) (xy 196.878746 -307.502654) (xy 196.843253 -307.536746) (xy 196.80275 -307.564702)
			(xy 196.758288 -307.5858) (xy 196.711017 -307.599492) (xy 196.662162 -307.605424) (xy 196.612987 -307.603443)
			(xy 196.564768 -307.593599) (xy 196.518752 -307.576147) (xy 196.476131 -307.55154) (xy 196.43801 -307.520415)
			(xy 196.405375 -307.483578) (xy 196.379072 -307.441982) (xy 196.359781 -307.396706) (xy 196.348004 -307.348922)
			(xy 196.344044 -307.299868) (xy 196.005196 -307.299868) (xy 196.004701 -307.324475) (xy 195.996806 -307.373052)
			(xy 195.981222 -307.419733) (xy 195.958351 -307.46331) (xy 195.928786 -307.502654) (xy 195.893293 -307.536746)
			(xy 195.85279 -307.564702) (xy 195.808328 -307.5858) (xy 195.761057 -307.599492) (xy 195.712202 -307.605424)
			(xy 195.663027 -307.603443) (xy 195.614808 -307.593599) (xy 195.568792 -307.576147) (xy 195.526171 -307.55154)
			(xy 195.48805 -307.520415) (xy 195.455415 -307.483578) (xy 195.429112 -307.441982) (xy 195.409821 -307.396706)
			(xy 195.398044 -307.348922) (xy 195.394084 -307.299868) (xy 194.105276 -307.299868) (xy 194.104781 -307.324475)
			(xy 194.096886 -307.373052) (xy 194.081302 -307.419733) (xy 194.058431 -307.46331) (xy 194.028866 -307.502654)
			(xy 193.993373 -307.536746) (xy 193.95287 -307.564702) (xy 193.908408 -307.5858) (xy 193.861137 -307.599492)
			(xy 193.812282 -307.605424) (xy 193.763107 -307.603443) (xy 193.714888 -307.593599) (xy 193.668872 -307.576147)
			(xy 193.626251 -307.55154) (xy 193.58813 -307.520415) (xy 193.555495 -307.483578) (xy 193.529192 -307.441982)
			(xy 193.509901 -307.396706) (xy 193.498124 -307.348922) (xy 193.494164 -307.299868) (xy 193.155316 -307.299868)
			(xy 193.154821 -307.324475) (xy 193.146926 -307.373052) (xy 193.131342 -307.419733) (xy 193.108471 -307.46331)
			(xy 193.078906 -307.502654) (xy 193.043413 -307.536746) (xy 193.00291 -307.564702) (xy 192.958448 -307.5858)
			(xy 192.911177 -307.599492) (xy 192.862322 -307.605424) (xy 192.813147 -307.603443) (xy 192.764928 -307.593599)
			(xy 192.718912 -307.576147) (xy 192.676291 -307.55154) (xy 192.63817 -307.520415) (xy 192.605535 -307.483578)
			(xy 192.579232 -307.441982) (xy 192.559941 -307.396706) (xy 192.548164 -307.348922) (xy 192.544204 -307.299868)
			(xy 158.955232 -307.299868) (xy 158.954737 -307.324475) (xy 158.946842 -307.373052) (xy 158.931258 -307.419733)
			(xy 158.908387 -307.46331) (xy 158.878822 -307.502654) (xy 158.843329 -307.536746) (xy 158.802826 -307.564702)
			(xy 158.758364 -307.5858) (xy 158.711093 -307.599492) (xy 158.662238 -307.605424) (xy 158.613063 -307.603443)
			(xy 158.564844 -307.593599) (xy 158.518828 -307.576147) (xy 158.476207 -307.55154) (xy 158.438086 -307.520415)
			(xy 158.405451 -307.483578) (xy 158.379148 -307.441982) (xy 158.359857 -307.396706) (xy 158.34808 -307.348922)
			(xy 158.34412 -307.299868) (xy 158.005272 -307.299868) (xy 158.004777 -307.324475) (xy 157.996882 -307.373052)
			(xy 157.981298 -307.419733) (xy 157.958427 -307.46331) (xy 157.928862 -307.502654) (xy 157.893369 -307.536746)
			(xy 157.852866 -307.564702) (xy 157.808404 -307.5858) (xy 157.761133 -307.599492) (xy 157.712278 -307.605424)
			(xy 157.663103 -307.603443) (xy 157.614884 -307.593599) (xy 157.568868 -307.576147) (xy 157.526247 -307.55154)
			(xy 157.488126 -307.520415) (xy 157.455491 -307.483578) (xy 157.429188 -307.441982) (xy 157.409897 -307.396706)
			(xy 157.39812 -307.348922) (xy 157.39416 -307.299868) (xy 156.105352 -307.299868) (xy 156.104857 -307.324475)
			(xy 156.096962 -307.373052) (xy 156.081378 -307.419733) (xy 156.058507 -307.46331) (xy 156.028942 -307.502654)
			(xy 155.993449 -307.536746) (xy 155.952946 -307.564702) (xy 155.908484 -307.5858) (xy 155.861213 -307.599492)
			(xy 155.812358 -307.605424) (xy 155.763183 -307.603443) (xy 155.714964 -307.593599) (xy 155.668948 -307.576147)
			(xy 155.626327 -307.55154) (xy 155.588206 -307.520415) (xy 155.555571 -307.483578) (xy 155.529268 -307.441982)
			(xy 155.509977 -307.396706) (xy 155.4982 -307.348922) (xy 155.49424 -307.299868) (xy 155.155392 -307.299868)
			(xy 155.154897 -307.324475) (xy 155.147002 -307.373052) (xy 155.131418 -307.419733) (xy 155.108547 -307.46331)
			(xy 155.078982 -307.502654) (xy 155.043489 -307.536746) (xy 155.002986 -307.564702) (xy 154.958524 -307.5858)
			(xy 154.911253 -307.599492) (xy 154.862398 -307.605424) (xy 154.813223 -307.603443) (xy 154.765004 -307.593599)
			(xy 154.718988 -307.576147) (xy 154.676367 -307.55154) (xy 154.638246 -307.520415) (xy 154.605611 -307.483578)
			(xy 154.579308 -307.441982) (xy 154.560017 -307.396706) (xy 154.54824 -307.348922) (xy 154.54428 -307.299868)
			(xy 80.855058 -307.299868) (xy 80.854563 -307.324475) (xy 80.846668 -307.373052) (xy 80.831084 -307.419733)
			(xy 80.808213 -307.46331) (xy 80.778648 -307.502654) (xy 80.743155 -307.536746) (xy 80.702652 -307.564702)
			(xy 80.65819 -307.5858) (xy 80.610919 -307.599492) (xy 80.562064 -307.605424) (xy 80.512889 -307.603443)
			(xy 80.46467 -307.593599) (xy 80.418654 -307.576147) (xy 80.376033 -307.55154) (xy 80.337912 -307.520415)
			(xy 80.305277 -307.483578) (xy 80.278974 -307.441982) (xy 80.259683 -307.396706) (xy 80.247906 -307.348922)
			(xy 80.243946 -307.299868) (xy 79.905098 -307.299868) (xy 79.904603 -307.324475) (xy 79.896708 -307.373052)
			(xy 79.881124 -307.419733) (xy 79.858253 -307.46331) (xy 79.828688 -307.502654) (xy 79.793195 -307.536746)
			(xy 79.752692 -307.564702) (xy 79.70823 -307.5858) (xy 79.660959 -307.599492) (xy 79.612104 -307.605424)
			(xy 79.562929 -307.603443) (xy 79.51471 -307.593599) (xy 79.468694 -307.576147) (xy 79.426073 -307.55154)
			(xy 79.387952 -307.520415) (xy 79.355317 -307.483578) (xy 79.329014 -307.441982) (xy 79.309723 -307.396706)
			(xy 79.297946 -307.348922) (xy 79.293986 -307.299868) (xy 78.005178 -307.299868) (xy 78.004683 -307.324475)
			(xy 77.996788 -307.373052) (xy 77.981204 -307.419733) (xy 77.958333 -307.46331) (xy 77.928768 -307.502654)
			(xy 77.893275 -307.536746) (xy 77.852772 -307.564702) (xy 77.80831 -307.5858) (xy 77.761039 -307.599492)
			(xy 77.712184 -307.605424) (xy 77.663009 -307.603443) (xy 77.61479 -307.593599) (xy 77.568774 -307.576147)
			(xy 77.526153 -307.55154) (xy 77.488032 -307.520415) (xy 77.455397 -307.483578) (xy 77.429094 -307.441982)
			(xy 77.409803 -307.396706) (xy 77.398026 -307.348922) (xy 77.394066 -307.299868) (xy 77.055218 -307.299868)
			(xy 77.054723 -307.324475) (xy 77.046828 -307.373052) (xy 77.031244 -307.419733) (xy 77.008373 -307.46331)
			(xy 76.978808 -307.502654) (xy 76.943315 -307.536746) (xy 76.902812 -307.564702) (xy 76.85835 -307.5858)
			(xy 76.811079 -307.599492) (xy 76.762224 -307.605424) (xy 76.713049 -307.603443) (xy 76.66483 -307.593599)
			(xy 76.618814 -307.576147) (xy 76.576193 -307.55154) (xy 76.538072 -307.520415) (xy 76.505437 -307.483578)
			(xy 76.479134 -307.441982) (xy 76.459843 -307.396706) (xy 76.448066 -307.348922) (xy 76.444106 -307.299868)
			(xy 42.855134 -307.299868) (xy 42.854639 -307.324475) (xy 42.846744 -307.373052) (xy 42.83116 -307.419733)
			(xy 42.808289 -307.46331) (xy 42.778724 -307.502654) (xy 42.743231 -307.536746) (xy 42.702728 -307.564702)
			(xy 42.658266 -307.5858) (xy 42.610995 -307.599492) (xy 42.56214 -307.605424) (xy 42.512965 -307.603443)
			(xy 42.464746 -307.593599) (xy 42.41873 -307.576147) (xy 42.376109 -307.55154) (xy 42.337988 -307.520415)
			(xy 42.305353 -307.483578) (xy 42.27905 -307.441982) (xy 42.259759 -307.396706) (xy 42.247982 -307.348922)
			(xy 42.244022 -307.299868) (xy 41.905174 -307.299868) (xy 41.904679 -307.324475) (xy 41.896784 -307.373052)
			(xy 41.8812 -307.419733) (xy 41.858329 -307.46331) (xy 41.828764 -307.502654) (xy 41.793271 -307.536746)
			(xy 41.752768 -307.564702) (xy 41.708306 -307.5858) (xy 41.661035 -307.599492) (xy 41.61218 -307.605424)
			(xy 41.563005 -307.603443) (xy 41.514786 -307.593599) (xy 41.46877 -307.576147) (xy 41.426149 -307.55154)
			(xy 41.388028 -307.520415) (xy 41.355393 -307.483578) (xy 41.32909 -307.441982) (xy 41.309799 -307.396706)
			(xy 41.298022 -307.348922) (xy 41.294062 -307.299868) (xy 40.005254 -307.299868) (xy 40.004759 -307.324475)
			(xy 39.996864 -307.373052) (xy 39.98128 -307.419733) (xy 39.958409 -307.46331) (xy 39.928844 -307.502654)
			(xy 39.893351 -307.536746) (xy 39.852848 -307.564702) (xy 39.808386 -307.5858) (xy 39.761115 -307.599492)
			(xy 39.71226 -307.605424) (xy 39.663085 -307.603443) (xy 39.614866 -307.593599) (xy 39.56885 -307.576147)
			(xy 39.526229 -307.55154) (xy 39.488108 -307.520415) (xy 39.455473 -307.483578) (xy 39.42917 -307.441982)
			(xy 39.409879 -307.396706) (xy 39.398102 -307.348922) (xy 39.394142 -307.299868) (xy 39.055294 -307.299868)
			(xy 39.054799 -307.324475) (xy 39.046904 -307.373052) (xy 39.03132 -307.419733) (xy 39.008449 -307.46331)
			(xy 38.978884 -307.502654) (xy 38.943391 -307.536746) (xy 38.902888 -307.564702) (xy 38.858426 -307.5858)
			(xy 38.811155 -307.599492) (xy 38.7623 -307.605424) (xy 38.713125 -307.603443) (xy 38.664906 -307.593599)
			(xy 38.61889 -307.576147) (xy 38.576269 -307.55154) (xy 38.538148 -307.520415) (xy 38.505513 -307.483578)
			(xy 38.47921 -307.441982) (xy 38.459919 -307.396706) (xy 38.448142 -307.348922) (xy 38.444182 -307.299868)
			(xy 0.509016 -307.299868) (xy 0.509016 -308.249828) (xy 36.544008 -308.249828) (xy 36.547968 -308.200774)
			(xy 36.559745 -308.15299) (xy 36.579036 -308.107714) (xy 36.605339 -308.066118) (xy 36.637974 -308.029281)
			(xy 36.676095 -307.998156) (xy 36.718716 -307.973549) (xy 36.764732 -307.956097) (xy 36.812951 -307.946253)
			(xy 36.862126 -307.944272) (xy 36.910981 -307.950204) (xy 36.958252 -307.963896) (xy 37.002714 -307.984994)
			(xy 37.043217 -308.01295) (xy 37.07871 -308.047042) (xy 37.108275 -308.086386) (xy 37.131146 -308.129963)
			(xy 37.14673 -308.176644) (xy 37.154625 -308.225221) (xy 37.15512 -308.249828) (xy 37.493968 -308.249828)
			(xy 37.497928 -308.200774) (xy 37.509705 -308.15299) (xy 37.528996 -308.107714) (xy 37.555299 -308.066118)
			(xy 37.587934 -308.029281) (xy 37.626055 -307.998156) (xy 37.668676 -307.973549) (xy 37.714692 -307.956097)
			(xy 37.762911 -307.946253) (xy 37.812086 -307.944272) (xy 37.860941 -307.950204) (xy 37.908212 -307.963896)
			(xy 37.952674 -307.984994) (xy 37.993177 -308.01295) (xy 38.02867 -308.047042) (xy 38.058235 -308.086386)
			(xy 38.081106 -308.129963) (xy 38.09669 -308.176644) (xy 38.104585 -308.225221) (xy 38.10508 -308.249828)
			(xy 43.193982 -308.249828) (xy 43.197942 -308.200774) (xy 43.209719 -308.15299) (xy 43.22901 -308.107714)
			(xy 43.255313 -308.066118) (xy 43.287948 -308.029281) (xy 43.326069 -307.998156) (xy 43.36869 -307.973549)
			(xy 43.414706 -307.956097) (xy 43.462925 -307.946253) (xy 43.5121 -307.944272) (xy 43.560955 -307.950204)
			(xy 43.608226 -307.963896) (xy 43.652688 -307.984994) (xy 43.693191 -308.01295) (xy 43.728684 -308.047042)
			(xy 43.758249 -308.086386) (xy 43.78112 -308.129963) (xy 43.796704 -308.176644) (xy 43.804599 -308.225221)
			(xy 43.805094 -308.249828) (xy 44.143942 -308.249828) (xy 44.147902 -308.200774) (xy 44.159679 -308.15299)
			(xy 44.17897 -308.107714) (xy 44.205273 -308.066118) (xy 44.237908 -308.029281) (xy 44.276029 -307.998156)
			(xy 44.31865 -307.973549) (xy 44.364666 -307.956097) (xy 44.412885 -307.946253) (xy 44.46206 -307.944272)
			(xy 44.510915 -307.950204) (xy 44.558186 -307.963896) (xy 44.602648 -307.984994) (xy 44.643151 -308.01295)
			(xy 44.678644 -308.047042) (xy 44.708209 -308.086386) (xy 44.73108 -308.129963) (xy 44.746664 -308.176644)
			(xy 44.754559 -308.225221) (xy 44.755054 -308.249828) (xy 74.544186 -308.249828) (xy 74.548146 -308.200774)
			(xy 74.559923 -308.15299) (xy 74.579214 -308.107714) (xy 74.605517 -308.066118) (xy 74.638152 -308.029281)
			(xy 74.676273 -307.998156) (xy 74.718894 -307.973549) (xy 74.76491 -307.956097) (xy 74.813129 -307.946253)
			(xy 74.862304 -307.944272) (xy 74.911159 -307.950204) (xy 74.95843 -307.963896) (xy 75.002892 -307.984994)
			(xy 75.043395 -308.01295) (xy 75.078888 -308.047042) (xy 75.108453 -308.086386) (xy 75.131324 -308.129963)
			(xy 75.146908 -308.176644) (xy 75.154803 -308.225221) (xy 75.155298 -308.249828) (xy 75.494146 -308.249828)
			(xy 75.498106 -308.200774) (xy 75.509883 -308.15299) (xy 75.529174 -308.107714) (xy 75.555477 -308.066118)
			(xy 75.588112 -308.029281) (xy 75.626233 -307.998156) (xy 75.668854 -307.973549) (xy 75.71487 -307.956097)
			(xy 75.763089 -307.946253) (xy 75.812264 -307.944272) (xy 75.861119 -307.950204) (xy 75.90839 -307.963896)
			(xy 75.952852 -307.984994) (xy 75.993355 -308.01295) (xy 76.028848 -308.047042) (xy 76.058413 -308.086386)
			(xy 76.081284 -308.129963) (xy 76.096868 -308.176644) (xy 76.104763 -308.225221) (xy 76.105258 -308.249828)
			(xy 81.19416 -308.249828) (xy 81.19812 -308.200774) (xy 81.209897 -308.15299) (xy 81.229188 -308.107714)
			(xy 81.255491 -308.066118) (xy 81.288126 -308.029281) (xy 81.326247 -307.998156) (xy 81.368868 -307.973549)
			(xy 81.414884 -307.956097) (xy 81.463103 -307.946253) (xy 81.512278 -307.944272) (xy 81.561133 -307.950204)
			(xy 81.608404 -307.963896) (xy 81.652866 -307.984994) (xy 81.693369 -308.01295) (xy 81.728862 -308.047042)
			(xy 81.758427 -308.086386) (xy 81.781298 -308.129963) (xy 81.796882 -308.176644) (xy 81.804777 -308.225221)
			(xy 81.805272 -308.249828) (xy 82.14412 -308.249828) (xy 82.14808 -308.200774) (xy 82.159857 -308.15299)
			(xy 82.179148 -308.107714) (xy 82.205451 -308.066118) (xy 82.238086 -308.029281) (xy 82.276207 -307.998156)
			(xy 82.318828 -307.973549) (xy 82.364844 -307.956097) (xy 82.413063 -307.946253) (xy 82.462238 -307.944272)
			(xy 82.511093 -307.950204) (xy 82.558364 -307.963896) (xy 82.602826 -307.984994) (xy 82.643329 -308.01295)
			(xy 82.678822 -308.047042) (xy 82.708387 -308.086386) (xy 82.731258 -308.129963) (xy 82.746842 -308.176644)
			(xy 82.754737 -308.225221) (xy 82.755232 -308.249828) (xy 152.644106 -308.249828) (xy 152.648066 -308.200774)
			(xy 152.659843 -308.15299) (xy 152.679134 -308.107714) (xy 152.705437 -308.066118) (xy 152.738072 -308.029281)
			(xy 152.776193 -307.998156) (xy 152.818814 -307.973549) (xy 152.86483 -307.956097) (xy 152.913049 -307.946253)
			(xy 152.962224 -307.944272) (xy 153.011079 -307.950204) (xy 153.05835 -307.963896) (xy 153.102812 -307.984994)
			(xy 153.143315 -308.01295) (xy 153.178808 -308.047042) (xy 153.208373 -308.086386) (xy 153.231244 -308.129963)
			(xy 153.246828 -308.176644) (xy 153.254723 -308.225221) (xy 153.255218 -308.249828) (xy 153.594066 -308.249828)
			(xy 153.598026 -308.200774) (xy 153.609803 -308.15299) (xy 153.629094 -308.107714) (xy 153.655397 -308.066118)
			(xy 153.688032 -308.029281) (xy 153.726153 -307.998156) (xy 153.768774 -307.973549) (xy 153.81479 -307.956097)
			(xy 153.863009 -307.946253) (xy 153.912184 -307.944272) (xy 153.961039 -307.950204) (xy 154.00831 -307.963896)
			(xy 154.052772 -307.984994) (xy 154.093275 -308.01295) (xy 154.128768 -308.047042) (xy 154.158333 -308.086386)
			(xy 154.181204 -308.129963) (xy 154.196788 -308.176644) (xy 154.204683 -308.225221) (xy 154.205178 -308.249828)
			(xy 159.29408 -308.249828) (xy 159.29804 -308.200774) (xy 159.309817 -308.15299) (xy 159.329108 -308.107714)
			(xy 159.355411 -308.066118) (xy 159.388046 -308.029281) (xy 159.426167 -307.998156) (xy 159.468788 -307.973549)
			(xy 159.514804 -307.956097) (xy 159.563023 -307.946253) (xy 159.612198 -307.944272) (xy 159.661053 -307.950204)
			(xy 159.708324 -307.963896) (xy 159.752786 -307.984994) (xy 159.793289 -308.01295) (xy 159.828782 -308.047042)
			(xy 159.858347 -308.086386) (xy 159.881218 -308.129963) (xy 159.896802 -308.176644) (xy 159.904697 -308.225221)
			(xy 159.905192 -308.249828) (xy 160.24404 -308.249828) (xy 160.248 -308.200774) (xy 160.259777 -308.15299)
			(xy 160.279068 -308.107714) (xy 160.305371 -308.066118) (xy 160.338006 -308.029281) (xy 160.376127 -307.998156)
			(xy 160.418748 -307.973549) (xy 160.464764 -307.956097) (xy 160.512983 -307.946253) (xy 160.562158 -307.944272)
			(xy 160.611013 -307.950204) (xy 160.658284 -307.963896) (xy 160.702746 -307.984994) (xy 160.743249 -308.01295)
			(xy 160.778742 -308.047042) (xy 160.808307 -308.086386) (xy 160.831178 -308.129963) (xy 160.846762 -308.176644)
			(xy 160.854657 -308.225221) (xy 160.855152 -308.249828) (xy 190.644284 -308.249828) (xy 190.648244 -308.200774)
			(xy 190.660021 -308.15299) (xy 190.679312 -308.107714) (xy 190.705615 -308.066118) (xy 190.73825 -308.029281)
			(xy 190.776371 -307.998156) (xy 190.818992 -307.973549) (xy 190.865008 -307.956097) (xy 190.913227 -307.946253)
			(xy 190.962402 -307.944272) (xy 191.011257 -307.950204) (xy 191.058528 -307.963896) (xy 191.10299 -307.984994)
			(xy 191.143493 -308.01295) (xy 191.178986 -308.047042) (xy 191.208551 -308.086386) (xy 191.231422 -308.129963)
			(xy 191.247006 -308.176644) (xy 191.254901 -308.225221) (xy 191.255396 -308.249828) (xy 191.594244 -308.249828)
			(xy 191.598204 -308.200774) (xy 191.609981 -308.15299) (xy 191.629272 -308.107714) (xy 191.655575 -308.066118)
			(xy 191.68821 -308.029281) (xy 191.726331 -307.998156) (xy 191.768952 -307.973549) (xy 191.814968 -307.956097)
			(xy 191.863187 -307.946253) (xy 191.912362 -307.944272) (xy 191.961217 -307.950204) (xy 192.008488 -307.963896)
			(xy 192.05295 -307.984994) (xy 192.093453 -308.01295) (xy 192.128946 -308.047042) (xy 192.158511 -308.086386)
			(xy 192.181382 -308.129963) (xy 192.196966 -308.176644) (xy 192.204861 -308.225221) (xy 192.205356 -308.249828)
			(xy 197.294258 -308.249828) (xy 197.298218 -308.200774) (xy 197.309995 -308.15299) (xy 197.329286 -308.107714)
			(xy 197.355589 -308.066118) (xy 197.388224 -308.029281) (xy 197.426345 -307.998156) (xy 197.468966 -307.973549)
			(xy 197.514982 -307.956097) (xy 197.563201 -307.946253) (xy 197.612376 -307.944272) (xy 197.661231 -307.950204)
			(xy 197.708502 -307.963896) (xy 197.752964 -307.984994) (xy 197.793467 -308.01295) (xy 197.82896 -308.047042)
			(xy 197.858525 -308.086386) (xy 197.881396 -308.129963) (xy 197.89698 -308.176644) (xy 197.904875 -308.225221)
			(xy 197.90537 -308.249828) (xy 198.244218 -308.249828) (xy 198.248178 -308.200774) (xy 198.259955 -308.15299)
			(xy 198.279246 -308.107714) (xy 198.305549 -308.066118) (xy 198.338184 -308.029281) (xy 198.376305 -307.998156)
			(xy 198.418926 -307.973549) (xy 198.464942 -307.956097) (xy 198.513161 -307.946253) (xy 198.562336 -307.944272)
			(xy 198.611191 -307.950204) (xy 198.658462 -307.963896) (xy 198.702924 -307.984994) (xy 198.743427 -308.01295)
			(xy 198.77892 -308.047042) (xy 198.808485 -308.086386) (xy 198.831356 -308.129963) (xy 198.84694 -308.176644)
			(xy 198.854835 -308.225221) (xy 198.85533 -308.249828) (xy 198.854835 -308.274435) (xy 198.84694 -308.323012)
			(xy 198.831356 -308.369693) (xy 198.808485 -308.41327) (xy 198.77892 -308.452614) (xy 198.743427 -308.486706)
			(xy 198.702924 -308.514662) (xy 198.658462 -308.53576) (xy 198.611191 -308.549452) (xy 198.562336 -308.555384)
			(xy 198.513161 -308.553403) (xy 198.464942 -308.543559) (xy 198.418926 -308.526107) (xy 198.376305 -308.5015)
			(xy 198.338184 -308.470375) (xy 198.305549 -308.433538) (xy 198.279246 -308.391942) (xy 198.259955 -308.346666)
			(xy 198.248178 -308.298882) (xy 198.244218 -308.249828) (xy 197.90537 -308.249828) (xy 197.904875 -308.274435)
			(xy 197.89698 -308.323012) (xy 197.881396 -308.369693) (xy 197.858525 -308.41327) (xy 197.82896 -308.452614)
			(xy 197.793467 -308.486706) (xy 197.752964 -308.514662) (xy 197.708502 -308.53576) (xy 197.661231 -308.549452)
			(xy 197.612376 -308.555384) (xy 197.563201 -308.553403) (xy 197.514982 -308.543559) (xy 197.468966 -308.526107)
			(xy 197.426345 -308.5015) (xy 197.388224 -308.470375) (xy 197.355589 -308.433538) (xy 197.329286 -308.391942)
			(xy 197.309995 -308.346666) (xy 197.298218 -308.298882) (xy 197.294258 -308.249828) (xy 192.205356 -308.249828)
			(xy 192.204861 -308.274435) (xy 192.196966 -308.323012) (xy 192.181382 -308.369693) (xy 192.158511 -308.41327)
			(xy 192.128946 -308.452614) (xy 192.093453 -308.486706) (xy 192.05295 -308.514662) (xy 192.008488 -308.53576)
			(xy 191.961217 -308.549452) (xy 191.912362 -308.555384) (xy 191.863187 -308.553403) (xy 191.814968 -308.543559)
			(xy 191.768952 -308.526107) (xy 191.726331 -308.5015) (xy 191.68821 -308.470375) (xy 191.655575 -308.433538)
			(xy 191.629272 -308.391942) (xy 191.609981 -308.346666) (xy 191.598204 -308.298882) (xy 191.594244 -308.249828)
			(xy 191.255396 -308.249828) (xy 191.254901 -308.274435) (xy 191.247006 -308.323012) (xy 191.231422 -308.369693)
			(xy 191.208551 -308.41327) (xy 191.178986 -308.452614) (xy 191.143493 -308.486706) (xy 191.10299 -308.514662)
			(xy 191.058528 -308.53576) (xy 191.011257 -308.549452) (xy 190.962402 -308.555384) (xy 190.913227 -308.553403)
			(xy 190.865008 -308.543559) (xy 190.818992 -308.526107) (xy 190.776371 -308.5015) (xy 190.73825 -308.470375)
			(xy 190.705615 -308.433538) (xy 190.679312 -308.391942) (xy 190.660021 -308.346666) (xy 190.648244 -308.298882)
			(xy 190.644284 -308.249828) (xy 160.855152 -308.249828) (xy 160.854657 -308.274435) (xy 160.846762 -308.323012)
			(xy 160.831178 -308.369693) (xy 160.808307 -308.41327) (xy 160.778742 -308.452614) (xy 160.743249 -308.486706)
			(xy 160.702746 -308.514662) (xy 160.658284 -308.53576) (xy 160.611013 -308.549452) (xy 160.562158 -308.555384)
			(xy 160.512983 -308.553403) (xy 160.464764 -308.543559) (xy 160.418748 -308.526107) (xy 160.376127 -308.5015)
			(xy 160.338006 -308.470375) (xy 160.305371 -308.433538) (xy 160.279068 -308.391942) (xy 160.259777 -308.346666)
			(xy 160.248 -308.298882) (xy 160.24404 -308.249828) (xy 159.905192 -308.249828) (xy 159.904697 -308.274435)
			(xy 159.896802 -308.323012) (xy 159.881218 -308.369693) (xy 159.858347 -308.41327) (xy 159.828782 -308.452614)
			(xy 159.793289 -308.486706) (xy 159.752786 -308.514662) (xy 159.708324 -308.53576) (xy 159.661053 -308.549452)
			(xy 159.612198 -308.555384) (xy 159.563023 -308.553403) (xy 159.514804 -308.543559) (xy 159.468788 -308.526107)
			(xy 159.426167 -308.5015) (xy 159.388046 -308.470375) (xy 159.355411 -308.433538) (xy 159.329108 -308.391942)
			(xy 159.309817 -308.346666) (xy 159.29804 -308.298882) (xy 159.29408 -308.249828) (xy 154.205178 -308.249828)
			(xy 154.204683 -308.274435) (xy 154.196788 -308.323012) (xy 154.181204 -308.369693) (xy 154.158333 -308.41327)
			(xy 154.128768 -308.452614) (xy 154.093275 -308.486706) (xy 154.052772 -308.514662) (xy 154.00831 -308.53576)
			(xy 153.961039 -308.549452) (xy 153.912184 -308.555384) (xy 153.863009 -308.553403) (xy 153.81479 -308.543559)
			(xy 153.768774 -308.526107) (xy 153.726153 -308.5015) (xy 153.688032 -308.470375) (xy 153.655397 -308.433538)
			(xy 153.629094 -308.391942) (xy 153.609803 -308.346666) (xy 153.598026 -308.298882) (xy 153.594066 -308.249828)
			(xy 153.255218 -308.249828) (xy 153.254723 -308.274435) (xy 153.246828 -308.323012) (xy 153.231244 -308.369693)
			(xy 153.208373 -308.41327) (xy 153.178808 -308.452614) (xy 153.143315 -308.486706) (xy 153.102812 -308.514662)
			(xy 153.05835 -308.53576) (xy 153.011079 -308.549452) (xy 152.962224 -308.555384) (xy 152.913049 -308.553403)
			(xy 152.86483 -308.543559) (xy 152.818814 -308.526107) (xy 152.776193 -308.5015) (xy 152.738072 -308.470375)
			(xy 152.705437 -308.433538) (xy 152.679134 -308.391942) (xy 152.659843 -308.346666) (xy 152.648066 -308.298882)
			(xy 152.644106 -308.249828) (xy 82.755232 -308.249828) (xy 82.754737 -308.274435) (xy 82.746842 -308.323012)
			(xy 82.731258 -308.369693) (xy 82.708387 -308.41327) (xy 82.678822 -308.452614) (xy 82.643329 -308.486706)
			(xy 82.602826 -308.514662) (xy 82.558364 -308.53576) (xy 82.511093 -308.549452) (xy 82.462238 -308.555384)
			(xy 82.413063 -308.553403) (xy 82.364844 -308.543559) (xy 82.318828 -308.526107) (xy 82.276207 -308.5015)
			(xy 82.238086 -308.470375) (xy 82.205451 -308.433538) (xy 82.179148 -308.391942) (xy 82.159857 -308.346666)
			(xy 82.14808 -308.298882) (xy 82.14412 -308.249828) (xy 81.805272 -308.249828) (xy 81.804777 -308.274435)
			(xy 81.796882 -308.323012) (xy 81.781298 -308.369693) (xy 81.758427 -308.41327) (xy 81.728862 -308.452614)
			(xy 81.693369 -308.486706) (xy 81.652866 -308.514662) (xy 81.608404 -308.53576) (xy 81.561133 -308.549452)
			(xy 81.512278 -308.555384) (xy 81.463103 -308.553403) (xy 81.414884 -308.543559) (xy 81.368868 -308.526107)
			(xy 81.326247 -308.5015) (xy 81.288126 -308.470375) (xy 81.255491 -308.433538) (xy 81.229188 -308.391942)
			(xy 81.209897 -308.346666) (xy 81.19812 -308.298882) (xy 81.19416 -308.249828) (xy 76.105258 -308.249828)
			(xy 76.104763 -308.274435) (xy 76.096868 -308.323012) (xy 76.081284 -308.369693) (xy 76.058413 -308.41327)
			(xy 76.028848 -308.452614) (xy 75.993355 -308.486706) (xy 75.952852 -308.514662) (xy 75.90839 -308.53576)
			(xy 75.861119 -308.549452) (xy 75.812264 -308.555384) (xy 75.763089 -308.553403) (xy 75.71487 -308.543559)
			(xy 75.668854 -308.526107) (xy 75.626233 -308.5015) (xy 75.588112 -308.470375) (xy 75.555477 -308.433538)
			(xy 75.529174 -308.391942) (xy 75.509883 -308.346666) (xy 75.498106 -308.298882) (xy 75.494146 -308.249828)
			(xy 75.155298 -308.249828) (xy 75.154803 -308.274435) (xy 75.146908 -308.323012) (xy 75.131324 -308.369693)
			(xy 75.108453 -308.41327) (xy 75.078888 -308.452614) (xy 75.043395 -308.486706) (xy 75.002892 -308.514662)
			(xy 74.95843 -308.53576) (xy 74.911159 -308.549452) (xy 74.862304 -308.555384) (xy 74.813129 -308.553403)
			(xy 74.76491 -308.543559) (xy 74.718894 -308.526107) (xy 74.676273 -308.5015) (xy 74.638152 -308.470375)
			(xy 74.605517 -308.433538) (xy 74.579214 -308.391942) (xy 74.559923 -308.346666) (xy 74.548146 -308.298882)
			(xy 74.544186 -308.249828) (xy 44.755054 -308.249828) (xy 44.754559 -308.274435) (xy 44.746664 -308.323012)
			(xy 44.73108 -308.369693) (xy 44.708209 -308.41327) (xy 44.678644 -308.452614) (xy 44.643151 -308.486706)
			(xy 44.602648 -308.514662) (xy 44.558186 -308.53576) (xy 44.510915 -308.549452) (xy 44.46206 -308.555384)
			(xy 44.412885 -308.553403) (xy 44.364666 -308.543559) (xy 44.31865 -308.526107) (xy 44.276029 -308.5015)
			(xy 44.237908 -308.470375) (xy 44.205273 -308.433538) (xy 44.17897 -308.391942) (xy 44.159679 -308.346666)
			(xy 44.147902 -308.298882) (xy 44.143942 -308.249828) (xy 43.805094 -308.249828) (xy 43.804599 -308.274435)
			(xy 43.796704 -308.323012) (xy 43.78112 -308.369693) (xy 43.758249 -308.41327) (xy 43.728684 -308.452614)
			(xy 43.693191 -308.486706) (xy 43.652688 -308.514662) (xy 43.608226 -308.53576) (xy 43.560955 -308.549452)
			(xy 43.5121 -308.555384) (xy 43.462925 -308.553403) (xy 43.414706 -308.543559) (xy 43.36869 -308.526107)
			(xy 43.326069 -308.5015) (xy 43.287948 -308.470375) (xy 43.255313 -308.433538) (xy 43.22901 -308.391942)
			(xy 43.209719 -308.346666) (xy 43.197942 -308.298882) (xy 43.193982 -308.249828) (xy 38.10508 -308.249828)
			(xy 38.104585 -308.274435) (xy 38.09669 -308.323012) (xy 38.081106 -308.369693) (xy 38.058235 -308.41327)
			(xy 38.02867 -308.452614) (xy 37.993177 -308.486706) (xy 37.952674 -308.514662) (xy 37.908212 -308.53576)
			(xy 37.860941 -308.549452) (xy 37.812086 -308.555384) (xy 37.762911 -308.553403) (xy 37.714692 -308.543559)
			(xy 37.668676 -308.526107) (xy 37.626055 -308.5015) (xy 37.587934 -308.470375) (xy 37.555299 -308.433538)
			(xy 37.528996 -308.391942) (xy 37.509705 -308.346666) (xy 37.497928 -308.298882) (xy 37.493968 -308.249828)
			(xy 37.15512 -308.249828) (xy 37.154625 -308.274435) (xy 37.14673 -308.323012) (xy 37.131146 -308.369693)
			(xy 37.108275 -308.41327) (xy 37.07871 -308.452614) (xy 37.043217 -308.486706) (xy 37.002714 -308.514662)
			(xy 36.958252 -308.53576) (xy 36.910981 -308.549452) (xy 36.862126 -308.555384) (xy 36.812951 -308.553403)
			(xy 36.764732 -308.543559) (xy 36.718716 -308.526107) (xy 36.676095 -308.5015) (xy 36.637974 -308.470375)
			(xy 36.605339 -308.433538) (xy 36.579036 -308.391942) (xy 36.559745 -308.346666) (xy 36.547968 -308.298882)
			(xy 36.544008 -308.249828) (xy 0.509016 -308.249828) (xy 0.509016 -308.568852) (xy 231.935526 -308.568852)
			(xy 231.939599 -308.513193) (xy 231.951734 -308.45872) (xy 231.97167 -308.406594) (xy 231.998984 -308.357926)
			(xy 232.033092 -308.313754) (xy 232.073269 -308.275019) (xy 232.118657 -308.242547) (xy 232.168289 -308.217029)
			(xy 232.221109 -308.19901) (xy 232.275988 -308.188873) (xy 232.331759 -308.186835) (xy 232.387233 -308.192938)
			(xy 232.441226 -308.207054) (xy 232.492589 -308.228881) (xy 232.540227 -308.257954) (xy 232.583123 -308.293653)
			(xy 232.620365 -308.335217) (xy 232.651159 -308.381761) (xy 232.674847 -308.432292) (xy 232.690925 -308.485734)
			(xy 232.699051 -308.540948) (xy 232.69956 -308.568852) (xy 248.185684 -308.568852) (xy 248.189757 -308.513193)
			(xy 248.201892 -308.45872) (xy 248.221828 -308.406594) (xy 248.249142 -308.357926) (xy 248.28325 -308.313754)
			(xy 248.323427 -308.275019) (xy 248.368815 -308.242547) (xy 248.418447 -308.217029) (xy 248.471267 -308.19901)
			(xy 248.526146 -308.188873) (xy 248.581917 -308.186835) (xy 248.637391 -308.192938) (xy 248.691384 -308.207054)
			(xy 248.742747 -308.228881) (xy 248.77707 -308.249828) (xy 268.74395 -308.249828) (xy 268.74791 -308.200774)
			(xy 268.759687 -308.15299) (xy 268.778978 -308.107714) (xy 268.805281 -308.066118) (xy 268.837916 -308.029281)
			(xy 268.876037 -307.998156) (xy 268.918658 -307.973549) (xy 268.964674 -307.956097) (xy 269.012893 -307.946253)
			(xy 269.062068 -307.944272) (xy 269.110923 -307.950204) (xy 269.158194 -307.963896) (xy 269.202656 -307.984994)
			(xy 269.243159 -308.01295) (xy 269.278652 -308.047042) (xy 269.308217 -308.086386) (xy 269.331088 -308.129963)
			(xy 269.346672 -308.176644) (xy 269.354567 -308.225221) (xy 269.355062 -308.249828) (xy 269.69391 -308.249828)
			(xy 269.69787 -308.200774) (xy 269.709647 -308.15299) (xy 269.728938 -308.107714) (xy 269.755241 -308.066118)
			(xy 269.787876 -308.029281) (xy 269.825997 -307.998156) (xy 269.868618 -307.973549) (xy 269.914634 -307.956097)
			(xy 269.962853 -307.946253) (xy 270.012028 -307.944272) (xy 270.060883 -307.950204) (xy 270.108154 -307.963896)
			(xy 270.152616 -307.984994) (xy 270.193119 -308.01295) (xy 270.228612 -308.047042) (xy 270.258177 -308.086386)
			(xy 270.281048 -308.129963) (xy 270.296632 -308.176644) (xy 270.304527 -308.225221) (xy 270.305022 -308.249828)
			(xy 275.393924 -308.249828) (xy 275.397884 -308.200774) (xy 275.409661 -308.15299) (xy 275.428952 -308.107714)
			(xy 275.455255 -308.066118) (xy 275.48789 -308.029281) (xy 275.526011 -307.998156) (xy 275.568632 -307.973549)
			(xy 275.614648 -307.956097) (xy 275.662867 -307.946253) (xy 275.712042 -307.944272) (xy 275.760897 -307.950204)
			(xy 275.808168 -307.963896) (xy 275.85263 -307.984994) (xy 275.893133 -308.01295) (xy 275.928626 -308.047042)
			(xy 275.958191 -308.086386) (xy 275.981062 -308.129963) (xy 275.996646 -308.176644) (xy 276.004541 -308.225221)
			(xy 276.005036 -308.249828) (xy 276.343884 -308.249828) (xy 276.347844 -308.200774) (xy 276.359621 -308.15299)
			(xy 276.378912 -308.107714) (xy 276.405215 -308.066118) (xy 276.43785 -308.029281) (xy 276.475971 -307.998156)
			(xy 276.518592 -307.973549) (xy 276.564608 -307.956097) (xy 276.612827 -307.946253) (xy 276.662002 -307.944272)
			(xy 276.710857 -307.950204) (xy 276.758128 -307.963896) (xy 276.80259 -307.984994) (xy 276.843093 -308.01295)
			(xy 276.878586 -308.047042) (xy 276.908151 -308.086386) (xy 276.931022 -308.129963) (xy 276.946606 -308.176644)
			(xy 276.954501 -308.225221) (xy 276.954996 -308.249828) (xy 306.744128 -308.249828) (xy 306.748088 -308.200774)
			(xy 306.759865 -308.15299) (xy 306.779156 -308.107714) (xy 306.805459 -308.066118) (xy 306.838094 -308.029281)
			(xy 306.876215 -307.998156) (xy 306.918836 -307.973549) (xy 306.964852 -307.956097) (xy 307.013071 -307.946253)
			(xy 307.062246 -307.944272) (xy 307.111101 -307.950204) (xy 307.158372 -307.963896) (xy 307.202834 -307.984994)
			(xy 307.243337 -308.01295) (xy 307.27883 -308.047042) (xy 307.308395 -308.086386) (xy 307.331266 -308.129963)
			(xy 307.34685 -308.176644) (xy 307.354745 -308.225221) (xy 307.35524 -308.249828) (xy 307.694088 -308.249828)
			(xy 307.698048 -308.200774) (xy 307.709825 -308.15299) (xy 307.729116 -308.107714) (xy 307.755419 -308.066118)
			(xy 307.788054 -308.029281) (xy 307.826175 -307.998156) (xy 307.868796 -307.973549) (xy 307.914812 -307.956097)
			(xy 307.963031 -307.946253) (xy 308.012206 -307.944272) (xy 308.061061 -307.950204) (xy 308.108332 -307.963896)
			(xy 308.152794 -307.984994) (xy 308.193297 -308.01295) (xy 308.22879 -308.047042) (xy 308.258355 -308.086386)
			(xy 308.281226 -308.129963) (xy 308.29681 -308.176644) (xy 308.304705 -308.225221) (xy 308.3052 -308.249828)
			(xy 313.394102 -308.249828) (xy 313.398062 -308.200774) (xy 313.409839 -308.15299) (xy 313.42913 -308.107714)
			(xy 313.455433 -308.066118) (xy 313.488068 -308.029281) (xy 313.526189 -307.998156) (xy 313.56881 -307.973549)
			(xy 313.614826 -307.956097) (xy 313.663045 -307.946253) (xy 313.71222 -307.944272) (xy 313.761075 -307.950204)
			(xy 313.808346 -307.963896) (xy 313.852808 -307.984994) (xy 313.893311 -308.01295) (xy 313.928804 -308.047042)
			(xy 313.958369 -308.086386) (xy 313.98124 -308.129963) (xy 313.996824 -308.176644) (xy 314.004719 -308.225221)
			(xy 314.005214 -308.249828) (xy 314.344062 -308.249828) (xy 314.348022 -308.200774) (xy 314.359799 -308.15299)
			(xy 314.37909 -308.107714) (xy 314.405393 -308.066118) (xy 314.438028 -308.029281) (xy 314.476149 -307.998156)
			(xy 314.51877 -307.973549) (xy 314.564786 -307.956097) (xy 314.613005 -307.946253) (xy 314.66218 -307.944272)
			(xy 314.711035 -307.950204) (xy 314.758306 -307.963896) (xy 314.802768 -307.984994) (xy 314.843271 -308.01295)
			(xy 314.878764 -308.047042) (xy 314.908329 -308.086386) (xy 314.9312 -308.129963) (xy 314.946784 -308.176644)
			(xy 314.954679 -308.225221) (xy 314.955174 -308.249828) (xy 384.844048 -308.249828) (xy 384.848008 -308.200774)
			(xy 384.859785 -308.15299) (xy 384.879076 -308.107714) (xy 384.905379 -308.066118) (xy 384.938014 -308.029281)
			(xy 384.976135 -307.998156) (xy 385.018756 -307.973549) (xy 385.064772 -307.956097) (xy 385.112991 -307.946253)
			(xy 385.162166 -307.944272) (xy 385.211021 -307.950204) (xy 385.258292 -307.963896) (xy 385.302754 -307.984994)
			(xy 385.343257 -308.01295) (xy 385.37875 -308.047042) (xy 385.408315 -308.086386) (xy 385.431186 -308.129963)
			(xy 385.44677 -308.176644) (xy 385.454665 -308.225221) (xy 385.45516 -308.249828) (xy 385.794008 -308.249828)
			(xy 385.797968 -308.200774) (xy 385.809745 -308.15299) (xy 385.829036 -308.107714) (xy 385.855339 -308.066118)
			(xy 385.887974 -308.029281) (xy 385.926095 -307.998156) (xy 385.968716 -307.973549) (xy 386.014732 -307.956097)
			(xy 386.062951 -307.946253) (xy 386.112126 -307.944272) (xy 386.160981 -307.950204) (xy 386.208252 -307.963896)
			(xy 386.252714 -307.984994) (xy 386.293217 -308.01295) (xy 386.32871 -308.047042) (xy 386.358275 -308.086386)
			(xy 386.381146 -308.129963) (xy 386.39673 -308.176644) (xy 386.404625 -308.225221) (xy 386.40512 -308.249828)
			(xy 391.494022 -308.249828) (xy 391.497982 -308.200774) (xy 391.509759 -308.15299) (xy 391.52905 -308.107714)
			(xy 391.555353 -308.066118) (xy 391.587988 -308.029281) (xy 391.626109 -307.998156) (xy 391.66873 -307.973549)
			(xy 391.714746 -307.956097) (xy 391.762965 -307.946253) (xy 391.81214 -307.944272) (xy 391.860995 -307.950204)
			(xy 391.908266 -307.963896) (xy 391.952728 -307.984994) (xy 391.993231 -308.01295) (xy 392.028724 -308.047042)
			(xy 392.058289 -308.086386) (xy 392.08116 -308.129963) (xy 392.096744 -308.176644) (xy 392.104639 -308.225221)
			(xy 392.105134 -308.249828) (xy 392.443982 -308.249828) (xy 392.447942 -308.200774) (xy 392.459719 -308.15299)
			(xy 392.47901 -308.107714) (xy 392.505313 -308.066118) (xy 392.537948 -308.029281) (xy 392.576069 -307.998156)
			(xy 392.61869 -307.973549) (xy 392.664706 -307.956097) (xy 392.712925 -307.946253) (xy 392.7621 -307.944272)
			(xy 392.810955 -307.950204) (xy 392.858226 -307.963896) (xy 392.902688 -307.984994) (xy 392.943191 -308.01295)
			(xy 392.978684 -308.047042) (xy 393.008249 -308.086386) (xy 393.03112 -308.129963) (xy 393.046704 -308.176644)
			(xy 393.054599 -308.225221) (xy 393.055094 -308.249828) (xy 422.844226 -308.249828) (xy 422.848186 -308.200774)
			(xy 422.859963 -308.15299) (xy 422.879254 -308.107714) (xy 422.905557 -308.066118) (xy 422.938192 -308.029281)
			(xy 422.976313 -307.998156) (xy 423.018934 -307.973549) (xy 423.06495 -307.956097) (xy 423.113169 -307.946253)
			(xy 423.162344 -307.944272) (xy 423.211199 -307.950204) (xy 423.25847 -307.963896) (xy 423.302932 -307.984994)
			(xy 423.343435 -308.01295) (xy 423.378928 -308.047042) (xy 423.408493 -308.086386) (xy 423.431364 -308.129963)
			(xy 423.446948 -308.176644) (xy 423.454843 -308.225221) (xy 423.455338 -308.249828) (xy 423.794186 -308.249828)
			(xy 423.798146 -308.200774) (xy 423.809923 -308.15299) (xy 423.829214 -308.107714) (xy 423.855517 -308.066118)
			(xy 423.888152 -308.029281) (xy 423.926273 -307.998156) (xy 423.968894 -307.973549) (xy 424.01491 -307.956097)
			(xy 424.063129 -307.946253) (xy 424.112304 -307.944272) (xy 424.161159 -307.950204) (xy 424.20843 -307.963896)
			(xy 424.252892 -307.984994) (xy 424.293395 -308.01295) (xy 424.328888 -308.047042) (xy 424.358453 -308.086386)
			(xy 424.381324 -308.129963) (xy 424.396908 -308.176644) (xy 424.404803 -308.225221) (xy 424.405298 -308.249828)
			(xy 429.4942 -308.249828) (xy 429.49816 -308.200774) (xy 429.509937 -308.15299) (xy 429.529228 -308.107714)
			(xy 429.555531 -308.066118) (xy 429.588166 -308.029281) (xy 429.626287 -307.998156) (xy 429.668908 -307.973549)
			(xy 429.714924 -307.956097) (xy 429.763143 -307.946253) (xy 429.812318 -307.944272) (xy 429.861173 -307.950204)
			(xy 429.908444 -307.963896) (xy 429.952906 -307.984994) (xy 429.993409 -308.01295) (xy 430.028902 -308.047042)
			(xy 430.058467 -308.086386) (xy 430.081338 -308.129963) (xy 430.096922 -308.176644) (xy 430.104817 -308.225221)
			(xy 430.105312 -308.249828) (xy 430.44416 -308.249828) (xy 430.44812 -308.200774) (xy 430.459897 -308.15299)
			(xy 430.479188 -308.107714) (xy 430.505491 -308.066118) (xy 430.538126 -308.029281) (xy 430.576247 -307.998156)
			(xy 430.618868 -307.973549) (xy 430.664884 -307.956097) (xy 430.713103 -307.946253) (xy 430.762278 -307.944272)
			(xy 430.811133 -307.950204) (xy 430.858404 -307.963896) (xy 430.902866 -307.984994) (xy 430.943369 -308.01295)
			(xy 430.978862 -308.047042) (xy 431.008427 -308.086386) (xy 431.031298 -308.129963) (xy 431.046882 -308.176644)
			(xy 431.054777 -308.225221) (xy 431.055272 -308.249828) (xy 431.054777 -308.274435) (xy 431.046882 -308.323012)
			(xy 431.031298 -308.369693) (xy 431.008427 -308.41327) (xy 430.978862 -308.452614) (xy 430.943369 -308.486706)
			(xy 430.902866 -308.514662) (xy 430.858404 -308.53576) (xy 430.811133 -308.549452) (xy 430.762278 -308.555384)
			(xy 430.713103 -308.553403) (xy 430.664884 -308.543559) (xy 430.618868 -308.526107) (xy 430.576247 -308.5015)
			(xy 430.538126 -308.470375) (xy 430.505491 -308.433538) (xy 430.479188 -308.391942) (xy 430.459897 -308.346666)
			(xy 430.44812 -308.298882) (xy 430.44416 -308.249828) (xy 430.105312 -308.249828) (xy 430.104817 -308.274435)
			(xy 430.096922 -308.323012) (xy 430.081338 -308.369693) (xy 430.058467 -308.41327) (xy 430.028902 -308.452614)
			(xy 429.993409 -308.486706) (xy 429.952906 -308.514662) (xy 429.908444 -308.53576) (xy 429.861173 -308.549452)
			(xy 429.812318 -308.555384) (xy 429.763143 -308.553403) (xy 429.714924 -308.543559) (xy 429.668908 -308.526107)
			(xy 429.626287 -308.5015) (xy 429.588166 -308.470375) (xy 429.555531 -308.433538) (xy 429.529228 -308.391942)
			(xy 429.509937 -308.346666) (xy 429.49816 -308.298882) (xy 429.4942 -308.249828) (xy 424.405298 -308.249828)
			(xy 424.404803 -308.274435) (xy 424.396908 -308.323012) (xy 424.381324 -308.369693) (xy 424.358453 -308.41327)
			(xy 424.328888 -308.452614) (xy 424.293395 -308.486706) (xy 424.252892 -308.514662) (xy 424.20843 -308.53576)
			(xy 424.161159 -308.549452) (xy 424.112304 -308.555384) (xy 424.063129 -308.553403) (xy 424.01491 -308.543559)
			(xy 423.968894 -308.526107) (xy 423.926273 -308.5015) (xy 423.888152 -308.470375) (xy 423.855517 -308.433538)
			(xy 423.829214 -308.391942) (xy 423.809923 -308.346666) (xy 423.798146 -308.298882) (xy 423.794186 -308.249828)
			(xy 423.455338 -308.249828) (xy 423.454843 -308.274435) (xy 423.446948 -308.323012) (xy 423.431364 -308.369693)
			(xy 423.408493 -308.41327) (xy 423.378928 -308.452614) (xy 423.343435 -308.486706) (xy 423.302932 -308.514662)
			(xy 423.25847 -308.53576) (xy 423.211199 -308.549452) (xy 423.162344 -308.555384) (xy 423.113169 -308.553403)
			(xy 423.06495 -308.543559) (xy 423.018934 -308.526107) (xy 422.976313 -308.5015) (xy 422.938192 -308.470375)
			(xy 422.905557 -308.433538) (xy 422.879254 -308.391942) (xy 422.859963 -308.346666) (xy 422.848186 -308.298882)
			(xy 422.844226 -308.249828) (xy 393.055094 -308.249828) (xy 393.054599 -308.274435) (xy 393.046704 -308.323012)
			(xy 393.03112 -308.369693) (xy 393.008249 -308.41327) (xy 392.978684 -308.452614) (xy 392.943191 -308.486706)
			(xy 392.902688 -308.514662) (xy 392.858226 -308.53576) (xy 392.810955 -308.549452) (xy 392.7621 -308.555384)
			(xy 392.712925 -308.553403) (xy 392.664706 -308.543559) (xy 392.61869 -308.526107) (xy 392.576069 -308.5015)
			(xy 392.537948 -308.470375) (xy 392.505313 -308.433538) (xy 392.47901 -308.391942) (xy 392.459719 -308.346666)
			(xy 392.447942 -308.298882) (xy 392.443982 -308.249828) (xy 392.105134 -308.249828) (xy 392.104639 -308.274435)
			(xy 392.096744 -308.323012) (xy 392.08116 -308.369693) (xy 392.058289 -308.41327) (xy 392.028724 -308.452614)
			(xy 391.993231 -308.486706) (xy 391.952728 -308.514662) (xy 391.908266 -308.53576) (xy 391.860995 -308.549452)
			(xy 391.81214 -308.555384) (xy 391.762965 -308.553403) (xy 391.714746 -308.543559) (xy 391.66873 -308.526107)
			(xy 391.626109 -308.5015) (xy 391.587988 -308.470375) (xy 391.555353 -308.433538) (xy 391.52905 -308.391942)
			(xy 391.509759 -308.346666) (xy 391.497982 -308.298882) (xy 391.494022 -308.249828) (xy 386.40512 -308.249828)
			(xy 386.404625 -308.274435) (xy 386.39673 -308.323012) (xy 386.381146 -308.369693) (xy 386.358275 -308.41327)
			(xy 386.32871 -308.452614) (xy 386.293217 -308.486706) (xy 386.252714 -308.514662) (xy 386.208252 -308.53576)
			(xy 386.160981 -308.549452) (xy 386.112126 -308.555384) (xy 386.062951 -308.553403) (xy 386.014732 -308.543559)
			(xy 385.968716 -308.526107) (xy 385.926095 -308.5015) (xy 385.887974 -308.470375) (xy 385.855339 -308.433538)
			(xy 385.829036 -308.391942) (xy 385.809745 -308.346666) (xy 385.797968 -308.298882) (xy 385.794008 -308.249828)
			(xy 385.45516 -308.249828) (xy 385.454665 -308.274435) (xy 385.44677 -308.323012) (xy 385.431186 -308.369693)
			(xy 385.408315 -308.41327) (xy 385.37875 -308.452614) (xy 385.343257 -308.486706) (xy 385.302754 -308.514662)
			(xy 385.258292 -308.53576) (xy 385.211021 -308.549452) (xy 385.162166 -308.555384) (xy 385.112991 -308.553403)
			(xy 385.064772 -308.543559) (xy 385.018756 -308.526107) (xy 384.976135 -308.5015) (xy 384.938014 -308.470375)
			(xy 384.905379 -308.433538) (xy 384.879076 -308.391942) (xy 384.859785 -308.346666) (xy 384.848008 -308.298882)
			(xy 384.844048 -308.249828) (xy 314.955174 -308.249828) (xy 314.954679 -308.274435) (xy 314.946784 -308.323012)
			(xy 314.9312 -308.369693) (xy 314.908329 -308.41327) (xy 314.878764 -308.452614) (xy 314.843271 -308.486706)
			(xy 314.802768 -308.514662) (xy 314.758306 -308.53576) (xy 314.711035 -308.549452) (xy 314.66218 -308.555384)
			(xy 314.613005 -308.553403) (xy 314.564786 -308.543559) (xy 314.51877 -308.526107) (xy 314.476149 -308.5015)
			(xy 314.438028 -308.470375) (xy 314.405393 -308.433538) (xy 314.37909 -308.391942) (xy 314.359799 -308.346666)
			(xy 314.348022 -308.298882) (xy 314.344062 -308.249828) (xy 314.005214 -308.249828) (xy 314.004719 -308.274435)
			(xy 313.996824 -308.323012) (xy 313.98124 -308.369693) (xy 313.958369 -308.41327) (xy 313.928804 -308.452614)
			(xy 313.893311 -308.486706) (xy 313.852808 -308.514662) (xy 313.808346 -308.53576) (xy 313.761075 -308.549452)
			(xy 313.71222 -308.555384) (xy 313.663045 -308.553403) (xy 313.614826 -308.543559) (xy 313.56881 -308.526107)
			(xy 313.526189 -308.5015) (xy 313.488068 -308.470375) (xy 313.455433 -308.433538) (xy 313.42913 -308.391942)
			(xy 313.409839 -308.346666) (xy 313.398062 -308.298882) (xy 313.394102 -308.249828) (xy 308.3052 -308.249828)
			(xy 308.304705 -308.274435) (xy 308.29681 -308.323012) (xy 308.281226 -308.369693) (xy 308.258355 -308.41327)
			(xy 308.22879 -308.452614) (xy 308.193297 -308.486706) (xy 308.152794 -308.514662) (xy 308.108332 -308.53576)
			(xy 308.061061 -308.549452) (xy 308.012206 -308.555384) (xy 307.963031 -308.553403) (xy 307.914812 -308.543559)
			(xy 307.868796 -308.526107) (xy 307.826175 -308.5015) (xy 307.788054 -308.470375) (xy 307.755419 -308.433538)
			(xy 307.729116 -308.391942) (xy 307.709825 -308.346666) (xy 307.698048 -308.298882) (xy 307.694088 -308.249828)
			(xy 307.35524 -308.249828) (xy 307.354745 -308.274435) (xy 307.34685 -308.323012) (xy 307.331266 -308.369693)
			(xy 307.308395 -308.41327) (xy 307.27883 -308.452614) (xy 307.243337 -308.486706) (xy 307.202834 -308.514662)
			(xy 307.158372 -308.53576) (xy 307.111101 -308.549452) (xy 307.062246 -308.555384) (xy 307.013071 -308.553403)
			(xy 306.964852 -308.543559) (xy 306.918836 -308.526107) (xy 306.876215 -308.5015) (xy 306.838094 -308.470375)
			(xy 306.805459 -308.433538) (xy 306.779156 -308.391942) (xy 306.759865 -308.346666) (xy 306.748088 -308.298882)
			(xy 306.744128 -308.249828) (xy 276.954996 -308.249828) (xy 276.954501 -308.274435) (xy 276.946606 -308.323012)
			(xy 276.931022 -308.369693) (xy 276.908151 -308.41327) (xy 276.878586 -308.452614) (xy 276.843093 -308.486706)
			(xy 276.80259 -308.514662) (xy 276.758128 -308.53576) (xy 276.710857 -308.549452) (xy 276.662002 -308.555384)
			(xy 276.612827 -308.553403) (xy 276.564608 -308.543559) (xy 276.518592 -308.526107) (xy 276.475971 -308.5015)
			(xy 276.43785 -308.470375) (xy 276.405215 -308.433538) (xy 276.378912 -308.391942) (xy 276.359621 -308.346666)
			(xy 276.347844 -308.298882) (xy 276.343884 -308.249828) (xy 276.005036 -308.249828) (xy 276.004541 -308.274435)
			(xy 275.996646 -308.323012) (xy 275.981062 -308.369693) (xy 275.958191 -308.41327) (xy 275.928626 -308.452614)
			(xy 275.893133 -308.486706) (xy 275.85263 -308.514662) (xy 275.808168 -308.53576) (xy 275.760897 -308.549452)
			(xy 275.712042 -308.555384) (xy 275.662867 -308.553403) (xy 275.614648 -308.543559) (xy 275.568632 -308.526107)
			(xy 275.526011 -308.5015) (xy 275.48789 -308.470375) (xy 275.455255 -308.433538) (xy 275.428952 -308.391942)
			(xy 275.409661 -308.346666) (xy 275.397884 -308.298882) (xy 275.393924 -308.249828) (xy 270.305022 -308.249828)
			(xy 270.304527 -308.274435) (xy 270.296632 -308.323012) (xy 270.281048 -308.369693) (xy 270.258177 -308.41327)
			(xy 270.228612 -308.452614) (xy 270.193119 -308.486706) (xy 270.152616 -308.514662) (xy 270.108154 -308.53576)
			(xy 270.060883 -308.549452) (xy 270.012028 -308.555384) (xy 269.962853 -308.553403) (xy 269.914634 -308.543559)
			(xy 269.868618 -308.526107) (xy 269.825997 -308.5015) (xy 269.787876 -308.470375) (xy 269.755241 -308.433538)
			(xy 269.728938 -308.391942) (xy 269.709647 -308.346666) (xy 269.69787 -308.298882) (xy 269.69391 -308.249828)
			(xy 269.355062 -308.249828) (xy 269.354567 -308.274435) (xy 269.346672 -308.323012) (xy 269.331088 -308.369693)
			(xy 269.308217 -308.41327) (xy 269.278652 -308.452614) (xy 269.243159 -308.486706) (xy 269.202656 -308.514662)
			(xy 269.158194 -308.53576) (xy 269.110923 -308.549452) (xy 269.062068 -308.555384) (xy 269.012893 -308.553403)
			(xy 268.964674 -308.543559) (xy 268.918658 -308.526107) (xy 268.876037 -308.5015) (xy 268.837916 -308.470375)
			(xy 268.805281 -308.433538) (xy 268.778978 -308.391942) (xy 268.759687 -308.346666) (xy 268.74791 -308.298882)
			(xy 268.74395 -308.249828) (xy 248.77707 -308.249828) (xy 248.790385 -308.257954) (xy 248.833281 -308.293653)
			(xy 248.870523 -308.335217) (xy 248.901317 -308.381761) (xy 248.925005 -308.432292) (xy 248.941083 -308.485734)
			(xy 248.949209 -308.540948) (xy 248.949718 -308.568852) (xy 248.949209 -308.596756) (xy 248.941083 -308.65197)
			(xy 248.928951 -308.692296) (xy 462.556604 -308.692296) (xy 462.560677 -308.636637) (xy 462.572812 -308.582164)
			(xy 462.592748 -308.530038) (xy 462.620062 -308.48137) (xy 462.65417 -308.437198) (xy 462.694347 -308.398463)
			(xy 462.739735 -308.365991) (xy 462.789367 -308.340473) (xy 462.842187 -308.322454) (xy 462.897066 -308.312317)
			(xy 462.952837 -308.310279) (xy 463.008311 -308.316382) (xy 463.062304 -308.330498) (xy 463.113667 -308.352325)
			(xy 463.161305 -308.381398) (xy 463.204201 -308.417097) (xy 463.241443 -308.458661) (xy 463.272237 -308.505205)
			(xy 463.295925 -308.555736) (xy 463.312003 -308.609178) (xy 463.320129 -308.664392) (xy 463.320638 -308.692296)
			(xy 463.320129 -308.7202) (xy 463.312003 -308.775414) (xy 463.295925 -308.828856) (xy 463.272237 -308.879387)
			(xy 463.241443 -308.925931) (xy 463.204201 -308.967495) (xy 463.161305 -309.003194) (xy 463.113667 -309.032267)
			(xy 463.062304 -309.054094) (xy 463.008311 -309.06821) (xy 462.952837 -309.074313) (xy 462.897066 -309.072275)
			(xy 462.842187 -309.062138) (xy 462.789367 -309.044119) (xy 462.739735 -309.018601) (xy 462.694347 -308.986129)
			(xy 462.65417 -308.947394) (xy 462.620062 -308.903222) (xy 462.592748 -308.854554) (xy 462.572812 -308.802428)
			(xy 462.560677 -308.747955) (xy 462.556604 -308.692296) (xy 248.928951 -308.692296) (xy 248.925005 -308.705412)
			(xy 248.901317 -308.755943) (xy 248.870523 -308.802487) (xy 248.833281 -308.844051) (xy 248.790385 -308.87975)
			(xy 248.742747 -308.908823) (xy 248.691384 -308.93065) (xy 248.637391 -308.944766) (xy 248.581917 -308.950869)
			(xy 248.526146 -308.948831) (xy 248.471267 -308.938694) (xy 248.418447 -308.920675) (xy 248.368815 -308.895157)
			(xy 248.323427 -308.862685) (xy 248.28325 -308.82395) (xy 248.249142 -308.779778) (xy 248.221828 -308.73111)
			(xy 248.201892 -308.678984) (xy 248.189757 -308.624511) (xy 248.185684 -308.568852) (xy 232.69956 -308.568852)
			(xy 232.699051 -308.596756) (xy 232.690925 -308.65197) (xy 232.674847 -308.705412) (xy 232.651159 -308.755943)
			(xy 232.620365 -308.802487) (xy 232.583123 -308.844051) (xy 232.540227 -308.87975) (xy 232.492589 -308.908823)
			(xy 232.441226 -308.93065) (xy 232.387233 -308.944766) (xy 232.331759 -308.950869) (xy 232.275988 -308.948831)
			(xy 232.221109 -308.938694) (xy 232.168289 -308.920675) (xy 232.118657 -308.895157) (xy 232.073269 -308.862685)
			(xy 232.033092 -308.82395) (xy 231.998984 -308.779778) (xy 231.97167 -308.73111) (xy 231.951734 -308.678984)
			(xy 231.939599 -308.624511) (xy 231.935526 -308.568852) (xy 0.509016 -308.568852) (xy 0.509016 -309.199788)
			(xy 38.444182 -309.199788) (xy 38.448142 -309.150734) (xy 38.459919 -309.10295) (xy 38.47921 -309.057674)
			(xy 38.505513 -309.016078) (xy 38.538148 -308.979241) (xy 38.576269 -308.948116) (xy 38.61889 -308.923509)
			(xy 38.664906 -308.906057) (xy 38.713125 -308.896213) (xy 38.7623 -308.894232) (xy 38.811155 -308.900164)
			(xy 38.858426 -308.913856) (xy 38.902888 -308.934954) (xy 38.943391 -308.96291) (xy 38.978884 -308.997002)
			(xy 39.008449 -309.036346) (xy 39.03132 -309.079923) (xy 39.046904 -309.126604) (xy 39.054799 -309.175181)
			(xy 39.055294 -309.199788) (xy 39.394142 -309.199788) (xy 39.398102 -309.150734) (xy 39.409879 -309.10295)
			(xy 39.42917 -309.057674) (xy 39.455473 -309.016078) (xy 39.488108 -308.979241) (xy 39.526229 -308.948116)
			(xy 39.56885 -308.923509) (xy 39.614866 -308.906057) (xy 39.663085 -308.896213) (xy 39.71226 -308.894232)
			(xy 39.761115 -308.900164) (xy 39.808386 -308.913856) (xy 39.852848 -308.934954) (xy 39.893351 -308.96291)
			(xy 39.928844 -308.997002) (xy 39.958409 -309.036346) (xy 39.98128 -309.079923) (xy 39.996864 -309.126604)
			(xy 40.004759 -309.175181) (xy 40.005254 -309.199788) (xy 41.294062 -309.199788) (xy 41.298022 -309.150734)
			(xy 41.309799 -309.10295) (xy 41.32909 -309.057674) (xy 41.355393 -309.016078) (xy 41.388028 -308.979241)
			(xy 41.426149 -308.948116) (xy 41.46877 -308.923509) (xy 41.514786 -308.906057) (xy 41.563005 -308.896213)
			(xy 41.61218 -308.894232) (xy 41.661035 -308.900164) (xy 41.708306 -308.913856) (xy 41.752768 -308.934954)
			(xy 41.793271 -308.96291) (xy 41.828764 -308.997002) (xy 41.858329 -309.036346) (xy 41.8812 -309.079923)
			(xy 41.896784 -309.126604) (xy 41.904679 -309.175181) (xy 41.905174 -309.199788) (xy 42.244022 -309.199788)
			(xy 42.247982 -309.150734) (xy 42.259759 -309.10295) (xy 42.27905 -309.057674) (xy 42.305353 -309.016078)
			(xy 42.337988 -308.979241) (xy 42.376109 -308.948116) (xy 42.41873 -308.923509) (xy 42.464746 -308.906057)
			(xy 42.512965 -308.896213) (xy 42.56214 -308.894232) (xy 42.610995 -308.900164) (xy 42.658266 -308.913856)
			(xy 42.702728 -308.934954) (xy 42.743231 -308.96291) (xy 42.778724 -308.997002) (xy 42.808289 -309.036346)
			(xy 42.83116 -309.079923) (xy 42.846744 -309.126604) (xy 42.854639 -309.175181) (xy 42.855134 -309.199788)
			(xy 76.444106 -309.199788) (xy 76.448066 -309.150734) (xy 76.459843 -309.10295) (xy 76.479134 -309.057674)
			(xy 76.505437 -309.016078) (xy 76.538072 -308.979241) (xy 76.576193 -308.948116) (xy 76.618814 -308.923509)
			(xy 76.66483 -308.906057) (xy 76.713049 -308.896213) (xy 76.762224 -308.894232) (xy 76.811079 -308.900164)
			(xy 76.85835 -308.913856) (xy 76.902812 -308.934954) (xy 76.943315 -308.96291) (xy 76.978808 -308.997002)
			(xy 77.008373 -309.036346) (xy 77.031244 -309.079923) (xy 77.046828 -309.126604) (xy 77.054723 -309.175181)
			(xy 77.055218 -309.199788) (xy 77.394066 -309.199788) (xy 77.398026 -309.150734) (xy 77.409803 -309.10295)
			(xy 77.429094 -309.057674) (xy 77.455397 -309.016078) (xy 77.488032 -308.979241) (xy 77.526153 -308.948116)
			(xy 77.568774 -308.923509) (xy 77.61479 -308.906057) (xy 77.663009 -308.896213) (xy 77.712184 -308.894232)
			(xy 77.761039 -308.900164) (xy 77.80831 -308.913856) (xy 77.852772 -308.934954) (xy 77.893275 -308.96291)
			(xy 77.928768 -308.997002) (xy 77.958333 -309.036346) (xy 77.981204 -309.079923) (xy 77.996788 -309.126604)
			(xy 78.004683 -309.175181) (xy 78.005178 -309.199788) (xy 79.293986 -309.199788) (xy 79.297946 -309.150734)
			(xy 79.309723 -309.10295) (xy 79.329014 -309.057674) (xy 79.355317 -309.016078) (xy 79.387952 -308.979241)
			(xy 79.426073 -308.948116) (xy 79.468694 -308.923509) (xy 79.51471 -308.906057) (xy 79.562929 -308.896213)
			(xy 79.612104 -308.894232) (xy 79.660959 -308.900164) (xy 79.70823 -308.913856) (xy 79.752692 -308.934954)
			(xy 79.793195 -308.96291) (xy 79.828688 -308.997002) (xy 79.858253 -309.036346) (xy 79.881124 -309.079923)
			(xy 79.896708 -309.126604) (xy 79.904603 -309.175181) (xy 79.905098 -309.199788) (xy 80.243946 -309.199788)
			(xy 80.247906 -309.150734) (xy 80.259683 -309.10295) (xy 80.278974 -309.057674) (xy 80.305277 -309.016078)
			(xy 80.337912 -308.979241) (xy 80.376033 -308.948116) (xy 80.418654 -308.923509) (xy 80.46467 -308.906057)
			(xy 80.512889 -308.896213) (xy 80.562064 -308.894232) (xy 80.610919 -308.900164) (xy 80.65819 -308.913856)
			(xy 80.702652 -308.934954) (xy 80.743155 -308.96291) (xy 80.778648 -308.997002) (xy 80.808213 -309.036346)
			(xy 80.831084 -309.079923) (xy 80.846668 -309.126604) (xy 80.854563 -309.175181) (xy 80.855058 -309.199788)
			(xy 154.54428 -309.199788) (xy 154.54824 -309.150734) (xy 154.560017 -309.10295) (xy 154.579308 -309.057674)
			(xy 154.605611 -309.016078) (xy 154.638246 -308.979241) (xy 154.676367 -308.948116) (xy 154.718988 -308.923509)
			(xy 154.765004 -308.906057) (xy 154.813223 -308.896213) (xy 154.862398 -308.894232) (xy 154.911253 -308.900164)
			(xy 154.958524 -308.913856) (xy 155.002986 -308.934954) (xy 155.043489 -308.96291) (xy 155.078982 -308.997002)
			(xy 155.108547 -309.036346) (xy 155.131418 -309.079923) (xy 155.147002 -309.126604) (xy 155.154897 -309.175181)
			(xy 155.155392 -309.199788) (xy 155.49424 -309.199788) (xy 155.4982 -309.150734) (xy 155.509977 -309.10295)
			(xy 155.529268 -309.057674) (xy 155.555571 -309.016078) (xy 155.588206 -308.979241) (xy 155.626327 -308.948116)
			(xy 155.668948 -308.923509) (xy 155.714964 -308.906057) (xy 155.763183 -308.896213) (xy 155.812358 -308.894232)
			(xy 155.861213 -308.900164) (xy 155.908484 -308.913856) (xy 155.952946 -308.934954) (xy 155.993449 -308.96291)
			(xy 156.028942 -308.997002) (xy 156.058507 -309.036346) (xy 156.081378 -309.079923) (xy 156.096962 -309.126604)
			(xy 156.104857 -309.175181) (xy 156.105352 -309.199788) (xy 157.39416 -309.199788) (xy 157.39812 -309.150734)
			(xy 157.409897 -309.10295) (xy 157.429188 -309.057674) (xy 157.455491 -309.016078) (xy 157.488126 -308.979241)
			(xy 157.526247 -308.948116) (xy 157.568868 -308.923509) (xy 157.614884 -308.906057) (xy 157.663103 -308.896213)
			(xy 157.712278 -308.894232) (xy 157.761133 -308.900164) (xy 157.808404 -308.913856) (xy 157.852866 -308.934954)
			(xy 157.893369 -308.96291) (xy 157.928862 -308.997002) (xy 157.958427 -309.036346) (xy 157.981298 -309.079923)
			(xy 157.996882 -309.126604) (xy 158.004777 -309.175181) (xy 158.005272 -309.199788) (xy 158.34412 -309.199788)
			(xy 158.34808 -309.150734) (xy 158.359857 -309.10295) (xy 158.379148 -309.057674) (xy 158.405451 -309.016078)
			(xy 158.438086 -308.979241) (xy 158.476207 -308.948116) (xy 158.518828 -308.923509) (xy 158.564844 -308.906057)
			(xy 158.613063 -308.896213) (xy 158.662238 -308.894232) (xy 158.711093 -308.900164) (xy 158.758364 -308.913856)
			(xy 158.802826 -308.934954) (xy 158.843329 -308.96291) (xy 158.878822 -308.997002) (xy 158.908387 -309.036346)
			(xy 158.931258 -309.079923) (xy 158.946842 -309.126604) (xy 158.954737 -309.175181) (xy 158.955232 -309.199788)
			(xy 192.544204 -309.199788) (xy 192.548164 -309.150734) (xy 192.559941 -309.10295) (xy 192.579232 -309.057674)
			(xy 192.605535 -309.016078) (xy 192.63817 -308.979241) (xy 192.676291 -308.948116) (xy 192.718912 -308.923509)
			(xy 192.764928 -308.906057) (xy 192.813147 -308.896213) (xy 192.862322 -308.894232) (xy 192.911177 -308.900164)
			(xy 192.958448 -308.913856) (xy 193.00291 -308.934954) (xy 193.043413 -308.96291) (xy 193.078906 -308.997002)
			(xy 193.108471 -309.036346) (xy 193.131342 -309.079923) (xy 193.146926 -309.126604) (xy 193.154821 -309.175181)
			(xy 193.155316 -309.199788) (xy 193.494164 -309.199788) (xy 193.498124 -309.150734) (xy 193.509901 -309.10295)
			(xy 193.529192 -309.057674) (xy 193.555495 -309.016078) (xy 193.58813 -308.979241) (xy 193.626251 -308.948116)
			(xy 193.668872 -308.923509) (xy 193.714888 -308.906057) (xy 193.763107 -308.896213) (xy 193.812282 -308.894232)
			(xy 193.861137 -308.900164) (xy 193.908408 -308.913856) (xy 193.95287 -308.934954) (xy 193.993373 -308.96291)
			(xy 194.028866 -308.997002) (xy 194.058431 -309.036346) (xy 194.081302 -309.079923) (xy 194.096886 -309.126604)
			(xy 194.104781 -309.175181) (xy 194.105276 -309.199788) (xy 195.394084 -309.199788) (xy 195.398044 -309.150734)
			(xy 195.409821 -309.10295) (xy 195.429112 -309.057674) (xy 195.455415 -309.016078) (xy 195.48805 -308.979241)
			(xy 195.526171 -308.948116) (xy 195.568792 -308.923509) (xy 195.614808 -308.906057) (xy 195.663027 -308.896213)
			(xy 195.712202 -308.894232) (xy 195.761057 -308.900164) (xy 195.808328 -308.913856) (xy 195.85279 -308.934954)
			(xy 195.893293 -308.96291) (xy 195.928786 -308.997002) (xy 195.958351 -309.036346) (xy 195.981222 -309.079923)
			(xy 195.996806 -309.126604) (xy 196.004701 -309.175181) (xy 196.005196 -309.199788) (xy 196.344044 -309.199788)
			(xy 196.348004 -309.150734) (xy 196.359781 -309.10295) (xy 196.379072 -309.057674) (xy 196.405375 -309.016078)
			(xy 196.43801 -308.979241) (xy 196.476131 -308.948116) (xy 196.518752 -308.923509) (xy 196.564768 -308.906057)
			(xy 196.612987 -308.896213) (xy 196.662162 -308.894232) (xy 196.711017 -308.900164) (xy 196.758288 -308.913856)
			(xy 196.80275 -308.934954) (xy 196.843253 -308.96291) (xy 196.878746 -308.997002) (xy 196.908311 -309.036346)
			(xy 196.931182 -309.079923) (xy 196.946766 -309.126604) (xy 196.954661 -309.175181) (xy 196.955156 -309.199788)
			(xy 270.644124 -309.199788) (xy 270.648084 -309.150734) (xy 270.659861 -309.10295) (xy 270.679152 -309.057674)
			(xy 270.705455 -309.016078) (xy 270.73809 -308.979241) (xy 270.776211 -308.948116) (xy 270.818832 -308.923509)
			(xy 270.864848 -308.906057) (xy 270.913067 -308.896213) (xy 270.962242 -308.894232) (xy 271.011097 -308.900164)
			(xy 271.058368 -308.913856) (xy 271.10283 -308.934954) (xy 271.143333 -308.96291) (xy 271.178826 -308.997002)
			(xy 271.208391 -309.036346) (xy 271.231262 -309.079923) (xy 271.246846 -309.126604) (xy 271.254741 -309.175181)
			(xy 271.255236 -309.199788) (xy 271.594084 -309.199788) (xy 271.598044 -309.150734) (xy 271.609821 -309.10295)
			(xy 271.629112 -309.057674) (xy 271.655415 -309.016078) (xy 271.68805 -308.979241) (xy 271.726171 -308.948116)
			(xy 271.768792 -308.923509) (xy 271.814808 -308.906057) (xy 271.863027 -308.896213) (xy 271.912202 -308.894232)
			(xy 271.961057 -308.900164) (xy 272.008328 -308.913856) (xy 272.05279 -308.934954) (xy 272.093293 -308.96291)
			(xy 272.128786 -308.997002) (xy 272.158351 -309.036346) (xy 272.181222 -309.079923) (xy 272.196806 -309.126604)
			(xy 272.204701 -309.175181) (xy 272.205196 -309.199788) (xy 273.494004 -309.199788) (xy 273.497964 -309.150734)
			(xy 273.509741 -309.10295) (xy 273.529032 -309.057674) (xy 273.555335 -309.016078) (xy 273.58797 -308.979241)
			(xy 273.626091 -308.948116) (xy 273.668712 -308.923509) (xy 273.714728 -308.906057) (xy 273.762947 -308.896213)
			(xy 273.812122 -308.894232) (xy 273.860977 -308.900164) (xy 273.908248 -308.913856) (xy 273.95271 -308.934954)
			(xy 273.993213 -308.96291) (xy 274.028706 -308.997002) (xy 274.058271 -309.036346) (xy 274.081142 -309.079923)
			(xy 274.096726 -309.126604) (xy 274.104621 -309.175181) (xy 274.105116 -309.199788) (xy 274.443964 -309.199788)
			(xy 274.447924 -309.150734) (xy 274.459701 -309.10295) (xy 274.478992 -309.057674) (xy 274.505295 -309.016078)
			(xy 274.53793 -308.979241) (xy 274.576051 -308.948116) (xy 274.618672 -308.923509) (xy 274.664688 -308.906057)
			(xy 274.712907 -308.896213) (xy 274.762082 -308.894232) (xy 274.810937 -308.900164) (xy 274.858208 -308.913856)
			(xy 274.90267 -308.934954) (xy 274.943173 -308.96291) (xy 274.978666 -308.997002) (xy 275.008231 -309.036346)
			(xy 275.031102 -309.079923) (xy 275.046686 -309.126604) (xy 275.054581 -309.175181) (xy 275.055076 -309.199788)
			(xy 308.644048 -309.199788) (xy 308.648008 -309.150734) (xy 308.659785 -309.10295) (xy 308.679076 -309.057674)
			(xy 308.705379 -309.016078) (xy 308.738014 -308.979241) (xy 308.776135 -308.948116) (xy 308.818756 -308.923509)
			(xy 308.864772 -308.906057) (xy 308.912991 -308.896213) (xy 308.962166 -308.894232) (xy 309.011021 -308.900164)
			(xy 309.058292 -308.913856) (xy 309.102754 -308.934954) (xy 309.143257 -308.96291) (xy 309.17875 -308.997002)
			(xy 309.208315 -309.036346) (xy 309.231186 -309.079923) (xy 309.24677 -309.126604) (xy 309.254665 -309.175181)
			(xy 309.25516 -309.199788) (xy 309.594008 -309.199788) (xy 309.597968 -309.150734) (xy 309.609745 -309.10295)
			(xy 309.629036 -309.057674) (xy 309.655339 -309.016078) (xy 309.687974 -308.979241) (xy 309.726095 -308.948116)
			(xy 309.768716 -308.923509) (xy 309.814732 -308.906057) (xy 309.862951 -308.896213) (xy 309.912126 -308.894232)
			(xy 309.960981 -308.900164) (xy 310.008252 -308.913856) (xy 310.052714 -308.934954) (xy 310.093217 -308.96291)
			(xy 310.12871 -308.997002) (xy 310.158275 -309.036346) (xy 310.181146 -309.079923) (xy 310.19673 -309.126604)
			(xy 310.204625 -309.175181) (xy 310.20512 -309.199788) (xy 311.493928 -309.199788) (xy 311.497888 -309.150734)
			(xy 311.509665 -309.10295) (xy 311.528956 -309.057674) (xy 311.555259 -309.016078) (xy 311.587894 -308.979241)
			(xy 311.626015 -308.948116) (xy 311.668636 -308.923509) (xy 311.714652 -308.906057) (xy 311.762871 -308.896213)
			(xy 311.812046 -308.894232) (xy 311.860901 -308.900164) (xy 311.908172 -308.913856) (xy 311.952634 -308.934954)
			(xy 311.993137 -308.96291) (xy 312.02863 -308.997002) (xy 312.058195 -309.036346) (xy 312.081066 -309.079923)
			(xy 312.09665 -309.126604) (xy 312.104545 -309.175181) (xy 312.10504 -309.199788) (xy 312.443888 -309.199788)
			(xy 312.447848 -309.150734) (xy 312.459625 -309.10295) (xy 312.478916 -309.057674) (xy 312.505219 -309.016078)
			(xy 312.537854 -308.979241) (xy 312.575975 -308.948116) (xy 312.618596 -308.923509) (xy 312.664612 -308.906057)
			(xy 312.712831 -308.896213) (xy 312.762006 -308.894232) (xy 312.810861 -308.900164) (xy 312.858132 -308.913856)
			(xy 312.902594 -308.934954) (xy 312.943097 -308.96291) (xy 312.97859 -308.997002) (xy 313.008155 -309.036346)
			(xy 313.031026 -309.079923) (xy 313.04661 -309.126604) (xy 313.054505 -309.175181) (xy 313.055 -309.199788)
			(xy 386.744222 -309.199788) (xy 386.748182 -309.150734) (xy 386.759959 -309.10295) (xy 386.77925 -309.057674)
			(xy 386.805553 -309.016078) (xy 386.838188 -308.979241) (xy 386.876309 -308.948116) (xy 386.91893 -308.923509)
			(xy 386.964946 -308.906057) (xy 387.013165 -308.896213) (xy 387.06234 -308.894232) (xy 387.111195 -308.900164)
			(xy 387.158466 -308.913856) (xy 387.202928 -308.934954) (xy 387.243431 -308.96291) (xy 387.278924 -308.997002)
			(xy 387.308489 -309.036346) (xy 387.33136 -309.079923) (xy 387.346944 -309.126604) (xy 387.354839 -309.175181)
			(xy 387.355334 -309.199788) (xy 387.694182 -309.199788) (xy 387.698142 -309.150734) (xy 387.709919 -309.10295)
			(xy 387.72921 -309.057674) (xy 387.755513 -309.016078) (xy 387.788148 -308.979241) (xy 387.826269 -308.948116)
			(xy 387.86889 -308.923509) (xy 387.914906 -308.906057) (xy 387.963125 -308.896213) (xy 388.0123 -308.894232)
			(xy 388.061155 -308.900164) (xy 388.108426 -308.913856) (xy 388.152888 -308.934954) (xy 388.193391 -308.96291)
			(xy 388.228884 -308.997002) (xy 388.258449 -309.036346) (xy 388.28132 -309.079923) (xy 388.296904 -309.126604)
			(xy 388.304799 -309.175181) (xy 388.305294 -309.199788) (xy 389.594102 -309.199788) (xy 389.598062 -309.150734)
			(xy 389.609839 -309.10295) (xy 389.62913 -309.057674) (xy 389.655433 -309.016078) (xy 389.688068 -308.979241)
			(xy 389.726189 -308.948116) (xy 389.76881 -308.923509) (xy 389.814826 -308.906057) (xy 389.863045 -308.896213)
			(xy 389.91222 -308.894232) (xy 389.961075 -308.900164) (xy 390.008346 -308.913856) (xy 390.052808 -308.934954)
			(xy 390.093311 -308.96291) (xy 390.128804 -308.997002) (xy 390.158369 -309.036346) (xy 390.18124 -309.079923)
			(xy 390.196824 -309.126604) (xy 390.204719 -309.175181) (xy 390.205214 -309.199788) (xy 390.544062 -309.199788)
			(xy 390.548022 -309.150734) (xy 390.559799 -309.10295) (xy 390.57909 -309.057674) (xy 390.605393 -309.016078)
			(xy 390.638028 -308.979241) (xy 390.676149 -308.948116) (xy 390.71877 -308.923509) (xy 390.764786 -308.906057)
			(xy 390.813005 -308.896213) (xy 390.86218 -308.894232) (xy 390.911035 -308.900164) (xy 390.958306 -308.913856)
			(xy 391.002768 -308.934954) (xy 391.043271 -308.96291) (xy 391.078764 -308.997002) (xy 391.108329 -309.036346)
			(xy 391.1312 -309.079923) (xy 391.146784 -309.126604) (xy 391.154679 -309.175181) (xy 391.155174 -309.199788)
			(xy 424.744146 -309.199788) (xy 424.748106 -309.150734) (xy 424.759883 -309.10295) (xy 424.779174 -309.057674)
			(xy 424.805477 -309.016078) (xy 424.838112 -308.979241) (xy 424.876233 -308.948116) (xy 424.918854 -308.923509)
			(xy 424.96487 -308.906057) (xy 425.013089 -308.896213) (xy 425.062264 -308.894232) (xy 425.111119 -308.900164)
			(xy 425.15839 -308.913856) (xy 425.202852 -308.934954) (xy 425.243355 -308.96291) (xy 425.278848 -308.997002)
			(xy 425.308413 -309.036346) (xy 425.331284 -309.079923) (xy 425.346868 -309.126604) (xy 425.354763 -309.175181)
			(xy 425.355258 -309.199788) (xy 425.694106 -309.199788) (xy 425.698066 -309.150734) (xy 425.709843 -309.10295)
			(xy 425.729134 -309.057674) (xy 425.755437 -309.016078) (xy 425.788072 -308.979241) (xy 425.826193 -308.948116)
			(xy 425.868814 -308.923509) (xy 425.91483 -308.906057) (xy 425.963049 -308.896213) (xy 426.012224 -308.894232)
			(xy 426.061079 -308.900164) (xy 426.10835 -308.913856) (xy 426.152812 -308.934954) (xy 426.193315 -308.96291)
			(xy 426.228808 -308.997002) (xy 426.258373 -309.036346) (xy 426.281244 -309.079923) (xy 426.296828 -309.126604)
			(xy 426.304723 -309.175181) (xy 426.305218 -309.199788) (xy 427.594026 -309.199788) (xy 427.597986 -309.150734)
			(xy 427.609763 -309.10295) (xy 427.629054 -309.057674) (xy 427.655357 -309.016078) (xy 427.687992 -308.979241)
			(xy 427.726113 -308.948116) (xy 427.768734 -308.923509) (xy 427.81475 -308.906057) (xy 427.862969 -308.896213)
			(xy 427.912144 -308.894232) (xy 427.960999 -308.900164) (xy 428.00827 -308.913856) (xy 428.052732 -308.934954)
			(xy 428.093235 -308.96291) (xy 428.128728 -308.997002) (xy 428.158293 -309.036346) (xy 428.181164 -309.079923)
			(xy 428.196748 -309.126604) (xy 428.204643 -309.175181) (xy 428.205138 -309.199788) (xy 428.543986 -309.199788)
			(xy 428.547946 -309.150734) (xy 428.559723 -309.10295) (xy 428.579014 -309.057674) (xy 428.605317 -309.016078)
			(xy 428.637952 -308.979241) (xy 428.676073 -308.948116) (xy 428.718694 -308.923509) (xy 428.76471 -308.906057)
			(xy 428.812929 -308.896213) (xy 428.862104 -308.894232) (xy 428.910959 -308.900164) (xy 428.95823 -308.913856)
			(xy 429.002692 -308.934954) (xy 429.043195 -308.96291) (xy 429.078688 -308.997002) (xy 429.108253 -309.036346)
			(xy 429.131124 -309.079923) (xy 429.146708 -309.126604) (xy 429.154603 -309.175181) (xy 429.155098 -309.199788)
			(xy 429.154603 -309.224395) (xy 429.146708 -309.272972) (xy 429.131124 -309.319653) (xy 429.108253 -309.36323)
			(xy 429.078688 -309.402574) (xy 429.043195 -309.436666) (xy 429.002692 -309.464622) (xy 428.95823 -309.48572)
			(xy 428.910959 -309.499412) (xy 428.862104 -309.505344) (xy 428.812929 -309.503363) (xy 428.76471 -309.493519)
			(xy 428.718694 -309.476067) (xy 428.676073 -309.45146) (xy 428.637952 -309.420335) (xy 428.605317 -309.383498)
			(xy 428.579014 -309.341902) (xy 428.559723 -309.296626) (xy 428.547946 -309.248842) (xy 428.543986 -309.199788)
			(xy 428.205138 -309.199788) (xy 428.204643 -309.224395) (xy 428.196748 -309.272972) (xy 428.181164 -309.319653)
			(xy 428.158293 -309.36323) (xy 428.128728 -309.402574) (xy 428.093235 -309.436666) (xy 428.052732 -309.464622)
			(xy 428.00827 -309.48572) (xy 427.960999 -309.499412) (xy 427.912144 -309.505344) (xy 427.862969 -309.503363)
			(xy 427.81475 -309.493519) (xy 427.768734 -309.476067) (xy 427.726113 -309.45146) (xy 427.687992 -309.420335)
			(xy 427.655357 -309.383498) (xy 427.629054 -309.341902) (xy 427.609763 -309.296626) (xy 427.597986 -309.248842)
			(xy 427.594026 -309.199788) (xy 426.305218 -309.199788) (xy 426.304723 -309.224395) (xy 426.296828 -309.272972)
			(xy 426.281244 -309.319653) (xy 426.258373 -309.36323) (xy 426.228808 -309.402574) (xy 426.193315 -309.436666)
			(xy 426.152812 -309.464622) (xy 426.10835 -309.48572) (xy 426.061079 -309.499412) (xy 426.012224 -309.505344)
			(xy 425.963049 -309.503363) (xy 425.91483 -309.493519) (xy 425.868814 -309.476067) (xy 425.826193 -309.45146)
			(xy 425.788072 -309.420335) (xy 425.755437 -309.383498) (xy 425.729134 -309.341902) (xy 425.709843 -309.296626)
			(xy 425.698066 -309.248842) (xy 425.694106 -309.199788) (xy 425.355258 -309.199788) (xy 425.354763 -309.224395)
			(xy 425.346868 -309.272972) (xy 425.331284 -309.319653) (xy 425.308413 -309.36323) (xy 425.278848 -309.402574)
			(xy 425.243355 -309.436666) (xy 425.202852 -309.464622) (xy 425.15839 -309.48572) (xy 425.111119 -309.499412)
			(xy 425.062264 -309.505344) (xy 425.013089 -309.503363) (xy 424.96487 -309.493519) (xy 424.918854 -309.476067)
			(xy 424.876233 -309.45146) (xy 424.838112 -309.420335) (xy 424.805477 -309.383498) (xy 424.779174 -309.341902)
			(xy 424.759883 -309.296626) (xy 424.748106 -309.248842) (xy 424.744146 -309.199788) (xy 391.155174 -309.199788)
			(xy 391.154679 -309.224395) (xy 391.146784 -309.272972) (xy 391.1312 -309.319653) (xy 391.108329 -309.36323)
			(xy 391.078764 -309.402574) (xy 391.043271 -309.436666) (xy 391.002768 -309.464622) (xy 390.958306 -309.48572)
			(xy 390.911035 -309.499412) (xy 390.86218 -309.505344) (xy 390.813005 -309.503363) (xy 390.764786 -309.493519)
			(xy 390.71877 -309.476067) (xy 390.676149 -309.45146) (xy 390.638028 -309.420335) (xy 390.605393 -309.383498)
			(xy 390.57909 -309.341902) (xy 390.559799 -309.296626) (xy 390.548022 -309.248842) (xy 390.544062 -309.199788)
			(xy 390.205214 -309.199788) (xy 390.204719 -309.224395) (xy 390.196824 -309.272972) (xy 390.18124 -309.319653)
			(xy 390.158369 -309.36323) (xy 390.128804 -309.402574) (xy 390.093311 -309.436666) (xy 390.052808 -309.464622)
			(xy 390.008346 -309.48572) (xy 389.961075 -309.499412) (xy 389.91222 -309.505344) (xy 389.863045 -309.503363)
			(xy 389.814826 -309.493519) (xy 389.76881 -309.476067) (xy 389.726189 -309.45146) (xy 389.688068 -309.420335)
			(xy 389.655433 -309.383498) (xy 389.62913 -309.341902) (xy 389.609839 -309.296626) (xy 389.598062 -309.248842)
			(xy 389.594102 -309.199788) (xy 388.305294 -309.199788) (xy 388.304799 -309.224395) (xy 388.296904 -309.272972)
			(xy 388.28132 -309.319653) (xy 388.258449 -309.36323) (xy 388.228884 -309.402574) (xy 388.193391 -309.436666)
			(xy 388.152888 -309.464622) (xy 388.108426 -309.48572) (xy 388.061155 -309.499412) (xy 388.0123 -309.505344)
			(xy 387.963125 -309.503363) (xy 387.914906 -309.493519) (xy 387.86889 -309.476067) (xy 387.826269 -309.45146)
			(xy 387.788148 -309.420335) (xy 387.755513 -309.383498) (xy 387.72921 -309.341902) (xy 387.709919 -309.296626)
			(xy 387.698142 -309.248842) (xy 387.694182 -309.199788) (xy 387.355334 -309.199788) (xy 387.354839 -309.224395)
			(xy 387.346944 -309.272972) (xy 387.33136 -309.319653) (xy 387.308489 -309.36323) (xy 387.278924 -309.402574)
			(xy 387.243431 -309.436666) (xy 387.202928 -309.464622) (xy 387.158466 -309.48572) (xy 387.111195 -309.499412)
			(xy 387.06234 -309.505344) (xy 387.013165 -309.503363) (xy 386.964946 -309.493519) (xy 386.91893 -309.476067)
			(xy 386.876309 -309.45146) (xy 386.838188 -309.420335) (xy 386.805553 -309.383498) (xy 386.77925 -309.341902)
			(xy 386.759959 -309.296626) (xy 386.748182 -309.248842) (xy 386.744222 -309.199788) (xy 313.055 -309.199788)
			(xy 313.054505 -309.224395) (xy 313.04661 -309.272972) (xy 313.031026 -309.319653) (xy 313.008155 -309.36323)
			(xy 312.97859 -309.402574) (xy 312.943097 -309.436666) (xy 312.902594 -309.464622) (xy 312.858132 -309.48572)
			(xy 312.810861 -309.499412) (xy 312.762006 -309.505344) (xy 312.712831 -309.503363) (xy 312.664612 -309.493519)
			(xy 312.618596 -309.476067) (xy 312.575975 -309.45146) (xy 312.537854 -309.420335) (xy 312.505219 -309.383498)
			(xy 312.478916 -309.341902) (xy 312.459625 -309.296626) (xy 312.447848 -309.248842) (xy 312.443888 -309.199788)
			(xy 312.10504 -309.199788) (xy 312.104545 -309.224395) (xy 312.09665 -309.272972) (xy 312.081066 -309.319653)
			(xy 312.058195 -309.36323) (xy 312.02863 -309.402574) (xy 311.993137 -309.436666) (xy 311.952634 -309.464622)
			(xy 311.908172 -309.48572) (xy 311.860901 -309.499412) (xy 311.812046 -309.505344) (xy 311.762871 -309.503363)
			(xy 311.714652 -309.493519) (xy 311.668636 -309.476067) (xy 311.626015 -309.45146) (xy 311.587894 -309.420335)
			(xy 311.555259 -309.383498) (xy 311.528956 -309.341902) (xy 311.509665 -309.296626) (xy 311.497888 -309.248842)
			(xy 311.493928 -309.199788) (xy 310.20512 -309.199788) (xy 310.204625 -309.224395) (xy 310.19673 -309.272972)
			(xy 310.181146 -309.319653) (xy 310.158275 -309.36323) (xy 310.12871 -309.402574) (xy 310.093217 -309.436666)
			(xy 310.052714 -309.464622) (xy 310.008252 -309.48572) (xy 309.960981 -309.499412) (xy 309.912126 -309.505344)
			(xy 309.862951 -309.503363) (xy 309.814732 -309.493519) (xy 309.768716 -309.476067) (xy 309.726095 -309.45146)
			(xy 309.687974 -309.420335) (xy 309.655339 -309.383498) (xy 309.629036 -309.341902) (xy 309.609745 -309.296626)
			(xy 309.597968 -309.248842) (xy 309.594008 -309.199788) (xy 309.25516 -309.199788) (xy 309.254665 -309.224395)
			(xy 309.24677 -309.272972) (xy 309.231186 -309.319653) (xy 309.208315 -309.36323) (xy 309.17875 -309.402574)
			(xy 309.143257 -309.436666) (xy 309.102754 -309.464622) (xy 309.058292 -309.48572) (xy 309.011021 -309.499412)
			(xy 308.962166 -309.505344) (xy 308.912991 -309.503363) (xy 308.864772 -309.493519) (xy 308.818756 -309.476067)
			(xy 308.776135 -309.45146) (xy 308.738014 -309.420335) (xy 308.705379 -309.383498) (xy 308.679076 -309.341902)
			(xy 308.659785 -309.296626) (xy 308.648008 -309.248842) (xy 308.644048 -309.199788) (xy 275.055076 -309.199788)
			(xy 275.054581 -309.224395) (xy 275.046686 -309.272972) (xy 275.031102 -309.319653) (xy 275.008231 -309.36323)
			(xy 274.978666 -309.402574) (xy 274.943173 -309.436666) (xy 274.90267 -309.464622) (xy 274.858208 -309.48572)
			(xy 274.810937 -309.499412) (xy 274.762082 -309.505344) (xy 274.712907 -309.503363) (xy 274.664688 -309.493519)
			(xy 274.618672 -309.476067) (xy 274.576051 -309.45146) (xy 274.53793 -309.420335) (xy 274.505295 -309.383498)
			(xy 274.478992 -309.341902) (xy 274.459701 -309.296626) (xy 274.447924 -309.248842) (xy 274.443964 -309.199788)
			(xy 274.105116 -309.199788) (xy 274.104621 -309.224395) (xy 274.096726 -309.272972) (xy 274.081142 -309.319653)
			(xy 274.058271 -309.36323) (xy 274.028706 -309.402574) (xy 273.993213 -309.436666) (xy 273.95271 -309.464622)
			(xy 273.908248 -309.48572) (xy 273.860977 -309.499412) (xy 273.812122 -309.505344) (xy 273.762947 -309.503363)
			(xy 273.714728 -309.493519) (xy 273.668712 -309.476067) (xy 273.626091 -309.45146) (xy 273.58797 -309.420335)
			(xy 273.555335 -309.383498) (xy 273.529032 -309.341902) (xy 273.509741 -309.296626) (xy 273.497964 -309.248842)
			(xy 273.494004 -309.199788) (xy 272.205196 -309.199788) (xy 272.204701 -309.224395) (xy 272.196806 -309.272972)
			(xy 272.181222 -309.319653) (xy 272.158351 -309.36323) (xy 272.128786 -309.402574) (xy 272.093293 -309.436666)
			(xy 272.05279 -309.464622) (xy 272.008328 -309.48572) (xy 271.961057 -309.499412) (xy 271.912202 -309.505344)
			(xy 271.863027 -309.503363) (xy 271.814808 -309.493519) (xy 271.768792 -309.476067) (xy 271.726171 -309.45146)
			(xy 271.68805 -309.420335) (xy 271.655415 -309.383498) (xy 271.629112 -309.341902) (xy 271.609821 -309.296626)
			(xy 271.598044 -309.248842) (xy 271.594084 -309.199788) (xy 271.255236 -309.199788) (xy 271.254741 -309.224395)
			(xy 271.246846 -309.272972) (xy 271.231262 -309.319653) (xy 271.208391 -309.36323) (xy 271.178826 -309.402574)
			(xy 271.143333 -309.436666) (xy 271.10283 -309.464622) (xy 271.058368 -309.48572) (xy 271.011097 -309.499412)
			(xy 270.962242 -309.505344) (xy 270.913067 -309.503363) (xy 270.864848 -309.493519) (xy 270.818832 -309.476067)
			(xy 270.776211 -309.45146) (xy 270.73809 -309.420335) (xy 270.705455 -309.383498) (xy 270.679152 -309.341902)
			(xy 270.659861 -309.296626) (xy 270.648084 -309.248842) (xy 270.644124 -309.199788) (xy 196.955156 -309.199788)
			(xy 196.954661 -309.224395) (xy 196.946766 -309.272972) (xy 196.931182 -309.319653) (xy 196.908311 -309.36323)
			(xy 196.878746 -309.402574) (xy 196.843253 -309.436666) (xy 196.80275 -309.464622) (xy 196.758288 -309.48572)
			(xy 196.711017 -309.499412) (xy 196.662162 -309.505344) (xy 196.612987 -309.503363) (xy 196.564768 -309.493519)
			(xy 196.518752 -309.476067) (xy 196.476131 -309.45146) (xy 196.43801 -309.420335) (xy 196.405375 -309.383498)
			(xy 196.379072 -309.341902) (xy 196.359781 -309.296626) (xy 196.348004 -309.248842) (xy 196.344044 -309.199788)
			(xy 196.005196 -309.199788) (xy 196.004701 -309.224395) (xy 195.996806 -309.272972) (xy 195.981222 -309.319653)
			(xy 195.958351 -309.36323) (xy 195.928786 -309.402574) (xy 195.893293 -309.436666) (xy 195.85279 -309.464622)
			(xy 195.808328 -309.48572) (xy 195.761057 -309.499412) (xy 195.712202 -309.505344) (xy 195.663027 -309.503363)
			(xy 195.614808 -309.493519) (xy 195.568792 -309.476067) (xy 195.526171 -309.45146) (xy 195.48805 -309.420335)
			(xy 195.455415 -309.383498) (xy 195.429112 -309.341902) (xy 195.409821 -309.296626) (xy 195.398044 -309.248842)
			(xy 195.394084 -309.199788) (xy 194.105276 -309.199788) (xy 194.104781 -309.224395) (xy 194.096886 -309.272972)
			(xy 194.081302 -309.319653) (xy 194.058431 -309.36323) (xy 194.028866 -309.402574) (xy 193.993373 -309.436666)
			(xy 193.95287 -309.464622) (xy 193.908408 -309.48572) (xy 193.861137 -309.499412) (xy 193.812282 -309.505344)
			(xy 193.763107 -309.503363) (xy 193.714888 -309.493519) (xy 193.668872 -309.476067) (xy 193.626251 -309.45146)
			(xy 193.58813 -309.420335) (xy 193.555495 -309.383498) (xy 193.529192 -309.341902) (xy 193.509901 -309.296626)
			(xy 193.498124 -309.248842) (xy 193.494164 -309.199788) (xy 193.155316 -309.199788) (xy 193.154821 -309.224395)
			(xy 193.146926 -309.272972) (xy 193.131342 -309.319653) (xy 193.108471 -309.36323) (xy 193.078906 -309.402574)
			(xy 193.043413 -309.436666) (xy 193.00291 -309.464622) (xy 192.958448 -309.48572) (xy 192.911177 -309.499412)
			(xy 192.862322 -309.505344) (xy 192.813147 -309.503363) (xy 192.764928 -309.493519) (xy 192.718912 -309.476067)
			(xy 192.676291 -309.45146) (xy 192.63817 -309.420335) (xy 192.605535 -309.383498) (xy 192.579232 -309.341902)
			(xy 192.559941 -309.296626) (xy 192.548164 -309.248842) (xy 192.544204 -309.199788) (xy 158.955232 -309.199788)
			(xy 158.954737 -309.224395) (xy 158.946842 -309.272972) (xy 158.931258 -309.319653) (xy 158.908387 -309.36323)
			(xy 158.878822 -309.402574) (xy 158.843329 -309.436666) (xy 158.802826 -309.464622) (xy 158.758364 -309.48572)
			(xy 158.711093 -309.499412) (xy 158.662238 -309.505344) (xy 158.613063 -309.503363) (xy 158.564844 -309.493519)
			(xy 158.518828 -309.476067) (xy 158.476207 -309.45146) (xy 158.438086 -309.420335) (xy 158.405451 -309.383498)
			(xy 158.379148 -309.341902) (xy 158.359857 -309.296626) (xy 158.34808 -309.248842) (xy 158.34412 -309.199788)
			(xy 158.005272 -309.199788) (xy 158.004777 -309.224395) (xy 157.996882 -309.272972) (xy 157.981298 -309.319653)
			(xy 157.958427 -309.36323) (xy 157.928862 -309.402574) (xy 157.893369 -309.436666) (xy 157.852866 -309.464622)
			(xy 157.808404 -309.48572) (xy 157.761133 -309.499412) (xy 157.712278 -309.505344) (xy 157.663103 -309.503363)
			(xy 157.614884 -309.493519) (xy 157.568868 -309.476067) (xy 157.526247 -309.45146) (xy 157.488126 -309.420335)
			(xy 157.455491 -309.383498) (xy 157.429188 -309.341902) (xy 157.409897 -309.296626) (xy 157.39812 -309.248842)
			(xy 157.39416 -309.199788) (xy 156.105352 -309.199788) (xy 156.104857 -309.224395) (xy 156.096962 -309.272972)
			(xy 156.081378 -309.319653) (xy 156.058507 -309.36323) (xy 156.028942 -309.402574) (xy 155.993449 -309.436666)
			(xy 155.952946 -309.464622) (xy 155.908484 -309.48572) (xy 155.861213 -309.499412) (xy 155.812358 -309.505344)
			(xy 155.763183 -309.503363) (xy 155.714964 -309.493519) (xy 155.668948 -309.476067) (xy 155.626327 -309.45146)
			(xy 155.588206 -309.420335) (xy 155.555571 -309.383498) (xy 155.529268 -309.341902) (xy 155.509977 -309.296626)
			(xy 155.4982 -309.248842) (xy 155.49424 -309.199788) (xy 155.155392 -309.199788) (xy 155.154897 -309.224395)
			(xy 155.147002 -309.272972) (xy 155.131418 -309.319653) (xy 155.108547 -309.36323) (xy 155.078982 -309.402574)
			(xy 155.043489 -309.436666) (xy 155.002986 -309.464622) (xy 154.958524 -309.48572) (xy 154.911253 -309.499412)
			(xy 154.862398 -309.505344) (xy 154.813223 -309.503363) (xy 154.765004 -309.493519) (xy 154.718988 -309.476067)
			(xy 154.676367 -309.45146) (xy 154.638246 -309.420335) (xy 154.605611 -309.383498) (xy 154.579308 -309.341902)
			(xy 154.560017 -309.296626) (xy 154.54824 -309.248842) (xy 154.54428 -309.199788) (xy 80.855058 -309.199788)
			(xy 80.854563 -309.224395) (xy 80.846668 -309.272972) (xy 80.831084 -309.319653) (xy 80.808213 -309.36323)
			(xy 80.778648 -309.402574) (xy 80.743155 -309.436666) (xy 80.702652 -309.464622) (xy 80.65819 -309.48572)
			(xy 80.610919 -309.499412) (xy 80.562064 -309.505344) (xy 80.512889 -309.503363) (xy 80.46467 -309.493519)
			(xy 80.418654 -309.476067) (xy 80.376033 -309.45146) (xy 80.337912 -309.420335) (xy 80.305277 -309.383498)
			(xy 80.278974 -309.341902) (xy 80.259683 -309.296626) (xy 80.247906 -309.248842) (xy 80.243946 -309.199788)
			(xy 79.905098 -309.199788) (xy 79.904603 -309.224395) (xy 79.896708 -309.272972) (xy 79.881124 -309.319653)
			(xy 79.858253 -309.36323) (xy 79.828688 -309.402574) (xy 79.793195 -309.436666) (xy 79.752692 -309.464622)
			(xy 79.70823 -309.48572) (xy 79.660959 -309.499412) (xy 79.612104 -309.505344) (xy 79.562929 -309.503363)
			(xy 79.51471 -309.493519) (xy 79.468694 -309.476067) (xy 79.426073 -309.45146) (xy 79.387952 -309.420335)
			(xy 79.355317 -309.383498) (xy 79.329014 -309.341902) (xy 79.309723 -309.296626) (xy 79.297946 -309.248842)
			(xy 79.293986 -309.199788) (xy 78.005178 -309.199788) (xy 78.004683 -309.224395) (xy 77.996788 -309.272972)
			(xy 77.981204 -309.319653) (xy 77.958333 -309.36323) (xy 77.928768 -309.402574) (xy 77.893275 -309.436666)
			(xy 77.852772 -309.464622) (xy 77.80831 -309.48572) (xy 77.761039 -309.499412) (xy 77.712184 -309.505344)
			(xy 77.663009 -309.503363) (xy 77.61479 -309.493519) (xy 77.568774 -309.476067) (xy 77.526153 -309.45146)
			(xy 77.488032 -309.420335) (xy 77.455397 -309.383498) (xy 77.429094 -309.341902) (xy 77.409803 -309.296626)
			(xy 77.398026 -309.248842) (xy 77.394066 -309.199788) (xy 77.055218 -309.199788) (xy 77.054723 -309.224395)
			(xy 77.046828 -309.272972) (xy 77.031244 -309.319653) (xy 77.008373 -309.36323) (xy 76.978808 -309.402574)
			(xy 76.943315 -309.436666) (xy 76.902812 -309.464622) (xy 76.85835 -309.48572) (xy 76.811079 -309.499412)
			(xy 76.762224 -309.505344) (xy 76.713049 -309.503363) (xy 76.66483 -309.493519) (xy 76.618814 -309.476067)
			(xy 76.576193 -309.45146) (xy 76.538072 -309.420335) (xy 76.505437 -309.383498) (xy 76.479134 -309.341902)
			(xy 76.459843 -309.296626) (xy 76.448066 -309.248842) (xy 76.444106 -309.199788) (xy 42.855134 -309.199788)
			(xy 42.854639 -309.224395) (xy 42.846744 -309.272972) (xy 42.83116 -309.319653) (xy 42.808289 -309.36323)
			(xy 42.778724 -309.402574) (xy 42.743231 -309.436666) (xy 42.702728 -309.464622) (xy 42.658266 -309.48572)
			(xy 42.610995 -309.499412) (xy 42.56214 -309.505344) (xy 42.512965 -309.503363) (xy 42.464746 -309.493519)
			(xy 42.41873 -309.476067) (xy 42.376109 -309.45146) (xy 42.337988 -309.420335) (xy 42.305353 -309.383498)
			(xy 42.27905 -309.341902) (xy 42.259759 -309.296626) (xy 42.247982 -309.248842) (xy 42.244022 -309.199788)
			(xy 41.905174 -309.199788) (xy 41.904679 -309.224395) (xy 41.896784 -309.272972) (xy 41.8812 -309.319653)
			(xy 41.858329 -309.36323) (xy 41.828764 -309.402574) (xy 41.793271 -309.436666) (xy 41.752768 -309.464622)
			(xy 41.708306 -309.48572) (xy 41.661035 -309.499412) (xy 41.61218 -309.505344) (xy 41.563005 -309.503363)
			(xy 41.514786 -309.493519) (xy 41.46877 -309.476067) (xy 41.426149 -309.45146) (xy 41.388028 -309.420335)
			(xy 41.355393 -309.383498) (xy 41.32909 -309.341902) (xy 41.309799 -309.296626) (xy 41.298022 -309.248842)
			(xy 41.294062 -309.199788) (xy 40.005254 -309.199788) (xy 40.004759 -309.224395) (xy 39.996864 -309.272972)
			(xy 39.98128 -309.319653) (xy 39.958409 -309.36323) (xy 39.928844 -309.402574) (xy 39.893351 -309.436666)
			(xy 39.852848 -309.464622) (xy 39.808386 -309.48572) (xy 39.761115 -309.499412) (xy 39.71226 -309.505344)
			(xy 39.663085 -309.503363) (xy 39.614866 -309.493519) (xy 39.56885 -309.476067) (xy 39.526229 -309.45146)
			(xy 39.488108 -309.420335) (xy 39.455473 -309.383498) (xy 39.42917 -309.341902) (xy 39.409879 -309.296626)
			(xy 39.398102 -309.248842) (xy 39.394142 -309.199788) (xy 39.055294 -309.199788) (xy 39.054799 -309.224395)
			(xy 39.046904 -309.272972) (xy 39.03132 -309.319653) (xy 39.008449 -309.36323) (xy 38.978884 -309.402574)
			(xy 38.943391 -309.436666) (xy 38.902888 -309.464622) (xy 38.858426 -309.48572) (xy 38.811155 -309.499412)
			(xy 38.7623 -309.505344) (xy 38.713125 -309.503363) (xy 38.664906 -309.493519) (xy 38.61889 -309.476067)
			(xy 38.576269 -309.45146) (xy 38.538148 -309.420335) (xy 38.505513 -309.383498) (xy 38.47921 -309.341902)
			(xy 38.459919 -309.296626) (xy 38.448142 -309.248842) (xy 38.444182 -309.199788) (xy 0.509016 -309.199788)
			(xy 0.509016 -310.149748) (xy 36.544008 -310.149748) (xy 36.547968 -310.100694) (xy 36.559745 -310.05291)
			(xy 36.579036 -310.007634) (xy 36.605339 -309.966038) (xy 36.637974 -309.929201) (xy 36.676095 -309.898076)
			(xy 36.718716 -309.873469) (xy 36.764732 -309.856017) (xy 36.812951 -309.846173) (xy 36.862126 -309.844192)
			(xy 36.910981 -309.850124) (xy 36.958252 -309.863816) (xy 37.002714 -309.884914) (xy 37.043217 -309.91287)
			(xy 37.07871 -309.946962) (xy 37.108275 -309.986306) (xy 37.131146 -310.029883) (xy 37.14673 -310.076564)
			(xy 37.154625 -310.125141) (xy 37.15512 -310.149748) (xy 37.493968 -310.149748) (xy 37.497928 -310.100694)
			(xy 37.509705 -310.05291) (xy 37.528996 -310.007634) (xy 37.555299 -309.966038) (xy 37.587934 -309.929201)
			(xy 37.626055 -309.898076) (xy 37.668676 -309.873469) (xy 37.714692 -309.856017) (xy 37.762911 -309.846173)
			(xy 37.812086 -309.844192) (xy 37.860941 -309.850124) (xy 37.908212 -309.863816) (xy 37.952674 -309.884914)
			(xy 37.993177 -309.91287) (xy 38.02867 -309.946962) (xy 38.058235 -309.986306) (xy 38.081106 -310.029883)
			(xy 38.09669 -310.076564) (xy 38.104585 -310.125141) (xy 38.10508 -310.149748) (xy 81.19416 -310.149748)
			(xy 81.19812 -310.100694) (xy 81.209897 -310.05291) (xy 81.229188 -310.007634) (xy 81.255491 -309.966038)
			(xy 81.288126 -309.929201) (xy 81.326247 -309.898076) (xy 81.368868 -309.873469) (xy 81.414884 -309.856017)
			(xy 81.463103 -309.846173) (xy 81.512278 -309.844192) (xy 81.561133 -309.850124) (xy 81.608404 -309.863816)
			(xy 81.652866 -309.884914) (xy 81.693369 -309.91287) (xy 81.728862 -309.946962) (xy 81.758427 -309.986306)
			(xy 81.781298 -310.029883) (xy 81.796882 -310.076564) (xy 81.804777 -310.125141) (xy 81.805272 -310.149748)
			(xy 82.14412 -310.149748) (xy 82.14808 -310.100694) (xy 82.159857 -310.05291) (xy 82.179148 -310.007634)
			(xy 82.205451 -309.966038) (xy 82.238086 -309.929201) (xy 82.276207 -309.898076) (xy 82.318828 -309.873469)
			(xy 82.364844 -309.856017) (xy 82.413063 -309.846173) (xy 82.462238 -309.844192) (xy 82.511093 -309.850124)
			(xy 82.558364 -309.863816) (xy 82.602826 -309.884914) (xy 82.643329 -309.91287) (xy 82.678822 -309.946962)
			(xy 82.708387 -309.986306) (xy 82.731258 -310.029883) (xy 82.746842 -310.076564) (xy 82.754737 -310.125141)
			(xy 82.755232 -310.149748) (xy 152.644106 -310.149748) (xy 152.648066 -310.100694) (xy 152.659843 -310.05291)
			(xy 152.679134 -310.007634) (xy 152.705437 -309.966038) (xy 152.738072 -309.929201) (xy 152.776193 -309.898076)
			(xy 152.818814 -309.873469) (xy 152.86483 -309.856017) (xy 152.913049 -309.846173) (xy 152.962224 -309.844192)
			(xy 153.011079 -309.850124) (xy 153.05835 -309.863816) (xy 153.102812 -309.884914) (xy 153.143315 -309.91287)
			(xy 153.178808 -309.946962) (xy 153.208373 -309.986306) (xy 153.231244 -310.029883) (xy 153.246828 -310.076564)
			(xy 153.254723 -310.125141) (xy 153.255218 -310.149748) (xy 153.594066 -310.149748) (xy 153.598026 -310.100694)
			(xy 153.609803 -310.05291) (xy 153.629094 -310.007634) (xy 153.655397 -309.966038) (xy 153.688032 -309.929201)
			(xy 153.726153 -309.898076) (xy 153.768774 -309.873469) (xy 153.81479 -309.856017) (xy 153.863009 -309.846173)
			(xy 153.912184 -309.844192) (xy 153.961039 -309.850124) (xy 154.00831 -309.863816) (xy 154.052772 -309.884914)
			(xy 154.093275 -309.91287) (xy 154.128768 -309.946962) (xy 154.158333 -309.986306) (xy 154.181204 -310.029883)
			(xy 154.196788 -310.076564) (xy 154.204683 -310.125141) (xy 154.205178 -310.149748) (xy 197.294258 -310.149748)
			(xy 197.298218 -310.100694) (xy 197.309995 -310.05291) (xy 197.329286 -310.007634) (xy 197.355589 -309.966038)
			(xy 197.388224 -309.929201) (xy 197.426345 -309.898076) (xy 197.468966 -309.873469) (xy 197.514982 -309.856017)
			(xy 197.563201 -309.846173) (xy 197.612376 -309.844192) (xy 197.661231 -309.850124) (xy 197.708502 -309.863816)
			(xy 197.752964 -309.884914) (xy 197.793467 -309.91287) (xy 197.82896 -309.946962) (xy 197.858525 -309.986306)
			(xy 197.881396 -310.029883) (xy 197.89698 -310.076564) (xy 197.904875 -310.125141) (xy 197.90537 -310.149748)
			(xy 198.244218 -310.149748) (xy 198.248178 -310.100694) (xy 198.259955 -310.05291) (xy 198.279246 -310.007634)
			(xy 198.305549 -309.966038) (xy 198.338184 -309.929201) (xy 198.376305 -309.898076) (xy 198.418926 -309.873469)
			(xy 198.464942 -309.856017) (xy 198.513161 -309.846173) (xy 198.562336 -309.844192) (xy 198.611191 -309.850124)
			(xy 198.658462 -309.863816) (xy 198.702924 -309.884914) (xy 198.743427 -309.91287) (xy 198.77892 -309.946962)
			(xy 198.808485 -309.986306) (xy 198.831356 -310.029883) (xy 198.84694 -310.076564) (xy 198.854835 -310.125141)
			(xy 198.85533 -310.149748) (xy 268.74395 -310.149748) (xy 268.74791 -310.100694) (xy 268.759687 -310.05291)
			(xy 268.778978 -310.007634) (xy 268.805281 -309.966038) (xy 268.837916 -309.929201) (xy 268.876037 -309.898076)
			(xy 268.918658 -309.873469) (xy 268.964674 -309.856017) (xy 269.012893 -309.846173) (xy 269.062068 -309.844192)
			(xy 269.110923 -309.850124) (xy 269.158194 -309.863816) (xy 269.202656 -309.884914) (xy 269.243159 -309.91287)
			(xy 269.278652 -309.946962) (xy 269.308217 -309.986306) (xy 269.331088 -310.029883) (xy 269.346672 -310.076564)
			(xy 269.354567 -310.125141) (xy 269.355062 -310.149748) (xy 269.69391 -310.149748) (xy 269.69787 -310.100694)
			(xy 269.709647 -310.05291) (xy 269.728938 -310.007634) (xy 269.755241 -309.966038) (xy 269.787876 -309.929201)
			(xy 269.825997 -309.898076) (xy 269.868618 -309.873469) (xy 269.914634 -309.856017) (xy 269.962853 -309.846173)
			(xy 270.012028 -309.844192) (xy 270.060883 -309.850124) (xy 270.108154 -309.863816) (xy 270.152616 -309.884914)
			(xy 270.193119 -309.91287) (xy 270.228612 -309.946962) (xy 270.258177 -309.986306) (xy 270.281048 -310.029883)
			(xy 270.296632 -310.076564) (xy 270.304527 -310.125141) (xy 270.305022 -310.149748) (xy 313.394102 -310.149748)
			(xy 313.398062 -310.100694) (xy 313.409839 -310.05291) (xy 313.42913 -310.007634) (xy 313.455433 -309.966038)
			(xy 313.488068 -309.929201) (xy 313.526189 -309.898076) (xy 313.56881 -309.873469) (xy 313.614826 -309.856017)
			(xy 313.663045 -309.846173) (xy 313.71222 -309.844192) (xy 313.761075 -309.850124) (xy 313.808346 -309.863816)
			(xy 313.852808 -309.884914) (xy 313.893311 -309.91287) (xy 313.928804 -309.946962) (xy 313.958369 -309.986306)
			(xy 313.98124 -310.029883) (xy 313.996824 -310.076564) (xy 314.004719 -310.125141) (xy 314.005214 -310.149748)
			(xy 314.344062 -310.149748) (xy 314.348022 -310.100694) (xy 314.359799 -310.05291) (xy 314.37909 -310.007634)
			(xy 314.405393 -309.966038) (xy 314.438028 -309.929201) (xy 314.476149 -309.898076) (xy 314.51877 -309.873469)
			(xy 314.564786 -309.856017) (xy 314.613005 -309.846173) (xy 314.66218 -309.844192) (xy 314.711035 -309.850124)
			(xy 314.758306 -309.863816) (xy 314.802768 -309.884914) (xy 314.843271 -309.91287) (xy 314.878764 -309.946962)
			(xy 314.908329 -309.986306) (xy 314.9312 -310.029883) (xy 314.946784 -310.076564) (xy 314.954679 -310.125141)
			(xy 314.955174 -310.149748) (xy 384.844048 -310.149748) (xy 384.848008 -310.100694) (xy 384.859785 -310.05291)
			(xy 384.879076 -310.007634) (xy 384.905379 -309.966038) (xy 384.938014 -309.929201) (xy 384.976135 -309.898076)
			(xy 385.018756 -309.873469) (xy 385.064772 -309.856017) (xy 385.112991 -309.846173) (xy 385.162166 -309.844192)
			(xy 385.211021 -309.850124) (xy 385.258292 -309.863816) (xy 385.302754 -309.884914) (xy 385.343257 -309.91287)
			(xy 385.37875 -309.946962) (xy 385.408315 -309.986306) (xy 385.431186 -310.029883) (xy 385.44677 -310.076564)
			(xy 385.454665 -310.125141) (xy 385.45516 -310.149748) (xy 385.794008 -310.149748) (xy 385.797968 -310.100694)
			(xy 385.809745 -310.05291) (xy 385.829036 -310.007634) (xy 385.855339 -309.966038) (xy 385.887974 -309.929201)
			(xy 385.926095 -309.898076) (xy 385.968716 -309.873469) (xy 386.014732 -309.856017) (xy 386.062951 -309.846173)
			(xy 386.112126 -309.844192) (xy 386.160981 -309.850124) (xy 386.208252 -309.863816) (xy 386.252714 -309.884914)
			(xy 386.293217 -309.91287) (xy 386.32871 -309.946962) (xy 386.358275 -309.986306) (xy 386.381146 -310.029883)
			(xy 386.39673 -310.076564) (xy 386.404625 -310.125141) (xy 386.40512 -310.149748) (xy 429.4942 -310.149748)
			(xy 429.49816 -310.100694) (xy 429.509937 -310.05291) (xy 429.529228 -310.007634) (xy 429.555531 -309.966038)
			(xy 429.588166 -309.929201) (xy 429.626287 -309.898076) (xy 429.668908 -309.873469) (xy 429.714924 -309.856017)
			(xy 429.763143 -309.846173) (xy 429.812318 -309.844192) (xy 429.861173 -309.850124) (xy 429.908444 -309.863816)
			(xy 429.952906 -309.884914) (xy 429.993409 -309.91287) (xy 430.028902 -309.946962) (xy 430.058467 -309.986306)
			(xy 430.081338 -310.029883) (xy 430.096922 -310.076564) (xy 430.104817 -310.125141) (xy 430.105312 -310.149748)
			(xy 430.44416 -310.149748) (xy 430.44812 -310.100694) (xy 430.459897 -310.05291) (xy 430.479188 -310.007634)
			(xy 430.505491 -309.966038) (xy 430.538126 -309.929201) (xy 430.576247 -309.898076) (xy 430.618868 -309.873469)
			(xy 430.664884 -309.856017) (xy 430.713103 -309.846173) (xy 430.762278 -309.844192) (xy 430.811133 -309.850124)
			(xy 430.858404 -309.863816) (xy 430.902866 -309.884914) (xy 430.943369 -309.91287) (xy 430.978862 -309.946962)
			(xy 431.008427 -309.986306) (xy 431.031298 -310.029883) (xy 431.046882 -310.076564) (xy 431.054777 -310.125141)
			(xy 431.055272 -310.149748) (xy 431.054777 -310.174355) (xy 431.046882 -310.222932) (xy 431.031298 -310.269613)
			(xy 431.008427 -310.31319) (xy 430.978862 -310.352534) (xy 430.943369 -310.386626) (xy 430.902866 -310.414582)
			(xy 430.858404 -310.43568) (xy 430.811133 -310.449372) (xy 430.762278 -310.455304) (xy 430.713103 -310.453323)
			(xy 430.664884 -310.443479) (xy 430.618868 -310.426027) (xy 430.576247 -310.40142) (xy 430.538126 -310.370295)
			(xy 430.505491 -310.333458) (xy 430.479188 -310.291862) (xy 430.459897 -310.246586) (xy 430.44812 -310.198802)
			(xy 430.44416 -310.149748) (xy 430.105312 -310.149748) (xy 430.104817 -310.174355) (xy 430.096922 -310.222932)
			(xy 430.081338 -310.269613) (xy 430.058467 -310.31319) (xy 430.028902 -310.352534) (xy 429.993409 -310.386626)
			(xy 429.952906 -310.414582) (xy 429.908444 -310.43568) (xy 429.861173 -310.449372) (xy 429.812318 -310.455304)
			(xy 429.763143 -310.453323) (xy 429.714924 -310.443479) (xy 429.668908 -310.426027) (xy 429.626287 -310.40142)
			(xy 429.588166 -310.370295) (xy 429.555531 -310.333458) (xy 429.529228 -310.291862) (xy 429.509937 -310.246586)
			(xy 429.49816 -310.198802) (xy 429.4942 -310.149748) (xy 386.40512 -310.149748) (xy 386.404625 -310.174355)
			(xy 386.39673 -310.222932) (xy 386.381146 -310.269613) (xy 386.358275 -310.31319) (xy 386.32871 -310.352534)
			(xy 386.293217 -310.386626) (xy 386.252714 -310.414582) (xy 386.208252 -310.43568) (xy 386.160981 -310.449372)
			(xy 386.112126 -310.455304) (xy 386.062951 -310.453323) (xy 386.014732 -310.443479) (xy 385.968716 -310.426027)
			(xy 385.926095 -310.40142) (xy 385.887974 -310.370295) (xy 385.855339 -310.333458) (xy 385.829036 -310.291862)
			(xy 385.809745 -310.246586) (xy 385.797968 -310.198802) (xy 385.794008 -310.149748) (xy 385.45516 -310.149748)
			(xy 385.454665 -310.174355) (xy 385.44677 -310.222932) (xy 385.431186 -310.269613) (xy 385.408315 -310.31319)
			(xy 385.37875 -310.352534) (xy 385.343257 -310.386626) (xy 385.302754 -310.414582) (xy 385.258292 -310.43568)
			(xy 385.211021 -310.449372) (xy 385.162166 -310.455304) (xy 385.112991 -310.453323) (xy 385.064772 -310.443479)
			(xy 385.018756 -310.426027) (xy 384.976135 -310.40142) (xy 384.938014 -310.370295) (xy 384.905379 -310.333458)
			(xy 384.879076 -310.291862) (xy 384.859785 -310.246586) (xy 384.848008 -310.198802) (xy 384.844048 -310.149748)
			(xy 314.955174 -310.149748) (xy 314.954679 -310.174355) (xy 314.946784 -310.222932) (xy 314.9312 -310.269613)
			(xy 314.908329 -310.31319) (xy 314.878764 -310.352534) (xy 314.843271 -310.386626) (xy 314.802768 -310.414582)
			(xy 314.758306 -310.43568) (xy 314.711035 -310.449372) (xy 314.66218 -310.455304) (xy 314.613005 -310.453323)
			(xy 314.564786 -310.443479) (xy 314.51877 -310.426027) (xy 314.476149 -310.40142) (xy 314.438028 -310.370295)
			(xy 314.405393 -310.333458) (xy 314.37909 -310.291862) (xy 314.359799 -310.246586) (xy 314.348022 -310.198802)
			(xy 314.344062 -310.149748) (xy 314.005214 -310.149748) (xy 314.004719 -310.174355) (xy 313.996824 -310.222932)
			(xy 313.98124 -310.269613) (xy 313.958369 -310.31319) (xy 313.928804 -310.352534) (xy 313.893311 -310.386626)
			(xy 313.852808 -310.414582) (xy 313.808346 -310.43568) (xy 313.761075 -310.449372) (xy 313.71222 -310.455304)
			(xy 313.663045 -310.453323) (xy 313.614826 -310.443479) (xy 313.56881 -310.426027) (xy 313.526189 -310.40142)
			(xy 313.488068 -310.370295) (xy 313.455433 -310.333458) (xy 313.42913 -310.291862) (xy 313.409839 -310.246586)
			(xy 313.398062 -310.198802) (xy 313.394102 -310.149748) (xy 270.305022 -310.149748) (xy 270.304527 -310.174355)
			(xy 270.296632 -310.222932) (xy 270.281048 -310.269613) (xy 270.258177 -310.31319) (xy 270.228612 -310.352534)
			(xy 270.193119 -310.386626) (xy 270.152616 -310.414582) (xy 270.108154 -310.43568) (xy 270.060883 -310.449372)
			(xy 270.012028 -310.455304) (xy 269.962853 -310.453323) (xy 269.914634 -310.443479) (xy 269.868618 -310.426027)
			(xy 269.825997 -310.40142) (xy 269.787876 -310.370295) (xy 269.755241 -310.333458) (xy 269.728938 -310.291862)
			(xy 269.709647 -310.246586) (xy 269.69787 -310.198802) (xy 269.69391 -310.149748) (xy 269.355062 -310.149748)
			(xy 269.354567 -310.174355) (xy 269.346672 -310.222932) (xy 269.331088 -310.269613) (xy 269.308217 -310.31319)
			(xy 269.278652 -310.352534) (xy 269.243159 -310.386626) (xy 269.202656 -310.414582) (xy 269.158194 -310.43568)
			(xy 269.110923 -310.449372) (xy 269.062068 -310.455304) (xy 269.012893 -310.453323) (xy 268.964674 -310.443479)
			(xy 268.918658 -310.426027) (xy 268.876037 -310.40142) (xy 268.837916 -310.370295) (xy 268.805281 -310.333458)
			(xy 268.778978 -310.291862) (xy 268.759687 -310.246586) (xy 268.74791 -310.198802) (xy 268.74395 -310.149748)
			(xy 198.85533 -310.149748) (xy 198.854835 -310.174355) (xy 198.84694 -310.222932) (xy 198.831356 -310.269613)
			(xy 198.808485 -310.31319) (xy 198.77892 -310.352534) (xy 198.743427 -310.386626) (xy 198.702924 -310.414582)
			(xy 198.658462 -310.43568) (xy 198.611191 -310.449372) (xy 198.562336 -310.455304) (xy 198.513161 -310.453323)
			(xy 198.464942 -310.443479) (xy 198.418926 -310.426027) (xy 198.376305 -310.40142) (xy 198.338184 -310.370295)
			(xy 198.305549 -310.333458) (xy 198.279246 -310.291862) (xy 198.259955 -310.246586) (xy 198.248178 -310.198802)
			(xy 198.244218 -310.149748) (xy 197.90537 -310.149748) (xy 197.904875 -310.174355) (xy 197.89698 -310.222932)
			(xy 197.881396 -310.269613) (xy 197.858525 -310.31319) (xy 197.82896 -310.352534) (xy 197.793467 -310.386626)
			(xy 197.752964 -310.414582) (xy 197.708502 -310.43568) (xy 197.661231 -310.449372) (xy 197.612376 -310.455304)
			(xy 197.563201 -310.453323) (xy 197.514982 -310.443479) (xy 197.468966 -310.426027) (xy 197.426345 -310.40142)
			(xy 197.388224 -310.370295) (xy 197.355589 -310.333458) (xy 197.329286 -310.291862) (xy 197.309995 -310.246586)
			(xy 197.298218 -310.198802) (xy 197.294258 -310.149748) (xy 154.205178 -310.149748) (xy 154.204683 -310.174355)
			(xy 154.196788 -310.222932) (xy 154.181204 -310.269613) (xy 154.158333 -310.31319) (xy 154.128768 -310.352534)
			(xy 154.093275 -310.386626) (xy 154.052772 -310.414582) (xy 154.00831 -310.43568) (xy 153.961039 -310.449372)
			(xy 153.912184 -310.455304) (xy 153.863009 -310.453323) (xy 153.81479 -310.443479) (xy 153.768774 -310.426027)
			(xy 153.726153 -310.40142) (xy 153.688032 -310.370295) (xy 153.655397 -310.333458) (xy 153.629094 -310.291862)
			(xy 153.609803 -310.246586) (xy 153.598026 -310.198802) (xy 153.594066 -310.149748) (xy 153.255218 -310.149748)
			(xy 153.254723 -310.174355) (xy 153.246828 -310.222932) (xy 153.231244 -310.269613) (xy 153.208373 -310.31319)
			(xy 153.178808 -310.352534) (xy 153.143315 -310.386626) (xy 153.102812 -310.414582) (xy 153.05835 -310.43568)
			(xy 153.011079 -310.449372) (xy 152.962224 -310.455304) (xy 152.913049 -310.453323) (xy 152.86483 -310.443479)
			(xy 152.818814 -310.426027) (xy 152.776193 -310.40142) (xy 152.738072 -310.370295) (xy 152.705437 -310.333458)
			(xy 152.679134 -310.291862) (xy 152.659843 -310.246586) (xy 152.648066 -310.198802) (xy 152.644106 -310.149748)
			(xy 82.755232 -310.149748) (xy 82.754737 -310.174355) (xy 82.746842 -310.222932) (xy 82.731258 -310.269613)
			(xy 82.708387 -310.31319) (xy 82.678822 -310.352534) (xy 82.643329 -310.386626) (xy 82.602826 -310.414582)
			(xy 82.558364 -310.43568) (xy 82.511093 -310.449372) (xy 82.462238 -310.455304) (xy 82.413063 -310.453323)
			(xy 82.364844 -310.443479) (xy 82.318828 -310.426027) (xy 82.276207 -310.40142) (xy 82.238086 -310.370295)
			(xy 82.205451 -310.333458) (xy 82.179148 -310.291862) (xy 82.159857 -310.246586) (xy 82.14808 -310.198802)
			(xy 82.14412 -310.149748) (xy 81.805272 -310.149748) (xy 81.804777 -310.174355) (xy 81.796882 -310.222932)
			(xy 81.781298 -310.269613) (xy 81.758427 -310.31319) (xy 81.728862 -310.352534) (xy 81.693369 -310.386626)
			(xy 81.652866 -310.414582) (xy 81.608404 -310.43568) (xy 81.561133 -310.449372) (xy 81.512278 -310.455304)
			(xy 81.463103 -310.453323) (xy 81.414884 -310.443479) (xy 81.368868 -310.426027) (xy 81.326247 -310.40142)
			(xy 81.288126 -310.370295) (xy 81.255491 -310.333458) (xy 81.229188 -310.291862) (xy 81.209897 -310.246586)
			(xy 81.19812 -310.198802) (xy 81.19416 -310.149748) (xy 38.10508 -310.149748) (xy 38.104585 -310.174355)
			(xy 38.09669 -310.222932) (xy 38.081106 -310.269613) (xy 38.058235 -310.31319) (xy 38.02867 -310.352534)
			(xy 37.993177 -310.386626) (xy 37.952674 -310.414582) (xy 37.908212 -310.43568) (xy 37.860941 -310.449372)
			(xy 37.812086 -310.455304) (xy 37.762911 -310.453323) (xy 37.714692 -310.443479) (xy 37.668676 -310.426027)
			(xy 37.626055 -310.40142) (xy 37.587934 -310.370295) (xy 37.555299 -310.333458) (xy 37.528996 -310.291862)
			(xy 37.509705 -310.246586) (xy 37.497928 -310.198802) (xy 37.493968 -310.149748) (xy 37.15512 -310.149748)
			(xy 37.154625 -310.174355) (xy 37.14673 -310.222932) (xy 37.131146 -310.269613) (xy 37.108275 -310.31319)
			(xy 37.07871 -310.352534) (xy 37.043217 -310.386626) (xy 37.002714 -310.414582) (xy 36.958252 -310.43568)
			(xy 36.910981 -310.449372) (xy 36.862126 -310.455304) (xy 36.812951 -310.453323) (xy 36.764732 -310.443479)
			(xy 36.718716 -310.426027) (xy 36.676095 -310.40142) (xy 36.637974 -310.370295) (xy 36.605339 -310.333458)
			(xy 36.579036 -310.291862) (xy 36.559745 -310.246586) (xy 36.547968 -310.198802) (xy 36.544008 -310.149748)
			(xy 0.509016 -310.149748) (xy 0.509016 -311.099962) (xy 39.394142 -311.099962) (xy 39.398102 -311.050908)
			(xy 39.409879 -311.003124) (xy 39.42917 -310.957848) (xy 39.455473 -310.916252) (xy 39.488108 -310.879415)
			(xy 39.526229 -310.84829) (xy 39.56885 -310.823683) (xy 39.614866 -310.806231) (xy 39.663085 -310.796387)
			(xy 39.71226 -310.794406) (xy 39.761115 -310.800338) (xy 39.808386 -310.81403) (xy 39.852848 -310.835128)
			(xy 39.893351 -310.863084) (xy 39.928844 -310.897176) (xy 39.958409 -310.93652) (xy 39.98128 -310.980097)
			(xy 39.996864 -311.026778) (xy 40.004759 -311.075355) (xy 40.005254 -311.099962) (xy 41.294062 -311.099962)
			(xy 41.298022 -311.050908) (xy 41.309799 -311.003124) (xy 41.32909 -310.957848) (xy 41.355393 -310.916252)
			(xy 41.388028 -310.879415) (xy 41.426149 -310.84829) (xy 41.46877 -310.823683) (xy 41.514786 -310.806231)
			(xy 41.563005 -310.796387) (xy 41.61218 -310.794406) (xy 41.661035 -310.800338) (xy 41.708306 -310.81403)
			(xy 41.752768 -310.835128) (xy 41.793271 -310.863084) (xy 41.828764 -310.897176) (xy 41.858329 -310.93652)
			(xy 41.8812 -310.980097) (xy 41.896784 -311.026778) (xy 41.904679 -311.075355) (xy 41.905174 -311.099962)
			(xy 43.193982 -311.099962) (xy 43.197942 -311.050908) (xy 43.209719 -311.003124) (xy 43.22901 -310.957848)
			(xy 43.255313 -310.916252) (xy 43.287948 -310.879415) (xy 43.326069 -310.84829) (xy 43.36869 -310.823683)
			(xy 43.414706 -310.806231) (xy 43.462925 -310.796387) (xy 43.5121 -310.794406) (xy 43.560955 -310.800338)
			(xy 43.608226 -310.81403) (xy 43.652688 -310.835128) (xy 43.693191 -310.863084) (xy 43.728684 -310.897176)
			(xy 43.758249 -310.93652) (xy 43.78112 -310.980097) (xy 43.796704 -311.026778) (xy 43.804599 -311.075355)
			(xy 43.805094 -311.099962) (xy 45.094156 -311.099962) (xy 45.098116 -311.050908) (xy 45.109893 -311.003124)
			(xy 45.129184 -310.957848) (xy 45.155487 -310.916252) (xy 45.188122 -310.879415) (xy 45.226243 -310.84829)
			(xy 45.268864 -310.823683) (xy 45.31488 -310.806231) (xy 45.363099 -310.796387) (xy 45.412274 -310.794406)
			(xy 45.461129 -310.800338) (xy 45.5084 -310.81403) (xy 45.552862 -310.835128) (xy 45.593365 -310.863084)
			(xy 45.628858 -310.897176) (xy 45.658423 -310.93652) (xy 45.681294 -310.980097) (xy 45.696878 -311.026778)
			(xy 45.704773 -311.075355) (xy 45.705268 -311.099962) (xy 46.994076 -311.099962) (xy 46.998036 -311.050908)
			(xy 47.009813 -311.003124) (xy 47.029104 -310.957848) (xy 47.055407 -310.916252) (xy 47.088042 -310.879415)
			(xy 47.126163 -310.84829) (xy 47.168784 -310.823683) (xy 47.2148 -310.806231) (xy 47.263019 -310.796387)
			(xy 47.312194 -310.794406) (xy 47.361049 -310.800338) (xy 47.40832 -310.81403) (xy 47.452782 -310.835128)
			(xy 47.493285 -310.863084) (xy 47.528778 -310.897176) (xy 47.558343 -310.93652) (xy 47.581214 -310.980097)
			(xy 47.596798 -311.026778) (xy 47.604693 -311.075355) (xy 47.605188 -311.099962) (xy 48.893996 -311.099962)
			(xy 48.897956 -311.050908) (xy 48.909733 -311.003124) (xy 48.929024 -310.957848) (xy 48.955327 -310.916252)
			(xy 48.987962 -310.879415) (xy 49.026083 -310.84829) (xy 49.068704 -310.823683) (xy 49.11472 -310.806231)
			(xy 49.162939 -310.796387) (xy 49.212114 -310.794406) (xy 49.260969 -310.800338) (xy 49.30824 -310.81403)
			(xy 49.352702 -310.835128) (xy 49.393205 -310.863084) (xy 49.428698 -310.897176) (xy 49.458263 -310.93652)
			(xy 49.481134 -310.980097) (xy 49.496718 -311.026778) (xy 49.504613 -311.075355) (xy 49.505108 -311.099962)
			(xy 50.79417 -311.099962) (xy 50.79813 -311.050908) (xy 50.809907 -311.003124) (xy 50.829198 -310.957848)
			(xy 50.855501 -310.916252) (xy 50.888136 -310.879415) (xy 50.926257 -310.84829) (xy 50.968878 -310.823683)
			(xy 51.014894 -310.806231) (xy 51.063113 -310.796387) (xy 51.112288 -310.794406) (xy 51.161143 -310.800338)
			(xy 51.208414 -310.81403) (xy 51.252876 -310.835128) (xy 51.293379 -310.863084) (xy 51.328872 -310.897176)
			(xy 51.358437 -310.93652) (xy 51.381308 -310.980097) (xy 51.396892 -311.026778) (xy 51.404787 -311.075355)
			(xy 51.405282 -311.099962) (xy 52.69409 -311.099962) (xy 52.69805 -311.050908) (xy 52.709827 -311.003124)
			(xy 52.729118 -310.957848) (xy 52.755421 -310.916252) (xy 52.788056 -310.879415) (xy 52.826177 -310.84829)
			(xy 52.868798 -310.823683) (xy 52.914814 -310.806231) (xy 52.963033 -310.796387) (xy 53.012208 -310.794406)
			(xy 53.061063 -310.800338) (xy 53.108334 -310.81403) (xy 53.152796 -310.835128) (xy 53.193299 -310.863084)
			(xy 53.228792 -310.897176) (xy 53.258357 -310.93652) (xy 53.281228 -310.980097) (xy 53.296812 -311.026778)
			(xy 53.304707 -311.075355) (xy 53.305202 -311.099962) (xy 54.59401 -311.099962) (xy 54.59797 -311.050908)
			(xy 54.609747 -311.003124) (xy 54.629038 -310.957848) (xy 54.655341 -310.916252) (xy 54.687976 -310.879415)
			(xy 54.726097 -310.84829) (xy 54.768718 -310.823683) (xy 54.814734 -310.806231) (xy 54.862953 -310.796387)
			(xy 54.912128 -310.794406) (xy 54.960983 -310.800338) (xy 55.008254 -310.81403) (xy 55.052716 -310.835128)
			(xy 55.093219 -310.863084) (xy 55.128712 -310.897176) (xy 55.158277 -310.93652) (xy 55.181148 -310.980097)
			(xy 55.196732 -311.026778) (xy 55.204627 -311.075355) (xy 55.205122 -311.099962) (xy 56.494184 -311.099962)
			(xy 56.498144 -311.050908) (xy 56.509921 -311.003124) (xy 56.529212 -310.957848) (xy 56.555515 -310.916252)
			(xy 56.58815 -310.879415) (xy 56.626271 -310.84829) (xy 56.668892 -310.823683) (xy 56.714908 -310.806231)
			(xy 56.763127 -310.796387) (xy 56.812302 -310.794406) (xy 56.861157 -310.800338) (xy 56.908428 -310.81403)
			(xy 56.95289 -310.835128) (xy 56.993393 -310.863084) (xy 57.028886 -310.897176) (xy 57.058451 -310.93652)
			(xy 57.081322 -310.980097) (xy 57.096906 -311.026778) (xy 57.104801 -311.075355) (xy 57.105296 -311.099962)
			(xy 58.394104 -311.099962) (xy 58.398064 -311.050908) (xy 58.409841 -311.003124) (xy 58.429132 -310.957848)
			(xy 58.455435 -310.916252) (xy 58.48807 -310.879415) (xy 58.526191 -310.84829) (xy 58.568812 -310.823683)
			(xy 58.614828 -310.806231) (xy 58.663047 -310.796387) (xy 58.712222 -310.794406) (xy 58.761077 -310.800338)
			(xy 58.808348 -310.81403) (xy 58.85281 -310.835128) (xy 58.893313 -310.863084) (xy 58.928806 -310.897176)
			(xy 58.958371 -310.93652) (xy 58.981242 -310.980097) (xy 58.996826 -311.026778) (xy 59.004721 -311.075355)
			(xy 59.005216 -311.099962) (xy 60.294024 -311.099962) (xy 60.297984 -311.050908) (xy 60.309761 -311.003124)
			(xy 60.329052 -310.957848) (xy 60.355355 -310.916252) (xy 60.38799 -310.879415) (xy 60.426111 -310.84829)
			(xy 60.468732 -310.823683) (xy 60.514748 -310.806231) (xy 60.562967 -310.796387) (xy 60.612142 -310.794406)
			(xy 60.660997 -310.800338) (xy 60.708268 -310.81403) (xy 60.75273 -310.835128) (xy 60.793233 -310.863084)
			(xy 60.828726 -310.897176) (xy 60.858291 -310.93652) (xy 60.881162 -310.980097) (xy 60.896746 -311.026778)
			(xy 60.904641 -311.075355) (xy 60.905136 -311.099962) (xy 62.193944 -311.099962) (xy 62.197904 -311.050908)
			(xy 62.209681 -311.003124) (xy 62.228972 -310.957848) (xy 62.255275 -310.916252) (xy 62.28791 -310.879415)
			(xy 62.326031 -310.84829) (xy 62.368652 -310.823683) (xy 62.414668 -310.806231) (xy 62.462887 -310.796387)
			(xy 62.512062 -310.794406) (xy 62.560917 -310.800338) (xy 62.608188 -310.81403) (xy 62.65265 -310.835128)
			(xy 62.693153 -310.863084) (xy 62.728646 -310.897176) (xy 62.758211 -310.93652) (xy 62.781082 -310.980097)
			(xy 62.796666 -311.026778) (xy 62.804561 -311.075355) (xy 62.805056 -311.099962) (xy 64.094118 -311.099962)
			(xy 64.098078 -311.050908) (xy 64.109855 -311.003124) (xy 64.129146 -310.957848) (xy 64.155449 -310.916252)
			(xy 64.188084 -310.879415) (xy 64.226205 -310.84829) (xy 64.268826 -310.823683) (xy 64.314842 -310.806231)
			(xy 64.363061 -310.796387) (xy 64.412236 -310.794406) (xy 64.461091 -310.800338) (xy 64.508362 -310.81403)
			(xy 64.552824 -310.835128) (xy 64.593327 -310.863084) (xy 64.62882 -310.897176) (xy 64.658385 -310.93652)
			(xy 64.681256 -310.980097) (xy 64.69684 -311.026778) (xy 64.704735 -311.075355) (xy 64.70523 -311.099962)
			(xy 65.994038 -311.099962) (xy 65.997998 -311.050908) (xy 66.009775 -311.003124) (xy 66.029066 -310.957848)
			(xy 66.055369 -310.916252) (xy 66.088004 -310.879415) (xy 66.126125 -310.84829) (xy 66.168746 -310.823683)
			(xy 66.214762 -310.806231) (xy 66.262981 -310.796387) (xy 66.312156 -310.794406) (xy 66.361011 -310.800338)
			(xy 66.408282 -310.81403) (xy 66.452744 -310.835128) (xy 66.493247 -310.863084) (xy 66.52874 -310.897176)
			(xy 66.558305 -310.93652) (xy 66.581176 -310.980097) (xy 66.59676 -311.026778) (xy 66.604655 -311.075355)
			(xy 66.60515 -311.099962) (xy 67.893958 -311.099962) (xy 67.897918 -311.050908) (xy 67.909695 -311.003124)
			(xy 67.928986 -310.957848) (xy 67.955289 -310.916252) (xy 67.987924 -310.879415) (xy 68.026045 -310.84829)
			(xy 68.068666 -310.823683) (xy 68.114682 -310.806231) (xy 68.162901 -310.796387) (xy 68.212076 -310.794406)
			(xy 68.260931 -310.800338) (xy 68.308202 -310.81403) (xy 68.352664 -310.835128) (xy 68.393167 -310.863084)
			(xy 68.42866 -310.897176) (xy 68.458225 -310.93652) (xy 68.481096 -310.980097) (xy 68.49668 -311.026778)
			(xy 68.504575 -311.075355) (xy 68.50507 -311.099962) (xy 69.794132 -311.099962) (xy 69.798092 -311.050908)
			(xy 69.809869 -311.003124) (xy 69.82916 -310.957848) (xy 69.855463 -310.916252) (xy 69.888098 -310.879415)
			(xy 69.926219 -310.84829) (xy 69.96884 -310.823683) (xy 70.014856 -310.806231) (xy 70.063075 -310.796387)
			(xy 70.11225 -310.794406) (xy 70.161105 -310.800338) (xy 70.208376 -310.81403) (xy 70.252838 -310.835128)
			(xy 70.293341 -310.863084) (xy 70.328834 -310.897176) (xy 70.358399 -310.93652) (xy 70.38127 -310.980097)
			(xy 70.396854 -311.026778) (xy 70.404749 -311.075355) (xy 70.405244 -311.099962) (xy 71.694052 -311.099962)
			(xy 71.698012 -311.050908) (xy 71.709789 -311.003124) (xy 71.72908 -310.957848) (xy 71.755383 -310.916252)
			(xy 71.788018 -310.879415) (xy 71.826139 -310.84829) (xy 71.86876 -310.823683) (xy 71.914776 -310.806231)
			(xy 71.962995 -310.796387) (xy 72.01217 -310.794406) (xy 72.061025 -310.800338) (xy 72.108296 -310.81403)
			(xy 72.152758 -310.835128) (xy 72.193261 -310.863084) (xy 72.228754 -310.897176) (xy 72.258319 -310.93652)
			(xy 72.28119 -310.980097) (xy 72.296774 -311.026778) (xy 72.304669 -311.075355) (xy 72.305164 -311.099962)
			(xy 73.593972 -311.099962) (xy 73.597932 -311.050908) (xy 73.609709 -311.003124) (xy 73.629 -310.957848)
			(xy 73.655303 -310.916252) (xy 73.687938 -310.879415) (xy 73.726059 -310.84829) (xy 73.76868 -310.823683)
			(xy 73.814696 -310.806231) (xy 73.862915 -310.796387) (xy 73.91209 -310.794406) (xy 73.960945 -310.800338)
			(xy 74.008216 -310.81403) (xy 74.052678 -310.835128) (xy 74.093181 -310.863084) (xy 74.128674 -310.897176)
			(xy 74.158239 -310.93652) (xy 74.18111 -310.980097) (xy 74.196694 -311.026778) (xy 74.204589 -311.075355)
			(xy 74.205084 -311.099962) (xy 75.494146 -311.099962) (xy 75.498106 -311.050908) (xy 75.509883 -311.003124)
			(xy 75.529174 -310.957848) (xy 75.555477 -310.916252) (xy 75.588112 -310.879415) (xy 75.626233 -310.84829)
			(xy 75.668854 -310.823683) (xy 75.71487 -310.806231) (xy 75.763089 -310.796387) (xy 75.812264 -310.794406)
			(xy 75.861119 -310.800338) (xy 75.90839 -310.81403) (xy 75.952852 -310.835128) (xy 75.993355 -310.863084)
			(xy 76.028848 -310.897176) (xy 76.058413 -310.93652) (xy 76.081284 -310.980097) (xy 76.096868 -311.026778)
			(xy 76.104763 -311.075355) (xy 76.105258 -311.099962) (xy 77.394066 -311.099962) (xy 77.398026 -311.050908)
			(xy 77.409803 -311.003124) (xy 77.429094 -310.957848) (xy 77.455397 -310.916252) (xy 77.488032 -310.879415)
			(xy 77.526153 -310.84829) (xy 77.568774 -310.823683) (xy 77.61479 -310.806231) (xy 77.663009 -310.796387)
			(xy 77.712184 -310.794406) (xy 77.761039 -310.800338) (xy 77.80831 -310.81403) (xy 77.852772 -310.835128)
			(xy 77.893275 -310.863084) (xy 77.928768 -310.897176) (xy 77.958333 -310.93652) (xy 77.981204 -310.980097)
			(xy 77.996788 -311.026778) (xy 78.004683 -311.075355) (xy 78.005178 -311.099962) (xy 79.293986 -311.099962)
			(xy 79.297946 -311.050908) (xy 79.309723 -311.003124) (xy 79.329014 -310.957848) (xy 79.355317 -310.916252)
			(xy 79.387952 -310.879415) (xy 79.426073 -310.84829) (xy 79.468694 -310.823683) (xy 79.51471 -310.806231)
			(xy 79.562929 -310.796387) (xy 79.612104 -310.794406) (xy 79.660959 -310.800338) (xy 79.70823 -310.81403)
			(xy 79.752692 -310.835128) (xy 79.793195 -310.863084) (xy 79.828688 -310.897176) (xy 79.858253 -310.93652)
			(xy 79.881124 -310.980097) (xy 79.896708 -311.026778) (xy 79.904603 -311.075355) (xy 79.905098 -311.099962)
			(xy 155.49424 -311.099962) (xy 155.4982 -311.050908) (xy 155.509977 -311.003124) (xy 155.529268 -310.957848)
			(xy 155.555571 -310.916252) (xy 155.588206 -310.879415) (xy 155.626327 -310.84829) (xy 155.668948 -310.823683)
			(xy 155.714964 -310.806231) (xy 155.763183 -310.796387) (xy 155.812358 -310.794406) (xy 155.861213 -310.800338)
			(xy 155.908484 -310.81403) (xy 155.952946 -310.835128) (xy 155.993449 -310.863084) (xy 156.028942 -310.897176)
			(xy 156.058507 -310.93652) (xy 156.081378 -310.980097) (xy 156.096962 -311.026778) (xy 156.104857 -311.075355)
			(xy 156.105352 -311.099962) (xy 157.39416 -311.099962) (xy 157.39812 -311.050908) (xy 157.409897 -311.003124)
			(xy 157.429188 -310.957848) (xy 157.455491 -310.916252) (xy 157.488126 -310.879415) (xy 157.526247 -310.84829)
			(xy 157.568868 -310.823683) (xy 157.614884 -310.806231) (xy 157.663103 -310.796387) (xy 157.712278 -310.794406)
			(xy 157.761133 -310.800338) (xy 157.808404 -310.81403) (xy 157.852866 -310.835128) (xy 157.893369 -310.863084)
			(xy 157.928862 -310.897176) (xy 157.958427 -310.93652) (xy 157.981298 -310.980097) (xy 157.996882 -311.026778)
			(xy 158.004777 -311.075355) (xy 158.005272 -311.099962) (xy 159.29408 -311.099962) (xy 159.29804 -311.050908)
			(xy 159.309817 -311.003124) (xy 159.329108 -310.957848) (xy 159.355411 -310.916252) (xy 159.388046 -310.879415)
			(xy 159.426167 -310.84829) (xy 159.468788 -310.823683) (xy 159.514804 -310.806231) (xy 159.563023 -310.796387)
			(xy 159.612198 -310.794406) (xy 159.661053 -310.800338) (xy 159.708324 -310.81403) (xy 159.752786 -310.835128)
			(xy 159.793289 -310.863084) (xy 159.828782 -310.897176) (xy 159.858347 -310.93652) (xy 159.881218 -310.980097)
			(xy 159.896802 -311.026778) (xy 159.904697 -311.075355) (xy 159.905192 -311.099962) (xy 161.194254 -311.099962)
			(xy 161.198214 -311.050908) (xy 161.209991 -311.003124) (xy 161.229282 -310.957848) (xy 161.255585 -310.916252)
			(xy 161.28822 -310.879415) (xy 161.326341 -310.84829) (xy 161.368962 -310.823683) (xy 161.414978 -310.806231)
			(xy 161.463197 -310.796387) (xy 161.512372 -310.794406) (xy 161.561227 -310.800338) (xy 161.608498 -310.81403)
			(xy 161.65296 -310.835128) (xy 161.693463 -310.863084) (xy 161.728956 -310.897176) (xy 161.758521 -310.93652)
			(xy 161.781392 -310.980097) (xy 161.796976 -311.026778) (xy 161.804871 -311.075355) (xy 161.805366 -311.099962)
			(xy 163.094174 -311.099962) (xy 163.098134 -311.050908) (xy 163.109911 -311.003124) (xy 163.129202 -310.957848)
			(xy 163.155505 -310.916252) (xy 163.18814 -310.879415) (xy 163.226261 -310.84829) (xy 163.268882 -310.823683)
			(xy 163.314898 -310.806231) (xy 163.363117 -310.796387) (xy 163.412292 -310.794406) (xy 163.461147 -310.800338)
			(xy 163.508418 -310.81403) (xy 163.55288 -310.835128) (xy 163.593383 -310.863084) (xy 163.628876 -310.897176)
			(xy 163.658441 -310.93652) (xy 163.681312 -310.980097) (xy 163.696896 -311.026778) (xy 163.704791 -311.075355)
			(xy 163.705286 -311.099962) (xy 164.994094 -311.099962) (xy 164.998054 -311.050908) (xy 165.009831 -311.003124)
			(xy 165.029122 -310.957848) (xy 165.055425 -310.916252) (xy 165.08806 -310.879415) (xy 165.126181 -310.84829)
			(xy 165.168802 -310.823683) (xy 165.214818 -310.806231) (xy 165.263037 -310.796387) (xy 165.312212 -310.794406)
			(xy 165.361067 -310.800338) (xy 165.408338 -310.81403) (xy 165.4528 -310.835128) (xy 165.493303 -310.863084)
			(xy 165.528796 -310.897176) (xy 165.558361 -310.93652) (xy 165.581232 -310.980097) (xy 165.596816 -311.026778)
			(xy 165.604711 -311.075355) (xy 165.605206 -311.099962) (xy 166.894268 -311.099962) (xy 166.898228 -311.050908)
			(xy 166.910005 -311.003124) (xy 166.929296 -310.957848) (xy 166.955599 -310.916252) (xy 166.988234 -310.879415)
			(xy 167.026355 -310.84829) (xy 167.068976 -310.823683) (xy 167.114992 -310.806231) (xy 167.163211 -310.796387)
			(xy 167.212386 -310.794406) (xy 167.261241 -310.800338) (xy 167.308512 -310.81403) (xy 167.352974 -310.835128)
			(xy 167.393477 -310.863084) (xy 167.42897 -310.897176) (xy 167.458535 -310.93652) (xy 167.481406 -310.980097)
			(xy 167.49699 -311.026778) (xy 167.504885 -311.075355) (xy 167.50538 -311.099962) (xy 168.794188 -311.099962)
			(xy 168.798148 -311.050908) (xy 168.809925 -311.003124) (xy 168.829216 -310.957848) (xy 168.855519 -310.916252)
			(xy 168.888154 -310.879415) (xy 168.926275 -310.84829) (xy 168.968896 -310.823683) (xy 169.014912 -310.806231)
			(xy 169.063131 -310.796387) (xy 169.112306 -310.794406) (xy 169.161161 -310.800338) (xy 169.208432 -310.81403)
			(xy 169.252894 -310.835128) (xy 169.293397 -310.863084) (xy 169.32889 -310.897176) (xy 169.358455 -310.93652)
			(xy 169.381326 -310.980097) (xy 169.39691 -311.026778) (xy 169.404805 -311.075355) (xy 169.4053 -311.099962)
			(xy 170.694108 -311.099962) (xy 170.698068 -311.050908) (xy 170.709845 -311.003124) (xy 170.729136 -310.957848)
			(xy 170.755439 -310.916252) (xy 170.788074 -310.879415) (xy 170.826195 -310.84829) (xy 170.868816 -310.823683)
			(xy 170.914832 -310.806231) (xy 170.963051 -310.796387) (xy 171.012226 -310.794406) (xy 171.061081 -310.800338)
			(xy 171.108352 -310.81403) (xy 171.152814 -310.835128) (xy 171.193317 -310.863084) (xy 171.22881 -310.897176)
			(xy 171.258375 -310.93652) (xy 171.281246 -310.980097) (xy 171.29683 -311.026778) (xy 171.304725 -311.075355)
			(xy 171.30522 -311.099962) (xy 172.594282 -311.099962) (xy 172.598242 -311.050908) (xy 172.610019 -311.003124)
			(xy 172.62931 -310.957848) (xy 172.655613 -310.916252) (xy 172.688248 -310.879415) (xy 172.726369 -310.84829)
			(xy 172.76899 -310.823683) (xy 172.815006 -310.806231) (xy 172.863225 -310.796387) (xy 172.9124 -310.794406)
			(xy 172.961255 -310.800338) (xy 173.008526 -310.81403) (xy 173.052988 -310.835128) (xy 173.093491 -310.863084)
			(xy 173.128984 -310.897176) (xy 173.158549 -310.93652) (xy 173.18142 -310.980097) (xy 173.197004 -311.026778)
			(xy 173.204899 -311.075355) (xy 173.205394 -311.099962) (xy 174.494202 -311.099962) (xy 174.498162 -311.050908)
			(xy 174.509939 -311.003124) (xy 174.52923 -310.957848) (xy 174.555533 -310.916252) (xy 174.588168 -310.879415)
			(xy 174.626289 -310.84829) (xy 174.66891 -310.823683) (xy 174.714926 -310.806231) (xy 174.763145 -310.796387)
			(xy 174.81232 -310.794406) (xy 174.861175 -310.800338) (xy 174.908446 -310.81403) (xy 174.952908 -310.835128)
			(xy 174.993411 -310.863084) (xy 175.028904 -310.897176) (xy 175.058469 -310.93652) (xy 175.08134 -310.980097)
			(xy 175.096924 -311.026778) (xy 175.104819 -311.075355) (xy 175.105314 -311.099962) (xy 176.394122 -311.099962)
			(xy 176.398082 -311.050908) (xy 176.409859 -311.003124) (xy 176.42915 -310.957848) (xy 176.455453 -310.916252)
			(xy 176.488088 -310.879415) (xy 176.526209 -310.84829) (xy 176.56883 -310.823683) (xy 176.614846 -310.806231)
			(xy 176.663065 -310.796387) (xy 176.71224 -310.794406) (xy 176.761095 -310.800338) (xy 176.808366 -310.81403)
			(xy 176.852828 -310.835128) (xy 176.893331 -310.863084) (xy 176.928824 -310.897176) (xy 176.958389 -310.93652)
			(xy 176.98126 -310.980097) (xy 176.996844 -311.026778) (xy 177.004739 -311.075355) (xy 177.005234 -311.099962)
			(xy 178.294042 -311.099962) (xy 178.298002 -311.050908) (xy 178.309779 -311.003124) (xy 178.32907 -310.957848)
			(xy 178.355373 -310.916252) (xy 178.388008 -310.879415) (xy 178.426129 -310.84829) (xy 178.46875 -310.823683)
			(xy 178.514766 -310.806231) (xy 178.562985 -310.796387) (xy 178.61216 -310.794406) (xy 178.661015 -310.800338)
			(xy 178.708286 -310.81403) (xy 178.752748 -310.835128) (xy 178.793251 -310.863084) (xy 178.828744 -310.897176)
			(xy 178.858309 -310.93652) (xy 178.88118 -310.980097) (xy 178.896764 -311.026778) (xy 178.904659 -311.075355)
			(xy 178.905154 -311.099962) (xy 180.194216 -311.099962) (xy 180.198176 -311.050908) (xy 180.209953 -311.003124)
			(xy 180.229244 -310.957848) (xy 180.255547 -310.916252) (xy 180.288182 -310.879415) (xy 180.326303 -310.84829)
			(xy 180.368924 -310.823683) (xy 180.41494 -310.806231) (xy 180.463159 -310.796387) (xy 180.512334 -310.794406)
			(xy 180.561189 -310.800338) (xy 180.60846 -310.81403) (xy 180.652922 -310.835128) (xy 180.693425 -310.863084)
			(xy 180.728918 -310.897176) (xy 180.758483 -310.93652) (xy 180.781354 -310.980097) (xy 180.796938 -311.026778)
			(xy 180.804833 -311.075355) (xy 180.805328 -311.099962) (xy 182.094136 -311.099962) (xy 182.098096 -311.050908)
			(xy 182.109873 -311.003124) (xy 182.129164 -310.957848) (xy 182.155467 -310.916252) (xy 182.188102 -310.879415)
			(xy 182.226223 -310.84829) (xy 182.268844 -310.823683) (xy 182.31486 -310.806231) (xy 182.363079 -310.796387)
			(xy 182.412254 -310.794406) (xy 182.461109 -310.800338) (xy 182.50838 -310.81403) (xy 182.552842 -310.835128)
			(xy 182.593345 -310.863084) (xy 182.628838 -310.897176) (xy 182.658403 -310.93652) (xy 182.681274 -310.980097)
			(xy 182.696858 -311.026778) (xy 182.704753 -311.075355) (xy 182.705248 -311.099962) (xy 183.994056 -311.099962)
			(xy 183.998016 -311.050908) (xy 184.009793 -311.003124) (xy 184.029084 -310.957848) (xy 184.055387 -310.916252)
			(xy 184.088022 -310.879415) (xy 184.126143 -310.84829) (xy 184.168764 -310.823683) (xy 184.21478 -310.806231)
			(xy 184.262999 -310.796387) (xy 184.312174 -310.794406) (xy 184.361029 -310.800338) (xy 184.4083 -310.81403)
			(xy 184.452762 -310.835128) (xy 184.493265 -310.863084) (xy 184.528758 -310.897176) (xy 184.558323 -310.93652)
			(xy 184.581194 -310.980097) (xy 184.596778 -311.026778) (xy 184.604673 -311.075355) (xy 184.605168 -311.099962)
			(xy 185.89423 -311.099962) (xy 185.89819 -311.050908) (xy 185.909967 -311.003124) (xy 185.929258 -310.957848)
			(xy 185.955561 -310.916252) (xy 185.988196 -310.879415) (xy 186.026317 -310.84829) (xy 186.068938 -310.823683)
			(xy 186.114954 -310.806231) (xy 186.163173 -310.796387) (xy 186.212348 -310.794406) (xy 186.261203 -310.800338)
			(xy 186.308474 -310.81403) (xy 186.352936 -310.835128) (xy 186.393439 -310.863084) (xy 186.428932 -310.897176)
			(xy 186.458497 -310.93652) (xy 186.481368 -310.980097) (xy 186.496952 -311.026778) (xy 186.504847 -311.075355)
			(xy 186.505342 -311.099962) (xy 187.79415 -311.099962) (xy 187.79811 -311.050908) (xy 187.809887 -311.003124)
			(xy 187.829178 -310.957848) (xy 187.855481 -310.916252) (xy 187.888116 -310.879415) (xy 187.926237 -310.84829)
			(xy 187.968858 -310.823683) (xy 188.014874 -310.806231) (xy 188.063093 -310.796387) (xy 188.112268 -310.794406)
			(xy 188.161123 -310.800338) (xy 188.208394 -310.81403) (xy 188.252856 -310.835128) (xy 188.293359 -310.863084)
			(xy 188.328852 -310.897176) (xy 188.358417 -310.93652) (xy 188.381288 -310.980097) (xy 188.396872 -311.026778)
			(xy 188.404767 -311.075355) (xy 188.405262 -311.099962) (xy 189.69407 -311.099962) (xy 189.69803 -311.050908)
			(xy 189.709807 -311.003124) (xy 189.729098 -310.957848) (xy 189.755401 -310.916252) (xy 189.788036 -310.879415)
			(xy 189.826157 -310.84829) (xy 189.868778 -310.823683) (xy 189.914794 -310.806231) (xy 189.963013 -310.796387)
			(xy 190.012188 -310.794406) (xy 190.061043 -310.800338) (xy 190.108314 -310.81403) (xy 190.152776 -310.835128)
			(xy 190.193279 -310.863084) (xy 190.228772 -310.897176) (xy 190.258337 -310.93652) (xy 190.281208 -310.980097)
			(xy 190.296792 -311.026778) (xy 190.304687 -311.075355) (xy 190.305182 -311.099962) (xy 191.594244 -311.099962)
			(xy 191.598204 -311.050908) (xy 191.609981 -311.003124) (xy 191.629272 -310.957848) (xy 191.655575 -310.916252)
			(xy 191.68821 -310.879415) (xy 191.726331 -310.84829) (xy 191.768952 -310.823683) (xy 191.814968 -310.806231)
			(xy 191.863187 -310.796387) (xy 191.912362 -310.794406) (xy 191.961217 -310.800338) (xy 192.008488 -310.81403)
			(xy 192.05295 -310.835128) (xy 192.093453 -310.863084) (xy 192.128946 -310.897176) (xy 192.158511 -310.93652)
			(xy 192.181382 -310.980097) (xy 192.196966 -311.026778) (xy 192.204861 -311.075355) (xy 192.205356 -311.099962)
			(xy 193.494164 -311.099962) (xy 193.498124 -311.050908) (xy 193.509901 -311.003124) (xy 193.529192 -310.957848)
			(xy 193.555495 -310.916252) (xy 193.58813 -310.879415) (xy 193.626251 -310.84829) (xy 193.668872 -310.823683)
			(xy 193.714888 -310.806231) (xy 193.763107 -310.796387) (xy 193.812282 -310.794406) (xy 193.861137 -310.800338)
			(xy 193.908408 -310.81403) (xy 193.95287 -310.835128) (xy 193.993373 -310.863084) (xy 194.028866 -310.897176)
			(xy 194.058431 -310.93652) (xy 194.081302 -310.980097) (xy 194.096886 -311.026778) (xy 194.104781 -311.075355)
			(xy 194.105276 -311.099962) (xy 195.394084 -311.099962) (xy 195.398044 -311.050908) (xy 195.409821 -311.003124)
			(xy 195.429112 -310.957848) (xy 195.455415 -310.916252) (xy 195.48805 -310.879415) (xy 195.526171 -310.84829)
			(xy 195.568792 -310.823683) (xy 195.614808 -310.806231) (xy 195.663027 -310.796387) (xy 195.712202 -310.794406)
			(xy 195.761057 -310.800338) (xy 195.808328 -310.81403) (xy 195.85279 -310.835128) (xy 195.893293 -310.863084)
			(xy 195.928786 -310.897176) (xy 195.958351 -310.93652) (xy 195.981222 -310.980097) (xy 195.996806 -311.026778)
			(xy 196.004701 -311.075355) (xy 196.005196 -311.099962) (xy 271.594084 -311.099962) (xy 271.598044 -311.050908)
			(xy 271.609821 -311.003124) (xy 271.629112 -310.957848) (xy 271.655415 -310.916252) (xy 271.68805 -310.879415)
			(xy 271.726171 -310.84829) (xy 271.768792 -310.823683) (xy 271.814808 -310.806231) (xy 271.863027 -310.796387)
			(xy 271.912202 -310.794406) (xy 271.961057 -310.800338) (xy 272.008328 -310.81403) (xy 272.05279 -310.835128)
			(xy 272.093293 -310.863084) (xy 272.128786 -310.897176) (xy 272.158351 -310.93652) (xy 272.181222 -310.980097)
			(xy 272.196806 -311.026778) (xy 272.204701 -311.075355) (xy 272.205196 -311.099962) (xy 273.494004 -311.099962)
			(xy 273.497964 -311.050908) (xy 273.509741 -311.003124) (xy 273.529032 -310.957848) (xy 273.555335 -310.916252)
			(xy 273.58797 -310.879415) (xy 273.626091 -310.84829) (xy 273.668712 -310.823683) (xy 273.714728 -310.806231)
			(xy 273.762947 -310.796387) (xy 273.812122 -310.794406) (xy 273.860977 -310.800338) (xy 273.908248 -310.81403)
			(xy 273.95271 -310.835128) (xy 273.993213 -310.863084) (xy 274.028706 -310.897176) (xy 274.058271 -310.93652)
			(xy 274.081142 -310.980097) (xy 274.096726 -311.026778) (xy 274.104621 -311.075355) (xy 274.105116 -311.099962)
			(xy 275.393924 -311.099962) (xy 275.397884 -311.050908) (xy 275.409661 -311.003124) (xy 275.428952 -310.957848)
			(xy 275.455255 -310.916252) (xy 275.48789 -310.879415) (xy 275.526011 -310.84829) (xy 275.568632 -310.823683)
			(xy 275.614648 -310.806231) (xy 275.662867 -310.796387) (xy 275.712042 -310.794406) (xy 275.760897 -310.800338)
			(xy 275.808168 -310.81403) (xy 275.85263 -310.835128) (xy 275.893133 -310.863084) (xy 275.928626 -310.897176)
			(xy 275.958191 -310.93652) (xy 275.981062 -310.980097) (xy 275.996646 -311.026778) (xy 276.004541 -311.075355)
			(xy 276.005036 -311.099962) (xy 277.294098 -311.099962) (xy 277.298058 -311.050908) (xy 277.309835 -311.003124)
			(xy 277.329126 -310.957848) (xy 277.355429 -310.916252) (xy 277.388064 -310.879415) (xy 277.426185 -310.84829)
			(xy 277.468806 -310.823683) (xy 277.514822 -310.806231) (xy 277.563041 -310.796387) (xy 277.612216 -310.794406)
			(xy 277.661071 -310.800338) (xy 277.708342 -310.81403) (xy 277.752804 -310.835128) (xy 277.793307 -310.863084)
			(xy 277.8288 -310.897176) (xy 277.858365 -310.93652) (xy 277.881236 -310.980097) (xy 277.89682 -311.026778)
			(xy 277.904715 -311.075355) (xy 277.90521 -311.099962) (xy 279.194018 -311.099962) (xy 279.197978 -311.050908)
			(xy 279.209755 -311.003124) (xy 279.229046 -310.957848) (xy 279.255349 -310.916252) (xy 279.287984 -310.879415)
			(xy 279.326105 -310.84829) (xy 279.368726 -310.823683) (xy 279.414742 -310.806231) (xy 279.462961 -310.796387)
			(xy 279.512136 -310.794406) (xy 279.560991 -310.800338) (xy 279.608262 -310.81403) (xy 279.652724 -310.835128)
			(xy 279.693227 -310.863084) (xy 279.72872 -310.897176) (xy 279.758285 -310.93652) (xy 279.781156 -310.980097)
			(xy 279.79674 -311.026778) (xy 279.804635 -311.075355) (xy 279.80513 -311.099962) (xy 281.093938 -311.099962)
			(xy 281.097898 -311.050908) (xy 281.109675 -311.003124) (xy 281.128966 -310.957848) (xy 281.155269 -310.916252)
			(xy 281.187904 -310.879415) (xy 281.226025 -310.84829) (xy 281.268646 -310.823683) (xy 281.314662 -310.806231)
			(xy 281.362881 -310.796387) (xy 281.412056 -310.794406) (xy 281.460911 -310.800338) (xy 281.508182 -310.81403)
			(xy 281.552644 -310.835128) (xy 281.593147 -310.863084) (xy 281.62864 -310.897176) (xy 281.658205 -310.93652)
			(xy 281.681076 -310.980097) (xy 281.69666 -311.026778) (xy 281.704555 -311.075355) (xy 281.70505 -311.099962)
			(xy 282.994112 -311.099962) (xy 282.998072 -311.050908) (xy 283.009849 -311.003124) (xy 283.02914 -310.957848)
			(xy 283.055443 -310.916252) (xy 283.088078 -310.879415) (xy 283.126199 -310.84829) (xy 283.16882 -310.823683)
			(xy 283.214836 -310.806231) (xy 283.263055 -310.796387) (xy 283.31223 -310.794406) (xy 283.361085 -310.800338)
			(xy 283.408356 -310.81403) (xy 283.452818 -310.835128) (xy 283.493321 -310.863084) (xy 283.528814 -310.897176)
			(xy 283.558379 -310.93652) (xy 283.58125 -310.980097) (xy 283.596834 -311.026778) (xy 283.604729 -311.075355)
			(xy 283.605224 -311.099962) (xy 284.894032 -311.099962) (xy 284.897992 -311.050908) (xy 284.909769 -311.003124)
			(xy 284.92906 -310.957848) (xy 284.955363 -310.916252) (xy 284.987998 -310.879415) (xy 285.026119 -310.84829)
			(xy 285.06874 -310.823683) (xy 285.114756 -310.806231) (xy 285.162975 -310.796387) (xy 285.21215 -310.794406)
			(xy 285.261005 -310.800338) (xy 285.308276 -310.81403) (xy 285.352738 -310.835128) (xy 285.393241 -310.863084)
			(xy 285.428734 -310.897176) (xy 285.458299 -310.93652) (xy 285.48117 -310.980097) (xy 285.496754 -311.026778)
			(xy 285.504649 -311.075355) (xy 285.505144 -311.099962) (xy 286.793952 -311.099962) (xy 286.797912 -311.050908)
			(xy 286.809689 -311.003124) (xy 286.82898 -310.957848) (xy 286.855283 -310.916252) (xy 286.887918 -310.879415)
			(xy 286.926039 -310.84829) (xy 286.96866 -310.823683) (xy 287.014676 -310.806231) (xy 287.062895 -310.796387)
			(xy 287.11207 -310.794406) (xy 287.160925 -310.800338) (xy 287.208196 -310.81403) (xy 287.252658 -310.835128)
			(xy 287.293161 -310.863084) (xy 287.328654 -310.897176) (xy 287.358219 -310.93652) (xy 287.38109 -310.980097)
			(xy 287.396674 -311.026778) (xy 287.404569 -311.075355) (xy 287.405064 -311.099962) (xy 288.694126 -311.099962)
			(xy 288.698086 -311.050908) (xy 288.709863 -311.003124) (xy 288.729154 -310.957848) (xy 288.755457 -310.916252)
			(xy 288.788092 -310.879415) (xy 288.826213 -310.84829) (xy 288.868834 -310.823683) (xy 288.91485 -310.806231)
			(xy 288.963069 -310.796387) (xy 289.012244 -310.794406) (xy 289.061099 -310.800338) (xy 289.10837 -310.81403)
			(xy 289.152832 -310.835128) (xy 289.193335 -310.863084) (xy 289.228828 -310.897176) (xy 289.258393 -310.93652)
			(xy 289.281264 -310.980097) (xy 289.296848 -311.026778) (xy 289.304743 -311.075355) (xy 289.305238 -311.099962)
			(xy 290.594046 -311.099962) (xy 290.598006 -311.050908) (xy 290.609783 -311.003124) (xy 290.629074 -310.957848)
			(xy 290.655377 -310.916252) (xy 290.688012 -310.879415) (xy 290.726133 -310.84829) (xy 290.768754 -310.823683)
			(xy 290.81477 -310.806231) (xy 290.862989 -310.796387) (xy 290.912164 -310.794406) (xy 290.961019 -310.800338)
			(xy 291.00829 -310.81403) (xy 291.052752 -310.835128) (xy 291.093255 -310.863084) (xy 291.128748 -310.897176)
			(xy 291.158313 -310.93652) (xy 291.181184 -310.980097) (xy 291.196768 -311.026778) (xy 291.204663 -311.075355)
			(xy 291.205158 -311.099962) (xy 292.493966 -311.099962) (xy 292.497926 -311.050908) (xy 292.509703 -311.003124)
			(xy 292.528994 -310.957848) (xy 292.555297 -310.916252) (xy 292.587932 -310.879415) (xy 292.626053 -310.84829)
			(xy 292.668674 -310.823683) (xy 292.71469 -310.806231) (xy 292.762909 -310.796387) (xy 292.812084 -310.794406)
			(xy 292.860939 -310.800338) (xy 292.90821 -310.81403) (xy 292.952672 -310.835128) (xy 292.993175 -310.863084)
			(xy 293.028668 -310.897176) (xy 293.058233 -310.93652) (xy 293.081104 -310.980097) (xy 293.096688 -311.026778)
			(xy 293.104583 -311.075355) (xy 293.105078 -311.099962) (xy 294.393886 -311.099962) (xy 294.397846 -311.050908)
			(xy 294.409623 -311.003124) (xy 294.428914 -310.957848) (xy 294.455217 -310.916252) (xy 294.487852 -310.879415)
			(xy 294.525973 -310.84829) (xy 294.568594 -310.823683) (xy 294.61461 -310.806231) (xy 294.662829 -310.796387)
			(xy 294.712004 -310.794406) (xy 294.760859 -310.800338) (xy 294.80813 -310.81403) (xy 294.852592 -310.835128)
			(xy 294.893095 -310.863084) (xy 294.928588 -310.897176) (xy 294.958153 -310.93652) (xy 294.981024 -310.980097)
			(xy 294.996608 -311.026778) (xy 295.004503 -311.075355) (xy 295.004998 -311.099962) (xy 296.29406 -311.099962)
			(xy 296.29802 -311.050908) (xy 296.309797 -311.003124) (xy 296.329088 -310.957848) (xy 296.355391 -310.916252)
			(xy 296.388026 -310.879415) (xy 296.426147 -310.84829) (xy 296.468768 -310.823683) (xy 296.514784 -310.806231)
			(xy 296.563003 -310.796387) (xy 296.612178 -310.794406) (xy 296.661033 -310.800338) (xy 296.708304 -310.81403)
			(xy 296.752766 -310.835128) (xy 296.793269 -310.863084) (xy 296.828762 -310.897176) (xy 296.858327 -310.93652)
			(xy 296.881198 -310.980097) (xy 296.896782 -311.026778) (xy 296.904677 -311.075355) (xy 296.905172 -311.099962)
			(xy 298.19398 -311.099962) (xy 298.19794 -311.050908) (xy 298.209717 -311.003124) (xy 298.229008 -310.957848)
			(xy 298.255311 -310.916252) (xy 298.287946 -310.879415) (xy 298.326067 -310.84829) (xy 298.368688 -310.823683)
			(xy 298.414704 -310.806231) (xy 298.462923 -310.796387) (xy 298.512098 -310.794406) (xy 298.560953 -310.800338)
			(xy 298.608224 -310.81403) (xy 298.652686 -310.835128) (xy 298.693189 -310.863084) (xy 298.728682 -310.897176)
			(xy 298.758247 -310.93652) (xy 298.781118 -310.980097) (xy 298.796702 -311.026778) (xy 298.804597 -311.075355)
			(xy 298.805092 -311.099962) (xy 300.0939 -311.099962) (xy 300.09786 -311.050908) (xy 300.109637 -311.003124)
			(xy 300.128928 -310.957848) (xy 300.155231 -310.916252) (xy 300.187866 -310.879415) (xy 300.225987 -310.84829)
			(xy 300.268608 -310.823683) (xy 300.314624 -310.806231) (xy 300.362843 -310.796387) (xy 300.412018 -310.794406)
			(xy 300.460873 -310.800338) (xy 300.508144 -310.81403) (xy 300.552606 -310.835128) (xy 300.593109 -310.863084)
			(xy 300.628602 -310.897176) (xy 300.658167 -310.93652) (xy 300.681038 -310.980097) (xy 300.696622 -311.026778)
			(xy 300.704517 -311.075355) (xy 300.705012 -311.099962) (xy 301.994074 -311.099962) (xy 301.998034 -311.050908)
			(xy 302.009811 -311.003124) (xy 302.029102 -310.957848) (xy 302.055405 -310.916252) (xy 302.08804 -310.879415)
			(xy 302.126161 -310.84829) (xy 302.168782 -310.823683) (xy 302.214798 -310.806231) (xy 302.263017 -310.796387)
			(xy 302.312192 -310.794406) (xy 302.361047 -310.800338) (xy 302.408318 -310.81403) (xy 302.45278 -310.835128)
			(xy 302.493283 -310.863084) (xy 302.528776 -310.897176) (xy 302.558341 -310.93652) (xy 302.581212 -310.980097)
			(xy 302.596796 -311.026778) (xy 302.604691 -311.075355) (xy 302.605186 -311.099962) (xy 303.893994 -311.099962)
			(xy 303.897954 -311.050908) (xy 303.909731 -311.003124) (xy 303.929022 -310.957848) (xy 303.955325 -310.916252)
			(xy 303.98796 -310.879415) (xy 304.026081 -310.84829) (xy 304.068702 -310.823683) (xy 304.114718 -310.806231)
			(xy 304.162937 -310.796387) (xy 304.212112 -310.794406) (xy 304.260967 -310.800338) (xy 304.308238 -310.81403)
			(xy 304.3527 -310.835128) (xy 304.393203 -310.863084) (xy 304.428696 -310.897176) (xy 304.458261 -310.93652)
			(xy 304.481132 -310.980097) (xy 304.496716 -311.026778) (xy 304.504611 -311.075355) (xy 304.505106 -311.099962)
			(xy 305.793914 -311.099962) (xy 305.797874 -311.050908) (xy 305.809651 -311.003124) (xy 305.828942 -310.957848)
			(xy 305.855245 -310.916252) (xy 305.88788 -310.879415) (xy 305.926001 -310.84829) (xy 305.968622 -310.823683)
			(xy 306.014638 -310.806231) (xy 306.062857 -310.796387) (xy 306.112032 -310.794406) (xy 306.160887 -310.800338)
			(xy 306.208158 -310.81403) (xy 306.25262 -310.835128) (xy 306.293123 -310.863084) (xy 306.328616 -310.897176)
			(xy 306.358181 -310.93652) (xy 306.381052 -310.980097) (xy 306.396636 -311.026778) (xy 306.404531 -311.075355)
			(xy 306.405026 -311.099962) (xy 307.694088 -311.099962) (xy 307.698048 -311.050908) (xy 307.709825 -311.003124)
			(xy 307.729116 -310.957848) (xy 307.755419 -310.916252) (xy 307.788054 -310.879415) (xy 307.826175 -310.84829)
			(xy 307.868796 -310.823683) (xy 307.914812 -310.806231) (xy 307.963031 -310.796387) (xy 308.012206 -310.794406)
			(xy 308.061061 -310.800338) (xy 308.108332 -310.81403) (xy 308.152794 -310.835128) (xy 308.193297 -310.863084)
			(xy 308.22879 -310.897176) (xy 308.258355 -310.93652) (xy 308.281226 -310.980097) (xy 308.29681 -311.026778)
			(xy 308.304705 -311.075355) (xy 308.3052 -311.099962) (xy 309.594008 -311.099962) (xy 309.597968 -311.050908)
			(xy 309.609745 -311.003124) (xy 309.629036 -310.957848) (xy 309.655339 -310.916252) (xy 309.687974 -310.879415)
			(xy 309.726095 -310.84829) (xy 309.768716 -310.823683) (xy 309.814732 -310.806231) (xy 309.862951 -310.796387)
			(xy 309.912126 -310.794406) (xy 309.960981 -310.800338) (xy 310.008252 -310.81403) (xy 310.052714 -310.835128)
			(xy 310.093217 -310.863084) (xy 310.12871 -310.897176) (xy 310.158275 -310.93652) (xy 310.181146 -310.980097)
			(xy 310.19673 -311.026778) (xy 310.204625 -311.075355) (xy 310.20512 -311.099962) (xy 311.493928 -311.099962)
			(xy 311.497888 -311.050908) (xy 311.509665 -311.003124) (xy 311.528956 -310.957848) (xy 311.555259 -310.916252)
			(xy 311.587894 -310.879415) (xy 311.626015 -310.84829) (xy 311.668636 -310.823683) (xy 311.714652 -310.806231)
			(xy 311.762871 -310.796387) (xy 311.812046 -310.794406) (xy 311.860901 -310.800338) (xy 311.908172 -310.81403)
			(xy 311.952634 -310.835128) (xy 311.993137 -310.863084) (xy 312.02863 -310.897176) (xy 312.058195 -310.93652)
			(xy 312.081066 -310.980097) (xy 312.09665 -311.026778) (xy 312.104545 -311.075355) (xy 312.10504 -311.099962)
			(xy 387.694182 -311.099962) (xy 387.698142 -311.050908) (xy 387.709919 -311.003124) (xy 387.72921 -310.957848)
			(xy 387.755513 -310.916252) (xy 387.788148 -310.879415) (xy 387.826269 -310.84829) (xy 387.86889 -310.823683)
			(xy 387.914906 -310.806231) (xy 387.963125 -310.796387) (xy 388.0123 -310.794406) (xy 388.061155 -310.800338)
			(xy 388.108426 -310.81403) (xy 388.152888 -310.835128) (xy 388.193391 -310.863084) (xy 388.228884 -310.897176)
			(xy 388.258449 -310.93652) (xy 388.28132 -310.980097) (xy 388.296904 -311.026778) (xy 388.304799 -311.075355)
			(xy 388.305294 -311.099962) (xy 389.594102 -311.099962) (xy 389.598062 -311.050908) (xy 389.609839 -311.003124)
			(xy 389.62913 -310.957848) (xy 389.655433 -310.916252) (xy 389.688068 -310.879415) (xy 389.726189 -310.84829)
			(xy 389.76881 -310.823683) (xy 389.814826 -310.806231) (xy 389.863045 -310.796387) (xy 389.91222 -310.794406)
			(xy 389.961075 -310.800338) (xy 390.008346 -310.81403) (xy 390.052808 -310.835128) (xy 390.093311 -310.863084)
			(xy 390.128804 -310.897176) (xy 390.158369 -310.93652) (xy 390.18124 -310.980097) (xy 390.196824 -311.026778)
			(xy 390.204719 -311.075355) (xy 390.205214 -311.099962) (xy 391.494022 -311.099962) (xy 391.497982 -311.050908)
			(xy 391.509759 -311.003124) (xy 391.52905 -310.957848) (xy 391.555353 -310.916252) (xy 391.587988 -310.879415)
			(xy 391.626109 -310.84829) (xy 391.66873 -310.823683) (xy 391.714746 -310.806231) (xy 391.762965 -310.796387)
			(xy 391.81214 -310.794406) (xy 391.860995 -310.800338) (xy 391.908266 -310.81403) (xy 391.952728 -310.835128)
			(xy 391.993231 -310.863084) (xy 392.028724 -310.897176) (xy 392.058289 -310.93652) (xy 392.08116 -310.980097)
			(xy 392.096744 -311.026778) (xy 392.104639 -311.075355) (xy 392.105134 -311.099962) (xy 393.394196 -311.099962)
			(xy 393.398156 -311.050908) (xy 393.409933 -311.003124) (xy 393.429224 -310.957848) (xy 393.455527 -310.916252)
			(xy 393.488162 -310.879415) (xy 393.526283 -310.84829) (xy 393.568904 -310.823683) (xy 393.61492 -310.806231)
			(xy 393.663139 -310.796387) (xy 393.712314 -310.794406) (xy 393.761169 -310.800338) (xy 393.80844 -310.81403)
			(xy 393.852902 -310.835128) (xy 393.893405 -310.863084) (xy 393.928898 -310.897176) (xy 393.958463 -310.93652)
			(xy 393.981334 -310.980097) (xy 393.996918 -311.026778) (xy 394.004813 -311.075355) (xy 394.005308 -311.099962)
			(xy 395.294116 -311.099962) (xy 395.298076 -311.050908) (xy 395.309853 -311.003124) (xy 395.329144 -310.957848)
			(xy 395.355447 -310.916252) (xy 395.388082 -310.879415) (xy 395.426203 -310.84829) (xy 395.468824 -310.823683)
			(xy 395.51484 -310.806231) (xy 395.563059 -310.796387) (xy 395.612234 -310.794406) (xy 395.661089 -310.800338)
			(xy 395.70836 -310.81403) (xy 395.752822 -310.835128) (xy 395.793325 -310.863084) (xy 395.828818 -310.897176)
			(xy 395.858383 -310.93652) (xy 395.881254 -310.980097) (xy 395.896838 -311.026778) (xy 395.904733 -311.075355)
			(xy 395.905228 -311.099962) (xy 397.194036 -311.099962) (xy 397.197996 -311.050908) (xy 397.209773 -311.003124)
			(xy 397.229064 -310.957848) (xy 397.255367 -310.916252) (xy 397.288002 -310.879415) (xy 397.326123 -310.84829)
			(xy 397.368744 -310.823683) (xy 397.41476 -310.806231) (xy 397.462979 -310.796387) (xy 397.512154 -310.794406)
			(xy 397.561009 -310.800338) (xy 397.60828 -310.81403) (xy 397.652742 -310.835128) (xy 397.693245 -310.863084)
			(xy 397.728738 -310.897176) (xy 397.758303 -310.93652) (xy 397.781174 -310.980097) (xy 397.796758 -311.026778)
			(xy 397.804653 -311.075355) (xy 397.805148 -311.099962) (xy 399.09421 -311.099962) (xy 399.09817 -311.050908)
			(xy 399.109947 -311.003124) (xy 399.129238 -310.957848) (xy 399.155541 -310.916252) (xy 399.188176 -310.879415)
			(xy 399.226297 -310.84829) (xy 399.268918 -310.823683) (xy 399.314934 -310.806231) (xy 399.363153 -310.796387)
			(xy 399.412328 -310.794406) (xy 399.461183 -310.800338) (xy 399.508454 -310.81403) (xy 399.552916 -310.835128)
			(xy 399.593419 -310.863084) (xy 399.628912 -310.897176) (xy 399.658477 -310.93652) (xy 399.681348 -310.980097)
			(xy 399.696932 -311.026778) (xy 399.704827 -311.075355) (xy 399.705322 -311.099962) (xy 400.99413 -311.099962)
			(xy 400.99809 -311.050908) (xy 401.009867 -311.003124) (xy 401.029158 -310.957848) (xy 401.055461 -310.916252)
			(xy 401.088096 -310.879415) (xy 401.126217 -310.84829) (xy 401.168838 -310.823683) (xy 401.214854 -310.806231)
			(xy 401.263073 -310.796387) (xy 401.312248 -310.794406) (xy 401.361103 -310.800338) (xy 401.408374 -310.81403)
			(xy 401.452836 -310.835128) (xy 401.493339 -310.863084) (xy 401.528832 -310.897176) (xy 401.558397 -310.93652)
			(xy 401.581268 -310.980097) (xy 401.596852 -311.026778) (xy 401.604747 -311.075355) (xy 401.605242 -311.099962)
			(xy 402.89405 -311.099962) (xy 402.89801 -311.050908) (xy 402.909787 -311.003124) (xy 402.929078 -310.957848)
			(xy 402.955381 -310.916252) (xy 402.988016 -310.879415) (xy 403.026137 -310.84829) (xy 403.068758 -310.823683)
			(xy 403.114774 -310.806231) (xy 403.162993 -310.796387) (xy 403.212168 -310.794406) (xy 403.261023 -310.800338)
			(xy 403.308294 -310.81403) (xy 403.352756 -310.835128) (xy 403.393259 -310.863084) (xy 403.428752 -310.897176)
			(xy 403.458317 -310.93652) (xy 403.481188 -310.980097) (xy 403.496772 -311.026778) (xy 403.504667 -311.075355)
			(xy 403.505162 -311.099962) (xy 404.794224 -311.099962) (xy 404.798184 -311.050908) (xy 404.809961 -311.003124)
			(xy 404.829252 -310.957848) (xy 404.855555 -310.916252) (xy 404.88819 -310.879415) (xy 404.926311 -310.84829)
			(xy 404.968932 -310.823683) (xy 405.014948 -310.806231) (xy 405.063167 -310.796387) (xy 405.112342 -310.794406)
			(xy 405.161197 -310.800338) (xy 405.208468 -310.81403) (xy 405.25293 -310.835128) (xy 405.293433 -310.863084)
			(xy 405.328926 -310.897176) (xy 405.358491 -310.93652) (xy 405.381362 -310.980097) (xy 405.396946 -311.026778)
			(xy 405.404841 -311.075355) (xy 405.405336 -311.099962) (xy 406.694144 -311.099962) (xy 406.698104 -311.050908)
			(xy 406.709881 -311.003124) (xy 406.729172 -310.957848) (xy 406.755475 -310.916252) (xy 406.78811 -310.879415)
			(xy 406.826231 -310.84829) (xy 406.868852 -310.823683) (xy 406.914868 -310.806231) (xy 406.963087 -310.796387)
			(xy 407.012262 -310.794406) (xy 407.061117 -310.800338) (xy 407.108388 -310.81403) (xy 407.15285 -310.835128)
			(xy 407.193353 -310.863084) (xy 407.228846 -310.897176) (xy 407.258411 -310.93652) (xy 407.281282 -310.980097)
			(xy 407.296866 -311.026778) (xy 407.304761 -311.075355) (xy 407.305256 -311.099962) (xy 408.594064 -311.099962)
			(xy 408.598024 -311.050908) (xy 408.609801 -311.003124) (xy 408.629092 -310.957848) (xy 408.655395 -310.916252)
			(xy 408.68803 -310.879415) (xy 408.726151 -310.84829) (xy 408.768772 -310.823683) (xy 408.814788 -310.806231)
			(xy 408.863007 -310.796387) (xy 408.912182 -310.794406) (xy 408.961037 -310.800338) (xy 409.008308 -310.81403)
			(xy 409.05277 -310.835128) (xy 409.093273 -310.863084) (xy 409.128766 -310.897176) (xy 409.158331 -310.93652)
			(xy 409.181202 -310.980097) (xy 409.196786 -311.026778) (xy 409.204681 -311.075355) (xy 409.205176 -311.099962)
			(xy 410.493984 -311.099962) (xy 410.497944 -311.050908) (xy 410.509721 -311.003124) (xy 410.529012 -310.957848)
			(xy 410.555315 -310.916252) (xy 410.58795 -310.879415) (xy 410.626071 -310.84829) (xy 410.668692 -310.823683)
			(xy 410.714708 -310.806231) (xy 410.762927 -310.796387) (xy 410.812102 -310.794406) (xy 410.860957 -310.800338)
			(xy 410.908228 -310.81403) (xy 410.95269 -310.835128) (xy 410.993193 -310.863084) (xy 411.028686 -310.897176)
			(xy 411.058251 -310.93652) (xy 411.081122 -310.980097) (xy 411.096706 -311.026778) (xy 411.104601 -311.075355)
			(xy 411.105096 -311.099962) (xy 412.394158 -311.099962) (xy 412.398118 -311.050908) (xy 412.409895 -311.003124)
			(xy 412.429186 -310.957848) (xy 412.455489 -310.916252) (xy 412.488124 -310.879415) (xy 412.526245 -310.84829)
			(xy 412.568866 -310.823683) (xy 412.614882 -310.806231) (xy 412.663101 -310.796387) (xy 412.712276 -310.794406)
			(xy 412.761131 -310.800338) (xy 412.808402 -310.81403) (xy 412.852864 -310.835128) (xy 412.893367 -310.863084)
			(xy 412.92886 -310.897176) (xy 412.958425 -310.93652) (xy 412.981296 -310.980097) (xy 412.99688 -311.026778)
			(xy 413.004775 -311.075355) (xy 413.00527 -311.099962) (xy 414.294078 -311.099962) (xy 414.298038 -311.050908)
			(xy 414.309815 -311.003124) (xy 414.329106 -310.957848) (xy 414.355409 -310.916252) (xy 414.388044 -310.879415)
			(xy 414.426165 -310.84829) (xy 414.468786 -310.823683) (xy 414.514802 -310.806231) (xy 414.563021 -310.796387)
			(xy 414.612196 -310.794406) (xy 414.661051 -310.800338) (xy 414.708322 -310.81403) (xy 414.752784 -310.835128)
			(xy 414.793287 -310.863084) (xy 414.82878 -310.897176) (xy 414.858345 -310.93652) (xy 414.881216 -310.980097)
			(xy 414.8968 -311.026778) (xy 414.904695 -311.075355) (xy 414.90519 -311.099962) (xy 416.193998 -311.099962)
			(xy 416.197958 -311.050908) (xy 416.209735 -311.003124) (xy 416.229026 -310.957848) (xy 416.255329 -310.916252)
			(xy 416.287964 -310.879415) (xy 416.326085 -310.84829) (xy 416.368706 -310.823683) (xy 416.414722 -310.806231)
			(xy 416.462941 -310.796387) (xy 416.512116 -310.794406) (xy 416.560971 -310.800338) (xy 416.608242 -310.81403)
			(xy 416.652704 -310.835128) (xy 416.693207 -310.863084) (xy 416.7287 -310.897176) (xy 416.758265 -310.93652)
			(xy 416.781136 -310.980097) (xy 416.79672 -311.026778) (xy 416.804615 -311.075355) (xy 416.80511 -311.099962)
			(xy 418.094172 -311.099962) (xy 418.098132 -311.050908) (xy 418.109909 -311.003124) (xy 418.1292 -310.957848)
			(xy 418.155503 -310.916252) (xy 418.188138 -310.879415) (xy 418.226259 -310.84829) (xy 418.26888 -310.823683)
			(xy 418.314896 -310.806231) (xy 418.363115 -310.796387) (xy 418.41229 -310.794406) (xy 418.461145 -310.800338)
			(xy 418.508416 -310.81403) (xy 418.552878 -310.835128) (xy 418.593381 -310.863084) (xy 418.628874 -310.897176)
			(xy 418.658439 -310.93652) (xy 418.68131 -310.980097) (xy 418.696894 -311.026778) (xy 418.704789 -311.075355)
			(xy 418.705284 -311.099962) (xy 419.994092 -311.099962) (xy 419.998052 -311.050908) (xy 420.009829 -311.003124)
			(xy 420.02912 -310.957848) (xy 420.055423 -310.916252) (xy 420.088058 -310.879415) (xy 420.126179 -310.84829)
			(xy 420.1688 -310.823683) (xy 420.214816 -310.806231) (xy 420.263035 -310.796387) (xy 420.31221 -310.794406)
			(xy 420.361065 -310.800338) (xy 420.408336 -310.81403) (xy 420.452798 -310.835128) (xy 420.493301 -310.863084)
			(xy 420.528794 -310.897176) (xy 420.558359 -310.93652) (xy 420.58123 -310.980097) (xy 420.596814 -311.026778)
			(xy 420.604709 -311.075355) (xy 420.605204 -311.099962) (xy 421.894012 -311.099962) (xy 421.897972 -311.050908)
			(xy 421.909749 -311.003124) (xy 421.92904 -310.957848) (xy 421.955343 -310.916252) (xy 421.987978 -310.879415)
			(xy 422.026099 -310.84829) (xy 422.06872 -310.823683) (xy 422.114736 -310.806231) (xy 422.162955 -310.796387)
			(xy 422.21213 -310.794406) (xy 422.260985 -310.800338) (xy 422.308256 -310.81403) (xy 422.352718 -310.835128)
			(xy 422.393221 -310.863084) (xy 422.428714 -310.897176) (xy 422.458279 -310.93652) (xy 422.48115 -310.980097)
			(xy 422.496734 -311.026778) (xy 422.504629 -311.075355) (xy 422.505124 -311.099962) (xy 423.794186 -311.099962)
			(xy 423.798146 -311.050908) (xy 423.809923 -311.003124) (xy 423.829214 -310.957848) (xy 423.855517 -310.916252)
			(xy 423.888152 -310.879415) (xy 423.926273 -310.84829) (xy 423.968894 -310.823683) (xy 424.01491 -310.806231)
			(xy 424.063129 -310.796387) (xy 424.112304 -310.794406) (xy 424.161159 -310.800338) (xy 424.20843 -310.81403)
			(xy 424.252892 -310.835128) (xy 424.293395 -310.863084) (xy 424.328888 -310.897176) (xy 424.358453 -310.93652)
			(xy 424.381324 -310.980097) (xy 424.396908 -311.026778) (xy 424.404803 -311.075355) (xy 424.405298 -311.099962)
			(xy 425.694106 -311.099962) (xy 425.698066 -311.050908) (xy 425.709843 -311.003124) (xy 425.729134 -310.957848)
			(xy 425.755437 -310.916252) (xy 425.788072 -310.879415) (xy 425.826193 -310.84829) (xy 425.868814 -310.823683)
			(xy 425.91483 -310.806231) (xy 425.963049 -310.796387) (xy 426.012224 -310.794406) (xy 426.061079 -310.800338)
			(xy 426.10835 -310.81403) (xy 426.152812 -310.835128) (xy 426.193315 -310.863084) (xy 426.228808 -310.897176)
			(xy 426.258373 -310.93652) (xy 426.281244 -310.980097) (xy 426.296828 -311.026778) (xy 426.304723 -311.075355)
			(xy 426.305218 -311.099962) (xy 427.594026 -311.099962) (xy 427.597986 -311.050908) (xy 427.609763 -311.003124)
			(xy 427.629054 -310.957848) (xy 427.655357 -310.916252) (xy 427.687992 -310.879415) (xy 427.726113 -310.84829)
			(xy 427.768734 -310.823683) (xy 427.81475 -310.806231) (xy 427.862969 -310.796387) (xy 427.912144 -310.794406)
			(xy 427.960999 -310.800338) (xy 428.00827 -310.81403) (xy 428.052732 -310.835128) (xy 428.093235 -310.863084)
			(xy 428.128728 -310.897176) (xy 428.158293 -310.93652) (xy 428.181164 -310.980097) (xy 428.196748 -311.026778)
			(xy 428.204643 -311.075355) (xy 428.205138 -311.099962) (xy 428.204643 -311.124569) (xy 428.196748 -311.173146)
			(xy 428.181164 -311.219827) (xy 428.158293 -311.263404) (xy 428.128728 -311.302748) (xy 428.093235 -311.33684)
			(xy 428.052732 -311.364796) (xy 428.00827 -311.385894) (xy 427.960999 -311.399586) (xy 427.912144 -311.405518)
			(xy 427.862969 -311.403537) (xy 427.81475 -311.393693) (xy 427.768734 -311.376241) (xy 427.726113 -311.351634)
			(xy 427.687992 -311.320509) (xy 427.655357 -311.283672) (xy 427.629054 -311.242076) (xy 427.609763 -311.1968)
			(xy 427.597986 -311.149016) (xy 427.594026 -311.099962) (xy 426.305218 -311.099962) (xy 426.304723 -311.124569)
			(xy 426.296828 -311.173146) (xy 426.281244 -311.219827) (xy 426.258373 -311.263404) (xy 426.228808 -311.302748)
			(xy 426.193315 -311.33684) (xy 426.152812 -311.364796) (xy 426.10835 -311.385894) (xy 426.061079 -311.399586)
			(xy 426.012224 -311.405518) (xy 425.963049 -311.403537) (xy 425.91483 -311.393693) (xy 425.868814 -311.376241)
			(xy 425.826193 -311.351634) (xy 425.788072 -311.320509) (xy 425.755437 -311.283672) (xy 425.729134 -311.242076)
			(xy 425.709843 -311.1968) (xy 425.698066 -311.149016) (xy 425.694106 -311.099962) (xy 424.405298 -311.099962)
			(xy 424.404803 -311.124569) (xy 424.396908 -311.173146) (xy 424.381324 -311.219827) (xy 424.358453 -311.263404)
			(xy 424.328888 -311.302748) (xy 424.293395 -311.33684) (xy 424.252892 -311.364796) (xy 424.20843 -311.385894)
			(xy 424.161159 -311.399586) (xy 424.112304 -311.405518) (xy 424.063129 -311.403537) (xy 424.01491 -311.393693)
			(xy 423.968894 -311.376241) (xy 423.926273 -311.351634) (xy 423.888152 -311.320509) (xy 423.855517 -311.283672)
			(xy 423.829214 -311.242076) (xy 423.809923 -311.1968) (xy 423.798146 -311.149016) (xy 423.794186 -311.099962)
			(xy 422.505124 -311.099962) (xy 422.504629 -311.124569) (xy 422.496734 -311.173146) (xy 422.48115 -311.219827)
			(xy 422.458279 -311.263404) (xy 422.428714 -311.302748) (xy 422.393221 -311.33684) (xy 422.352718 -311.364796)
			(xy 422.308256 -311.385894) (xy 422.260985 -311.399586) (xy 422.21213 -311.405518) (xy 422.162955 -311.403537)
			(xy 422.114736 -311.393693) (xy 422.06872 -311.376241) (xy 422.026099 -311.351634) (xy 421.987978 -311.320509)
			(xy 421.955343 -311.283672) (xy 421.92904 -311.242076) (xy 421.909749 -311.1968) (xy 421.897972 -311.149016)
			(xy 421.894012 -311.099962) (xy 420.605204 -311.099962) (xy 420.604709 -311.124569) (xy 420.596814 -311.173146)
			(xy 420.58123 -311.219827) (xy 420.558359 -311.263404) (xy 420.528794 -311.302748) (xy 420.493301 -311.33684)
			(xy 420.452798 -311.364796) (xy 420.408336 -311.385894) (xy 420.361065 -311.399586) (xy 420.31221 -311.405518)
			(xy 420.263035 -311.403537) (xy 420.214816 -311.393693) (xy 420.1688 -311.376241) (xy 420.126179 -311.351634)
			(xy 420.088058 -311.320509) (xy 420.055423 -311.283672) (xy 420.02912 -311.242076) (xy 420.009829 -311.1968)
			(xy 419.998052 -311.149016) (xy 419.994092 -311.099962) (xy 418.705284 -311.099962) (xy 418.704789 -311.124569)
			(xy 418.696894 -311.173146) (xy 418.68131 -311.219827) (xy 418.658439 -311.263404) (xy 418.628874 -311.302748)
			(xy 418.593381 -311.33684) (xy 418.552878 -311.364796) (xy 418.508416 -311.385894) (xy 418.461145 -311.399586)
			(xy 418.41229 -311.405518) (xy 418.363115 -311.403537) (xy 418.314896 -311.393693) (xy 418.26888 -311.376241)
			(xy 418.226259 -311.351634) (xy 418.188138 -311.320509) (xy 418.155503 -311.283672) (xy 418.1292 -311.242076)
			(xy 418.109909 -311.1968) (xy 418.098132 -311.149016) (xy 418.094172 -311.099962) (xy 416.80511 -311.099962)
			(xy 416.804615 -311.124569) (xy 416.79672 -311.173146) (xy 416.781136 -311.219827) (xy 416.758265 -311.263404)
			(xy 416.7287 -311.302748) (xy 416.693207 -311.33684) (xy 416.652704 -311.364796) (xy 416.608242 -311.385894)
			(xy 416.560971 -311.399586) (xy 416.512116 -311.405518) (xy 416.462941 -311.403537) (xy 416.414722 -311.393693)
			(xy 416.368706 -311.376241) (xy 416.326085 -311.351634) (xy 416.287964 -311.320509) (xy 416.255329 -311.283672)
			(xy 416.229026 -311.242076) (xy 416.209735 -311.1968) (xy 416.197958 -311.149016) (xy 416.193998 -311.099962)
			(xy 414.90519 -311.099962) (xy 414.904695 -311.124569) (xy 414.8968 -311.173146) (xy 414.881216 -311.219827)
			(xy 414.858345 -311.263404) (xy 414.82878 -311.302748) (xy 414.793287 -311.33684) (xy 414.752784 -311.364796)
			(xy 414.708322 -311.385894) (xy 414.661051 -311.399586) (xy 414.612196 -311.405518) (xy 414.563021 -311.403537)
			(xy 414.514802 -311.393693) (xy 414.468786 -311.376241) (xy 414.426165 -311.351634) (xy 414.388044 -311.320509)
			(xy 414.355409 -311.283672) (xy 414.329106 -311.242076) (xy 414.309815 -311.1968) (xy 414.298038 -311.149016)
			(xy 414.294078 -311.099962) (xy 413.00527 -311.099962) (xy 413.004775 -311.124569) (xy 412.99688 -311.173146)
			(xy 412.981296 -311.219827) (xy 412.958425 -311.263404) (xy 412.92886 -311.302748) (xy 412.893367 -311.33684)
			(xy 412.852864 -311.364796) (xy 412.808402 -311.385894) (xy 412.761131 -311.399586) (xy 412.712276 -311.405518)
			(xy 412.663101 -311.403537) (xy 412.614882 -311.393693) (xy 412.568866 -311.376241) (xy 412.526245 -311.351634)
			(xy 412.488124 -311.320509) (xy 412.455489 -311.283672) (xy 412.429186 -311.242076) (xy 412.409895 -311.1968)
			(xy 412.398118 -311.149016) (xy 412.394158 -311.099962) (xy 411.105096 -311.099962) (xy 411.104601 -311.124569)
			(xy 411.096706 -311.173146) (xy 411.081122 -311.219827) (xy 411.058251 -311.263404) (xy 411.028686 -311.302748)
			(xy 410.993193 -311.33684) (xy 410.95269 -311.364796) (xy 410.908228 -311.385894) (xy 410.860957 -311.399586)
			(xy 410.812102 -311.405518) (xy 410.762927 -311.403537) (xy 410.714708 -311.393693) (xy 410.668692 -311.376241)
			(xy 410.626071 -311.351634) (xy 410.58795 -311.320509) (xy 410.555315 -311.283672) (xy 410.529012 -311.242076)
			(xy 410.509721 -311.1968) (xy 410.497944 -311.149016) (xy 410.493984 -311.099962) (xy 409.205176 -311.099962)
			(xy 409.204681 -311.124569) (xy 409.196786 -311.173146) (xy 409.181202 -311.219827) (xy 409.158331 -311.263404)
			(xy 409.128766 -311.302748) (xy 409.093273 -311.33684) (xy 409.05277 -311.364796) (xy 409.008308 -311.385894)
			(xy 408.961037 -311.399586) (xy 408.912182 -311.405518) (xy 408.863007 -311.403537) (xy 408.814788 -311.393693)
			(xy 408.768772 -311.376241) (xy 408.726151 -311.351634) (xy 408.68803 -311.320509) (xy 408.655395 -311.283672)
			(xy 408.629092 -311.242076) (xy 408.609801 -311.1968) (xy 408.598024 -311.149016) (xy 408.594064 -311.099962)
			(xy 407.305256 -311.099962) (xy 407.304761 -311.124569) (xy 407.296866 -311.173146) (xy 407.281282 -311.219827)
			(xy 407.258411 -311.263404) (xy 407.228846 -311.302748) (xy 407.193353 -311.33684) (xy 407.15285 -311.364796)
			(xy 407.108388 -311.385894) (xy 407.061117 -311.399586) (xy 407.012262 -311.405518) (xy 406.963087 -311.403537)
			(xy 406.914868 -311.393693) (xy 406.868852 -311.376241) (xy 406.826231 -311.351634) (xy 406.78811 -311.320509)
			(xy 406.755475 -311.283672) (xy 406.729172 -311.242076) (xy 406.709881 -311.1968) (xy 406.698104 -311.149016)
			(xy 406.694144 -311.099962) (xy 405.405336 -311.099962) (xy 405.404841 -311.124569) (xy 405.396946 -311.173146)
			(xy 405.381362 -311.219827) (xy 405.358491 -311.263404) (xy 405.328926 -311.302748) (xy 405.293433 -311.33684)
			(xy 405.25293 -311.364796) (xy 405.208468 -311.385894) (xy 405.161197 -311.399586) (xy 405.112342 -311.405518)
			(xy 405.063167 -311.403537) (xy 405.014948 -311.393693) (xy 404.968932 -311.376241) (xy 404.926311 -311.351634)
			(xy 404.88819 -311.320509) (xy 404.855555 -311.283672) (xy 404.829252 -311.242076) (xy 404.809961 -311.1968)
			(xy 404.798184 -311.149016) (xy 404.794224 -311.099962) (xy 403.505162 -311.099962) (xy 403.504667 -311.124569)
			(xy 403.496772 -311.173146) (xy 403.481188 -311.219827) (xy 403.458317 -311.263404) (xy 403.428752 -311.302748)
			(xy 403.393259 -311.33684) (xy 403.352756 -311.364796) (xy 403.308294 -311.385894) (xy 403.261023 -311.399586)
			(xy 403.212168 -311.405518) (xy 403.162993 -311.403537) (xy 403.114774 -311.393693) (xy 403.068758 -311.376241)
			(xy 403.026137 -311.351634) (xy 402.988016 -311.320509) (xy 402.955381 -311.283672) (xy 402.929078 -311.242076)
			(xy 402.909787 -311.1968) (xy 402.89801 -311.149016) (xy 402.89405 -311.099962) (xy 401.605242 -311.099962)
			(xy 401.604747 -311.124569) (xy 401.596852 -311.173146) (xy 401.581268 -311.219827) (xy 401.558397 -311.263404)
			(xy 401.528832 -311.302748) (xy 401.493339 -311.33684) (xy 401.452836 -311.364796) (xy 401.408374 -311.385894)
			(xy 401.361103 -311.399586) (xy 401.312248 -311.405518) (xy 401.263073 -311.403537) (xy 401.214854 -311.393693)
			(xy 401.168838 -311.376241) (xy 401.126217 -311.351634) (xy 401.088096 -311.320509) (xy 401.055461 -311.283672)
			(xy 401.029158 -311.242076) (xy 401.009867 -311.1968) (xy 400.99809 -311.149016) (xy 400.99413 -311.099962)
			(xy 399.705322 -311.099962) (xy 399.704827 -311.124569) (xy 399.696932 -311.173146) (xy 399.681348 -311.219827)
			(xy 399.658477 -311.263404) (xy 399.628912 -311.302748) (xy 399.593419 -311.33684) (xy 399.552916 -311.364796)
			(xy 399.508454 -311.385894) (xy 399.461183 -311.399586) (xy 399.412328 -311.405518) (xy 399.363153 -311.403537)
			(xy 399.314934 -311.393693) (xy 399.268918 -311.376241) (xy 399.226297 -311.351634) (xy 399.188176 -311.320509)
			(xy 399.155541 -311.283672) (xy 399.129238 -311.242076) (xy 399.109947 -311.1968) (xy 399.09817 -311.149016)
			(xy 399.09421 -311.099962) (xy 397.805148 -311.099962) (xy 397.804653 -311.124569) (xy 397.796758 -311.173146)
			(xy 397.781174 -311.219827) (xy 397.758303 -311.263404) (xy 397.728738 -311.302748) (xy 397.693245 -311.33684)
			(xy 397.652742 -311.364796) (xy 397.60828 -311.385894) (xy 397.561009 -311.399586) (xy 397.512154 -311.405518)
			(xy 397.462979 -311.403537) (xy 397.41476 -311.393693) (xy 397.368744 -311.376241) (xy 397.326123 -311.351634)
			(xy 397.288002 -311.320509) (xy 397.255367 -311.283672) (xy 397.229064 -311.242076) (xy 397.209773 -311.1968)
			(xy 397.197996 -311.149016) (xy 397.194036 -311.099962) (xy 395.905228 -311.099962) (xy 395.904733 -311.124569)
			(xy 395.896838 -311.173146) (xy 395.881254 -311.219827) (xy 395.858383 -311.263404) (xy 395.828818 -311.302748)
			(xy 395.793325 -311.33684) (xy 395.752822 -311.364796) (xy 395.70836 -311.385894) (xy 395.661089 -311.399586)
			(xy 395.612234 -311.405518) (xy 395.563059 -311.403537) (xy 395.51484 -311.393693) (xy 395.468824 -311.376241)
			(xy 395.426203 -311.351634) (xy 395.388082 -311.320509) (xy 395.355447 -311.283672) (xy 395.329144 -311.242076)
			(xy 395.309853 -311.1968) (xy 395.298076 -311.149016) (xy 395.294116 -311.099962) (xy 394.005308 -311.099962)
			(xy 394.004813 -311.124569) (xy 393.996918 -311.173146) (xy 393.981334 -311.219827) (xy 393.958463 -311.263404)
			(xy 393.928898 -311.302748) (xy 393.893405 -311.33684) (xy 393.852902 -311.364796) (xy 393.80844 -311.385894)
			(xy 393.761169 -311.399586) (xy 393.712314 -311.405518) (xy 393.663139 -311.403537) (xy 393.61492 -311.393693)
			(xy 393.568904 -311.376241) (xy 393.526283 -311.351634) (xy 393.488162 -311.320509) (xy 393.455527 -311.283672)
			(xy 393.429224 -311.242076) (xy 393.409933 -311.1968) (xy 393.398156 -311.149016) (xy 393.394196 -311.099962)
			(xy 392.105134 -311.099962) (xy 392.104639 -311.124569) (xy 392.096744 -311.173146) (xy 392.08116 -311.219827)
			(xy 392.058289 -311.263404) (xy 392.028724 -311.302748) (xy 391.993231 -311.33684) (xy 391.952728 -311.364796)
			(xy 391.908266 -311.385894) (xy 391.860995 -311.399586) (xy 391.81214 -311.405518) (xy 391.762965 -311.403537)
			(xy 391.714746 -311.393693) (xy 391.66873 -311.376241) (xy 391.626109 -311.351634) (xy 391.587988 -311.320509)
			(xy 391.555353 -311.283672) (xy 391.52905 -311.242076) (xy 391.509759 -311.1968) (xy 391.497982 -311.149016)
			(xy 391.494022 -311.099962) (xy 390.205214 -311.099962) (xy 390.204719 -311.124569) (xy 390.196824 -311.173146)
			(xy 390.18124 -311.219827) (xy 390.158369 -311.263404) (xy 390.128804 -311.302748) (xy 390.093311 -311.33684)
			(xy 390.052808 -311.364796) (xy 390.008346 -311.385894) (xy 389.961075 -311.399586) (xy 389.91222 -311.405518)
			(xy 389.863045 -311.403537) (xy 389.814826 -311.393693) (xy 389.76881 -311.376241) (xy 389.726189 -311.351634)
			(xy 389.688068 -311.320509) (xy 389.655433 -311.283672) (xy 389.62913 -311.242076) (xy 389.609839 -311.1968)
			(xy 389.598062 -311.149016) (xy 389.594102 -311.099962) (xy 388.305294 -311.099962) (xy 388.304799 -311.124569)
			(xy 388.296904 -311.173146) (xy 388.28132 -311.219827) (xy 388.258449 -311.263404) (xy 388.228884 -311.302748)
			(xy 388.193391 -311.33684) (xy 388.152888 -311.364796) (xy 388.108426 -311.385894) (xy 388.061155 -311.399586)
			(xy 388.0123 -311.405518) (xy 387.963125 -311.403537) (xy 387.914906 -311.393693) (xy 387.86889 -311.376241)
			(xy 387.826269 -311.351634) (xy 387.788148 -311.320509) (xy 387.755513 -311.283672) (xy 387.72921 -311.242076)
			(xy 387.709919 -311.1968) (xy 387.698142 -311.149016) (xy 387.694182 -311.099962) (xy 312.10504 -311.099962)
			(xy 312.104545 -311.124569) (xy 312.09665 -311.173146) (xy 312.081066 -311.219827) (xy 312.058195 -311.263404)
			(xy 312.02863 -311.302748) (xy 311.993137 -311.33684) (xy 311.952634 -311.364796) (xy 311.908172 -311.385894)
			(xy 311.860901 -311.399586) (xy 311.812046 -311.405518) (xy 311.762871 -311.403537) (xy 311.714652 -311.393693)
			(xy 311.668636 -311.376241) (xy 311.626015 -311.351634) (xy 311.587894 -311.320509) (xy 311.555259 -311.283672)
			(xy 311.528956 -311.242076) (xy 311.509665 -311.1968) (xy 311.497888 -311.149016) (xy 311.493928 -311.099962)
			(xy 310.20512 -311.099962) (xy 310.204625 -311.124569) (xy 310.19673 -311.173146) (xy 310.181146 -311.219827)
			(xy 310.158275 -311.263404) (xy 310.12871 -311.302748) (xy 310.093217 -311.33684) (xy 310.052714 -311.364796)
			(xy 310.008252 -311.385894) (xy 309.960981 -311.399586) (xy 309.912126 -311.405518) (xy 309.862951 -311.403537)
			(xy 309.814732 -311.393693) (xy 309.768716 -311.376241) (xy 309.726095 -311.351634) (xy 309.687974 -311.320509)
			(xy 309.655339 -311.283672) (xy 309.629036 -311.242076) (xy 309.609745 -311.1968) (xy 309.597968 -311.149016)
			(xy 309.594008 -311.099962) (xy 308.3052 -311.099962) (xy 308.304705 -311.124569) (xy 308.29681 -311.173146)
			(xy 308.281226 -311.219827) (xy 308.258355 -311.263404) (xy 308.22879 -311.302748) (xy 308.193297 -311.33684)
			(xy 308.152794 -311.364796) (xy 308.108332 -311.385894) (xy 308.061061 -311.399586) (xy 308.012206 -311.405518)
			(xy 307.963031 -311.403537) (xy 307.914812 -311.393693) (xy 307.868796 -311.376241) (xy 307.826175 -311.351634)
			(xy 307.788054 -311.320509) (xy 307.755419 -311.283672) (xy 307.729116 -311.242076) (xy 307.709825 -311.1968)
			(xy 307.698048 -311.149016) (xy 307.694088 -311.099962) (xy 306.405026 -311.099962) (xy 306.404531 -311.124569)
			(xy 306.396636 -311.173146) (xy 306.381052 -311.219827) (xy 306.358181 -311.263404) (xy 306.328616 -311.302748)
			(xy 306.293123 -311.33684) (xy 306.25262 -311.364796) (xy 306.208158 -311.385894) (xy 306.160887 -311.399586)
			(xy 306.112032 -311.405518) (xy 306.062857 -311.403537) (xy 306.014638 -311.393693) (xy 305.968622 -311.376241)
			(xy 305.926001 -311.351634) (xy 305.88788 -311.320509) (xy 305.855245 -311.283672) (xy 305.828942 -311.242076)
			(xy 305.809651 -311.1968) (xy 305.797874 -311.149016) (xy 305.793914 -311.099962) (xy 304.505106 -311.099962)
			(xy 304.504611 -311.124569) (xy 304.496716 -311.173146) (xy 304.481132 -311.219827) (xy 304.458261 -311.263404)
			(xy 304.428696 -311.302748) (xy 304.393203 -311.33684) (xy 304.3527 -311.364796) (xy 304.308238 -311.385894)
			(xy 304.260967 -311.399586) (xy 304.212112 -311.405518) (xy 304.162937 -311.403537) (xy 304.114718 -311.393693)
			(xy 304.068702 -311.376241) (xy 304.026081 -311.351634) (xy 303.98796 -311.320509) (xy 303.955325 -311.283672)
			(xy 303.929022 -311.242076) (xy 303.909731 -311.1968) (xy 303.897954 -311.149016) (xy 303.893994 -311.099962)
			(xy 302.605186 -311.099962) (xy 302.604691 -311.124569) (xy 302.596796 -311.173146) (xy 302.581212 -311.219827)
			(xy 302.558341 -311.263404) (xy 302.528776 -311.302748) (xy 302.493283 -311.33684) (xy 302.45278 -311.364796)
			(xy 302.408318 -311.385894) (xy 302.361047 -311.399586) (xy 302.312192 -311.405518) (xy 302.263017 -311.403537)
			(xy 302.214798 -311.393693) (xy 302.168782 -311.376241) (xy 302.126161 -311.351634) (xy 302.08804 -311.320509)
			(xy 302.055405 -311.283672) (xy 302.029102 -311.242076) (xy 302.009811 -311.1968) (xy 301.998034 -311.149016)
			(xy 301.994074 -311.099962) (xy 300.705012 -311.099962) (xy 300.704517 -311.124569) (xy 300.696622 -311.173146)
			(xy 300.681038 -311.219827) (xy 300.658167 -311.263404) (xy 300.628602 -311.302748) (xy 300.593109 -311.33684)
			(xy 300.552606 -311.364796) (xy 300.508144 -311.385894) (xy 300.460873 -311.399586) (xy 300.412018 -311.405518)
			(xy 300.362843 -311.403537) (xy 300.314624 -311.393693) (xy 300.268608 -311.376241) (xy 300.225987 -311.351634)
			(xy 300.187866 -311.320509) (xy 300.155231 -311.283672) (xy 300.128928 -311.242076) (xy 300.109637 -311.1968)
			(xy 300.09786 -311.149016) (xy 300.0939 -311.099962) (xy 298.805092 -311.099962) (xy 298.804597 -311.124569)
			(xy 298.796702 -311.173146) (xy 298.781118 -311.219827) (xy 298.758247 -311.263404) (xy 298.728682 -311.302748)
			(xy 298.693189 -311.33684) (xy 298.652686 -311.364796) (xy 298.608224 -311.385894) (xy 298.560953 -311.399586)
			(xy 298.512098 -311.405518) (xy 298.462923 -311.403537) (xy 298.414704 -311.393693) (xy 298.368688 -311.376241)
			(xy 298.326067 -311.351634) (xy 298.287946 -311.320509) (xy 298.255311 -311.283672) (xy 298.229008 -311.242076)
			(xy 298.209717 -311.1968) (xy 298.19794 -311.149016) (xy 298.19398 -311.099962) (xy 296.905172 -311.099962)
			(xy 296.904677 -311.124569) (xy 296.896782 -311.173146) (xy 296.881198 -311.219827) (xy 296.858327 -311.263404)
			(xy 296.828762 -311.302748) (xy 296.793269 -311.33684) (xy 296.752766 -311.364796) (xy 296.708304 -311.385894)
			(xy 296.661033 -311.399586) (xy 296.612178 -311.405518) (xy 296.563003 -311.403537) (xy 296.514784 -311.393693)
			(xy 296.468768 -311.376241) (xy 296.426147 -311.351634) (xy 296.388026 -311.320509) (xy 296.355391 -311.283672)
			(xy 296.329088 -311.242076) (xy 296.309797 -311.1968) (xy 296.29802 -311.149016) (xy 296.29406 -311.099962)
			(xy 295.004998 -311.099962) (xy 295.004503 -311.124569) (xy 294.996608 -311.173146) (xy 294.981024 -311.219827)
			(xy 294.958153 -311.263404) (xy 294.928588 -311.302748) (xy 294.893095 -311.33684) (xy 294.852592 -311.364796)
			(xy 294.80813 -311.385894) (xy 294.760859 -311.399586) (xy 294.712004 -311.405518) (xy 294.662829 -311.403537)
			(xy 294.61461 -311.393693) (xy 294.568594 -311.376241) (xy 294.525973 -311.351634) (xy 294.487852 -311.320509)
			(xy 294.455217 -311.283672) (xy 294.428914 -311.242076) (xy 294.409623 -311.1968) (xy 294.397846 -311.149016)
			(xy 294.393886 -311.099962) (xy 293.105078 -311.099962) (xy 293.104583 -311.124569) (xy 293.096688 -311.173146)
			(xy 293.081104 -311.219827) (xy 293.058233 -311.263404) (xy 293.028668 -311.302748) (xy 292.993175 -311.33684)
			(xy 292.952672 -311.364796) (xy 292.90821 -311.385894) (xy 292.860939 -311.399586) (xy 292.812084 -311.405518)
			(xy 292.762909 -311.403537) (xy 292.71469 -311.393693) (xy 292.668674 -311.376241) (xy 292.626053 -311.351634)
			(xy 292.587932 -311.320509) (xy 292.555297 -311.283672) (xy 292.528994 -311.242076) (xy 292.509703 -311.1968)
			(xy 292.497926 -311.149016) (xy 292.493966 -311.099962) (xy 291.205158 -311.099962) (xy 291.204663 -311.124569)
			(xy 291.196768 -311.173146) (xy 291.181184 -311.219827) (xy 291.158313 -311.263404) (xy 291.128748 -311.302748)
			(xy 291.093255 -311.33684) (xy 291.052752 -311.364796) (xy 291.00829 -311.385894) (xy 290.961019 -311.399586)
			(xy 290.912164 -311.405518) (xy 290.862989 -311.403537) (xy 290.81477 -311.393693) (xy 290.768754 -311.376241)
			(xy 290.726133 -311.351634) (xy 290.688012 -311.320509) (xy 290.655377 -311.283672) (xy 290.629074 -311.242076)
			(xy 290.609783 -311.1968) (xy 290.598006 -311.149016) (xy 290.594046 -311.099962) (xy 289.305238 -311.099962)
			(xy 289.304743 -311.124569) (xy 289.296848 -311.173146) (xy 289.281264 -311.219827) (xy 289.258393 -311.263404)
			(xy 289.228828 -311.302748) (xy 289.193335 -311.33684) (xy 289.152832 -311.364796) (xy 289.10837 -311.385894)
			(xy 289.061099 -311.399586) (xy 289.012244 -311.405518) (xy 288.963069 -311.403537) (xy 288.91485 -311.393693)
			(xy 288.868834 -311.376241) (xy 288.826213 -311.351634) (xy 288.788092 -311.320509) (xy 288.755457 -311.283672)
			(xy 288.729154 -311.242076) (xy 288.709863 -311.1968) (xy 288.698086 -311.149016) (xy 288.694126 -311.099962)
			(xy 287.405064 -311.099962) (xy 287.404569 -311.124569) (xy 287.396674 -311.173146) (xy 287.38109 -311.219827)
			(xy 287.358219 -311.263404) (xy 287.328654 -311.302748) (xy 287.293161 -311.33684) (xy 287.252658 -311.364796)
			(xy 287.208196 -311.385894) (xy 287.160925 -311.399586) (xy 287.11207 -311.405518) (xy 287.062895 -311.403537)
			(xy 287.014676 -311.393693) (xy 286.96866 -311.376241) (xy 286.926039 -311.351634) (xy 286.887918 -311.320509)
			(xy 286.855283 -311.283672) (xy 286.82898 -311.242076) (xy 286.809689 -311.1968) (xy 286.797912 -311.149016)
			(xy 286.793952 -311.099962) (xy 285.505144 -311.099962) (xy 285.504649 -311.124569) (xy 285.496754 -311.173146)
			(xy 285.48117 -311.219827) (xy 285.458299 -311.263404) (xy 285.428734 -311.302748) (xy 285.393241 -311.33684)
			(xy 285.352738 -311.364796) (xy 285.308276 -311.385894) (xy 285.261005 -311.399586) (xy 285.21215 -311.405518)
			(xy 285.162975 -311.403537) (xy 285.114756 -311.393693) (xy 285.06874 -311.376241) (xy 285.026119 -311.351634)
			(xy 284.987998 -311.320509) (xy 284.955363 -311.283672) (xy 284.92906 -311.242076) (xy 284.909769 -311.1968)
			(xy 284.897992 -311.149016) (xy 284.894032 -311.099962) (xy 283.605224 -311.099962) (xy 283.604729 -311.124569)
			(xy 283.596834 -311.173146) (xy 283.58125 -311.219827) (xy 283.558379 -311.263404) (xy 283.528814 -311.302748)
			(xy 283.493321 -311.33684) (xy 283.452818 -311.364796) (xy 283.408356 -311.385894) (xy 283.361085 -311.399586)
			(xy 283.31223 -311.405518) (xy 283.263055 -311.403537) (xy 283.214836 -311.393693) (xy 283.16882 -311.376241)
			(xy 283.126199 -311.351634) (xy 283.088078 -311.320509) (xy 283.055443 -311.283672) (xy 283.02914 -311.242076)
			(xy 283.009849 -311.1968) (xy 282.998072 -311.149016) (xy 282.994112 -311.099962) (xy 281.70505 -311.099962)
			(xy 281.704555 -311.124569) (xy 281.69666 -311.173146) (xy 281.681076 -311.219827) (xy 281.658205 -311.263404)
			(xy 281.62864 -311.302748) (xy 281.593147 -311.33684) (xy 281.552644 -311.364796) (xy 281.508182 -311.385894)
			(xy 281.460911 -311.399586) (xy 281.412056 -311.405518) (xy 281.362881 -311.403537) (xy 281.314662 -311.393693)
			(xy 281.268646 -311.376241) (xy 281.226025 -311.351634) (xy 281.187904 -311.320509) (xy 281.155269 -311.283672)
			(xy 281.128966 -311.242076) (xy 281.109675 -311.1968) (xy 281.097898 -311.149016) (xy 281.093938 -311.099962)
			(xy 279.80513 -311.099962) (xy 279.804635 -311.124569) (xy 279.79674 -311.173146) (xy 279.781156 -311.219827)
			(xy 279.758285 -311.263404) (xy 279.72872 -311.302748) (xy 279.693227 -311.33684) (xy 279.652724 -311.364796)
			(xy 279.608262 -311.385894) (xy 279.560991 -311.399586) (xy 279.512136 -311.405518) (xy 279.462961 -311.403537)
			(xy 279.414742 -311.393693) (xy 279.368726 -311.376241) (xy 279.326105 -311.351634) (xy 279.287984 -311.320509)
			(xy 279.255349 -311.283672) (xy 279.229046 -311.242076) (xy 279.209755 -311.1968) (xy 279.197978 -311.149016)
			(xy 279.194018 -311.099962) (xy 277.90521 -311.099962) (xy 277.904715 -311.124569) (xy 277.89682 -311.173146)
			(xy 277.881236 -311.219827) (xy 277.858365 -311.263404) (xy 277.8288 -311.302748) (xy 277.793307 -311.33684)
			(xy 277.752804 -311.364796) (xy 277.708342 -311.385894) (xy 277.661071 -311.399586) (xy 277.612216 -311.405518)
			(xy 277.563041 -311.403537) (xy 277.514822 -311.393693) (xy 277.468806 -311.376241) (xy 277.426185 -311.351634)
			(xy 277.388064 -311.320509) (xy 277.355429 -311.283672) (xy 277.329126 -311.242076) (xy 277.309835 -311.1968)
			(xy 277.298058 -311.149016) (xy 277.294098 -311.099962) (xy 276.005036 -311.099962) (xy 276.004541 -311.124569)
			(xy 275.996646 -311.173146) (xy 275.981062 -311.219827) (xy 275.958191 -311.263404) (xy 275.928626 -311.302748)
			(xy 275.893133 -311.33684) (xy 275.85263 -311.364796) (xy 275.808168 -311.385894) (xy 275.760897 -311.399586)
			(xy 275.712042 -311.405518) (xy 275.662867 -311.403537) (xy 275.614648 -311.393693) (xy 275.568632 -311.376241)
			(xy 275.526011 -311.351634) (xy 275.48789 -311.320509) (xy 275.455255 -311.283672) (xy 275.428952 -311.242076)
			(xy 275.409661 -311.1968) (xy 275.397884 -311.149016) (xy 275.393924 -311.099962) (xy 274.105116 -311.099962)
			(xy 274.104621 -311.124569) (xy 274.096726 -311.173146) (xy 274.081142 -311.219827) (xy 274.058271 -311.263404)
			(xy 274.028706 -311.302748) (xy 273.993213 -311.33684) (xy 273.95271 -311.364796) (xy 273.908248 -311.385894)
			(xy 273.860977 -311.399586) (xy 273.812122 -311.405518) (xy 273.762947 -311.403537) (xy 273.714728 -311.393693)
			(xy 273.668712 -311.376241) (xy 273.626091 -311.351634) (xy 273.58797 -311.320509) (xy 273.555335 -311.283672)
			(xy 273.529032 -311.242076) (xy 273.509741 -311.1968) (xy 273.497964 -311.149016) (xy 273.494004 -311.099962)
			(xy 272.205196 -311.099962) (xy 272.204701 -311.124569) (xy 272.196806 -311.173146) (xy 272.181222 -311.219827)
			(xy 272.158351 -311.263404) (xy 272.128786 -311.302748) (xy 272.093293 -311.33684) (xy 272.05279 -311.364796)
			(xy 272.008328 -311.385894) (xy 271.961057 -311.399586) (xy 271.912202 -311.405518) (xy 271.863027 -311.403537)
			(xy 271.814808 -311.393693) (xy 271.768792 -311.376241) (xy 271.726171 -311.351634) (xy 271.68805 -311.320509)
			(xy 271.655415 -311.283672) (xy 271.629112 -311.242076) (xy 271.609821 -311.1968) (xy 271.598044 -311.149016)
			(xy 271.594084 -311.099962) (xy 196.005196 -311.099962) (xy 196.004701 -311.124569) (xy 195.996806 -311.173146)
			(xy 195.981222 -311.219827) (xy 195.958351 -311.263404) (xy 195.928786 -311.302748) (xy 195.893293 -311.33684)
			(xy 195.85279 -311.364796) (xy 195.808328 -311.385894) (xy 195.761057 -311.399586) (xy 195.712202 -311.405518)
			(xy 195.663027 -311.403537) (xy 195.614808 -311.393693) (xy 195.568792 -311.376241) (xy 195.526171 -311.351634)
			(xy 195.48805 -311.320509) (xy 195.455415 -311.283672) (xy 195.429112 -311.242076) (xy 195.409821 -311.1968)
			(xy 195.398044 -311.149016) (xy 195.394084 -311.099962) (xy 194.105276 -311.099962) (xy 194.104781 -311.124569)
			(xy 194.096886 -311.173146) (xy 194.081302 -311.219827) (xy 194.058431 -311.263404) (xy 194.028866 -311.302748)
			(xy 193.993373 -311.33684) (xy 193.95287 -311.364796) (xy 193.908408 -311.385894) (xy 193.861137 -311.399586)
			(xy 193.812282 -311.405518) (xy 193.763107 -311.403537) (xy 193.714888 -311.393693) (xy 193.668872 -311.376241)
			(xy 193.626251 -311.351634) (xy 193.58813 -311.320509) (xy 193.555495 -311.283672) (xy 193.529192 -311.242076)
			(xy 193.509901 -311.1968) (xy 193.498124 -311.149016) (xy 193.494164 -311.099962) (xy 192.205356 -311.099962)
			(xy 192.204861 -311.124569) (xy 192.196966 -311.173146) (xy 192.181382 -311.219827) (xy 192.158511 -311.263404)
			(xy 192.128946 -311.302748) (xy 192.093453 -311.33684) (xy 192.05295 -311.364796) (xy 192.008488 -311.385894)
			(xy 191.961217 -311.399586) (xy 191.912362 -311.405518) (xy 191.863187 -311.403537) (xy 191.814968 -311.393693)
			(xy 191.768952 -311.376241) (xy 191.726331 -311.351634) (xy 191.68821 -311.320509) (xy 191.655575 -311.283672)
			(xy 191.629272 -311.242076) (xy 191.609981 -311.1968) (xy 191.598204 -311.149016) (xy 191.594244 -311.099962)
			(xy 190.305182 -311.099962) (xy 190.304687 -311.124569) (xy 190.296792 -311.173146) (xy 190.281208 -311.219827)
			(xy 190.258337 -311.263404) (xy 190.228772 -311.302748) (xy 190.193279 -311.33684) (xy 190.152776 -311.364796)
			(xy 190.108314 -311.385894) (xy 190.061043 -311.399586) (xy 190.012188 -311.405518) (xy 189.963013 -311.403537)
			(xy 189.914794 -311.393693) (xy 189.868778 -311.376241) (xy 189.826157 -311.351634) (xy 189.788036 -311.320509)
			(xy 189.755401 -311.283672) (xy 189.729098 -311.242076) (xy 189.709807 -311.1968) (xy 189.69803 -311.149016)
			(xy 189.69407 -311.099962) (xy 188.405262 -311.099962) (xy 188.404767 -311.124569) (xy 188.396872 -311.173146)
			(xy 188.381288 -311.219827) (xy 188.358417 -311.263404) (xy 188.328852 -311.302748) (xy 188.293359 -311.33684)
			(xy 188.252856 -311.364796) (xy 188.208394 -311.385894) (xy 188.161123 -311.399586) (xy 188.112268 -311.405518)
			(xy 188.063093 -311.403537) (xy 188.014874 -311.393693) (xy 187.968858 -311.376241) (xy 187.926237 -311.351634)
			(xy 187.888116 -311.320509) (xy 187.855481 -311.283672) (xy 187.829178 -311.242076) (xy 187.809887 -311.1968)
			(xy 187.79811 -311.149016) (xy 187.79415 -311.099962) (xy 186.505342 -311.099962) (xy 186.504847 -311.124569)
			(xy 186.496952 -311.173146) (xy 186.481368 -311.219827) (xy 186.458497 -311.263404) (xy 186.428932 -311.302748)
			(xy 186.393439 -311.33684) (xy 186.352936 -311.364796) (xy 186.308474 -311.385894) (xy 186.261203 -311.399586)
			(xy 186.212348 -311.405518) (xy 186.163173 -311.403537) (xy 186.114954 -311.393693) (xy 186.068938 -311.376241)
			(xy 186.026317 -311.351634) (xy 185.988196 -311.320509) (xy 185.955561 -311.283672) (xy 185.929258 -311.242076)
			(xy 185.909967 -311.1968) (xy 185.89819 -311.149016) (xy 185.89423 -311.099962) (xy 184.605168 -311.099962)
			(xy 184.604673 -311.124569) (xy 184.596778 -311.173146) (xy 184.581194 -311.219827) (xy 184.558323 -311.263404)
			(xy 184.528758 -311.302748) (xy 184.493265 -311.33684) (xy 184.452762 -311.364796) (xy 184.4083 -311.385894)
			(xy 184.361029 -311.399586) (xy 184.312174 -311.405518) (xy 184.262999 -311.403537) (xy 184.21478 -311.393693)
			(xy 184.168764 -311.376241) (xy 184.126143 -311.351634) (xy 184.088022 -311.320509) (xy 184.055387 -311.283672)
			(xy 184.029084 -311.242076) (xy 184.009793 -311.1968) (xy 183.998016 -311.149016) (xy 183.994056 -311.099962)
			(xy 182.705248 -311.099962) (xy 182.704753 -311.124569) (xy 182.696858 -311.173146) (xy 182.681274 -311.219827)
			(xy 182.658403 -311.263404) (xy 182.628838 -311.302748) (xy 182.593345 -311.33684) (xy 182.552842 -311.364796)
			(xy 182.50838 -311.385894) (xy 182.461109 -311.399586) (xy 182.412254 -311.405518) (xy 182.363079 -311.403537)
			(xy 182.31486 -311.393693) (xy 182.268844 -311.376241) (xy 182.226223 -311.351634) (xy 182.188102 -311.320509)
			(xy 182.155467 -311.283672) (xy 182.129164 -311.242076) (xy 182.109873 -311.1968) (xy 182.098096 -311.149016)
			(xy 182.094136 -311.099962) (xy 180.805328 -311.099962) (xy 180.804833 -311.124569) (xy 180.796938 -311.173146)
			(xy 180.781354 -311.219827) (xy 180.758483 -311.263404) (xy 180.728918 -311.302748) (xy 180.693425 -311.33684)
			(xy 180.652922 -311.364796) (xy 180.60846 -311.385894) (xy 180.561189 -311.399586) (xy 180.512334 -311.405518)
			(xy 180.463159 -311.403537) (xy 180.41494 -311.393693) (xy 180.368924 -311.376241) (xy 180.326303 -311.351634)
			(xy 180.288182 -311.320509) (xy 180.255547 -311.283672) (xy 180.229244 -311.242076) (xy 180.209953 -311.1968)
			(xy 180.198176 -311.149016) (xy 180.194216 -311.099962) (xy 178.905154 -311.099962) (xy 178.904659 -311.124569)
			(xy 178.896764 -311.173146) (xy 178.88118 -311.219827) (xy 178.858309 -311.263404) (xy 178.828744 -311.302748)
			(xy 178.793251 -311.33684) (xy 178.752748 -311.364796) (xy 178.708286 -311.385894) (xy 178.661015 -311.399586)
			(xy 178.61216 -311.405518) (xy 178.562985 -311.403537) (xy 178.514766 -311.393693) (xy 178.46875 -311.376241)
			(xy 178.426129 -311.351634) (xy 178.388008 -311.320509) (xy 178.355373 -311.283672) (xy 178.32907 -311.242076)
			(xy 178.309779 -311.1968) (xy 178.298002 -311.149016) (xy 178.294042 -311.099962) (xy 177.005234 -311.099962)
			(xy 177.004739 -311.124569) (xy 176.996844 -311.173146) (xy 176.98126 -311.219827) (xy 176.958389 -311.263404)
			(xy 176.928824 -311.302748) (xy 176.893331 -311.33684) (xy 176.852828 -311.364796) (xy 176.808366 -311.385894)
			(xy 176.761095 -311.399586) (xy 176.71224 -311.405518) (xy 176.663065 -311.403537) (xy 176.614846 -311.393693)
			(xy 176.56883 -311.376241) (xy 176.526209 -311.351634) (xy 176.488088 -311.320509) (xy 176.455453 -311.283672)
			(xy 176.42915 -311.242076) (xy 176.409859 -311.1968) (xy 176.398082 -311.149016) (xy 176.394122 -311.099962)
			(xy 175.105314 -311.099962) (xy 175.104819 -311.124569) (xy 175.096924 -311.173146) (xy 175.08134 -311.219827)
			(xy 175.058469 -311.263404) (xy 175.028904 -311.302748) (xy 174.993411 -311.33684) (xy 174.952908 -311.364796)
			(xy 174.908446 -311.385894) (xy 174.861175 -311.399586) (xy 174.81232 -311.405518) (xy 174.763145 -311.403537)
			(xy 174.714926 -311.393693) (xy 174.66891 -311.376241) (xy 174.626289 -311.351634) (xy 174.588168 -311.320509)
			(xy 174.555533 -311.283672) (xy 174.52923 -311.242076) (xy 174.509939 -311.1968) (xy 174.498162 -311.149016)
			(xy 174.494202 -311.099962) (xy 173.205394 -311.099962) (xy 173.204899 -311.124569) (xy 173.197004 -311.173146)
			(xy 173.18142 -311.219827) (xy 173.158549 -311.263404) (xy 173.128984 -311.302748) (xy 173.093491 -311.33684)
			(xy 173.052988 -311.364796) (xy 173.008526 -311.385894) (xy 172.961255 -311.399586) (xy 172.9124 -311.405518)
			(xy 172.863225 -311.403537) (xy 172.815006 -311.393693) (xy 172.76899 -311.376241) (xy 172.726369 -311.351634)
			(xy 172.688248 -311.320509) (xy 172.655613 -311.283672) (xy 172.62931 -311.242076) (xy 172.610019 -311.1968)
			(xy 172.598242 -311.149016) (xy 172.594282 -311.099962) (xy 171.30522 -311.099962) (xy 171.304725 -311.124569)
			(xy 171.29683 -311.173146) (xy 171.281246 -311.219827) (xy 171.258375 -311.263404) (xy 171.22881 -311.302748)
			(xy 171.193317 -311.33684) (xy 171.152814 -311.364796) (xy 171.108352 -311.385894) (xy 171.061081 -311.399586)
			(xy 171.012226 -311.405518) (xy 170.963051 -311.403537) (xy 170.914832 -311.393693) (xy 170.868816 -311.376241)
			(xy 170.826195 -311.351634) (xy 170.788074 -311.320509) (xy 170.755439 -311.283672) (xy 170.729136 -311.242076)
			(xy 170.709845 -311.1968) (xy 170.698068 -311.149016) (xy 170.694108 -311.099962) (xy 169.4053 -311.099962)
			(xy 169.404805 -311.124569) (xy 169.39691 -311.173146) (xy 169.381326 -311.219827) (xy 169.358455 -311.263404)
			(xy 169.32889 -311.302748) (xy 169.293397 -311.33684) (xy 169.252894 -311.364796) (xy 169.208432 -311.385894)
			(xy 169.161161 -311.399586) (xy 169.112306 -311.405518) (xy 169.063131 -311.403537) (xy 169.014912 -311.393693)
			(xy 168.968896 -311.376241) (xy 168.926275 -311.351634) (xy 168.888154 -311.320509) (xy 168.855519 -311.283672)
			(xy 168.829216 -311.242076) (xy 168.809925 -311.1968) (xy 168.798148 -311.149016) (xy 168.794188 -311.099962)
			(xy 167.50538 -311.099962) (xy 167.504885 -311.124569) (xy 167.49699 -311.173146) (xy 167.481406 -311.219827)
			(xy 167.458535 -311.263404) (xy 167.42897 -311.302748) (xy 167.393477 -311.33684) (xy 167.352974 -311.364796)
			(xy 167.308512 -311.385894) (xy 167.261241 -311.399586) (xy 167.212386 -311.405518) (xy 167.163211 -311.403537)
			(xy 167.114992 -311.393693) (xy 167.068976 -311.376241) (xy 167.026355 -311.351634) (xy 166.988234 -311.320509)
			(xy 166.955599 -311.283672) (xy 166.929296 -311.242076) (xy 166.910005 -311.1968) (xy 166.898228 -311.149016)
			(xy 166.894268 -311.099962) (xy 165.605206 -311.099962) (xy 165.604711 -311.124569) (xy 165.596816 -311.173146)
			(xy 165.581232 -311.219827) (xy 165.558361 -311.263404) (xy 165.528796 -311.302748) (xy 165.493303 -311.33684)
			(xy 165.4528 -311.364796) (xy 165.408338 -311.385894) (xy 165.361067 -311.399586) (xy 165.312212 -311.405518)
			(xy 165.263037 -311.403537) (xy 165.214818 -311.393693) (xy 165.168802 -311.376241) (xy 165.126181 -311.351634)
			(xy 165.08806 -311.320509) (xy 165.055425 -311.283672) (xy 165.029122 -311.242076) (xy 165.009831 -311.1968)
			(xy 164.998054 -311.149016) (xy 164.994094 -311.099962) (xy 163.705286 -311.099962) (xy 163.704791 -311.124569)
			(xy 163.696896 -311.173146) (xy 163.681312 -311.219827) (xy 163.658441 -311.263404) (xy 163.628876 -311.302748)
			(xy 163.593383 -311.33684) (xy 163.55288 -311.364796) (xy 163.508418 -311.385894) (xy 163.461147 -311.399586)
			(xy 163.412292 -311.405518) (xy 163.363117 -311.403537) (xy 163.314898 -311.393693) (xy 163.268882 -311.376241)
			(xy 163.226261 -311.351634) (xy 163.18814 -311.320509) (xy 163.155505 -311.283672) (xy 163.129202 -311.242076)
			(xy 163.109911 -311.1968) (xy 163.098134 -311.149016) (xy 163.094174 -311.099962) (xy 161.805366 -311.099962)
			(xy 161.804871 -311.124569) (xy 161.796976 -311.173146) (xy 161.781392 -311.219827) (xy 161.758521 -311.263404)
			(xy 161.728956 -311.302748) (xy 161.693463 -311.33684) (xy 161.65296 -311.364796) (xy 161.608498 -311.385894)
			(xy 161.561227 -311.399586) (xy 161.512372 -311.405518) (xy 161.463197 -311.403537) (xy 161.414978 -311.393693)
			(xy 161.368962 -311.376241) (xy 161.326341 -311.351634) (xy 161.28822 -311.320509) (xy 161.255585 -311.283672)
			(xy 161.229282 -311.242076) (xy 161.209991 -311.1968) (xy 161.198214 -311.149016) (xy 161.194254 -311.099962)
			(xy 159.905192 -311.099962) (xy 159.904697 -311.124569) (xy 159.896802 -311.173146) (xy 159.881218 -311.219827)
			(xy 159.858347 -311.263404) (xy 159.828782 -311.302748) (xy 159.793289 -311.33684) (xy 159.752786 -311.364796)
			(xy 159.708324 -311.385894) (xy 159.661053 -311.399586) (xy 159.612198 -311.405518) (xy 159.563023 -311.403537)
			(xy 159.514804 -311.393693) (xy 159.468788 -311.376241) (xy 159.426167 -311.351634) (xy 159.388046 -311.320509)
			(xy 159.355411 -311.283672) (xy 159.329108 -311.242076) (xy 159.309817 -311.1968) (xy 159.29804 -311.149016)
			(xy 159.29408 -311.099962) (xy 158.005272 -311.099962) (xy 158.004777 -311.124569) (xy 157.996882 -311.173146)
			(xy 157.981298 -311.219827) (xy 157.958427 -311.263404) (xy 157.928862 -311.302748) (xy 157.893369 -311.33684)
			(xy 157.852866 -311.364796) (xy 157.808404 -311.385894) (xy 157.761133 -311.399586) (xy 157.712278 -311.405518)
			(xy 157.663103 -311.403537) (xy 157.614884 -311.393693) (xy 157.568868 -311.376241) (xy 157.526247 -311.351634)
			(xy 157.488126 -311.320509) (xy 157.455491 -311.283672) (xy 157.429188 -311.242076) (xy 157.409897 -311.1968)
			(xy 157.39812 -311.149016) (xy 157.39416 -311.099962) (xy 156.105352 -311.099962) (xy 156.104857 -311.124569)
			(xy 156.096962 -311.173146) (xy 156.081378 -311.219827) (xy 156.058507 -311.263404) (xy 156.028942 -311.302748)
			(xy 155.993449 -311.33684) (xy 155.952946 -311.364796) (xy 155.908484 -311.385894) (xy 155.861213 -311.399586)
			(xy 155.812358 -311.405518) (xy 155.763183 -311.403537) (xy 155.714964 -311.393693) (xy 155.668948 -311.376241)
			(xy 155.626327 -311.351634) (xy 155.588206 -311.320509) (xy 155.555571 -311.283672) (xy 155.529268 -311.242076)
			(xy 155.509977 -311.1968) (xy 155.4982 -311.149016) (xy 155.49424 -311.099962) (xy 79.905098 -311.099962)
			(xy 79.904603 -311.124569) (xy 79.896708 -311.173146) (xy 79.881124 -311.219827) (xy 79.858253 -311.263404)
			(xy 79.828688 -311.302748) (xy 79.793195 -311.33684) (xy 79.752692 -311.364796) (xy 79.70823 -311.385894)
			(xy 79.660959 -311.399586) (xy 79.612104 -311.405518) (xy 79.562929 -311.403537) (xy 79.51471 -311.393693)
			(xy 79.468694 -311.376241) (xy 79.426073 -311.351634) (xy 79.387952 -311.320509) (xy 79.355317 -311.283672)
			(xy 79.329014 -311.242076) (xy 79.309723 -311.1968) (xy 79.297946 -311.149016) (xy 79.293986 -311.099962)
			(xy 78.005178 -311.099962) (xy 78.004683 -311.124569) (xy 77.996788 -311.173146) (xy 77.981204 -311.219827)
			(xy 77.958333 -311.263404) (xy 77.928768 -311.302748) (xy 77.893275 -311.33684) (xy 77.852772 -311.364796)
			(xy 77.80831 -311.385894) (xy 77.761039 -311.399586) (xy 77.712184 -311.405518) (xy 77.663009 -311.403537)
			(xy 77.61479 -311.393693) (xy 77.568774 -311.376241) (xy 77.526153 -311.351634) (xy 77.488032 -311.320509)
			(xy 77.455397 -311.283672) (xy 77.429094 -311.242076) (xy 77.409803 -311.1968) (xy 77.398026 -311.149016)
			(xy 77.394066 -311.099962) (xy 76.105258 -311.099962) (xy 76.104763 -311.124569) (xy 76.096868 -311.173146)
			(xy 76.081284 -311.219827) (xy 76.058413 -311.263404) (xy 76.028848 -311.302748) (xy 75.993355 -311.33684)
			(xy 75.952852 -311.364796) (xy 75.90839 -311.385894) (xy 75.861119 -311.399586) (xy 75.812264 -311.405518)
			(xy 75.763089 -311.403537) (xy 75.71487 -311.393693) (xy 75.668854 -311.376241) (xy 75.626233 -311.351634)
			(xy 75.588112 -311.320509) (xy 75.555477 -311.283672) (xy 75.529174 -311.242076) (xy 75.509883 -311.1968)
			(xy 75.498106 -311.149016) (xy 75.494146 -311.099962) (xy 74.205084 -311.099962) (xy 74.204589 -311.124569)
			(xy 74.196694 -311.173146) (xy 74.18111 -311.219827) (xy 74.158239 -311.263404) (xy 74.128674 -311.302748)
			(xy 74.093181 -311.33684) (xy 74.052678 -311.364796) (xy 74.008216 -311.385894) (xy 73.960945 -311.399586)
			(xy 73.91209 -311.405518) (xy 73.862915 -311.403537) (xy 73.814696 -311.393693) (xy 73.76868 -311.376241)
			(xy 73.726059 -311.351634) (xy 73.687938 -311.320509) (xy 73.655303 -311.283672) (xy 73.629 -311.242076)
			(xy 73.609709 -311.1968) (xy 73.597932 -311.149016) (xy 73.593972 -311.099962) (xy 72.305164 -311.099962)
			(xy 72.304669 -311.124569) (xy 72.296774 -311.173146) (xy 72.28119 -311.219827) (xy 72.258319 -311.263404)
			(xy 72.228754 -311.302748) (xy 72.193261 -311.33684) (xy 72.152758 -311.364796) (xy 72.108296 -311.385894)
			(xy 72.061025 -311.399586) (xy 72.01217 -311.405518) (xy 71.962995 -311.403537) (xy 71.914776 -311.393693)
			(xy 71.86876 -311.376241) (xy 71.826139 -311.351634) (xy 71.788018 -311.320509) (xy 71.755383 -311.283672)
			(xy 71.72908 -311.242076) (xy 71.709789 -311.1968) (xy 71.698012 -311.149016) (xy 71.694052 -311.099962)
			(xy 70.405244 -311.099962) (xy 70.404749 -311.124569) (xy 70.396854 -311.173146) (xy 70.38127 -311.219827)
			(xy 70.358399 -311.263404) (xy 70.328834 -311.302748) (xy 70.293341 -311.33684) (xy 70.252838 -311.364796)
			(xy 70.208376 -311.385894) (xy 70.161105 -311.399586) (xy 70.11225 -311.405518) (xy 70.063075 -311.403537)
			(xy 70.014856 -311.393693) (xy 69.96884 -311.376241) (xy 69.926219 -311.351634) (xy 69.888098 -311.320509)
			(xy 69.855463 -311.283672) (xy 69.82916 -311.242076) (xy 69.809869 -311.1968) (xy 69.798092 -311.149016)
			(xy 69.794132 -311.099962) (xy 68.50507 -311.099962) (xy 68.504575 -311.124569) (xy 68.49668 -311.173146)
			(xy 68.481096 -311.219827) (xy 68.458225 -311.263404) (xy 68.42866 -311.302748) (xy 68.393167 -311.33684)
			(xy 68.352664 -311.364796) (xy 68.308202 -311.385894) (xy 68.260931 -311.399586) (xy 68.212076 -311.405518)
			(xy 68.162901 -311.403537) (xy 68.114682 -311.393693) (xy 68.068666 -311.376241) (xy 68.026045 -311.351634)
			(xy 67.987924 -311.320509) (xy 67.955289 -311.283672) (xy 67.928986 -311.242076) (xy 67.909695 -311.1968)
			(xy 67.897918 -311.149016) (xy 67.893958 -311.099962) (xy 66.60515 -311.099962) (xy 66.604655 -311.124569)
			(xy 66.59676 -311.173146) (xy 66.581176 -311.219827) (xy 66.558305 -311.263404) (xy 66.52874 -311.302748)
			(xy 66.493247 -311.33684) (xy 66.452744 -311.364796) (xy 66.408282 -311.385894) (xy 66.361011 -311.399586)
			(xy 66.312156 -311.405518) (xy 66.262981 -311.403537) (xy 66.214762 -311.393693) (xy 66.168746 -311.376241)
			(xy 66.126125 -311.351634) (xy 66.088004 -311.320509) (xy 66.055369 -311.283672) (xy 66.029066 -311.242076)
			(xy 66.009775 -311.1968) (xy 65.997998 -311.149016) (xy 65.994038 -311.099962) (xy 64.70523 -311.099962)
			(xy 64.704735 -311.124569) (xy 64.69684 -311.173146) (xy 64.681256 -311.219827) (xy 64.658385 -311.263404)
			(xy 64.62882 -311.302748) (xy 64.593327 -311.33684) (xy 64.552824 -311.364796) (xy 64.508362 -311.385894)
			(xy 64.461091 -311.399586) (xy 64.412236 -311.405518) (xy 64.363061 -311.403537) (xy 64.314842 -311.393693)
			(xy 64.268826 -311.376241) (xy 64.226205 -311.351634) (xy 64.188084 -311.320509) (xy 64.155449 -311.283672)
			(xy 64.129146 -311.242076) (xy 64.109855 -311.1968) (xy 64.098078 -311.149016) (xy 64.094118 -311.099962)
			(xy 62.805056 -311.099962) (xy 62.804561 -311.124569) (xy 62.796666 -311.173146) (xy 62.781082 -311.219827)
			(xy 62.758211 -311.263404) (xy 62.728646 -311.302748) (xy 62.693153 -311.33684) (xy 62.65265 -311.364796)
			(xy 62.608188 -311.385894) (xy 62.560917 -311.399586) (xy 62.512062 -311.405518) (xy 62.462887 -311.403537)
			(xy 62.414668 -311.393693) (xy 62.368652 -311.376241) (xy 62.326031 -311.351634) (xy 62.28791 -311.320509)
			(xy 62.255275 -311.283672) (xy 62.228972 -311.242076) (xy 62.209681 -311.1968) (xy 62.197904 -311.149016)
			(xy 62.193944 -311.099962) (xy 60.905136 -311.099962) (xy 60.904641 -311.124569) (xy 60.896746 -311.173146)
			(xy 60.881162 -311.219827) (xy 60.858291 -311.263404) (xy 60.828726 -311.302748) (xy 60.793233 -311.33684)
			(xy 60.75273 -311.364796) (xy 60.708268 -311.385894) (xy 60.660997 -311.399586) (xy 60.612142 -311.405518)
			(xy 60.562967 -311.403537) (xy 60.514748 -311.393693) (xy 60.468732 -311.376241) (xy 60.426111 -311.351634)
			(xy 60.38799 -311.320509) (xy 60.355355 -311.283672) (xy 60.329052 -311.242076) (xy 60.309761 -311.1968)
			(xy 60.297984 -311.149016) (xy 60.294024 -311.099962) (xy 59.005216 -311.099962) (xy 59.004721 -311.124569)
			(xy 58.996826 -311.173146) (xy 58.981242 -311.219827) (xy 58.958371 -311.263404) (xy 58.928806 -311.302748)
			(xy 58.893313 -311.33684) (xy 58.85281 -311.364796) (xy 58.808348 -311.385894) (xy 58.761077 -311.399586)
			(xy 58.712222 -311.405518) (xy 58.663047 -311.403537) (xy 58.614828 -311.393693) (xy 58.568812 -311.376241)
			(xy 58.526191 -311.351634) (xy 58.48807 -311.320509) (xy 58.455435 -311.283672) (xy 58.429132 -311.242076)
			(xy 58.409841 -311.1968) (xy 58.398064 -311.149016) (xy 58.394104 -311.099962) (xy 57.105296 -311.099962)
			(xy 57.104801 -311.124569) (xy 57.096906 -311.173146) (xy 57.081322 -311.219827) (xy 57.058451 -311.263404)
			(xy 57.028886 -311.302748) (xy 56.993393 -311.33684) (xy 56.95289 -311.364796) (xy 56.908428 -311.385894)
			(xy 56.861157 -311.399586) (xy 56.812302 -311.405518) (xy 56.763127 -311.403537) (xy 56.714908 -311.393693)
			(xy 56.668892 -311.376241) (xy 56.626271 -311.351634) (xy 56.58815 -311.320509) (xy 56.555515 -311.283672)
			(xy 56.529212 -311.242076) (xy 56.509921 -311.1968) (xy 56.498144 -311.149016) (xy 56.494184 -311.099962)
			(xy 55.205122 -311.099962) (xy 55.204627 -311.124569) (xy 55.196732 -311.173146) (xy 55.181148 -311.219827)
			(xy 55.158277 -311.263404) (xy 55.128712 -311.302748) (xy 55.093219 -311.33684) (xy 55.052716 -311.364796)
			(xy 55.008254 -311.385894) (xy 54.960983 -311.399586) (xy 54.912128 -311.405518) (xy 54.862953 -311.403537)
			(xy 54.814734 -311.393693) (xy 54.768718 -311.376241) (xy 54.726097 -311.351634) (xy 54.687976 -311.320509)
			(xy 54.655341 -311.283672) (xy 54.629038 -311.242076) (xy 54.609747 -311.1968) (xy 54.59797 -311.149016)
			(xy 54.59401 -311.099962) (xy 53.305202 -311.099962) (xy 53.304707 -311.124569) (xy 53.296812 -311.173146)
			(xy 53.281228 -311.219827) (xy 53.258357 -311.263404) (xy 53.228792 -311.302748) (xy 53.193299 -311.33684)
			(xy 53.152796 -311.364796) (xy 53.108334 -311.385894) (xy 53.061063 -311.399586) (xy 53.012208 -311.405518)
			(xy 52.963033 -311.403537) (xy 52.914814 -311.393693) (xy 52.868798 -311.376241) (xy 52.826177 -311.351634)
			(xy 52.788056 -311.320509) (xy 52.755421 -311.283672) (xy 52.729118 -311.242076) (xy 52.709827 -311.1968)
			(xy 52.69805 -311.149016) (xy 52.69409 -311.099962) (xy 51.405282 -311.099962) (xy 51.404787 -311.124569)
			(xy 51.396892 -311.173146) (xy 51.381308 -311.219827) (xy 51.358437 -311.263404) (xy 51.328872 -311.302748)
			(xy 51.293379 -311.33684) (xy 51.252876 -311.364796) (xy 51.208414 -311.385894) (xy 51.161143 -311.399586)
			(xy 51.112288 -311.405518) (xy 51.063113 -311.403537) (xy 51.014894 -311.393693) (xy 50.968878 -311.376241)
			(xy 50.926257 -311.351634) (xy 50.888136 -311.320509) (xy 50.855501 -311.283672) (xy 50.829198 -311.242076)
			(xy 50.809907 -311.1968) (xy 50.79813 -311.149016) (xy 50.79417 -311.099962) (xy 49.505108 -311.099962)
			(xy 49.504613 -311.124569) (xy 49.496718 -311.173146) (xy 49.481134 -311.219827) (xy 49.458263 -311.263404)
			(xy 49.428698 -311.302748) (xy 49.393205 -311.33684) (xy 49.352702 -311.364796) (xy 49.30824 -311.385894)
			(xy 49.260969 -311.399586) (xy 49.212114 -311.405518) (xy 49.162939 -311.403537) (xy 49.11472 -311.393693)
			(xy 49.068704 -311.376241) (xy 49.026083 -311.351634) (xy 48.987962 -311.320509) (xy 48.955327 -311.283672)
			(xy 48.929024 -311.242076) (xy 48.909733 -311.1968) (xy 48.897956 -311.149016) (xy 48.893996 -311.099962)
			(xy 47.605188 -311.099962) (xy 47.604693 -311.124569) (xy 47.596798 -311.173146) (xy 47.581214 -311.219827)
			(xy 47.558343 -311.263404) (xy 47.528778 -311.302748) (xy 47.493285 -311.33684) (xy 47.452782 -311.364796)
			(xy 47.40832 -311.385894) (xy 47.361049 -311.399586) (xy 47.312194 -311.405518) (xy 47.263019 -311.403537)
			(xy 47.2148 -311.393693) (xy 47.168784 -311.376241) (xy 47.126163 -311.351634) (xy 47.088042 -311.320509)
			(xy 47.055407 -311.283672) (xy 47.029104 -311.242076) (xy 47.009813 -311.1968) (xy 46.998036 -311.149016)
			(xy 46.994076 -311.099962) (xy 45.705268 -311.099962) (xy 45.704773 -311.124569) (xy 45.696878 -311.173146)
			(xy 45.681294 -311.219827) (xy 45.658423 -311.263404) (xy 45.628858 -311.302748) (xy 45.593365 -311.33684)
			(xy 45.552862 -311.364796) (xy 45.5084 -311.385894) (xy 45.461129 -311.399586) (xy 45.412274 -311.405518)
			(xy 45.363099 -311.403537) (xy 45.31488 -311.393693) (xy 45.268864 -311.376241) (xy 45.226243 -311.351634)
			(xy 45.188122 -311.320509) (xy 45.155487 -311.283672) (xy 45.129184 -311.242076) (xy 45.109893 -311.1968)
			(xy 45.098116 -311.149016) (xy 45.094156 -311.099962) (xy 43.805094 -311.099962) (xy 43.804599 -311.124569)
			(xy 43.796704 -311.173146) (xy 43.78112 -311.219827) (xy 43.758249 -311.263404) (xy 43.728684 -311.302748)
			(xy 43.693191 -311.33684) (xy 43.652688 -311.364796) (xy 43.608226 -311.385894) (xy 43.560955 -311.399586)
			(xy 43.5121 -311.405518) (xy 43.462925 -311.403537) (xy 43.414706 -311.393693) (xy 43.36869 -311.376241)
			(xy 43.326069 -311.351634) (xy 43.287948 -311.320509) (xy 43.255313 -311.283672) (xy 43.22901 -311.242076)
			(xy 43.209719 -311.1968) (xy 43.197942 -311.149016) (xy 43.193982 -311.099962) (xy 41.905174 -311.099962)
			(xy 41.904679 -311.124569) (xy 41.896784 -311.173146) (xy 41.8812 -311.219827) (xy 41.858329 -311.263404)
			(xy 41.828764 -311.302748) (xy 41.793271 -311.33684) (xy 41.752768 -311.364796) (xy 41.708306 -311.385894)
			(xy 41.661035 -311.399586) (xy 41.61218 -311.405518) (xy 41.563005 -311.403537) (xy 41.514786 -311.393693)
			(xy 41.46877 -311.376241) (xy 41.426149 -311.351634) (xy 41.388028 -311.320509) (xy 41.355393 -311.283672)
			(xy 41.32909 -311.242076) (xy 41.309799 -311.1968) (xy 41.298022 -311.149016) (xy 41.294062 -311.099962)
			(xy 40.005254 -311.099962) (xy 40.004759 -311.124569) (xy 39.996864 -311.173146) (xy 39.98128 -311.219827)
			(xy 39.958409 -311.263404) (xy 39.928844 -311.302748) (xy 39.893351 -311.33684) (xy 39.852848 -311.364796)
			(xy 39.808386 -311.385894) (xy 39.761115 -311.399586) (xy 39.71226 -311.405518) (xy 39.663085 -311.403537)
			(xy 39.614866 -311.393693) (xy 39.56885 -311.376241) (xy 39.526229 -311.351634) (xy 39.488108 -311.320509)
			(xy 39.455473 -311.283672) (xy 39.42917 -311.242076) (xy 39.409879 -311.1968) (xy 39.398102 -311.149016)
			(xy 39.394142 -311.099962) (xy 0.509016 -311.099962) (xy 0.509016 -312.049922) (xy 36.544008 -312.049922)
			(xy 36.547968 -312.000868) (xy 36.559745 -311.953084) (xy 36.579036 -311.907808) (xy 36.605339 -311.866212)
			(xy 36.637974 -311.829375) (xy 36.676095 -311.79825) (xy 36.718716 -311.773643) (xy 36.764732 -311.756191)
			(xy 36.812951 -311.746347) (xy 36.862126 -311.744366) (xy 36.910981 -311.750298) (xy 36.958252 -311.76399)
			(xy 37.002714 -311.785088) (xy 37.043217 -311.813044) (xy 37.07871 -311.847136) (xy 37.108275 -311.88648)
			(xy 37.131146 -311.930057) (xy 37.14673 -311.976738) (xy 37.154625 -312.025315) (xy 37.15512 -312.049922)
			(xy 37.493968 -312.049922) (xy 37.497928 -312.000868) (xy 37.509705 -311.953084) (xy 37.528996 -311.907808)
			(xy 37.555299 -311.866212) (xy 37.587934 -311.829375) (xy 37.626055 -311.79825) (xy 37.668676 -311.773643)
			(xy 37.714692 -311.756191) (xy 37.762911 -311.746347) (xy 37.812086 -311.744366) (xy 37.860941 -311.750298)
			(xy 37.908212 -311.76399) (xy 37.952674 -311.785088) (xy 37.993177 -311.813044) (xy 38.02867 -311.847136)
			(xy 38.058235 -311.88648) (xy 38.081106 -311.930057) (xy 38.09669 -311.976738) (xy 38.104585 -312.025315)
			(xy 38.10508 -312.049922) (xy 39.394142 -312.049922) (xy 39.398102 -312.000868) (xy 39.409879 -311.953084)
			(xy 39.42917 -311.907808) (xy 39.455473 -311.866212) (xy 39.488108 -311.829375) (xy 39.526229 -311.79825)
			(xy 39.56885 -311.773643) (xy 39.614866 -311.756191) (xy 39.663085 -311.746347) (xy 39.71226 -311.744366)
			(xy 39.761115 -311.750298) (xy 39.808386 -311.76399) (xy 39.852848 -311.785088) (xy 39.893351 -311.813044)
			(xy 39.928844 -311.847136) (xy 39.958409 -311.88648) (xy 39.98128 -311.930057) (xy 39.996864 -311.976738)
			(xy 40.004759 -312.025315) (xy 40.005254 -312.049922) (xy 41.294062 -312.049922) (xy 41.298022 -312.000868)
			(xy 41.309799 -311.953084) (xy 41.32909 -311.907808) (xy 41.355393 -311.866212) (xy 41.388028 -311.829375)
			(xy 41.426149 -311.79825) (xy 41.46877 -311.773643) (xy 41.514786 -311.756191) (xy 41.563005 -311.746347)
			(xy 41.61218 -311.744366) (xy 41.661035 -311.750298) (xy 41.708306 -311.76399) (xy 41.752768 -311.785088)
			(xy 41.793271 -311.813044) (xy 41.828764 -311.847136) (xy 41.858329 -311.88648) (xy 41.8812 -311.930057)
			(xy 41.896784 -311.976738) (xy 41.904679 -312.025315) (xy 41.905174 -312.049922) (xy 43.193982 -312.049922)
			(xy 43.197942 -312.000868) (xy 43.209719 -311.953084) (xy 43.22901 -311.907808) (xy 43.255313 -311.866212)
			(xy 43.287948 -311.829375) (xy 43.326069 -311.79825) (xy 43.36869 -311.773643) (xy 43.414706 -311.756191)
			(xy 43.462925 -311.746347) (xy 43.5121 -311.744366) (xy 43.560955 -311.750298) (xy 43.608226 -311.76399)
			(xy 43.652688 -311.785088) (xy 43.693191 -311.813044) (xy 43.728684 -311.847136) (xy 43.758249 -311.88648)
			(xy 43.78112 -311.930057) (xy 43.796704 -311.976738) (xy 43.804599 -312.025315) (xy 43.805094 -312.049922)
			(xy 45.094156 -312.049922) (xy 45.098116 -312.000868) (xy 45.109893 -311.953084) (xy 45.129184 -311.907808)
			(xy 45.155487 -311.866212) (xy 45.188122 -311.829375) (xy 45.226243 -311.79825) (xy 45.268864 -311.773643)
			(xy 45.31488 -311.756191) (xy 45.363099 -311.746347) (xy 45.412274 -311.744366) (xy 45.461129 -311.750298)
			(xy 45.5084 -311.76399) (xy 45.552862 -311.785088) (xy 45.593365 -311.813044) (xy 45.628858 -311.847136)
			(xy 45.658423 -311.88648) (xy 45.681294 -311.930057) (xy 45.696878 -311.976738) (xy 45.704773 -312.025315)
			(xy 45.705268 -312.049922) (xy 46.994076 -312.049922) (xy 46.998036 -312.000868) (xy 47.009813 -311.953084)
			(xy 47.029104 -311.907808) (xy 47.055407 -311.866212) (xy 47.088042 -311.829375) (xy 47.126163 -311.79825)
			(xy 47.168784 -311.773643) (xy 47.2148 -311.756191) (xy 47.263019 -311.746347) (xy 47.312194 -311.744366)
			(xy 47.361049 -311.750298) (xy 47.40832 -311.76399) (xy 47.452782 -311.785088) (xy 47.493285 -311.813044)
			(xy 47.528778 -311.847136) (xy 47.558343 -311.88648) (xy 47.581214 -311.930057) (xy 47.596798 -311.976738)
			(xy 47.604693 -312.025315) (xy 47.605188 -312.049922) (xy 48.893996 -312.049922) (xy 48.897956 -312.000868)
			(xy 48.909733 -311.953084) (xy 48.929024 -311.907808) (xy 48.955327 -311.866212) (xy 48.987962 -311.829375)
			(xy 49.026083 -311.79825) (xy 49.068704 -311.773643) (xy 49.11472 -311.756191) (xy 49.162939 -311.746347)
			(xy 49.212114 -311.744366) (xy 49.260969 -311.750298) (xy 49.30824 -311.76399) (xy 49.352702 -311.785088)
			(xy 49.393205 -311.813044) (xy 49.428698 -311.847136) (xy 49.458263 -311.88648) (xy 49.481134 -311.930057)
			(xy 49.496718 -311.976738) (xy 49.504613 -312.025315) (xy 49.505108 -312.049922) (xy 50.79417 -312.049922)
			(xy 50.79813 -312.000868) (xy 50.809907 -311.953084) (xy 50.829198 -311.907808) (xy 50.855501 -311.866212)
			(xy 50.888136 -311.829375) (xy 50.926257 -311.79825) (xy 50.968878 -311.773643) (xy 51.014894 -311.756191)
			(xy 51.063113 -311.746347) (xy 51.112288 -311.744366) (xy 51.161143 -311.750298) (xy 51.208414 -311.76399)
			(xy 51.252876 -311.785088) (xy 51.293379 -311.813044) (xy 51.328872 -311.847136) (xy 51.358437 -311.88648)
			(xy 51.381308 -311.930057) (xy 51.396892 -311.976738) (xy 51.404787 -312.025315) (xy 51.405282 -312.049922)
			(xy 52.69409 -312.049922) (xy 52.69805 -312.000868) (xy 52.709827 -311.953084) (xy 52.729118 -311.907808)
			(xy 52.755421 -311.866212) (xy 52.788056 -311.829375) (xy 52.826177 -311.79825) (xy 52.868798 -311.773643)
			(xy 52.914814 -311.756191) (xy 52.963033 -311.746347) (xy 53.012208 -311.744366) (xy 53.061063 -311.750298)
			(xy 53.108334 -311.76399) (xy 53.152796 -311.785088) (xy 53.193299 -311.813044) (xy 53.228792 -311.847136)
			(xy 53.258357 -311.88648) (xy 53.281228 -311.930057) (xy 53.296812 -311.976738) (xy 53.304707 -312.025315)
			(xy 53.305202 -312.049922) (xy 54.59401 -312.049922) (xy 54.59797 -312.000868) (xy 54.609747 -311.953084)
			(xy 54.629038 -311.907808) (xy 54.655341 -311.866212) (xy 54.687976 -311.829375) (xy 54.726097 -311.79825)
			(xy 54.768718 -311.773643) (xy 54.814734 -311.756191) (xy 54.862953 -311.746347) (xy 54.912128 -311.744366)
			(xy 54.960983 -311.750298) (xy 55.008254 -311.76399) (xy 55.052716 -311.785088) (xy 55.093219 -311.813044)
			(xy 55.128712 -311.847136) (xy 55.158277 -311.88648) (xy 55.181148 -311.930057) (xy 55.196732 -311.976738)
			(xy 55.204627 -312.025315) (xy 55.205122 -312.049922) (xy 56.494184 -312.049922) (xy 56.498144 -312.000868)
			(xy 56.509921 -311.953084) (xy 56.529212 -311.907808) (xy 56.555515 -311.866212) (xy 56.58815 -311.829375)
			(xy 56.626271 -311.79825) (xy 56.668892 -311.773643) (xy 56.714908 -311.756191) (xy 56.763127 -311.746347)
			(xy 56.812302 -311.744366) (xy 56.861157 -311.750298) (xy 56.908428 -311.76399) (xy 56.95289 -311.785088)
			(xy 56.993393 -311.813044) (xy 57.028886 -311.847136) (xy 57.058451 -311.88648) (xy 57.081322 -311.930057)
			(xy 57.096906 -311.976738) (xy 57.104801 -312.025315) (xy 57.105296 -312.049922) (xy 58.394104 -312.049922)
			(xy 58.398064 -312.000868) (xy 58.409841 -311.953084) (xy 58.429132 -311.907808) (xy 58.455435 -311.866212)
			(xy 58.48807 -311.829375) (xy 58.526191 -311.79825) (xy 58.568812 -311.773643) (xy 58.614828 -311.756191)
			(xy 58.663047 -311.746347) (xy 58.712222 -311.744366) (xy 58.761077 -311.750298) (xy 58.808348 -311.76399)
			(xy 58.85281 -311.785088) (xy 58.893313 -311.813044) (xy 58.928806 -311.847136) (xy 58.958371 -311.88648)
			(xy 58.981242 -311.930057) (xy 58.996826 -311.976738) (xy 59.004721 -312.025315) (xy 59.005216 -312.049922)
			(xy 60.294024 -312.049922) (xy 60.297984 -312.000868) (xy 60.309761 -311.953084) (xy 60.329052 -311.907808)
			(xy 60.355355 -311.866212) (xy 60.38799 -311.829375) (xy 60.426111 -311.79825) (xy 60.468732 -311.773643)
			(xy 60.514748 -311.756191) (xy 60.562967 -311.746347) (xy 60.612142 -311.744366) (xy 60.660997 -311.750298)
			(xy 60.708268 -311.76399) (xy 60.75273 -311.785088) (xy 60.793233 -311.813044) (xy 60.828726 -311.847136)
			(xy 60.858291 -311.88648) (xy 60.881162 -311.930057) (xy 60.896746 -311.976738) (xy 60.904641 -312.025315)
			(xy 60.905136 -312.049922) (xy 62.193944 -312.049922) (xy 62.197904 -312.000868) (xy 62.209681 -311.953084)
			(xy 62.228972 -311.907808) (xy 62.255275 -311.866212) (xy 62.28791 -311.829375) (xy 62.326031 -311.79825)
			(xy 62.368652 -311.773643) (xy 62.414668 -311.756191) (xy 62.462887 -311.746347) (xy 62.512062 -311.744366)
			(xy 62.560917 -311.750298) (xy 62.608188 -311.76399) (xy 62.65265 -311.785088) (xy 62.693153 -311.813044)
			(xy 62.728646 -311.847136) (xy 62.758211 -311.88648) (xy 62.781082 -311.930057) (xy 62.796666 -311.976738)
			(xy 62.804561 -312.025315) (xy 62.805056 -312.049922) (xy 64.094118 -312.049922) (xy 64.098078 -312.000868)
			(xy 64.109855 -311.953084) (xy 64.129146 -311.907808) (xy 64.155449 -311.866212) (xy 64.188084 -311.829375)
			(xy 64.226205 -311.79825) (xy 64.268826 -311.773643) (xy 64.314842 -311.756191) (xy 64.363061 -311.746347)
			(xy 64.412236 -311.744366) (xy 64.461091 -311.750298) (xy 64.508362 -311.76399) (xy 64.552824 -311.785088)
			(xy 64.593327 -311.813044) (xy 64.62882 -311.847136) (xy 64.658385 -311.88648) (xy 64.681256 -311.930057)
			(xy 64.69684 -311.976738) (xy 64.704735 -312.025315) (xy 64.70523 -312.049922) (xy 65.994038 -312.049922)
			(xy 65.997998 -312.000868) (xy 66.009775 -311.953084) (xy 66.029066 -311.907808) (xy 66.055369 -311.866212)
			(xy 66.088004 -311.829375) (xy 66.126125 -311.79825) (xy 66.168746 -311.773643) (xy 66.214762 -311.756191)
			(xy 66.262981 -311.746347) (xy 66.312156 -311.744366) (xy 66.361011 -311.750298) (xy 66.408282 -311.76399)
			(xy 66.452744 -311.785088) (xy 66.493247 -311.813044) (xy 66.52874 -311.847136) (xy 66.558305 -311.88648)
			(xy 66.581176 -311.930057) (xy 66.59676 -311.976738) (xy 66.604655 -312.025315) (xy 66.60515 -312.049922)
			(xy 67.893958 -312.049922) (xy 67.897918 -312.000868) (xy 67.909695 -311.953084) (xy 67.928986 -311.907808)
			(xy 67.955289 -311.866212) (xy 67.987924 -311.829375) (xy 68.026045 -311.79825) (xy 68.068666 -311.773643)
			(xy 68.114682 -311.756191) (xy 68.162901 -311.746347) (xy 68.212076 -311.744366) (xy 68.260931 -311.750298)
			(xy 68.308202 -311.76399) (xy 68.352664 -311.785088) (xy 68.393167 -311.813044) (xy 68.42866 -311.847136)
			(xy 68.458225 -311.88648) (xy 68.481096 -311.930057) (xy 68.49668 -311.976738) (xy 68.504575 -312.025315)
			(xy 68.50507 -312.049922) (xy 69.794132 -312.049922) (xy 69.798092 -312.000868) (xy 69.809869 -311.953084)
			(xy 69.82916 -311.907808) (xy 69.855463 -311.866212) (xy 69.888098 -311.829375) (xy 69.926219 -311.79825)
			(xy 69.96884 -311.773643) (xy 70.014856 -311.756191) (xy 70.063075 -311.746347) (xy 70.11225 -311.744366)
			(xy 70.161105 -311.750298) (xy 70.208376 -311.76399) (xy 70.252838 -311.785088) (xy 70.293341 -311.813044)
			(xy 70.328834 -311.847136) (xy 70.358399 -311.88648) (xy 70.38127 -311.930057) (xy 70.396854 -311.976738)
			(xy 70.404749 -312.025315) (xy 70.405244 -312.049922) (xy 71.694052 -312.049922) (xy 71.698012 -312.000868)
			(xy 71.709789 -311.953084) (xy 71.72908 -311.907808) (xy 71.755383 -311.866212) (xy 71.788018 -311.829375)
			(xy 71.826139 -311.79825) (xy 71.86876 -311.773643) (xy 71.914776 -311.756191) (xy 71.962995 -311.746347)
			(xy 72.01217 -311.744366) (xy 72.061025 -311.750298) (xy 72.108296 -311.76399) (xy 72.152758 -311.785088)
			(xy 72.193261 -311.813044) (xy 72.228754 -311.847136) (xy 72.258319 -311.88648) (xy 72.28119 -311.930057)
			(xy 72.296774 -311.976738) (xy 72.304669 -312.025315) (xy 72.305164 -312.049922) (xy 73.593972 -312.049922)
			(xy 73.597932 -312.000868) (xy 73.609709 -311.953084) (xy 73.629 -311.907808) (xy 73.655303 -311.866212)
			(xy 73.687938 -311.829375) (xy 73.726059 -311.79825) (xy 73.76868 -311.773643) (xy 73.814696 -311.756191)
			(xy 73.862915 -311.746347) (xy 73.91209 -311.744366) (xy 73.960945 -311.750298) (xy 74.008216 -311.76399)
			(xy 74.052678 -311.785088) (xy 74.093181 -311.813044) (xy 74.128674 -311.847136) (xy 74.158239 -311.88648)
			(xy 74.18111 -311.930057) (xy 74.196694 -311.976738) (xy 74.204589 -312.025315) (xy 74.205084 -312.049922)
			(xy 75.494146 -312.049922) (xy 75.498106 -312.000868) (xy 75.509883 -311.953084) (xy 75.529174 -311.907808)
			(xy 75.555477 -311.866212) (xy 75.588112 -311.829375) (xy 75.626233 -311.79825) (xy 75.668854 -311.773643)
			(xy 75.71487 -311.756191) (xy 75.763089 -311.746347) (xy 75.812264 -311.744366) (xy 75.861119 -311.750298)
			(xy 75.90839 -311.76399) (xy 75.952852 -311.785088) (xy 75.993355 -311.813044) (xy 76.028848 -311.847136)
			(xy 76.058413 -311.88648) (xy 76.081284 -311.930057) (xy 76.096868 -311.976738) (xy 76.104763 -312.025315)
			(xy 76.105258 -312.049922) (xy 77.394066 -312.049922) (xy 77.398026 -312.000868) (xy 77.409803 -311.953084)
			(xy 77.429094 -311.907808) (xy 77.455397 -311.866212) (xy 77.488032 -311.829375) (xy 77.526153 -311.79825)
			(xy 77.568774 -311.773643) (xy 77.61479 -311.756191) (xy 77.663009 -311.746347) (xy 77.712184 -311.744366)
			(xy 77.761039 -311.750298) (xy 77.80831 -311.76399) (xy 77.852772 -311.785088) (xy 77.893275 -311.813044)
			(xy 77.928768 -311.847136) (xy 77.958333 -311.88648) (xy 77.981204 -311.930057) (xy 77.996788 -311.976738)
			(xy 78.004683 -312.025315) (xy 78.005178 -312.049922) (xy 79.293986 -312.049922) (xy 79.297946 -312.000868)
			(xy 79.309723 -311.953084) (xy 79.329014 -311.907808) (xy 79.355317 -311.866212) (xy 79.387952 -311.829375)
			(xy 79.426073 -311.79825) (xy 79.468694 -311.773643) (xy 79.51471 -311.756191) (xy 79.562929 -311.746347)
			(xy 79.612104 -311.744366) (xy 79.660959 -311.750298) (xy 79.70823 -311.76399) (xy 79.752692 -311.785088)
			(xy 79.793195 -311.813044) (xy 79.828688 -311.847136) (xy 79.858253 -311.88648) (xy 79.881124 -311.930057)
			(xy 79.896708 -311.976738) (xy 79.904603 -312.025315) (xy 79.905098 -312.049922) (xy 81.19416 -312.049922)
			(xy 81.19812 -312.000868) (xy 81.209897 -311.953084) (xy 81.229188 -311.907808) (xy 81.255491 -311.866212)
			(xy 81.288126 -311.829375) (xy 81.326247 -311.79825) (xy 81.368868 -311.773643) (xy 81.414884 -311.756191)
			(xy 81.463103 -311.746347) (xy 81.512278 -311.744366) (xy 81.561133 -311.750298) (xy 81.608404 -311.76399)
			(xy 81.652866 -311.785088) (xy 81.693369 -311.813044) (xy 81.728862 -311.847136) (xy 81.758427 -311.88648)
			(xy 81.781298 -311.930057) (xy 81.796882 -311.976738) (xy 81.804777 -312.025315) (xy 81.805272 -312.049922)
			(xy 82.14412 -312.049922) (xy 82.14808 -312.000868) (xy 82.159857 -311.953084) (xy 82.179148 -311.907808)
			(xy 82.205451 -311.866212) (xy 82.238086 -311.829375) (xy 82.276207 -311.79825) (xy 82.318828 -311.773643)
			(xy 82.364844 -311.756191) (xy 82.413063 -311.746347) (xy 82.462238 -311.744366) (xy 82.511093 -311.750298)
			(xy 82.558364 -311.76399) (xy 82.602826 -311.785088) (xy 82.643329 -311.813044) (xy 82.678822 -311.847136)
			(xy 82.708387 -311.88648) (xy 82.731258 -311.930057) (xy 82.746842 -311.976738) (xy 82.754737 -312.025315)
			(xy 82.755232 -312.049922) (xy 152.644106 -312.049922) (xy 152.648066 -312.000868) (xy 152.659843 -311.953084)
			(xy 152.679134 -311.907808) (xy 152.705437 -311.866212) (xy 152.738072 -311.829375) (xy 152.776193 -311.79825)
			(xy 152.818814 -311.773643) (xy 152.86483 -311.756191) (xy 152.913049 -311.746347) (xy 152.962224 -311.744366)
			(xy 153.011079 -311.750298) (xy 153.05835 -311.76399) (xy 153.102812 -311.785088) (xy 153.143315 -311.813044)
			(xy 153.178808 -311.847136) (xy 153.208373 -311.88648) (xy 153.231244 -311.930057) (xy 153.246828 -311.976738)
			(xy 153.254723 -312.025315) (xy 153.255218 -312.049922) (xy 153.594066 -312.049922) (xy 153.598026 -312.000868)
			(xy 153.609803 -311.953084) (xy 153.629094 -311.907808) (xy 153.655397 -311.866212) (xy 153.688032 -311.829375)
			(xy 153.726153 -311.79825) (xy 153.768774 -311.773643) (xy 153.81479 -311.756191) (xy 153.863009 -311.746347)
			(xy 153.912184 -311.744366) (xy 153.961039 -311.750298) (xy 154.00831 -311.76399) (xy 154.052772 -311.785088)
			(xy 154.093275 -311.813044) (xy 154.128768 -311.847136) (xy 154.158333 -311.88648) (xy 154.181204 -311.930057)
			(xy 154.196788 -311.976738) (xy 154.204683 -312.025315) (xy 154.205178 -312.049922) (xy 155.49424 -312.049922)
			(xy 155.4982 -312.000868) (xy 155.509977 -311.953084) (xy 155.529268 -311.907808) (xy 155.555571 -311.866212)
			(xy 155.588206 -311.829375) (xy 155.626327 -311.79825) (xy 155.668948 -311.773643) (xy 155.714964 -311.756191)
			(xy 155.763183 -311.746347) (xy 155.812358 -311.744366) (xy 155.861213 -311.750298) (xy 155.908484 -311.76399)
			(xy 155.952946 -311.785088) (xy 155.993449 -311.813044) (xy 156.028942 -311.847136) (xy 156.058507 -311.88648)
			(xy 156.081378 -311.930057) (xy 156.096962 -311.976738) (xy 156.104857 -312.025315) (xy 156.105352 -312.049922)
			(xy 157.39416 -312.049922) (xy 157.39812 -312.000868) (xy 157.409897 -311.953084) (xy 157.429188 -311.907808)
			(xy 157.455491 -311.866212) (xy 157.488126 -311.829375) (xy 157.526247 -311.79825) (xy 157.568868 -311.773643)
			(xy 157.614884 -311.756191) (xy 157.663103 -311.746347) (xy 157.712278 -311.744366) (xy 157.761133 -311.750298)
			(xy 157.808404 -311.76399) (xy 157.852866 -311.785088) (xy 157.893369 -311.813044) (xy 157.928862 -311.847136)
			(xy 157.958427 -311.88648) (xy 157.981298 -311.930057) (xy 157.996882 -311.976738) (xy 158.004777 -312.025315)
			(xy 158.005272 -312.049922) (xy 159.29408 -312.049922) (xy 159.29804 -312.000868) (xy 159.309817 -311.953084)
			(xy 159.329108 -311.907808) (xy 159.355411 -311.866212) (xy 159.388046 -311.829375) (xy 159.426167 -311.79825)
			(xy 159.468788 -311.773643) (xy 159.514804 -311.756191) (xy 159.563023 -311.746347) (xy 159.612198 -311.744366)
			(xy 159.661053 -311.750298) (xy 159.708324 -311.76399) (xy 159.752786 -311.785088) (xy 159.793289 -311.813044)
			(xy 159.828782 -311.847136) (xy 159.858347 -311.88648) (xy 159.881218 -311.930057) (xy 159.896802 -311.976738)
			(xy 159.904697 -312.025315) (xy 159.905192 -312.049922) (xy 161.194254 -312.049922) (xy 161.198214 -312.000868)
			(xy 161.209991 -311.953084) (xy 161.229282 -311.907808) (xy 161.255585 -311.866212) (xy 161.28822 -311.829375)
			(xy 161.326341 -311.79825) (xy 161.368962 -311.773643) (xy 161.414978 -311.756191) (xy 161.463197 -311.746347)
			(xy 161.512372 -311.744366) (xy 161.561227 -311.750298) (xy 161.608498 -311.76399) (xy 161.65296 -311.785088)
			(xy 161.693463 -311.813044) (xy 161.728956 -311.847136) (xy 161.758521 -311.88648) (xy 161.781392 -311.930057)
			(xy 161.796976 -311.976738) (xy 161.804871 -312.025315) (xy 161.805366 -312.049922) (xy 163.094174 -312.049922)
			(xy 163.098134 -312.000868) (xy 163.109911 -311.953084) (xy 163.129202 -311.907808) (xy 163.155505 -311.866212)
			(xy 163.18814 -311.829375) (xy 163.226261 -311.79825) (xy 163.268882 -311.773643) (xy 163.314898 -311.756191)
			(xy 163.363117 -311.746347) (xy 163.412292 -311.744366) (xy 163.461147 -311.750298) (xy 163.508418 -311.76399)
			(xy 163.55288 -311.785088) (xy 163.593383 -311.813044) (xy 163.628876 -311.847136) (xy 163.658441 -311.88648)
			(xy 163.681312 -311.930057) (xy 163.696896 -311.976738) (xy 163.704791 -312.025315) (xy 163.705286 -312.049922)
			(xy 164.994094 -312.049922) (xy 164.998054 -312.000868) (xy 165.009831 -311.953084) (xy 165.029122 -311.907808)
			(xy 165.055425 -311.866212) (xy 165.08806 -311.829375) (xy 165.126181 -311.79825) (xy 165.168802 -311.773643)
			(xy 165.214818 -311.756191) (xy 165.263037 -311.746347) (xy 165.312212 -311.744366) (xy 165.361067 -311.750298)
			(xy 165.408338 -311.76399) (xy 165.4528 -311.785088) (xy 165.493303 -311.813044) (xy 165.528796 -311.847136)
			(xy 165.558361 -311.88648) (xy 165.581232 -311.930057) (xy 165.596816 -311.976738) (xy 165.604711 -312.025315)
			(xy 165.605206 -312.049922) (xy 166.894268 -312.049922) (xy 166.898228 -312.000868) (xy 166.910005 -311.953084)
			(xy 166.929296 -311.907808) (xy 166.955599 -311.866212) (xy 166.988234 -311.829375) (xy 167.026355 -311.79825)
			(xy 167.068976 -311.773643) (xy 167.114992 -311.756191) (xy 167.163211 -311.746347) (xy 167.212386 -311.744366)
			(xy 167.261241 -311.750298) (xy 167.308512 -311.76399) (xy 167.352974 -311.785088) (xy 167.393477 -311.813044)
			(xy 167.42897 -311.847136) (xy 167.458535 -311.88648) (xy 167.481406 -311.930057) (xy 167.49699 -311.976738)
			(xy 167.504885 -312.025315) (xy 167.50538 -312.049922) (xy 168.794188 -312.049922) (xy 168.798148 -312.000868)
			(xy 168.809925 -311.953084) (xy 168.829216 -311.907808) (xy 168.855519 -311.866212) (xy 168.888154 -311.829375)
			(xy 168.926275 -311.79825) (xy 168.968896 -311.773643) (xy 169.014912 -311.756191) (xy 169.063131 -311.746347)
			(xy 169.112306 -311.744366) (xy 169.161161 -311.750298) (xy 169.208432 -311.76399) (xy 169.252894 -311.785088)
			(xy 169.293397 -311.813044) (xy 169.32889 -311.847136) (xy 169.358455 -311.88648) (xy 169.381326 -311.930057)
			(xy 169.39691 -311.976738) (xy 169.404805 -312.025315) (xy 169.4053 -312.049922) (xy 170.694108 -312.049922)
			(xy 170.698068 -312.000868) (xy 170.709845 -311.953084) (xy 170.729136 -311.907808) (xy 170.755439 -311.866212)
			(xy 170.788074 -311.829375) (xy 170.826195 -311.79825) (xy 170.868816 -311.773643) (xy 170.914832 -311.756191)
			(xy 170.963051 -311.746347) (xy 171.012226 -311.744366) (xy 171.061081 -311.750298) (xy 171.108352 -311.76399)
			(xy 171.152814 -311.785088) (xy 171.193317 -311.813044) (xy 171.22881 -311.847136) (xy 171.258375 -311.88648)
			(xy 171.281246 -311.930057) (xy 171.29683 -311.976738) (xy 171.304725 -312.025315) (xy 171.30522 -312.049922)
			(xy 172.594282 -312.049922) (xy 172.598242 -312.000868) (xy 172.610019 -311.953084) (xy 172.62931 -311.907808)
			(xy 172.655613 -311.866212) (xy 172.688248 -311.829375) (xy 172.726369 -311.79825) (xy 172.76899 -311.773643)
			(xy 172.815006 -311.756191) (xy 172.863225 -311.746347) (xy 172.9124 -311.744366) (xy 172.961255 -311.750298)
			(xy 173.008526 -311.76399) (xy 173.052988 -311.785088) (xy 173.093491 -311.813044) (xy 173.128984 -311.847136)
			(xy 173.158549 -311.88648) (xy 173.18142 -311.930057) (xy 173.197004 -311.976738) (xy 173.204899 -312.025315)
			(xy 173.205394 -312.049922) (xy 174.494202 -312.049922) (xy 174.498162 -312.000868) (xy 174.509939 -311.953084)
			(xy 174.52923 -311.907808) (xy 174.555533 -311.866212) (xy 174.588168 -311.829375) (xy 174.626289 -311.79825)
			(xy 174.66891 -311.773643) (xy 174.714926 -311.756191) (xy 174.763145 -311.746347) (xy 174.81232 -311.744366)
			(xy 174.861175 -311.750298) (xy 174.908446 -311.76399) (xy 174.952908 -311.785088) (xy 174.993411 -311.813044)
			(xy 175.028904 -311.847136) (xy 175.058469 -311.88648) (xy 175.08134 -311.930057) (xy 175.096924 -311.976738)
			(xy 175.104819 -312.025315) (xy 175.105314 -312.049922) (xy 176.394122 -312.049922) (xy 176.398082 -312.000868)
			(xy 176.409859 -311.953084) (xy 176.42915 -311.907808) (xy 176.455453 -311.866212) (xy 176.488088 -311.829375)
			(xy 176.526209 -311.79825) (xy 176.56883 -311.773643) (xy 176.614846 -311.756191) (xy 176.663065 -311.746347)
			(xy 176.71224 -311.744366) (xy 176.761095 -311.750298) (xy 176.808366 -311.76399) (xy 176.852828 -311.785088)
			(xy 176.893331 -311.813044) (xy 176.928824 -311.847136) (xy 176.958389 -311.88648) (xy 176.98126 -311.930057)
			(xy 176.996844 -311.976738) (xy 177.004739 -312.025315) (xy 177.005234 -312.049922) (xy 178.294042 -312.049922)
			(xy 178.298002 -312.000868) (xy 178.309779 -311.953084) (xy 178.32907 -311.907808) (xy 178.355373 -311.866212)
			(xy 178.388008 -311.829375) (xy 178.426129 -311.79825) (xy 178.46875 -311.773643) (xy 178.514766 -311.756191)
			(xy 178.562985 -311.746347) (xy 178.61216 -311.744366) (xy 178.661015 -311.750298) (xy 178.708286 -311.76399)
			(xy 178.752748 -311.785088) (xy 178.793251 -311.813044) (xy 178.828744 -311.847136) (xy 178.858309 -311.88648)
			(xy 178.88118 -311.930057) (xy 178.896764 -311.976738) (xy 178.904659 -312.025315) (xy 178.905154 -312.049922)
			(xy 180.194216 -312.049922) (xy 180.198176 -312.000868) (xy 180.209953 -311.953084) (xy 180.229244 -311.907808)
			(xy 180.255547 -311.866212) (xy 180.288182 -311.829375) (xy 180.326303 -311.79825) (xy 180.368924 -311.773643)
			(xy 180.41494 -311.756191) (xy 180.463159 -311.746347) (xy 180.512334 -311.744366) (xy 180.561189 -311.750298)
			(xy 180.60846 -311.76399) (xy 180.652922 -311.785088) (xy 180.693425 -311.813044) (xy 180.728918 -311.847136)
			(xy 180.758483 -311.88648) (xy 180.781354 -311.930057) (xy 180.796938 -311.976738) (xy 180.804833 -312.025315)
			(xy 180.805328 -312.049922) (xy 182.094136 -312.049922) (xy 182.098096 -312.000868) (xy 182.109873 -311.953084)
			(xy 182.129164 -311.907808) (xy 182.155467 -311.866212) (xy 182.188102 -311.829375) (xy 182.226223 -311.79825)
			(xy 182.268844 -311.773643) (xy 182.31486 -311.756191) (xy 182.363079 -311.746347) (xy 182.412254 -311.744366)
			(xy 182.461109 -311.750298) (xy 182.50838 -311.76399) (xy 182.552842 -311.785088) (xy 182.593345 -311.813044)
			(xy 182.628838 -311.847136) (xy 182.658403 -311.88648) (xy 182.681274 -311.930057) (xy 182.696858 -311.976738)
			(xy 182.704753 -312.025315) (xy 182.705248 -312.049922) (xy 183.994056 -312.049922) (xy 183.998016 -312.000868)
			(xy 184.009793 -311.953084) (xy 184.029084 -311.907808) (xy 184.055387 -311.866212) (xy 184.088022 -311.829375)
			(xy 184.126143 -311.79825) (xy 184.168764 -311.773643) (xy 184.21478 -311.756191) (xy 184.262999 -311.746347)
			(xy 184.312174 -311.744366) (xy 184.361029 -311.750298) (xy 184.4083 -311.76399) (xy 184.452762 -311.785088)
			(xy 184.493265 -311.813044) (xy 184.528758 -311.847136) (xy 184.558323 -311.88648) (xy 184.581194 -311.930057)
			(xy 184.596778 -311.976738) (xy 184.604673 -312.025315) (xy 184.605168 -312.049922) (xy 185.89423 -312.049922)
			(xy 185.89819 -312.000868) (xy 185.909967 -311.953084) (xy 185.929258 -311.907808) (xy 185.955561 -311.866212)
			(xy 185.988196 -311.829375) (xy 186.026317 -311.79825) (xy 186.068938 -311.773643) (xy 186.114954 -311.756191)
			(xy 186.163173 -311.746347) (xy 186.212348 -311.744366) (xy 186.261203 -311.750298) (xy 186.308474 -311.76399)
			(xy 186.352936 -311.785088) (xy 186.393439 -311.813044) (xy 186.428932 -311.847136) (xy 186.458497 -311.88648)
			(xy 186.481368 -311.930057) (xy 186.496952 -311.976738) (xy 186.504847 -312.025315) (xy 186.505342 -312.049922)
			(xy 187.79415 -312.049922) (xy 187.79811 -312.000868) (xy 187.809887 -311.953084) (xy 187.829178 -311.907808)
			(xy 187.855481 -311.866212) (xy 187.888116 -311.829375) (xy 187.926237 -311.79825) (xy 187.968858 -311.773643)
			(xy 188.014874 -311.756191) (xy 188.063093 -311.746347) (xy 188.112268 -311.744366) (xy 188.161123 -311.750298)
			(xy 188.208394 -311.76399) (xy 188.252856 -311.785088) (xy 188.293359 -311.813044) (xy 188.328852 -311.847136)
			(xy 188.358417 -311.88648) (xy 188.381288 -311.930057) (xy 188.396872 -311.976738) (xy 188.404767 -312.025315)
			(xy 188.405262 -312.049922) (xy 189.69407 -312.049922) (xy 189.69803 -312.000868) (xy 189.709807 -311.953084)
			(xy 189.729098 -311.907808) (xy 189.755401 -311.866212) (xy 189.788036 -311.829375) (xy 189.826157 -311.79825)
			(xy 189.868778 -311.773643) (xy 189.914794 -311.756191) (xy 189.963013 -311.746347) (xy 190.012188 -311.744366)
			(xy 190.061043 -311.750298) (xy 190.108314 -311.76399) (xy 190.152776 -311.785088) (xy 190.193279 -311.813044)
			(xy 190.228772 -311.847136) (xy 190.258337 -311.88648) (xy 190.281208 -311.930057) (xy 190.296792 -311.976738)
			(xy 190.304687 -312.025315) (xy 190.305182 -312.049922) (xy 191.594244 -312.049922) (xy 191.598204 -312.000868)
			(xy 191.609981 -311.953084) (xy 191.629272 -311.907808) (xy 191.655575 -311.866212) (xy 191.68821 -311.829375)
			(xy 191.726331 -311.79825) (xy 191.768952 -311.773643) (xy 191.814968 -311.756191) (xy 191.863187 -311.746347)
			(xy 191.912362 -311.744366) (xy 191.961217 -311.750298) (xy 192.008488 -311.76399) (xy 192.05295 -311.785088)
			(xy 192.093453 -311.813044) (xy 192.128946 -311.847136) (xy 192.158511 -311.88648) (xy 192.181382 -311.930057)
			(xy 192.196966 -311.976738) (xy 192.204861 -312.025315) (xy 192.205356 -312.049922) (xy 193.494164 -312.049922)
			(xy 193.498124 -312.000868) (xy 193.509901 -311.953084) (xy 193.529192 -311.907808) (xy 193.555495 -311.866212)
			(xy 193.58813 -311.829375) (xy 193.626251 -311.79825) (xy 193.668872 -311.773643) (xy 193.714888 -311.756191)
			(xy 193.763107 -311.746347) (xy 193.812282 -311.744366) (xy 193.861137 -311.750298) (xy 193.908408 -311.76399)
			(xy 193.95287 -311.785088) (xy 193.993373 -311.813044) (xy 194.028866 -311.847136) (xy 194.058431 -311.88648)
			(xy 194.081302 -311.930057) (xy 194.096886 -311.976738) (xy 194.104781 -312.025315) (xy 194.105276 -312.049922)
			(xy 195.394084 -312.049922) (xy 195.398044 -312.000868) (xy 195.409821 -311.953084) (xy 195.429112 -311.907808)
			(xy 195.455415 -311.866212) (xy 195.48805 -311.829375) (xy 195.526171 -311.79825) (xy 195.568792 -311.773643)
			(xy 195.614808 -311.756191) (xy 195.663027 -311.746347) (xy 195.712202 -311.744366) (xy 195.761057 -311.750298)
			(xy 195.808328 -311.76399) (xy 195.85279 -311.785088) (xy 195.893293 -311.813044) (xy 195.928786 -311.847136)
			(xy 195.958351 -311.88648) (xy 195.981222 -311.930057) (xy 195.996806 -311.976738) (xy 196.004701 -312.025315)
			(xy 196.005196 -312.049922) (xy 197.294258 -312.049922) (xy 197.298218 -312.000868) (xy 197.309995 -311.953084)
			(xy 197.329286 -311.907808) (xy 197.355589 -311.866212) (xy 197.388224 -311.829375) (xy 197.426345 -311.79825)
			(xy 197.468966 -311.773643) (xy 197.514982 -311.756191) (xy 197.563201 -311.746347) (xy 197.612376 -311.744366)
			(xy 197.661231 -311.750298) (xy 197.708502 -311.76399) (xy 197.752964 -311.785088) (xy 197.793467 -311.813044)
			(xy 197.82896 -311.847136) (xy 197.858525 -311.88648) (xy 197.881396 -311.930057) (xy 197.89698 -311.976738)
			(xy 197.904875 -312.025315) (xy 197.90537 -312.049922) (xy 198.244218 -312.049922) (xy 198.248178 -312.000868)
			(xy 198.259955 -311.953084) (xy 198.279246 -311.907808) (xy 198.305549 -311.866212) (xy 198.338184 -311.829375)
			(xy 198.376305 -311.79825) (xy 198.418926 -311.773643) (xy 198.464942 -311.756191) (xy 198.513161 -311.746347)
			(xy 198.562336 -311.744366) (xy 198.611191 -311.750298) (xy 198.658462 -311.76399) (xy 198.702924 -311.785088)
			(xy 198.743427 -311.813044) (xy 198.77892 -311.847136) (xy 198.808485 -311.88648) (xy 198.831356 -311.930057)
			(xy 198.84694 -311.976738) (xy 198.854835 -312.025315) (xy 198.85533 -312.049922) (xy 268.74395 -312.049922)
			(xy 268.74791 -312.000868) (xy 268.759687 -311.953084) (xy 268.778978 -311.907808) (xy 268.805281 -311.866212)
			(xy 268.837916 -311.829375) (xy 268.876037 -311.79825) (xy 268.918658 -311.773643) (xy 268.964674 -311.756191)
			(xy 269.012893 -311.746347) (xy 269.062068 -311.744366) (xy 269.110923 -311.750298) (xy 269.158194 -311.76399)
			(xy 269.202656 -311.785088) (xy 269.243159 -311.813044) (xy 269.278652 -311.847136) (xy 269.308217 -311.88648)
			(xy 269.331088 -311.930057) (xy 269.346672 -311.976738) (xy 269.354567 -312.025315) (xy 269.355062 -312.049922)
			(xy 269.69391 -312.049922) (xy 269.69787 -312.000868) (xy 269.709647 -311.953084) (xy 269.728938 -311.907808)
			(xy 269.755241 -311.866212) (xy 269.787876 -311.829375) (xy 269.825997 -311.79825) (xy 269.868618 -311.773643)
			(xy 269.914634 -311.756191) (xy 269.962853 -311.746347) (xy 270.012028 -311.744366) (xy 270.060883 -311.750298)
			(xy 270.108154 -311.76399) (xy 270.152616 -311.785088) (xy 270.193119 -311.813044) (xy 270.228612 -311.847136)
			(xy 270.258177 -311.88648) (xy 270.281048 -311.930057) (xy 270.296632 -311.976738) (xy 270.304527 -312.025315)
			(xy 270.305022 -312.049922) (xy 271.594084 -312.049922) (xy 271.598044 -312.000868) (xy 271.609821 -311.953084)
			(xy 271.629112 -311.907808) (xy 271.655415 -311.866212) (xy 271.68805 -311.829375) (xy 271.726171 -311.79825)
			(xy 271.768792 -311.773643) (xy 271.814808 -311.756191) (xy 271.863027 -311.746347) (xy 271.912202 -311.744366)
			(xy 271.961057 -311.750298) (xy 272.008328 -311.76399) (xy 272.05279 -311.785088) (xy 272.093293 -311.813044)
			(xy 272.128786 -311.847136) (xy 272.158351 -311.88648) (xy 272.181222 -311.930057) (xy 272.196806 -311.976738)
			(xy 272.204701 -312.025315) (xy 272.205196 -312.049922) (xy 273.494004 -312.049922) (xy 273.497964 -312.000868)
			(xy 273.509741 -311.953084) (xy 273.529032 -311.907808) (xy 273.555335 -311.866212) (xy 273.58797 -311.829375)
			(xy 273.626091 -311.79825) (xy 273.668712 -311.773643) (xy 273.714728 -311.756191) (xy 273.762947 -311.746347)
			(xy 273.812122 -311.744366) (xy 273.860977 -311.750298) (xy 273.908248 -311.76399) (xy 273.95271 -311.785088)
			(xy 273.993213 -311.813044) (xy 274.028706 -311.847136) (xy 274.058271 -311.88648) (xy 274.081142 -311.930057)
			(xy 274.096726 -311.976738) (xy 274.104621 -312.025315) (xy 274.105116 -312.049922) (xy 275.393924 -312.049922)
			(xy 275.397884 -312.000868) (xy 275.409661 -311.953084) (xy 275.428952 -311.907808) (xy 275.455255 -311.866212)
			(xy 275.48789 -311.829375) (xy 275.526011 -311.79825) (xy 275.568632 -311.773643) (xy 275.614648 -311.756191)
			(xy 275.662867 -311.746347) (xy 275.712042 -311.744366) (xy 275.760897 -311.750298) (xy 275.808168 -311.76399)
			(xy 275.85263 -311.785088) (xy 275.893133 -311.813044) (xy 275.928626 -311.847136) (xy 275.958191 -311.88648)
			(xy 275.981062 -311.930057) (xy 275.996646 -311.976738) (xy 276.004541 -312.025315) (xy 276.005036 -312.049922)
			(xy 277.294098 -312.049922) (xy 277.298058 -312.000868) (xy 277.309835 -311.953084) (xy 277.329126 -311.907808)
			(xy 277.355429 -311.866212) (xy 277.388064 -311.829375) (xy 277.426185 -311.79825) (xy 277.468806 -311.773643)
			(xy 277.514822 -311.756191) (xy 277.563041 -311.746347) (xy 277.612216 -311.744366) (xy 277.661071 -311.750298)
			(xy 277.708342 -311.76399) (xy 277.752804 -311.785088) (xy 277.793307 -311.813044) (xy 277.8288 -311.847136)
			(xy 277.858365 -311.88648) (xy 277.881236 -311.930057) (xy 277.89682 -311.976738) (xy 277.904715 -312.025315)
			(xy 277.90521 -312.049922) (xy 279.194018 -312.049922) (xy 279.197978 -312.000868) (xy 279.209755 -311.953084)
			(xy 279.229046 -311.907808) (xy 279.255349 -311.866212) (xy 279.287984 -311.829375) (xy 279.326105 -311.79825)
			(xy 279.368726 -311.773643) (xy 279.414742 -311.756191) (xy 279.462961 -311.746347) (xy 279.512136 -311.744366)
			(xy 279.560991 -311.750298) (xy 279.608262 -311.76399) (xy 279.652724 -311.785088) (xy 279.693227 -311.813044)
			(xy 279.72872 -311.847136) (xy 279.758285 -311.88648) (xy 279.781156 -311.930057) (xy 279.79674 -311.976738)
			(xy 279.804635 -312.025315) (xy 279.80513 -312.049922) (xy 281.093938 -312.049922) (xy 281.097898 -312.000868)
			(xy 281.109675 -311.953084) (xy 281.128966 -311.907808) (xy 281.155269 -311.866212) (xy 281.187904 -311.829375)
			(xy 281.226025 -311.79825) (xy 281.268646 -311.773643) (xy 281.314662 -311.756191) (xy 281.362881 -311.746347)
			(xy 281.412056 -311.744366) (xy 281.460911 -311.750298) (xy 281.508182 -311.76399) (xy 281.552644 -311.785088)
			(xy 281.593147 -311.813044) (xy 281.62864 -311.847136) (xy 281.658205 -311.88648) (xy 281.681076 -311.930057)
			(xy 281.69666 -311.976738) (xy 281.704555 -312.025315) (xy 281.70505 -312.049922) (xy 282.994112 -312.049922)
			(xy 282.998072 -312.000868) (xy 283.009849 -311.953084) (xy 283.02914 -311.907808) (xy 283.055443 -311.866212)
			(xy 283.088078 -311.829375) (xy 283.126199 -311.79825) (xy 283.16882 -311.773643) (xy 283.214836 -311.756191)
			(xy 283.263055 -311.746347) (xy 283.31223 -311.744366) (xy 283.361085 -311.750298) (xy 283.408356 -311.76399)
			(xy 283.452818 -311.785088) (xy 283.493321 -311.813044) (xy 283.528814 -311.847136) (xy 283.558379 -311.88648)
			(xy 283.58125 -311.930057) (xy 283.596834 -311.976738) (xy 283.604729 -312.025315) (xy 283.605224 -312.049922)
			(xy 284.894032 -312.049922) (xy 284.897992 -312.000868) (xy 284.909769 -311.953084) (xy 284.92906 -311.907808)
			(xy 284.955363 -311.866212) (xy 284.987998 -311.829375) (xy 285.026119 -311.79825) (xy 285.06874 -311.773643)
			(xy 285.114756 -311.756191) (xy 285.162975 -311.746347) (xy 285.21215 -311.744366) (xy 285.261005 -311.750298)
			(xy 285.308276 -311.76399) (xy 285.352738 -311.785088) (xy 285.393241 -311.813044) (xy 285.428734 -311.847136)
			(xy 285.458299 -311.88648) (xy 285.48117 -311.930057) (xy 285.496754 -311.976738) (xy 285.504649 -312.025315)
			(xy 285.505144 -312.049922) (xy 286.793952 -312.049922) (xy 286.797912 -312.000868) (xy 286.809689 -311.953084)
			(xy 286.82898 -311.907808) (xy 286.855283 -311.866212) (xy 286.887918 -311.829375) (xy 286.926039 -311.79825)
			(xy 286.96866 -311.773643) (xy 287.014676 -311.756191) (xy 287.062895 -311.746347) (xy 287.11207 -311.744366)
			(xy 287.160925 -311.750298) (xy 287.208196 -311.76399) (xy 287.252658 -311.785088) (xy 287.293161 -311.813044)
			(xy 287.328654 -311.847136) (xy 287.358219 -311.88648) (xy 287.38109 -311.930057) (xy 287.396674 -311.976738)
			(xy 287.404569 -312.025315) (xy 287.405064 -312.049922) (xy 288.694126 -312.049922) (xy 288.698086 -312.000868)
			(xy 288.709863 -311.953084) (xy 288.729154 -311.907808) (xy 288.755457 -311.866212) (xy 288.788092 -311.829375)
			(xy 288.826213 -311.79825) (xy 288.868834 -311.773643) (xy 288.91485 -311.756191) (xy 288.963069 -311.746347)
			(xy 289.012244 -311.744366) (xy 289.061099 -311.750298) (xy 289.10837 -311.76399) (xy 289.152832 -311.785088)
			(xy 289.193335 -311.813044) (xy 289.228828 -311.847136) (xy 289.258393 -311.88648) (xy 289.281264 -311.930057)
			(xy 289.296848 -311.976738) (xy 289.304743 -312.025315) (xy 289.305238 -312.049922) (xy 290.594046 -312.049922)
			(xy 290.598006 -312.000868) (xy 290.609783 -311.953084) (xy 290.629074 -311.907808) (xy 290.655377 -311.866212)
			(xy 290.688012 -311.829375) (xy 290.726133 -311.79825) (xy 290.768754 -311.773643) (xy 290.81477 -311.756191)
			(xy 290.862989 -311.746347) (xy 290.912164 -311.744366) (xy 290.961019 -311.750298) (xy 291.00829 -311.76399)
			(xy 291.052752 -311.785088) (xy 291.093255 -311.813044) (xy 291.128748 -311.847136) (xy 291.158313 -311.88648)
			(xy 291.181184 -311.930057) (xy 291.196768 -311.976738) (xy 291.204663 -312.025315) (xy 291.205158 -312.049922)
			(xy 292.493966 -312.049922) (xy 292.497926 -312.000868) (xy 292.509703 -311.953084) (xy 292.528994 -311.907808)
			(xy 292.555297 -311.866212) (xy 292.587932 -311.829375) (xy 292.626053 -311.79825) (xy 292.668674 -311.773643)
			(xy 292.71469 -311.756191) (xy 292.762909 -311.746347) (xy 292.812084 -311.744366) (xy 292.860939 -311.750298)
			(xy 292.90821 -311.76399) (xy 292.952672 -311.785088) (xy 292.993175 -311.813044) (xy 293.028668 -311.847136)
			(xy 293.058233 -311.88648) (xy 293.081104 -311.930057) (xy 293.096688 -311.976738) (xy 293.104583 -312.025315)
			(xy 293.105078 -312.049922) (xy 294.393886 -312.049922) (xy 294.397846 -312.000868) (xy 294.409623 -311.953084)
			(xy 294.428914 -311.907808) (xy 294.455217 -311.866212) (xy 294.487852 -311.829375) (xy 294.525973 -311.79825)
			(xy 294.568594 -311.773643) (xy 294.61461 -311.756191) (xy 294.662829 -311.746347) (xy 294.712004 -311.744366)
			(xy 294.760859 -311.750298) (xy 294.80813 -311.76399) (xy 294.852592 -311.785088) (xy 294.893095 -311.813044)
			(xy 294.928588 -311.847136) (xy 294.958153 -311.88648) (xy 294.981024 -311.930057) (xy 294.996608 -311.976738)
			(xy 295.004503 -312.025315) (xy 295.004998 -312.049922) (xy 296.29406 -312.049922) (xy 296.29802 -312.000868)
			(xy 296.309797 -311.953084) (xy 296.329088 -311.907808) (xy 296.355391 -311.866212) (xy 296.388026 -311.829375)
			(xy 296.426147 -311.79825) (xy 296.468768 -311.773643) (xy 296.514784 -311.756191) (xy 296.563003 -311.746347)
			(xy 296.612178 -311.744366) (xy 296.661033 -311.750298) (xy 296.708304 -311.76399) (xy 296.752766 -311.785088)
			(xy 296.793269 -311.813044) (xy 296.828762 -311.847136) (xy 296.858327 -311.88648) (xy 296.881198 -311.930057)
			(xy 296.896782 -311.976738) (xy 296.904677 -312.025315) (xy 296.905172 -312.049922) (xy 298.19398 -312.049922)
			(xy 298.19794 -312.000868) (xy 298.209717 -311.953084) (xy 298.229008 -311.907808) (xy 298.255311 -311.866212)
			(xy 298.287946 -311.829375) (xy 298.326067 -311.79825) (xy 298.368688 -311.773643) (xy 298.414704 -311.756191)
			(xy 298.462923 -311.746347) (xy 298.512098 -311.744366) (xy 298.560953 -311.750298) (xy 298.608224 -311.76399)
			(xy 298.652686 -311.785088) (xy 298.693189 -311.813044) (xy 298.728682 -311.847136) (xy 298.758247 -311.88648)
			(xy 298.781118 -311.930057) (xy 298.796702 -311.976738) (xy 298.804597 -312.025315) (xy 298.805092 -312.049922)
			(xy 300.0939 -312.049922) (xy 300.09786 -312.000868) (xy 300.109637 -311.953084) (xy 300.128928 -311.907808)
			(xy 300.155231 -311.866212) (xy 300.187866 -311.829375) (xy 300.225987 -311.79825) (xy 300.268608 -311.773643)
			(xy 300.314624 -311.756191) (xy 300.362843 -311.746347) (xy 300.412018 -311.744366) (xy 300.460873 -311.750298)
			(xy 300.508144 -311.76399) (xy 300.552606 -311.785088) (xy 300.593109 -311.813044) (xy 300.628602 -311.847136)
			(xy 300.658167 -311.88648) (xy 300.681038 -311.930057) (xy 300.696622 -311.976738) (xy 300.704517 -312.025315)
			(xy 300.705012 -312.049922) (xy 301.994074 -312.049922) (xy 301.998034 -312.000868) (xy 302.009811 -311.953084)
			(xy 302.029102 -311.907808) (xy 302.055405 -311.866212) (xy 302.08804 -311.829375) (xy 302.126161 -311.79825)
			(xy 302.168782 -311.773643) (xy 302.214798 -311.756191) (xy 302.263017 -311.746347) (xy 302.312192 -311.744366)
			(xy 302.361047 -311.750298) (xy 302.408318 -311.76399) (xy 302.45278 -311.785088) (xy 302.493283 -311.813044)
			(xy 302.528776 -311.847136) (xy 302.558341 -311.88648) (xy 302.581212 -311.930057) (xy 302.596796 -311.976738)
			(xy 302.604691 -312.025315) (xy 302.605186 -312.049922) (xy 303.893994 -312.049922) (xy 303.897954 -312.000868)
			(xy 303.909731 -311.953084) (xy 303.929022 -311.907808) (xy 303.955325 -311.866212) (xy 303.98796 -311.829375)
			(xy 304.026081 -311.79825) (xy 304.068702 -311.773643) (xy 304.114718 -311.756191) (xy 304.162937 -311.746347)
			(xy 304.212112 -311.744366) (xy 304.260967 -311.750298) (xy 304.308238 -311.76399) (xy 304.3527 -311.785088)
			(xy 304.393203 -311.813044) (xy 304.428696 -311.847136) (xy 304.458261 -311.88648) (xy 304.481132 -311.930057)
			(xy 304.496716 -311.976738) (xy 304.504611 -312.025315) (xy 304.505106 -312.049922) (xy 305.793914 -312.049922)
			(xy 305.797874 -312.000868) (xy 305.809651 -311.953084) (xy 305.828942 -311.907808) (xy 305.855245 -311.866212)
			(xy 305.88788 -311.829375) (xy 305.926001 -311.79825) (xy 305.968622 -311.773643) (xy 306.014638 -311.756191)
			(xy 306.062857 -311.746347) (xy 306.112032 -311.744366) (xy 306.160887 -311.750298) (xy 306.208158 -311.76399)
			(xy 306.25262 -311.785088) (xy 306.293123 -311.813044) (xy 306.328616 -311.847136) (xy 306.358181 -311.88648)
			(xy 306.381052 -311.930057) (xy 306.396636 -311.976738) (xy 306.404531 -312.025315) (xy 306.405026 -312.049922)
			(xy 307.694088 -312.049922) (xy 307.698048 -312.000868) (xy 307.709825 -311.953084) (xy 307.729116 -311.907808)
			(xy 307.755419 -311.866212) (xy 307.788054 -311.829375) (xy 307.826175 -311.79825) (xy 307.868796 -311.773643)
			(xy 307.914812 -311.756191) (xy 307.963031 -311.746347) (xy 308.012206 -311.744366) (xy 308.061061 -311.750298)
			(xy 308.108332 -311.76399) (xy 308.152794 -311.785088) (xy 308.193297 -311.813044) (xy 308.22879 -311.847136)
			(xy 308.258355 -311.88648) (xy 308.281226 -311.930057) (xy 308.29681 -311.976738) (xy 308.304705 -312.025315)
			(xy 308.3052 -312.049922) (xy 309.594008 -312.049922) (xy 309.597968 -312.000868) (xy 309.609745 -311.953084)
			(xy 309.629036 -311.907808) (xy 309.655339 -311.866212) (xy 309.687974 -311.829375) (xy 309.726095 -311.79825)
			(xy 309.768716 -311.773643) (xy 309.814732 -311.756191) (xy 309.862951 -311.746347) (xy 309.912126 -311.744366)
			(xy 309.960981 -311.750298) (xy 310.008252 -311.76399) (xy 310.052714 -311.785088) (xy 310.093217 -311.813044)
			(xy 310.12871 -311.847136) (xy 310.158275 -311.88648) (xy 310.181146 -311.930057) (xy 310.19673 -311.976738)
			(xy 310.204625 -312.025315) (xy 310.20512 -312.049922) (xy 311.493928 -312.049922) (xy 311.497888 -312.000868)
			(xy 311.509665 -311.953084) (xy 311.528956 -311.907808) (xy 311.555259 -311.866212) (xy 311.587894 -311.829375)
			(xy 311.626015 -311.79825) (xy 311.668636 -311.773643) (xy 311.714652 -311.756191) (xy 311.762871 -311.746347)
			(xy 311.812046 -311.744366) (xy 311.860901 -311.750298) (xy 311.908172 -311.76399) (xy 311.952634 -311.785088)
			(xy 311.993137 -311.813044) (xy 312.02863 -311.847136) (xy 312.058195 -311.88648) (xy 312.081066 -311.930057)
			(xy 312.09665 -311.976738) (xy 312.104545 -312.025315) (xy 312.10504 -312.049922) (xy 313.394102 -312.049922)
			(xy 313.398062 -312.000868) (xy 313.409839 -311.953084) (xy 313.42913 -311.907808) (xy 313.455433 -311.866212)
			(xy 313.488068 -311.829375) (xy 313.526189 -311.79825) (xy 313.56881 -311.773643) (xy 313.614826 -311.756191)
			(xy 313.663045 -311.746347) (xy 313.71222 -311.744366) (xy 313.761075 -311.750298) (xy 313.808346 -311.76399)
			(xy 313.852808 -311.785088) (xy 313.893311 -311.813044) (xy 313.928804 -311.847136) (xy 313.958369 -311.88648)
			(xy 313.98124 -311.930057) (xy 313.996824 -311.976738) (xy 314.004719 -312.025315) (xy 314.005214 -312.049922)
			(xy 314.344062 -312.049922) (xy 314.348022 -312.000868) (xy 314.359799 -311.953084) (xy 314.37909 -311.907808)
			(xy 314.405393 -311.866212) (xy 314.438028 -311.829375) (xy 314.476149 -311.79825) (xy 314.51877 -311.773643)
			(xy 314.564786 -311.756191) (xy 314.613005 -311.746347) (xy 314.66218 -311.744366) (xy 314.711035 -311.750298)
			(xy 314.758306 -311.76399) (xy 314.802768 -311.785088) (xy 314.843271 -311.813044) (xy 314.878764 -311.847136)
			(xy 314.908329 -311.88648) (xy 314.9312 -311.930057) (xy 314.946784 -311.976738) (xy 314.954679 -312.025315)
			(xy 314.955174 -312.049922) (xy 384.844048 -312.049922) (xy 384.848008 -312.000868) (xy 384.859785 -311.953084)
			(xy 384.879076 -311.907808) (xy 384.905379 -311.866212) (xy 384.938014 -311.829375) (xy 384.976135 -311.79825)
			(xy 385.018756 -311.773643) (xy 385.064772 -311.756191) (xy 385.112991 -311.746347) (xy 385.162166 -311.744366)
			(xy 385.211021 -311.750298) (xy 385.258292 -311.76399) (xy 385.302754 -311.785088) (xy 385.343257 -311.813044)
			(xy 385.37875 -311.847136) (xy 385.408315 -311.88648) (xy 385.431186 -311.930057) (xy 385.44677 -311.976738)
			(xy 385.454665 -312.025315) (xy 385.45516 -312.049922) (xy 385.794008 -312.049922) (xy 385.797968 -312.000868)
			(xy 385.809745 -311.953084) (xy 385.829036 -311.907808) (xy 385.855339 -311.866212) (xy 385.887974 -311.829375)
			(xy 385.926095 -311.79825) (xy 385.968716 -311.773643) (xy 386.014732 -311.756191) (xy 386.062951 -311.746347)
			(xy 386.112126 -311.744366) (xy 386.160981 -311.750298) (xy 386.208252 -311.76399) (xy 386.252714 -311.785088)
			(xy 386.293217 -311.813044) (xy 386.32871 -311.847136) (xy 386.358275 -311.88648) (xy 386.381146 -311.930057)
			(xy 386.39673 -311.976738) (xy 386.404625 -312.025315) (xy 386.40512 -312.049922) (xy 387.694182 -312.049922)
			(xy 387.698142 -312.000868) (xy 387.709919 -311.953084) (xy 387.72921 -311.907808) (xy 387.755513 -311.866212)
			(xy 387.788148 -311.829375) (xy 387.826269 -311.79825) (xy 387.86889 -311.773643) (xy 387.914906 -311.756191)
			(xy 387.963125 -311.746347) (xy 388.0123 -311.744366) (xy 388.061155 -311.750298) (xy 388.108426 -311.76399)
			(xy 388.152888 -311.785088) (xy 388.193391 -311.813044) (xy 388.228884 -311.847136) (xy 388.258449 -311.88648)
			(xy 388.28132 -311.930057) (xy 388.296904 -311.976738) (xy 388.304799 -312.025315) (xy 388.305294 -312.049922)
			(xy 389.594102 -312.049922) (xy 389.598062 -312.000868) (xy 389.609839 -311.953084) (xy 389.62913 -311.907808)
			(xy 389.655433 -311.866212) (xy 389.688068 -311.829375) (xy 389.726189 -311.79825) (xy 389.76881 -311.773643)
			(xy 389.814826 -311.756191) (xy 389.863045 -311.746347) (xy 389.91222 -311.744366) (xy 389.961075 -311.750298)
			(xy 390.008346 -311.76399) (xy 390.052808 -311.785088) (xy 390.093311 -311.813044) (xy 390.128804 -311.847136)
			(xy 390.158369 -311.88648) (xy 390.18124 -311.930057) (xy 390.196824 -311.976738) (xy 390.204719 -312.025315)
			(xy 390.205214 -312.049922) (xy 391.494022 -312.049922) (xy 391.497982 -312.000868) (xy 391.509759 -311.953084)
			(xy 391.52905 -311.907808) (xy 391.555353 -311.866212) (xy 391.587988 -311.829375) (xy 391.626109 -311.79825)
			(xy 391.66873 -311.773643) (xy 391.714746 -311.756191) (xy 391.762965 -311.746347) (xy 391.81214 -311.744366)
			(xy 391.860995 -311.750298) (xy 391.908266 -311.76399) (xy 391.952728 -311.785088) (xy 391.993231 -311.813044)
			(xy 392.028724 -311.847136) (xy 392.058289 -311.88648) (xy 392.08116 -311.930057) (xy 392.096744 -311.976738)
			(xy 392.104639 -312.025315) (xy 392.105134 -312.049922) (xy 393.394196 -312.049922) (xy 393.398156 -312.000868)
			(xy 393.409933 -311.953084) (xy 393.429224 -311.907808) (xy 393.455527 -311.866212) (xy 393.488162 -311.829375)
			(xy 393.526283 -311.79825) (xy 393.568904 -311.773643) (xy 393.61492 -311.756191) (xy 393.663139 -311.746347)
			(xy 393.712314 -311.744366) (xy 393.761169 -311.750298) (xy 393.80844 -311.76399) (xy 393.852902 -311.785088)
			(xy 393.893405 -311.813044) (xy 393.928898 -311.847136) (xy 393.958463 -311.88648) (xy 393.981334 -311.930057)
			(xy 393.996918 -311.976738) (xy 394.004813 -312.025315) (xy 394.005308 -312.049922) (xy 395.294116 -312.049922)
			(xy 395.298076 -312.000868) (xy 395.309853 -311.953084) (xy 395.329144 -311.907808) (xy 395.355447 -311.866212)
			(xy 395.388082 -311.829375) (xy 395.426203 -311.79825) (xy 395.468824 -311.773643) (xy 395.51484 -311.756191)
			(xy 395.563059 -311.746347) (xy 395.612234 -311.744366) (xy 395.661089 -311.750298) (xy 395.70836 -311.76399)
			(xy 395.752822 -311.785088) (xy 395.793325 -311.813044) (xy 395.828818 -311.847136) (xy 395.858383 -311.88648)
			(xy 395.881254 -311.930057) (xy 395.896838 -311.976738) (xy 395.904733 -312.025315) (xy 395.905228 -312.049922)
			(xy 397.194036 -312.049922) (xy 397.197996 -312.000868) (xy 397.209773 -311.953084) (xy 397.229064 -311.907808)
			(xy 397.255367 -311.866212) (xy 397.288002 -311.829375) (xy 397.326123 -311.79825) (xy 397.368744 -311.773643)
			(xy 397.41476 -311.756191) (xy 397.462979 -311.746347) (xy 397.512154 -311.744366) (xy 397.561009 -311.750298)
			(xy 397.60828 -311.76399) (xy 397.652742 -311.785088) (xy 397.693245 -311.813044) (xy 397.728738 -311.847136)
			(xy 397.758303 -311.88648) (xy 397.781174 -311.930057) (xy 397.796758 -311.976738) (xy 397.804653 -312.025315)
			(xy 397.805148 -312.049922) (xy 399.09421 -312.049922) (xy 399.09817 -312.000868) (xy 399.109947 -311.953084)
			(xy 399.129238 -311.907808) (xy 399.155541 -311.866212) (xy 399.188176 -311.829375) (xy 399.226297 -311.79825)
			(xy 399.268918 -311.773643) (xy 399.314934 -311.756191) (xy 399.363153 -311.746347) (xy 399.412328 -311.744366)
			(xy 399.461183 -311.750298) (xy 399.508454 -311.76399) (xy 399.552916 -311.785088) (xy 399.593419 -311.813044)
			(xy 399.628912 -311.847136) (xy 399.658477 -311.88648) (xy 399.681348 -311.930057) (xy 399.696932 -311.976738)
			(xy 399.704827 -312.025315) (xy 399.705322 -312.049922) (xy 400.99413 -312.049922) (xy 400.99809 -312.000868)
			(xy 401.009867 -311.953084) (xy 401.029158 -311.907808) (xy 401.055461 -311.866212) (xy 401.088096 -311.829375)
			(xy 401.126217 -311.79825) (xy 401.168838 -311.773643) (xy 401.214854 -311.756191) (xy 401.263073 -311.746347)
			(xy 401.312248 -311.744366) (xy 401.361103 -311.750298) (xy 401.408374 -311.76399) (xy 401.452836 -311.785088)
			(xy 401.493339 -311.813044) (xy 401.528832 -311.847136) (xy 401.558397 -311.88648) (xy 401.581268 -311.930057)
			(xy 401.596852 -311.976738) (xy 401.604747 -312.025315) (xy 401.605242 -312.049922) (xy 402.89405 -312.049922)
			(xy 402.89801 -312.000868) (xy 402.909787 -311.953084) (xy 402.929078 -311.907808) (xy 402.955381 -311.866212)
			(xy 402.988016 -311.829375) (xy 403.026137 -311.79825) (xy 403.068758 -311.773643) (xy 403.114774 -311.756191)
			(xy 403.162993 -311.746347) (xy 403.212168 -311.744366) (xy 403.261023 -311.750298) (xy 403.308294 -311.76399)
			(xy 403.352756 -311.785088) (xy 403.393259 -311.813044) (xy 403.428752 -311.847136) (xy 403.458317 -311.88648)
			(xy 403.481188 -311.930057) (xy 403.496772 -311.976738) (xy 403.504667 -312.025315) (xy 403.505162 -312.049922)
			(xy 404.794224 -312.049922) (xy 404.798184 -312.000868) (xy 404.809961 -311.953084) (xy 404.829252 -311.907808)
			(xy 404.855555 -311.866212) (xy 404.88819 -311.829375) (xy 404.926311 -311.79825) (xy 404.968932 -311.773643)
			(xy 405.014948 -311.756191) (xy 405.063167 -311.746347) (xy 405.112342 -311.744366) (xy 405.161197 -311.750298)
			(xy 405.208468 -311.76399) (xy 405.25293 -311.785088) (xy 405.293433 -311.813044) (xy 405.328926 -311.847136)
			(xy 405.358491 -311.88648) (xy 405.381362 -311.930057) (xy 405.396946 -311.976738) (xy 405.404841 -312.025315)
			(xy 405.405336 -312.049922) (xy 406.694144 -312.049922) (xy 406.698104 -312.000868) (xy 406.709881 -311.953084)
			(xy 406.729172 -311.907808) (xy 406.755475 -311.866212) (xy 406.78811 -311.829375) (xy 406.826231 -311.79825)
			(xy 406.868852 -311.773643) (xy 406.914868 -311.756191) (xy 406.963087 -311.746347) (xy 407.012262 -311.744366)
			(xy 407.061117 -311.750298) (xy 407.108388 -311.76399) (xy 407.15285 -311.785088) (xy 407.193353 -311.813044)
			(xy 407.228846 -311.847136) (xy 407.258411 -311.88648) (xy 407.281282 -311.930057) (xy 407.296866 -311.976738)
			(xy 407.304761 -312.025315) (xy 407.305256 -312.049922) (xy 408.594064 -312.049922) (xy 408.598024 -312.000868)
			(xy 408.609801 -311.953084) (xy 408.629092 -311.907808) (xy 408.655395 -311.866212) (xy 408.68803 -311.829375)
			(xy 408.726151 -311.79825) (xy 408.768772 -311.773643) (xy 408.814788 -311.756191) (xy 408.863007 -311.746347)
			(xy 408.912182 -311.744366) (xy 408.961037 -311.750298) (xy 409.008308 -311.76399) (xy 409.05277 -311.785088)
			(xy 409.093273 -311.813044) (xy 409.128766 -311.847136) (xy 409.158331 -311.88648) (xy 409.181202 -311.930057)
			(xy 409.196786 -311.976738) (xy 409.204681 -312.025315) (xy 409.205176 -312.049922) (xy 410.493984 -312.049922)
			(xy 410.497944 -312.000868) (xy 410.509721 -311.953084) (xy 410.529012 -311.907808) (xy 410.555315 -311.866212)
			(xy 410.58795 -311.829375) (xy 410.626071 -311.79825) (xy 410.668692 -311.773643) (xy 410.714708 -311.756191)
			(xy 410.762927 -311.746347) (xy 410.812102 -311.744366) (xy 410.860957 -311.750298) (xy 410.908228 -311.76399)
			(xy 410.95269 -311.785088) (xy 410.993193 -311.813044) (xy 411.028686 -311.847136) (xy 411.058251 -311.88648)
			(xy 411.081122 -311.930057) (xy 411.096706 -311.976738) (xy 411.104601 -312.025315) (xy 411.105096 -312.049922)
			(xy 412.394158 -312.049922) (xy 412.398118 -312.000868) (xy 412.409895 -311.953084) (xy 412.429186 -311.907808)
			(xy 412.455489 -311.866212) (xy 412.488124 -311.829375) (xy 412.526245 -311.79825) (xy 412.568866 -311.773643)
			(xy 412.614882 -311.756191) (xy 412.663101 -311.746347) (xy 412.712276 -311.744366) (xy 412.761131 -311.750298)
			(xy 412.808402 -311.76399) (xy 412.852864 -311.785088) (xy 412.893367 -311.813044) (xy 412.92886 -311.847136)
			(xy 412.958425 -311.88648) (xy 412.981296 -311.930057) (xy 412.99688 -311.976738) (xy 413.004775 -312.025315)
			(xy 413.00527 -312.049922) (xy 414.294078 -312.049922) (xy 414.298038 -312.000868) (xy 414.309815 -311.953084)
			(xy 414.329106 -311.907808) (xy 414.355409 -311.866212) (xy 414.388044 -311.829375) (xy 414.426165 -311.79825)
			(xy 414.468786 -311.773643) (xy 414.514802 -311.756191) (xy 414.563021 -311.746347) (xy 414.612196 -311.744366)
			(xy 414.661051 -311.750298) (xy 414.708322 -311.76399) (xy 414.752784 -311.785088) (xy 414.793287 -311.813044)
			(xy 414.82878 -311.847136) (xy 414.858345 -311.88648) (xy 414.881216 -311.930057) (xy 414.8968 -311.976738)
			(xy 414.904695 -312.025315) (xy 414.90519 -312.049922) (xy 416.193998 -312.049922) (xy 416.197958 -312.000868)
			(xy 416.209735 -311.953084) (xy 416.229026 -311.907808) (xy 416.255329 -311.866212) (xy 416.287964 -311.829375)
			(xy 416.326085 -311.79825) (xy 416.368706 -311.773643) (xy 416.414722 -311.756191) (xy 416.462941 -311.746347)
			(xy 416.512116 -311.744366) (xy 416.560971 -311.750298) (xy 416.608242 -311.76399) (xy 416.652704 -311.785088)
			(xy 416.693207 -311.813044) (xy 416.7287 -311.847136) (xy 416.758265 -311.88648) (xy 416.781136 -311.930057)
			(xy 416.79672 -311.976738) (xy 416.804615 -312.025315) (xy 416.80511 -312.049922) (xy 418.094172 -312.049922)
			(xy 418.098132 -312.000868) (xy 418.109909 -311.953084) (xy 418.1292 -311.907808) (xy 418.155503 -311.866212)
			(xy 418.188138 -311.829375) (xy 418.226259 -311.79825) (xy 418.26888 -311.773643) (xy 418.314896 -311.756191)
			(xy 418.363115 -311.746347) (xy 418.41229 -311.744366) (xy 418.461145 -311.750298) (xy 418.508416 -311.76399)
			(xy 418.552878 -311.785088) (xy 418.593381 -311.813044) (xy 418.628874 -311.847136) (xy 418.658439 -311.88648)
			(xy 418.68131 -311.930057) (xy 418.696894 -311.976738) (xy 418.704789 -312.025315) (xy 418.705284 -312.049922)
			(xy 419.994092 -312.049922) (xy 419.998052 -312.000868) (xy 420.009829 -311.953084) (xy 420.02912 -311.907808)
			(xy 420.055423 -311.866212) (xy 420.088058 -311.829375) (xy 420.126179 -311.79825) (xy 420.1688 -311.773643)
			(xy 420.214816 -311.756191) (xy 420.263035 -311.746347) (xy 420.31221 -311.744366) (xy 420.361065 -311.750298)
			(xy 420.408336 -311.76399) (xy 420.452798 -311.785088) (xy 420.493301 -311.813044) (xy 420.528794 -311.847136)
			(xy 420.558359 -311.88648) (xy 420.58123 -311.930057) (xy 420.596814 -311.976738) (xy 420.604709 -312.025315)
			(xy 420.605204 -312.049922) (xy 421.894012 -312.049922) (xy 421.897972 -312.000868) (xy 421.909749 -311.953084)
			(xy 421.92904 -311.907808) (xy 421.955343 -311.866212) (xy 421.987978 -311.829375) (xy 422.026099 -311.79825)
			(xy 422.06872 -311.773643) (xy 422.114736 -311.756191) (xy 422.162955 -311.746347) (xy 422.21213 -311.744366)
			(xy 422.260985 -311.750298) (xy 422.308256 -311.76399) (xy 422.352718 -311.785088) (xy 422.393221 -311.813044)
			(xy 422.428714 -311.847136) (xy 422.458279 -311.88648) (xy 422.48115 -311.930057) (xy 422.496734 -311.976738)
			(xy 422.504629 -312.025315) (xy 422.505124 -312.049922) (xy 423.794186 -312.049922) (xy 423.798146 -312.000868)
			(xy 423.809923 -311.953084) (xy 423.829214 -311.907808) (xy 423.855517 -311.866212) (xy 423.888152 -311.829375)
			(xy 423.926273 -311.79825) (xy 423.968894 -311.773643) (xy 424.01491 -311.756191) (xy 424.063129 -311.746347)
			(xy 424.112304 -311.744366) (xy 424.161159 -311.750298) (xy 424.20843 -311.76399) (xy 424.252892 -311.785088)
			(xy 424.293395 -311.813044) (xy 424.328888 -311.847136) (xy 424.358453 -311.88648) (xy 424.381324 -311.930057)
			(xy 424.396908 -311.976738) (xy 424.404803 -312.025315) (xy 424.405298 -312.049922) (xy 425.694106 -312.049922)
			(xy 425.698066 -312.000868) (xy 425.709843 -311.953084) (xy 425.729134 -311.907808) (xy 425.755437 -311.866212)
			(xy 425.788072 -311.829375) (xy 425.826193 -311.79825) (xy 425.868814 -311.773643) (xy 425.91483 -311.756191)
			(xy 425.963049 -311.746347) (xy 426.012224 -311.744366) (xy 426.061079 -311.750298) (xy 426.10835 -311.76399)
			(xy 426.152812 -311.785088) (xy 426.193315 -311.813044) (xy 426.228808 -311.847136) (xy 426.258373 -311.88648)
			(xy 426.281244 -311.930057) (xy 426.296828 -311.976738) (xy 426.304723 -312.025315) (xy 426.305218 -312.049922)
			(xy 427.594026 -312.049922) (xy 427.597986 -312.000868) (xy 427.609763 -311.953084) (xy 427.629054 -311.907808)
			(xy 427.655357 -311.866212) (xy 427.687992 -311.829375) (xy 427.726113 -311.79825) (xy 427.768734 -311.773643)
			(xy 427.81475 -311.756191) (xy 427.862969 -311.746347) (xy 427.912144 -311.744366) (xy 427.960999 -311.750298)
			(xy 428.00827 -311.76399) (xy 428.052732 -311.785088) (xy 428.093235 -311.813044) (xy 428.128728 -311.847136)
			(xy 428.158293 -311.88648) (xy 428.181164 -311.930057) (xy 428.196748 -311.976738) (xy 428.204643 -312.025315)
			(xy 428.205138 -312.049922) (xy 429.4942 -312.049922) (xy 429.49816 -312.000868) (xy 429.509937 -311.953084)
			(xy 429.529228 -311.907808) (xy 429.555531 -311.866212) (xy 429.588166 -311.829375) (xy 429.626287 -311.79825)
			(xy 429.668908 -311.773643) (xy 429.714924 -311.756191) (xy 429.763143 -311.746347) (xy 429.812318 -311.744366)
			(xy 429.861173 -311.750298) (xy 429.908444 -311.76399) (xy 429.952906 -311.785088) (xy 429.993409 -311.813044)
			(xy 430.028902 -311.847136) (xy 430.058467 -311.88648) (xy 430.081338 -311.930057) (xy 430.096922 -311.976738)
			(xy 430.104817 -312.025315) (xy 430.105312 -312.049922) (xy 430.44416 -312.049922) (xy 430.44812 -312.000868)
			(xy 430.459897 -311.953084) (xy 430.479188 -311.907808) (xy 430.505491 -311.866212) (xy 430.538126 -311.829375)
			(xy 430.576247 -311.79825) (xy 430.618868 -311.773643) (xy 430.664884 -311.756191) (xy 430.713103 -311.746347)
			(xy 430.762278 -311.744366) (xy 430.811133 -311.750298) (xy 430.858404 -311.76399) (xy 430.902866 -311.785088)
			(xy 430.943369 -311.813044) (xy 430.978862 -311.847136) (xy 431.008427 -311.88648) (xy 431.031298 -311.930057)
			(xy 431.046882 -311.976738) (xy 431.054777 -312.025315) (xy 431.055272 -312.049922) (xy 431.054777 -312.074529)
			(xy 431.046882 -312.123106) (xy 431.031298 -312.169787) (xy 431.008427 -312.213364) (xy 430.978862 -312.252708)
			(xy 430.943369 -312.2868) (xy 430.902866 -312.314756) (xy 430.858404 -312.335854) (xy 430.811133 -312.349546)
			(xy 430.762278 -312.355478) (xy 430.713103 -312.353497) (xy 430.664884 -312.343653) (xy 430.618868 -312.326201)
			(xy 430.576247 -312.301594) (xy 430.538126 -312.270469) (xy 430.505491 -312.233632) (xy 430.479188 -312.192036)
			(xy 430.459897 -312.14676) (xy 430.44812 -312.098976) (xy 430.44416 -312.049922) (xy 430.105312 -312.049922)
			(xy 430.104817 -312.074529) (xy 430.096922 -312.123106) (xy 430.081338 -312.169787) (xy 430.058467 -312.213364)
			(xy 430.028902 -312.252708) (xy 429.993409 -312.2868) (xy 429.952906 -312.314756) (xy 429.908444 -312.335854)
			(xy 429.861173 -312.349546) (xy 429.812318 -312.355478) (xy 429.763143 -312.353497) (xy 429.714924 -312.343653)
			(xy 429.668908 -312.326201) (xy 429.626287 -312.301594) (xy 429.588166 -312.270469) (xy 429.555531 -312.233632)
			(xy 429.529228 -312.192036) (xy 429.509937 -312.14676) (xy 429.49816 -312.098976) (xy 429.4942 -312.049922)
			(xy 428.205138 -312.049922) (xy 428.204643 -312.074529) (xy 428.196748 -312.123106) (xy 428.181164 -312.169787)
			(xy 428.158293 -312.213364) (xy 428.128728 -312.252708) (xy 428.093235 -312.2868) (xy 428.052732 -312.314756)
			(xy 428.00827 -312.335854) (xy 427.960999 -312.349546) (xy 427.912144 -312.355478) (xy 427.862969 -312.353497)
			(xy 427.81475 -312.343653) (xy 427.768734 -312.326201) (xy 427.726113 -312.301594) (xy 427.687992 -312.270469)
			(xy 427.655357 -312.233632) (xy 427.629054 -312.192036) (xy 427.609763 -312.14676) (xy 427.597986 -312.098976)
			(xy 427.594026 -312.049922) (xy 426.305218 -312.049922) (xy 426.304723 -312.074529) (xy 426.296828 -312.123106)
			(xy 426.281244 -312.169787) (xy 426.258373 -312.213364) (xy 426.228808 -312.252708) (xy 426.193315 -312.2868)
			(xy 426.152812 -312.314756) (xy 426.10835 -312.335854) (xy 426.061079 -312.349546) (xy 426.012224 -312.355478)
			(xy 425.963049 -312.353497) (xy 425.91483 -312.343653) (xy 425.868814 -312.326201) (xy 425.826193 -312.301594)
			(xy 425.788072 -312.270469) (xy 425.755437 -312.233632) (xy 425.729134 -312.192036) (xy 425.709843 -312.14676)
			(xy 425.698066 -312.098976) (xy 425.694106 -312.049922) (xy 424.405298 -312.049922) (xy 424.404803 -312.074529)
			(xy 424.396908 -312.123106) (xy 424.381324 -312.169787) (xy 424.358453 -312.213364) (xy 424.328888 -312.252708)
			(xy 424.293395 -312.2868) (xy 424.252892 -312.314756) (xy 424.20843 -312.335854) (xy 424.161159 -312.349546)
			(xy 424.112304 -312.355478) (xy 424.063129 -312.353497) (xy 424.01491 -312.343653) (xy 423.968894 -312.326201)
			(xy 423.926273 -312.301594) (xy 423.888152 -312.270469) (xy 423.855517 -312.233632) (xy 423.829214 -312.192036)
			(xy 423.809923 -312.14676) (xy 423.798146 -312.098976) (xy 423.794186 -312.049922) (xy 422.505124 -312.049922)
			(xy 422.504629 -312.074529) (xy 422.496734 -312.123106) (xy 422.48115 -312.169787) (xy 422.458279 -312.213364)
			(xy 422.428714 -312.252708) (xy 422.393221 -312.2868) (xy 422.352718 -312.314756) (xy 422.308256 -312.335854)
			(xy 422.260985 -312.349546) (xy 422.21213 -312.355478) (xy 422.162955 -312.353497) (xy 422.114736 -312.343653)
			(xy 422.06872 -312.326201) (xy 422.026099 -312.301594) (xy 421.987978 -312.270469) (xy 421.955343 -312.233632)
			(xy 421.92904 -312.192036) (xy 421.909749 -312.14676) (xy 421.897972 -312.098976) (xy 421.894012 -312.049922)
			(xy 420.605204 -312.049922) (xy 420.604709 -312.074529) (xy 420.596814 -312.123106) (xy 420.58123 -312.169787)
			(xy 420.558359 -312.213364) (xy 420.528794 -312.252708) (xy 420.493301 -312.2868) (xy 420.452798 -312.314756)
			(xy 420.408336 -312.335854) (xy 420.361065 -312.349546) (xy 420.31221 -312.355478) (xy 420.263035 -312.353497)
			(xy 420.214816 -312.343653) (xy 420.1688 -312.326201) (xy 420.126179 -312.301594) (xy 420.088058 -312.270469)
			(xy 420.055423 -312.233632) (xy 420.02912 -312.192036) (xy 420.009829 -312.14676) (xy 419.998052 -312.098976)
			(xy 419.994092 -312.049922) (xy 418.705284 -312.049922) (xy 418.704789 -312.074529) (xy 418.696894 -312.123106)
			(xy 418.68131 -312.169787) (xy 418.658439 -312.213364) (xy 418.628874 -312.252708) (xy 418.593381 -312.2868)
			(xy 418.552878 -312.314756) (xy 418.508416 -312.335854) (xy 418.461145 -312.349546) (xy 418.41229 -312.355478)
			(xy 418.363115 -312.353497) (xy 418.314896 -312.343653) (xy 418.26888 -312.326201) (xy 418.226259 -312.301594)
			(xy 418.188138 -312.270469) (xy 418.155503 -312.233632) (xy 418.1292 -312.192036) (xy 418.109909 -312.14676)
			(xy 418.098132 -312.098976) (xy 418.094172 -312.049922) (xy 416.80511 -312.049922) (xy 416.804615 -312.074529)
			(xy 416.79672 -312.123106) (xy 416.781136 -312.169787) (xy 416.758265 -312.213364) (xy 416.7287 -312.252708)
			(xy 416.693207 -312.2868) (xy 416.652704 -312.314756) (xy 416.608242 -312.335854) (xy 416.560971 -312.349546)
			(xy 416.512116 -312.355478) (xy 416.462941 -312.353497) (xy 416.414722 -312.343653) (xy 416.368706 -312.326201)
			(xy 416.326085 -312.301594) (xy 416.287964 -312.270469) (xy 416.255329 -312.233632) (xy 416.229026 -312.192036)
			(xy 416.209735 -312.14676) (xy 416.197958 -312.098976) (xy 416.193998 -312.049922) (xy 414.90519 -312.049922)
			(xy 414.904695 -312.074529) (xy 414.8968 -312.123106) (xy 414.881216 -312.169787) (xy 414.858345 -312.213364)
			(xy 414.82878 -312.252708) (xy 414.793287 -312.2868) (xy 414.752784 -312.314756) (xy 414.708322 -312.335854)
			(xy 414.661051 -312.349546) (xy 414.612196 -312.355478) (xy 414.563021 -312.353497) (xy 414.514802 -312.343653)
			(xy 414.468786 -312.326201) (xy 414.426165 -312.301594) (xy 414.388044 -312.270469) (xy 414.355409 -312.233632)
			(xy 414.329106 -312.192036) (xy 414.309815 -312.14676) (xy 414.298038 -312.098976) (xy 414.294078 -312.049922)
			(xy 413.00527 -312.049922) (xy 413.004775 -312.074529) (xy 412.99688 -312.123106) (xy 412.981296 -312.169787)
			(xy 412.958425 -312.213364) (xy 412.92886 -312.252708) (xy 412.893367 -312.2868) (xy 412.852864 -312.314756)
			(xy 412.808402 -312.335854) (xy 412.761131 -312.349546) (xy 412.712276 -312.355478) (xy 412.663101 -312.353497)
			(xy 412.614882 -312.343653) (xy 412.568866 -312.326201) (xy 412.526245 -312.301594) (xy 412.488124 -312.270469)
			(xy 412.455489 -312.233632) (xy 412.429186 -312.192036) (xy 412.409895 -312.14676) (xy 412.398118 -312.098976)
			(xy 412.394158 -312.049922) (xy 411.105096 -312.049922) (xy 411.104601 -312.074529) (xy 411.096706 -312.123106)
			(xy 411.081122 -312.169787) (xy 411.058251 -312.213364) (xy 411.028686 -312.252708) (xy 410.993193 -312.2868)
			(xy 410.95269 -312.314756) (xy 410.908228 -312.335854) (xy 410.860957 -312.349546) (xy 410.812102 -312.355478)
			(xy 410.762927 -312.353497) (xy 410.714708 -312.343653) (xy 410.668692 -312.326201) (xy 410.626071 -312.301594)
			(xy 410.58795 -312.270469) (xy 410.555315 -312.233632) (xy 410.529012 -312.192036) (xy 410.509721 -312.14676)
			(xy 410.497944 -312.098976) (xy 410.493984 -312.049922) (xy 409.205176 -312.049922) (xy 409.204681 -312.074529)
			(xy 409.196786 -312.123106) (xy 409.181202 -312.169787) (xy 409.158331 -312.213364) (xy 409.128766 -312.252708)
			(xy 409.093273 -312.2868) (xy 409.05277 -312.314756) (xy 409.008308 -312.335854) (xy 408.961037 -312.349546)
			(xy 408.912182 -312.355478) (xy 408.863007 -312.353497) (xy 408.814788 -312.343653) (xy 408.768772 -312.326201)
			(xy 408.726151 -312.301594) (xy 408.68803 -312.270469) (xy 408.655395 -312.233632) (xy 408.629092 -312.192036)
			(xy 408.609801 -312.14676) (xy 408.598024 -312.098976) (xy 408.594064 -312.049922) (xy 407.305256 -312.049922)
			(xy 407.304761 -312.074529) (xy 407.296866 -312.123106) (xy 407.281282 -312.169787) (xy 407.258411 -312.213364)
			(xy 407.228846 -312.252708) (xy 407.193353 -312.2868) (xy 407.15285 -312.314756) (xy 407.108388 -312.335854)
			(xy 407.061117 -312.349546) (xy 407.012262 -312.355478) (xy 406.963087 -312.353497) (xy 406.914868 -312.343653)
			(xy 406.868852 -312.326201) (xy 406.826231 -312.301594) (xy 406.78811 -312.270469) (xy 406.755475 -312.233632)
			(xy 406.729172 -312.192036) (xy 406.709881 -312.14676) (xy 406.698104 -312.098976) (xy 406.694144 -312.049922)
			(xy 405.405336 -312.049922) (xy 405.404841 -312.074529) (xy 405.396946 -312.123106) (xy 405.381362 -312.169787)
			(xy 405.358491 -312.213364) (xy 405.328926 -312.252708) (xy 405.293433 -312.2868) (xy 405.25293 -312.314756)
			(xy 405.208468 -312.335854) (xy 405.161197 -312.349546) (xy 405.112342 -312.355478) (xy 405.063167 -312.353497)
			(xy 405.014948 -312.343653) (xy 404.968932 -312.326201) (xy 404.926311 -312.301594) (xy 404.88819 -312.270469)
			(xy 404.855555 -312.233632) (xy 404.829252 -312.192036) (xy 404.809961 -312.14676) (xy 404.798184 -312.098976)
			(xy 404.794224 -312.049922) (xy 403.505162 -312.049922) (xy 403.504667 -312.074529) (xy 403.496772 -312.123106)
			(xy 403.481188 -312.169787) (xy 403.458317 -312.213364) (xy 403.428752 -312.252708) (xy 403.393259 -312.2868)
			(xy 403.352756 -312.314756) (xy 403.308294 -312.335854) (xy 403.261023 -312.349546) (xy 403.212168 -312.355478)
			(xy 403.162993 -312.353497) (xy 403.114774 -312.343653) (xy 403.068758 -312.326201) (xy 403.026137 -312.301594)
			(xy 402.988016 -312.270469) (xy 402.955381 -312.233632) (xy 402.929078 -312.192036) (xy 402.909787 -312.14676)
			(xy 402.89801 -312.098976) (xy 402.89405 -312.049922) (xy 401.605242 -312.049922) (xy 401.604747 -312.074529)
			(xy 401.596852 -312.123106) (xy 401.581268 -312.169787) (xy 401.558397 -312.213364) (xy 401.528832 -312.252708)
			(xy 401.493339 -312.2868) (xy 401.452836 -312.314756) (xy 401.408374 -312.335854) (xy 401.361103 -312.349546)
			(xy 401.312248 -312.355478) (xy 401.263073 -312.353497) (xy 401.214854 -312.343653) (xy 401.168838 -312.326201)
			(xy 401.126217 -312.301594) (xy 401.088096 -312.270469) (xy 401.055461 -312.233632) (xy 401.029158 -312.192036)
			(xy 401.009867 -312.14676) (xy 400.99809 -312.098976) (xy 400.99413 -312.049922) (xy 399.705322 -312.049922)
			(xy 399.704827 -312.074529) (xy 399.696932 -312.123106) (xy 399.681348 -312.169787) (xy 399.658477 -312.213364)
			(xy 399.628912 -312.252708) (xy 399.593419 -312.2868) (xy 399.552916 -312.314756) (xy 399.508454 -312.335854)
			(xy 399.461183 -312.349546) (xy 399.412328 -312.355478) (xy 399.363153 -312.353497) (xy 399.314934 -312.343653)
			(xy 399.268918 -312.326201) (xy 399.226297 -312.301594) (xy 399.188176 -312.270469) (xy 399.155541 -312.233632)
			(xy 399.129238 -312.192036) (xy 399.109947 -312.14676) (xy 399.09817 -312.098976) (xy 399.09421 -312.049922)
			(xy 397.805148 -312.049922) (xy 397.804653 -312.074529) (xy 397.796758 -312.123106) (xy 397.781174 -312.169787)
			(xy 397.758303 -312.213364) (xy 397.728738 -312.252708) (xy 397.693245 -312.2868) (xy 397.652742 -312.314756)
			(xy 397.60828 -312.335854) (xy 397.561009 -312.349546) (xy 397.512154 -312.355478) (xy 397.462979 -312.353497)
			(xy 397.41476 -312.343653) (xy 397.368744 -312.326201) (xy 397.326123 -312.301594) (xy 397.288002 -312.270469)
			(xy 397.255367 -312.233632) (xy 397.229064 -312.192036) (xy 397.209773 -312.14676) (xy 397.197996 -312.098976)
			(xy 397.194036 -312.049922) (xy 395.905228 -312.049922) (xy 395.904733 -312.074529) (xy 395.896838 -312.123106)
			(xy 395.881254 -312.169787) (xy 395.858383 -312.213364) (xy 395.828818 -312.252708) (xy 395.793325 -312.2868)
			(xy 395.752822 -312.314756) (xy 395.70836 -312.335854) (xy 395.661089 -312.349546) (xy 395.612234 -312.355478)
			(xy 395.563059 -312.353497) (xy 395.51484 -312.343653) (xy 395.468824 -312.326201) (xy 395.426203 -312.301594)
			(xy 395.388082 -312.270469) (xy 395.355447 -312.233632) (xy 395.329144 -312.192036) (xy 395.309853 -312.14676)
			(xy 395.298076 -312.098976) (xy 395.294116 -312.049922) (xy 394.005308 -312.049922) (xy 394.004813 -312.074529)
			(xy 393.996918 -312.123106) (xy 393.981334 -312.169787) (xy 393.958463 -312.213364) (xy 393.928898 -312.252708)
			(xy 393.893405 -312.2868) (xy 393.852902 -312.314756) (xy 393.80844 -312.335854) (xy 393.761169 -312.349546)
			(xy 393.712314 -312.355478) (xy 393.663139 -312.353497) (xy 393.61492 -312.343653) (xy 393.568904 -312.326201)
			(xy 393.526283 -312.301594) (xy 393.488162 -312.270469) (xy 393.455527 -312.233632) (xy 393.429224 -312.192036)
			(xy 393.409933 -312.14676) (xy 393.398156 -312.098976) (xy 393.394196 -312.049922) (xy 392.105134 -312.049922)
			(xy 392.104639 -312.074529) (xy 392.096744 -312.123106) (xy 392.08116 -312.169787) (xy 392.058289 -312.213364)
			(xy 392.028724 -312.252708) (xy 391.993231 -312.2868) (xy 391.952728 -312.314756) (xy 391.908266 -312.335854)
			(xy 391.860995 -312.349546) (xy 391.81214 -312.355478) (xy 391.762965 -312.353497) (xy 391.714746 -312.343653)
			(xy 391.66873 -312.326201) (xy 391.626109 -312.301594) (xy 391.587988 -312.270469) (xy 391.555353 -312.233632)
			(xy 391.52905 -312.192036) (xy 391.509759 -312.14676) (xy 391.497982 -312.098976) (xy 391.494022 -312.049922)
			(xy 390.205214 -312.049922) (xy 390.204719 -312.074529) (xy 390.196824 -312.123106) (xy 390.18124 -312.169787)
			(xy 390.158369 -312.213364) (xy 390.128804 -312.252708) (xy 390.093311 -312.2868) (xy 390.052808 -312.314756)
			(xy 390.008346 -312.335854) (xy 389.961075 -312.349546) (xy 389.91222 -312.355478) (xy 389.863045 -312.353497)
			(xy 389.814826 -312.343653) (xy 389.76881 -312.326201) (xy 389.726189 -312.301594) (xy 389.688068 -312.270469)
			(xy 389.655433 -312.233632) (xy 389.62913 -312.192036) (xy 389.609839 -312.14676) (xy 389.598062 -312.098976)
			(xy 389.594102 -312.049922) (xy 388.305294 -312.049922) (xy 388.304799 -312.074529) (xy 388.296904 -312.123106)
			(xy 388.28132 -312.169787) (xy 388.258449 -312.213364) (xy 388.228884 -312.252708) (xy 388.193391 -312.2868)
			(xy 388.152888 -312.314756) (xy 388.108426 -312.335854) (xy 388.061155 -312.349546) (xy 388.0123 -312.355478)
			(xy 387.963125 -312.353497) (xy 387.914906 -312.343653) (xy 387.86889 -312.326201) (xy 387.826269 -312.301594)
			(xy 387.788148 -312.270469) (xy 387.755513 -312.233632) (xy 387.72921 -312.192036) (xy 387.709919 -312.14676)
			(xy 387.698142 -312.098976) (xy 387.694182 -312.049922) (xy 386.40512 -312.049922) (xy 386.404625 -312.074529)
			(xy 386.39673 -312.123106) (xy 386.381146 -312.169787) (xy 386.358275 -312.213364) (xy 386.32871 -312.252708)
			(xy 386.293217 -312.2868) (xy 386.252714 -312.314756) (xy 386.208252 -312.335854) (xy 386.160981 -312.349546)
			(xy 386.112126 -312.355478) (xy 386.062951 -312.353497) (xy 386.014732 -312.343653) (xy 385.968716 -312.326201)
			(xy 385.926095 -312.301594) (xy 385.887974 -312.270469) (xy 385.855339 -312.233632) (xy 385.829036 -312.192036)
			(xy 385.809745 -312.14676) (xy 385.797968 -312.098976) (xy 385.794008 -312.049922) (xy 385.45516 -312.049922)
			(xy 385.454665 -312.074529) (xy 385.44677 -312.123106) (xy 385.431186 -312.169787) (xy 385.408315 -312.213364)
			(xy 385.37875 -312.252708) (xy 385.343257 -312.2868) (xy 385.302754 -312.314756) (xy 385.258292 -312.335854)
			(xy 385.211021 -312.349546) (xy 385.162166 -312.355478) (xy 385.112991 -312.353497) (xy 385.064772 -312.343653)
			(xy 385.018756 -312.326201) (xy 384.976135 -312.301594) (xy 384.938014 -312.270469) (xy 384.905379 -312.233632)
			(xy 384.879076 -312.192036) (xy 384.859785 -312.14676) (xy 384.848008 -312.098976) (xy 384.844048 -312.049922)
			(xy 314.955174 -312.049922) (xy 314.954679 -312.074529) (xy 314.946784 -312.123106) (xy 314.9312 -312.169787)
			(xy 314.908329 -312.213364) (xy 314.878764 -312.252708) (xy 314.843271 -312.2868) (xy 314.802768 -312.314756)
			(xy 314.758306 -312.335854) (xy 314.711035 -312.349546) (xy 314.66218 -312.355478) (xy 314.613005 -312.353497)
			(xy 314.564786 -312.343653) (xy 314.51877 -312.326201) (xy 314.476149 -312.301594) (xy 314.438028 -312.270469)
			(xy 314.405393 -312.233632) (xy 314.37909 -312.192036) (xy 314.359799 -312.14676) (xy 314.348022 -312.098976)
			(xy 314.344062 -312.049922) (xy 314.005214 -312.049922) (xy 314.004719 -312.074529) (xy 313.996824 -312.123106)
			(xy 313.98124 -312.169787) (xy 313.958369 -312.213364) (xy 313.928804 -312.252708) (xy 313.893311 -312.2868)
			(xy 313.852808 -312.314756) (xy 313.808346 -312.335854) (xy 313.761075 -312.349546) (xy 313.71222 -312.355478)
			(xy 313.663045 -312.353497) (xy 313.614826 -312.343653) (xy 313.56881 -312.326201) (xy 313.526189 -312.301594)
			(xy 313.488068 -312.270469) (xy 313.455433 -312.233632) (xy 313.42913 -312.192036) (xy 313.409839 -312.14676)
			(xy 313.398062 -312.098976) (xy 313.394102 -312.049922) (xy 312.10504 -312.049922) (xy 312.104545 -312.074529)
			(xy 312.09665 -312.123106) (xy 312.081066 -312.169787) (xy 312.058195 -312.213364) (xy 312.02863 -312.252708)
			(xy 311.993137 -312.2868) (xy 311.952634 -312.314756) (xy 311.908172 -312.335854) (xy 311.860901 -312.349546)
			(xy 311.812046 -312.355478) (xy 311.762871 -312.353497) (xy 311.714652 -312.343653) (xy 311.668636 -312.326201)
			(xy 311.626015 -312.301594) (xy 311.587894 -312.270469) (xy 311.555259 -312.233632) (xy 311.528956 -312.192036)
			(xy 311.509665 -312.14676) (xy 311.497888 -312.098976) (xy 311.493928 -312.049922) (xy 310.20512 -312.049922)
			(xy 310.204625 -312.074529) (xy 310.19673 -312.123106) (xy 310.181146 -312.169787) (xy 310.158275 -312.213364)
			(xy 310.12871 -312.252708) (xy 310.093217 -312.2868) (xy 310.052714 -312.314756) (xy 310.008252 -312.335854)
			(xy 309.960981 -312.349546) (xy 309.912126 -312.355478) (xy 309.862951 -312.353497) (xy 309.814732 -312.343653)
			(xy 309.768716 -312.326201) (xy 309.726095 -312.301594) (xy 309.687974 -312.270469) (xy 309.655339 -312.233632)
			(xy 309.629036 -312.192036) (xy 309.609745 -312.14676) (xy 309.597968 -312.098976) (xy 309.594008 -312.049922)
			(xy 308.3052 -312.049922) (xy 308.304705 -312.074529) (xy 308.29681 -312.123106) (xy 308.281226 -312.169787)
			(xy 308.258355 -312.213364) (xy 308.22879 -312.252708) (xy 308.193297 -312.2868) (xy 308.152794 -312.314756)
			(xy 308.108332 -312.335854) (xy 308.061061 -312.349546) (xy 308.012206 -312.355478) (xy 307.963031 -312.353497)
			(xy 307.914812 -312.343653) (xy 307.868796 -312.326201) (xy 307.826175 -312.301594) (xy 307.788054 -312.270469)
			(xy 307.755419 -312.233632) (xy 307.729116 -312.192036) (xy 307.709825 -312.14676) (xy 307.698048 -312.098976)
			(xy 307.694088 -312.049922) (xy 306.405026 -312.049922) (xy 306.404531 -312.074529) (xy 306.396636 -312.123106)
			(xy 306.381052 -312.169787) (xy 306.358181 -312.213364) (xy 306.328616 -312.252708) (xy 306.293123 -312.2868)
			(xy 306.25262 -312.314756) (xy 306.208158 -312.335854) (xy 306.160887 -312.349546) (xy 306.112032 -312.355478)
			(xy 306.062857 -312.353497) (xy 306.014638 -312.343653) (xy 305.968622 -312.326201) (xy 305.926001 -312.301594)
			(xy 305.88788 -312.270469) (xy 305.855245 -312.233632) (xy 305.828942 -312.192036) (xy 305.809651 -312.14676)
			(xy 305.797874 -312.098976) (xy 305.793914 -312.049922) (xy 304.505106 -312.049922) (xy 304.504611 -312.074529)
			(xy 304.496716 -312.123106) (xy 304.481132 -312.169787) (xy 304.458261 -312.213364) (xy 304.428696 -312.252708)
			(xy 304.393203 -312.2868) (xy 304.3527 -312.314756) (xy 304.308238 -312.335854) (xy 304.260967 -312.349546)
			(xy 304.212112 -312.355478) (xy 304.162937 -312.353497) (xy 304.114718 -312.343653) (xy 304.068702 -312.326201)
			(xy 304.026081 -312.301594) (xy 303.98796 -312.270469) (xy 303.955325 -312.233632) (xy 303.929022 -312.192036)
			(xy 303.909731 -312.14676) (xy 303.897954 -312.098976) (xy 303.893994 -312.049922) (xy 302.605186 -312.049922)
			(xy 302.604691 -312.074529) (xy 302.596796 -312.123106) (xy 302.581212 -312.169787) (xy 302.558341 -312.213364)
			(xy 302.528776 -312.252708) (xy 302.493283 -312.2868) (xy 302.45278 -312.314756) (xy 302.408318 -312.335854)
			(xy 302.361047 -312.349546) (xy 302.312192 -312.355478) (xy 302.263017 -312.353497) (xy 302.214798 -312.343653)
			(xy 302.168782 -312.326201) (xy 302.126161 -312.301594) (xy 302.08804 -312.270469) (xy 302.055405 -312.233632)
			(xy 302.029102 -312.192036) (xy 302.009811 -312.14676) (xy 301.998034 -312.098976) (xy 301.994074 -312.049922)
			(xy 300.705012 -312.049922) (xy 300.704517 -312.074529) (xy 300.696622 -312.123106) (xy 300.681038 -312.169787)
			(xy 300.658167 -312.213364) (xy 300.628602 -312.252708) (xy 300.593109 -312.2868) (xy 300.552606 -312.314756)
			(xy 300.508144 -312.335854) (xy 300.460873 -312.349546) (xy 300.412018 -312.355478) (xy 300.362843 -312.353497)
			(xy 300.314624 -312.343653) (xy 300.268608 -312.326201) (xy 300.225987 -312.301594) (xy 300.187866 -312.270469)
			(xy 300.155231 -312.233632) (xy 300.128928 -312.192036) (xy 300.109637 -312.14676) (xy 300.09786 -312.098976)
			(xy 300.0939 -312.049922) (xy 298.805092 -312.049922) (xy 298.804597 -312.074529) (xy 298.796702 -312.123106)
			(xy 298.781118 -312.169787) (xy 298.758247 -312.213364) (xy 298.728682 -312.252708) (xy 298.693189 -312.2868)
			(xy 298.652686 -312.314756) (xy 298.608224 -312.335854) (xy 298.560953 -312.349546) (xy 298.512098 -312.355478)
			(xy 298.462923 -312.353497) (xy 298.414704 -312.343653) (xy 298.368688 -312.326201) (xy 298.326067 -312.301594)
			(xy 298.287946 -312.270469) (xy 298.255311 -312.233632) (xy 298.229008 -312.192036) (xy 298.209717 -312.14676)
			(xy 298.19794 -312.098976) (xy 298.19398 -312.049922) (xy 296.905172 -312.049922) (xy 296.904677 -312.074529)
			(xy 296.896782 -312.123106) (xy 296.881198 -312.169787) (xy 296.858327 -312.213364) (xy 296.828762 -312.252708)
			(xy 296.793269 -312.2868) (xy 296.752766 -312.314756) (xy 296.708304 -312.335854) (xy 296.661033 -312.349546)
			(xy 296.612178 -312.355478) (xy 296.563003 -312.353497) (xy 296.514784 -312.343653) (xy 296.468768 -312.326201)
			(xy 296.426147 -312.301594) (xy 296.388026 -312.270469) (xy 296.355391 -312.233632) (xy 296.329088 -312.192036)
			(xy 296.309797 -312.14676) (xy 296.29802 -312.098976) (xy 296.29406 -312.049922) (xy 295.004998 -312.049922)
			(xy 295.004503 -312.074529) (xy 294.996608 -312.123106) (xy 294.981024 -312.169787) (xy 294.958153 -312.213364)
			(xy 294.928588 -312.252708) (xy 294.893095 -312.2868) (xy 294.852592 -312.314756) (xy 294.80813 -312.335854)
			(xy 294.760859 -312.349546) (xy 294.712004 -312.355478) (xy 294.662829 -312.353497) (xy 294.61461 -312.343653)
			(xy 294.568594 -312.326201) (xy 294.525973 -312.301594) (xy 294.487852 -312.270469) (xy 294.455217 -312.233632)
			(xy 294.428914 -312.192036) (xy 294.409623 -312.14676) (xy 294.397846 -312.098976) (xy 294.393886 -312.049922)
			(xy 293.105078 -312.049922) (xy 293.104583 -312.074529) (xy 293.096688 -312.123106) (xy 293.081104 -312.169787)
			(xy 293.058233 -312.213364) (xy 293.028668 -312.252708) (xy 292.993175 -312.2868) (xy 292.952672 -312.314756)
			(xy 292.90821 -312.335854) (xy 292.860939 -312.349546) (xy 292.812084 -312.355478) (xy 292.762909 -312.353497)
			(xy 292.71469 -312.343653) (xy 292.668674 -312.326201) (xy 292.626053 -312.301594) (xy 292.587932 -312.270469)
			(xy 292.555297 -312.233632) (xy 292.528994 -312.192036) (xy 292.509703 -312.14676) (xy 292.497926 -312.098976)
			(xy 292.493966 -312.049922) (xy 291.205158 -312.049922) (xy 291.204663 -312.074529) (xy 291.196768 -312.123106)
			(xy 291.181184 -312.169787) (xy 291.158313 -312.213364) (xy 291.128748 -312.252708) (xy 291.093255 -312.2868)
			(xy 291.052752 -312.314756) (xy 291.00829 -312.335854) (xy 290.961019 -312.349546) (xy 290.912164 -312.355478)
			(xy 290.862989 -312.353497) (xy 290.81477 -312.343653) (xy 290.768754 -312.326201) (xy 290.726133 -312.301594)
			(xy 290.688012 -312.270469) (xy 290.655377 -312.233632) (xy 290.629074 -312.192036) (xy 290.609783 -312.14676)
			(xy 290.598006 -312.098976) (xy 290.594046 -312.049922) (xy 289.305238 -312.049922) (xy 289.304743 -312.074529)
			(xy 289.296848 -312.123106) (xy 289.281264 -312.169787) (xy 289.258393 -312.213364) (xy 289.228828 -312.252708)
			(xy 289.193335 -312.2868) (xy 289.152832 -312.314756) (xy 289.10837 -312.335854) (xy 289.061099 -312.349546)
			(xy 289.012244 -312.355478) (xy 288.963069 -312.353497) (xy 288.91485 -312.343653) (xy 288.868834 -312.326201)
			(xy 288.826213 -312.301594) (xy 288.788092 -312.270469) (xy 288.755457 -312.233632) (xy 288.729154 -312.192036)
			(xy 288.709863 -312.14676) (xy 288.698086 -312.098976) (xy 288.694126 -312.049922) (xy 287.405064 -312.049922)
			(xy 287.404569 -312.074529) (xy 287.396674 -312.123106) (xy 287.38109 -312.169787) (xy 287.358219 -312.213364)
			(xy 287.328654 -312.252708) (xy 287.293161 -312.2868) (xy 287.252658 -312.314756) (xy 287.208196 -312.335854)
			(xy 287.160925 -312.349546) (xy 287.11207 -312.355478) (xy 287.062895 -312.353497) (xy 287.014676 -312.343653)
			(xy 286.96866 -312.326201) (xy 286.926039 -312.301594) (xy 286.887918 -312.270469) (xy 286.855283 -312.233632)
			(xy 286.82898 -312.192036) (xy 286.809689 -312.14676) (xy 286.797912 -312.098976) (xy 286.793952 -312.049922)
			(xy 285.505144 -312.049922) (xy 285.504649 -312.074529) (xy 285.496754 -312.123106) (xy 285.48117 -312.169787)
			(xy 285.458299 -312.213364) (xy 285.428734 -312.252708) (xy 285.393241 -312.2868) (xy 285.352738 -312.314756)
			(xy 285.308276 -312.335854) (xy 285.261005 -312.349546) (xy 285.21215 -312.355478) (xy 285.162975 -312.353497)
			(xy 285.114756 -312.343653) (xy 285.06874 -312.326201) (xy 285.026119 -312.301594) (xy 284.987998 -312.270469)
			(xy 284.955363 -312.233632) (xy 284.92906 -312.192036) (xy 284.909769 -312.14676) (xy 284.897992 -312.098976)
			(xy 284.894032 -312.049922) (xy 283.605224 -312.049922) (xy 283.604729 -312.074529) (xy 283.596834 -312.123106)
			(xy 283.58125 -312.169787) (xy 283.558379 -312.213364) (xy 283.528814 -312.252708) (xy 283.493321 -312.2868)
			(xy 283.452818 -312.314756) (xy 283.408356 -312.335854) (xy 283.361085 -312.349546) (xy 283.31223 -312.355478)
			(xy 283.263055 -312.353497) (xy 283.214836 -312.343653) (xy 283.16882 -312.326201) (xy 283.126199 -312.301594)
			(xy 283.088078 -312.270469) (xy 283.055443 -312.233632) (xy 283.02914 -312.192036) (xy 283.009849 -312.14676)
			(xy 282.998072 -312.098976) (xy 282.994112 -312.049922) (xy 281.70505 -312.049922) (xy 281.704555 -312.074529)
			(xy 281.69666 -312.123106) (xy 281.681076 -312.169787) (xy 281.658205 -312.213364) (xy 281.62864 -312.252708)
			(xy 281.593147 -312.2868) (xy 281.552644 -312.314756) (xy 281.508182 -312.335854) (xy 281.460911 -312.349546)
			(xy 281.412056 -312.355478) (xy 281.362881 -312.353497) (xy 281.314662 -312.343653) (xy 281.268646 -312.326201)
			(xy 281.226025 -312.301594) (xy 281.187904 -312.270469) (xy 281.155269 -312.233632) (xy 281.128966 -312.192036)
			(xy 281.109675 -312.14676) (xy 281.097898 -312.098976) (xy 281.093938 -312.049922) (xy 279.80513 -312.049922)
			(xy 279.804635 -312.074529) (xy 279.79674 -312.123106) (xy 279.781156 -312.169787) (xy 279.758285 -312.213364)
			(xy 279.72872 -312.252708) (xy 279.693227 -312.2868) (xy 279.652724 -312.314756) (xy 279.608262 -312.335854)
			(xy 279.560991 -312.349546) (xy 279.512136 -312.355478) (xy 279.462961 -312.353497) (xy 279.414742 -312.343653)
			(xy 279.368726 -312.326201) (xy 279.326105 -312.301594) (xy 279.287984 -312.270469) (xy 279.255349 -312.233632)
			(xy 279.229046 -312.192036) (xy 279.209755 -312.14676) (xy 279.197978 -312.098976) (xy 279.194018 -312.049922)
			(xy 277.90521 -312.049922) (xy 277.904715 -312.074529) (xy 277.89682 -312.123106) (xy 277.881236 -312.169787)
			(xy 277.858365 -312.213364) (xy 277.8288 -312.252708) (xy 277.793307 -312.2868) (xy 277.752804 -312.314756)
			(xy 277.708342 -312.335854) (xy 277.661071 -312.349546) (xy 277.612216 -312.355478) (xy 277.563041 -312.353497)
			(xy 277.514822 -312.343653) (xy 277.468806 -312.326201) (xy 277.426185 -312.301594) (xy 277.388064 -312.270469)
			(xy 277.355429 -312.233632) (xy 277.329126 -312.192036) (xy 277.309835 -312.14676) (xy 277.298058 -312.098976)
			(xy 277.294098 -312.049922) (xy 276.005036 -312.049922) (xy 276.004541 -312.074529) (xy 275.996646 -312.123106)
			(xy 275.981062 -312.169787) (xy 275.958191 -312.213364) (xy 275.928626 -312.252708) (xy 275.893133 -312.2868)
			(xy 275.85263 -312.314756) (xy 275.808168 -312.335854) (xy 275.760897 -312.349546) (xy 275.712042 -312.355478)
			(xy 275.662867 -312.353497) (xy 275.614648 -312.343653) (xy 275.568632 -312.326201) (xy 275.526011 -312.301594)
			(xy 275.48789 -312.270469) (xy 275.455255 -312.233632) (xy 275.428952 -312.192036) (xy 275.409661 -312.14676)
			(xy 275.397884 -312.098976) (xy 275.393924 -312.049922) (xy 274.105116 -312.049922) (xy 274.104621 -312.074529)
			(xy 274.096726 -312.123106) (xy 274.081142 -312.169787) (xy 274.058271 -312.213364) (xy 274.028706 -312.252708)
			(xy 273.993213 -312.2868) (xy 273.95271 -312.314756) (xy 273.908248 -312.335854) (xy 273.860977 -312.349546)
			(xy 273.812122 -312.355478) (xy 273.762947 -312.353497) (xy 273.714728 -312.343653) (xy 273.668712 -312.326201)
			(xy 273.626091 -312.301594) (xy 273.58797 -312.270469) (xy 273.555335 -312.233632) (xy 273.529032 -312.192036)
			(xy 273.509741 -312.14676) (xy 273.497964 -312.098976) (xy 273.494004 -312.049922) (xy 272.205196 -312.049922)
			(xy 272.204701 -312.074529) (xy 272.196806 -312.123106) (xy 272.181222 -312.169787) (xy 272.158351 -312.213364)
			(xy 272.128786 -312.252708) (xy 272.093293 -312.2868) (xy 272.05279 -312.314756) (xy 272.008328 -312.335854)
			(xy 271.961057 -312.349546) (xy 271.912202 -312.355478) (xy 271.863027 -312.353497) (xy 271.814808 -312.343653)
			(xy 271.768792 -312.326201) (xy 271.726171 -312.301594) (xy 271.68805 -312.270469) (xy 271.655415 -312.233632)
			(xy 271.629112 -312.192036) (xy 271.609821 -312.14676) (xy 271.598044 -312.098976) (xy 271.594084 -312.049922)
			(xy 270.305022 -312.049922) (xy 270.304527 -312.074529) (xy 270.296632 -312.123106) (xy 270.281048 -312.169787)
			(xy 270.258177 -312.213364) (xy 270.228612 -312.252708) (xy 270.193119 -312.2868) (xy 270.152616 -312.314756)
			(xy 270.108154 -312.335854) (xy 270.060883 -312.349546) (xy 270.012028 -312.355478) (xy 269.962853 -312.353497)
			(xy 269.914634 -312.343653) (xy 269.868618 -312.326201) (xy 269.825997 -312.301594) (xy 269.787876 -312.270469)
			(xy 269.755241 -312.233632) (xy 269.728938 -312.192036) (xy 269.709647 -312.14676) (xy 269.69787 -312.098976)
			(xy 269.69391 -312.049922) (xy 269.355062 -312.049922) (xy 269.354567 -312.074529) (xy 269.346672 -312.123106)
			(xy 269.331088 -312.169787) (xy 269.308217 -312.213364) (xy 269.278652 -312.252708) (xy 269.243159 -312.2868)
			(xy 269.202656 -312.314756) (xy 269.158194 -312.335854) (xy 269.110923 -312.349546) (xy 269.062068 -312.355478)
			(xy 269.012893 -312.353497) (xy 268.964674 -312.343653) (xy 268.918658 -312.326201) (xy 268.876037 -312.301594)
			(xy 268.837916 -312.270469) (xy 268.805281 -312.233632) (xy 268.778978 -312.192036) (xy 268.759687 -312.14676)
			(xy 268.74791 -312.098976) (xy 268.74395 -312.049922) (xy 198.85533 -312.049922) (xy 198.854835 -312.074529)
			(xy 198.84694 -312.123106) (xy 198.831356 -312.169787) (xy 198.808485 -312.213364) (xy 198.77892 -312.252708)
			(xy 198.743427 -312.2868) (xy 198.702924 -312.314756) (xy 198.658462 -312.335854) (xy 198.611191 -312.349546)
			(xy 198.562336 -312.355478) (xy 198.513161 -312.353497) (xy 198.464942 -312.343653) (xy 198.418926 -312.326201)
			(xy 198.376305 -312.301594) (xy 198.338184 -312.270469) (xy 198.305549 -312.233632) (xy 198.279246 -312.192036)
			(xy 198.259955 -312.14676) (xy 198.248178 -312.098976) (xy 198.244218 -312.049922) (xy 197.90537 -312.049922)
			(xy 197.904875 -312.074529) (xy 197.89698 -312.123106) (xy 197.881396 -312.169787) (xy 197.858525 -312.213364)
			(xy 197.82896 -312.252708) (xy 197.793467 -312.2868) (xy 197.752964 -312.314756) (xy 197.708502 -312.335854)
			(xy 197.661231 -312.349546) (xy 197.612376 -312.355478) (xy 197.563201 -312.353497) (xy 197.514982 -312.343653)
			(xy 197.468966 -312.326201) (xy 197.426345 -312.301594) (xy 197.388224 -312.270469) (xy 197.355589 -312.233632)
			(xy 197.329286 -312.192036) (xy 197.309995 -312.14676) (xy 197.298218 -312.098976) (xy 197.294258 -312.049922)
			(xy 196.005196 -312.049922) (xy 196.004701 -312.074529) (xy 195.996806 -312.123106) (xy 195.981222 -312.169787)
			(xy 195.958351 -312.213364) (xy 195.928786 -312.252708) (xy 195.893293 -312.2868) (xy 195.85279 -312.314756)
			(xy 195.808328 -312.335854) (xy 195.761057 -312.349546) (xy 195.712202 -312.355478) (xy 195.663027 -312.353497)
			(xy 195.614808 -312.343653) (xy 195.568792 -312.326201) (xy 195.526171 -312.301594) (xy 195.48805 -312.270469)
			(xy 195.455415 -312.233632) (xy 195.429112 -312.192036) (xy 195.409821 -312.14676) (xy 195.398044 -312.098976)
			(xy 195.394084 -312.049922) (xy 194.105276 -312.049922) (xy 194.104781 -312.074529) (xy 194.096886 -312.123106)
			(xy 194.081302 -312.169787) (xy 194.058431 -312.213364) (xy 194.028866 -312.252708) (xy 193.993373 -312.2868)
			(xy 193.95287 -312.314756) (xy 193.908408 -312.335854) (xy 193.861137 -312.349546) (xy 193.812282 -312.355478)
			(xy 193.763107 -312.353497) (xy 193.714888 -312.343653) (xy 193.668872 -312.326201) (xy 193.626251 -312.301594)
			(xy 193.58813 -312.270469) (xy 193.555495 -312.233632) (xy 193.529192 -312.192036) (xy 193.509901 -312.14676)
			(xy 193.498124 -312.098976) (xy 193.494164 -312.049922) (xy 192.205356 -312.049922) (xy 192.204861 -312.074529)
			(xy 192.196966 -312.123106) (xy 192.181382 -312.169787) (xy 192.158511 -312.213364) (xy 192.128946 -312.252708)
			(xy 192.093453 -312.2868) (xy 192.05295 -312.314756) (xy 192.008488 -312.335854) (xy 191.961217 -312.349546)
			(xy 191.912362 -312.355478) (xy 191.863187 -312.353497) (xy 191.814968 -312.343653) (xy 191.768952 -312.326201)
			(xy 191.726331 -312.301594) (xy 191.68821 -312.270469) (xy 191.655575 -312.233632) (xy 191.629272 -312.192036)
			(xy 191.609981 -312.14676) (xy 191.598204 -312.098976) (xy 191.594244 -312.049922) (xy 190.305182 -312.049922)
			(xy 190.304687 -312.074529) (xy 190.296792 -312.123106) (xy 190.281208 -312.169787) (xy 190.258337 -312.213364)
			(xy 190.228772 -312.252708) (xy 190.193279 -312.2868) (xy 190.152776 -312.314756) (xy 190.108314 -312.335854)
			(xy 190.061043 -312.349546) (xy 190.012188 -312.355478) (xy 189.963013 -312.353497) (xy 189.914794 -312.343653)
			(xy 189.868778 -312.326201) (xy 189.826157 -312.301594) (xy 189.788036 -312.270469) (xy 189.755401 -312.233632)
			(xy 189.729098 -312.192036) (xy 189.709807 -312.14676) (xy 189.69803 -312.098976) (xy 189.69407 -312.049922)
			(xy 188.405262 -312.049922) (xy 188.404767 -312.074529) (xy 188.396872 -312.123106) (xy 188.381288 -312.169787)
			(xy 188.358417 -312.213364) (xy 188.328852 -312.252708) (xy 188.293359 -312.2868) (xy 188.252856 -312.314756)
			(xy 188.208394 -312.335854) (xy 188.161123 -312.349546) (xy 188.112268 -312.355478) (xy 188.063093 -312.353497)
			(xy 188.014874 -312.343653) (xy 187.968858 -312.326201) (xy 187.926237 -312.301594) (xy 187.888116 -312.270469)
			(xy 187.855481 -312.233632) (xy 187.829178 -312.192036) (xy 187.809887 -312.14676) (xy 187.79811 -312.098976)
			(xy 187.79415 -312.049922) (xy 186.505342 -312.049922) (xy 186.504847 -312.074529) (xy 186.496952 -312.123106)
			(xy 186.481368 -312.169787) (xy 186.458497 -312.213364) (xy 186.428932 -312.252708) (xy 186.393439 -312.2868)
			(xy 186.352936 -312.314756) (xy 186.308474 -312.335854) (xy 186.261203 -312.349546) (xy 186.212348 -312.355478)
			(xy 186.163173 -312.353497) (xy 186.114954 -312.343653) (xy 186.068938 -312.326201) (xy 186.026317 -312.301594)
			(xy 185.988196 -312.270469) (xy 185.955561 -312.233632) (xy 185.929258 -312.192036) (xy 185.909967 -312.14676)
			(xy 185.89819 -312.098976) (xy 185.89423 -312.049922) (xy 184.605168 -312.049922) (xy 184.604673 -312.074529)
			(xy 184.596778 -312.123106) (xy 184.581194 -312.169787) (xy 184.558323 -312.213364) (xy 184.528758 -312.252708)
			(xy 184.493265 -312.2868) (xy 184.452762 -312.314756) (xy 184.4083 -312.335854) (xy 184.361029 -312.349546)
			(xy 184.312174 -312.355478) (xy 184.262999 -312.353497) (xy 184.21478 -312.343653) (xy 184.168764 -312.326201)
			(xy 184.126143 -312.301594) (xy 184.088022 -312.270469) (xy 184.055387 -312.233632) (xy 184.029084 -312.192036)
			(xy 184.009793 -312.14676) (xy 183.998016 -312.098976) (xy 183.994056 -312.049922) (xy 182.705248 -312.049922)
			(xy 182.704753 -312.074529) (xy 182.696858 -312.123106) (xy 182.681274 -312.169787) (xy 182.658403 -312.213364)
			(xy 182.628838 -312.252708) (xy 182.593345 -312.2868) (xy 182.552842 -312.314756) (xy 182.50838 -312.335854)
			(xy 182.461109 -312.349546) (xy 182.412254 -312.355478) (xy 182.363079 -312.353497) (xy 182.31486 -312.343653)
			(xy 182.268844 -312.326201) (xy 182.226223 -312.301594) (xy 182.188102 -312.270469) (xy 182.155467 -312.233632)
			(xy 182.129164 -312.192036) (xy 182.109873 -312.14676) (xy 182.098096 -312.098976) (xy 182.094136 -312.049922)
			(xy 180.805328 -312.049922) (xy 180.804833 -312.074529) (xy 180.796938 -312.123106) (xy 180.781354 -312.169787)
			(xy 180.758483 -312.213364) (xy 180.728918 -312.252708) (xy 180.693425 -312.2868) (xy 180.652922 -312.314756)
			(xy 180.60846 -312.335854) (xy 180.561189 -312.349546) (xy 180.512334 -312.355478) (xy 180.463159 -312.353497)
			(xy 180.41494 -312.343653) (xy 180.368924 -312.326201) (xy 180.326303 -312.301594) (xy 180.288182 -312.270469)
			(xy 180.255547 -312.233632) (xy 180.229244 -312.192036) (xy 180.209953 -312.14676) (xy 180.198176 -312.098976)
			(xy 180.194216 -312.049922) (xy 178.905154 -312.049922) (xy 178.904659 -312.074529) (xy 178.896764 -312.123106)
			(xy 178.88118 -312.169787) (xy 178.858309 -312.213364) (xy 178.828744 -312.252708) (xy 178.793251 -312.2868)
			(xy 178.752748 -312.314756) (xy 178.708286 -312.335854) (xy 178.661015 -312.349546) (xy 178.61216 -312.355478)
			(xy 178.562985 -312.353497) (xy 178.514766 -312.343653) (xy 178.46875 -312.326201) (xy 178.426129 -312.301594)
			(xy 178.388008 -312.270469) (xy 178.355373 -312.233632) (xy 178.32907 -312.192036) (xy 178.309779 -312.14676)
			(xy 178.298002 -312.098976) (xy 178.294042 -312.049922) (xy 177.005234 -312.049922) (xy 177.004739 -312.074529)
			(xy 176.996844 -312.123106) (xy 176.98126 -312.169787) (xy 176.958389 -312.213364) (xy 176.928824 -312.252708)
			(xy 176.893331 -312.2868) (xy 176.852828 -312.314756) (xy 176.808366 -312.335854) (xy 176.761095 -312.349546)
			(xy 176.71224 -312.355478) (xy 176.663065 -312.353497) (xy 176.614846 -312.343653) (xy 176.56883 -312.326201)
			(xy 176.526209 -312.301594) (xy 176.488088 -312.270469) (xy 176.455453 -312.233632) (xy 176.42915 -312.192036)
			(xy 176.409859 -312.14676) (xy 176.398082 -312.098976) (xy 176.394122 -312.049922) (xy 175.105314 -312.049922)
			(xy 175.104819 -312.074529) (xy 175.096924 -312.123106) (xy 175.08134 -312.169787) (xy 175.058469 -312.213364)
			(xy 175.028904 -312.252708) (xy 174.993411 -312.2868) (xy 174.952908 -312.314756) (xy 174.908446 -312.335854)
			(xy 174.861175 -312.349546) (xy 174.81232 -312.355478) (xy 174.763145 -312.353497) (xy 174.714926 -312.343653)
			(xy 174.66891 -312.326201) (xy 174.626289 -312.301594) (xy 174.588168 -312.270469) (xy 174.555533 -312.233632)
			(xy 174.52923 -312.192036) (xy 174.509939 -312.14676) (xy 174.498162 -312.098976) (xy 174.494202 -312.049922)
			(xy 173.205394 -312.049922) (xy 173.204899 -312.074529) (xy 173.197004 -312.123106) (xy 173.18142 -312.169787)
			(xy 173.158549 -312.213364) (xy 173.128984 -312.252708) (xy 173.093491 -312.2868) (xy 173.052988 -312.314756)
			(xy 173.008526 -312.335854) (xy 172.961255 -312.349546) (xy 172.9124 -312.355478) (xy 172.863225 -312.353497)
			(xy 172.815006 -312.343653) (xy 172.76899 -312.326201) (xy 172.726369 -312.301594) (xy 172.688248 -312.270469)
			(xy 172.655613 -312.233632) (xy 172.62931 -312.192036) (xy 172.610019 -312.14676) (xy 172.598242 -312.098976)
			(xy 172.594282 -312.049922) (xy 171.30522 -312.049922) (xy 171.304725 -312.074529) (xy 171.29683 -312.123106)
			(xy 171.281246 -312.169787) (xy 171.258375 -312.213364) (xy 171.22881 -312.252708) (xy 171.193317 -312.2868)
			(xy 171.152814 -312.314756) (xy 171.108352 -312.335854) (xy 171.061081 -312.349546) (xy 171.012226 -312.355478)
			(xy 170.963051 -312.353497) (xy 170.914832 -312.343653) (xy 170.868816 -312.326201) (xy 170.826195 -312.301594)
			(xy 170.788074 -312.270469) (xy 170.755439 -312.233632) (xy 170.729136 -312.192036) (xy 170.709845 -312.14676)
			(xy 170.698068 -312.098976) (xy 170.694108 -312.049922) (xy 169.4053 -312.049922) (xy 169.404805 -312.074529)
			(xy 169.39691 -312.123106) (xy 169.381326 -312.169787) (xy 169.358455 -312.213364) (xy 169.32889 -312.252708)
			(xy 169.293397 -312.2868) (xy 169.252894 -312.314756) (xy 169.208432 -312.335854) (xy 169.161161 -312.349546)
			(xy 169.112306 -312.355478) (xy 169.063131 -312.353497) (xy 169.014912 -312.343653) (xy 168.968896 -312.326201)
			(xy 168.926275 -312.301594) (xy 168.888154 -312.270469) (xy 168.855519 -312.233632) (xy 168.829216 -312.192036)
			(xy 168.809925 -312.14676) (xy 168.798148 -312.098976) (xy 168.794188 -312.049922) (xy 167.50538 -312.049922)
			(xy 167.504885 -312.074529) (xy 167.49699 -312.123106) (xy 167.481406 -312.169787) (xy 167.458535 -312.213364)
			(xy 167.42897 -312.252708) (xy 167.393477 -312.2868) (xy 167.352974 -312.314756) (xy 167.308512 -312.335854)
			(xy 167.261241 -312.349546) (xy 167.212386 -312.355478) (xy 167.163211 -312.353497) (xy 167.114992 -312.343653)
			(xy 167.068976 -312.326201) (xy 167.026355 -312.301594) (xy 166.988234 -312.270469) (xy 166.955599 -312.233632)
			(xy 166.929296 -312.192036) (xy 166.910005 -312.14676) (xy 166.898228 -312.098976) (xy 166.894268 -312.049922)
			(xy 165.605206 -312.049922) (xy 165.604711 -312.074529) (xy 165.596816 -312.123106) (xy 165.581232 -312.169787)
			(xy 165.558361 -312.213364) (xy 165.528796 -312.252708) (xy 165.493303 -312.2868) (xy 165.4528 -312.314756)
			(xy 165.408338 -312.335854) (xy 165.361067 -312.349546) (xy 165.312212 -312.355478) (xy 165.263037 -312.353497)
			(xy 165.214818 -312.343653) (xy 165.168802 -312.326201) (xy 165.126181 -312.301594) (xy 165.08806 -312.270469)
			(xy 165.055425 -312.233632) (xy 165.029122 -312.192036) (xy 165.009831 -312.14676) (xy 164.998054 -312.098976)
			(xy 164.994094 -312.049922) (xy 163.705286 -312.049922) (xy 163.704791 -312.074529) (xy 163.696896 -312.123106)
			(xy 163.681312 -312.169787) (xy 163.658441 -312.213364) (xy 163.628876 -312.252708) (xy 163.593383 -312.2868)
			(xy 163.55288 -312.314756) (xy 163.508418 -312.335854) (xy 163.461147 -312.349546) (xy 163.412292 -312.355478)
			(xy 163.363117 -312.353497) (xy 163.314898 -312.343653) (xy 163.268882 -312.326201) (xy 163.226261 -312.301594)
			(xy 163.18814 -312.270469) (xy 163.155505 -312.233632) (xy 163.129202 -312.192036) (xy 163.109911 -312.14676)
			(xy 163.098134 -312.098976) (xy 163.094174 -312.049922) (xy 161.805366 -312.049922) (xy 161.804871 -312.074529)
			(xy 161.796976 -312.123106) (xy 161.781392 -312.169787) (xy 161.758521 -312.213364) (xy 161.728956 -312.252708)
			(xy 161.693463 -312.2868) (xy 161.65296 -312.314756) (xy 161.608498 -312.335854) (xy 161.561227 -312.349546)
			(xy 161.512372 -312.355478) (xy 161.463197 -312.353497) (xy 161.414978 -312.343653) (xy 161.368962 -312.326201)
			(xy 161.326341 -312.301594) (xy 161.28822 -312.270469) (xy 161.255585 -312.233632) (xy 161.229282 -312.192036)
			(xy 161.209991 -312.14676) (xy 161.198214 -312.098976) (xy 161.194254 -312.049922) (xy 159.905192 -312.049922)
			(xy 159.904697 -312.074529) (xy 159.896802 -312.123106) (xy 159.881218 -312.169787) (xy 159.858347 -312.213364)
			(xy 159.828782 -312.252708) (xy 159.793289 -312.2868) (xy 159.752786 -312.314756) (xy 159.708324 -312.335854)
			(xy 159.661053 -312.349546) (xy 159.612198 -312.355478) (xy 159.563023 -312.353497) (xy 159.514804 -312.343653)
			(xy 159.468788 -312.326201) (xy 159.426167 -312.301594) (xy 159.388046 -312.270469) (xy 159.355411 -312.233632)
			(xy 159.329108 -312.192036) (xy 159.309817 -312.14676) (xy 159.29804 -312.098976) (xy 159.29408 -312.049922)
			(xy 158.005272 -312.049922) (xy 158.004777 -312.074529) (xy 157.996882 -312.123106) (xy 157.981298 -312.169787)
			(xy 157.958427 -312.213364) (xy 157.928862 -312.252708) (xy 157.893369 -312.2868) (xy 157.852866 -312.314756)
			(xy 157.808404 -312.335854) (xy 157.761133 -312.349546) (xy 157.712278 -312.355478) (xy 157.663103 -312.353497)
			(xy 157.614884 -312.343653) (xy 157.568868 -312.326201) (xy 157.526247 -312.301594) (xy 157.488126 -312.270469)
			(xy 157.455491 -312.233632) (xy 157.429188 -312.192036) (xy 157.409897 -312.14676) (xy 157.39812 -312.098976)
			(xy 157.39416 -312.049922) (xy 156.105352 -312.049922) (xy 156.104857 -312.074529) (xy 156.096962 -312.123106)
			(xy 156.081378 -312.169787) (xy 156.058507 -312.213364) (xy 156.028942 -312.252708) (xy 155.993449 -312.2868)
			(xy 155.952946 -312.314756) (xy 155.908484 -312.335854) (xy 155.861213 -312.349546) (xy 155.812358 -312.355478)
			(xy 155.763183 -312.353497) (xy 155.714964 -312.343653) (xy 155.668948 -312.326201) (xy 155.626327 -312.301594)
			(xy 155.588206 -312.270469) (xy 155.555571 -312.233632) (xy 155.529268 -312.192036) (xy 155.509977 -312.14676)
			(xy 155.4982 -312.098976) (xy 155.49424 -312.049922) (xy 154.205178 -312.049922) (xy 154.204683 -312.074529)
			(xy 154.196788 -312.123106) (xy 154.181204 -312.169787) (xy 154.158333 -312.213364) (xy 154.128768 -312.252708)
			(xy 154.093275 -312.2868) (xy 154.052772 -312.314756) (xy 154.00831 -312.335854) (xy 153.961039 -312.349546)
			(xy 153.912184 -312.355478) (xy 153.863009 -312.353497) (xy 153.81479 -312.343653) (xy 153.768774 -312.326201)
			(xy 153.726153 -312.301594) (xy 153.688032 -312.270469) (xy 153.655397 -312.233632) (xy 153.629094 -312.192036)
			(xy 153.609803 -312.14676) (xy 153.598026 -312.098976) (xy 153.594066 -312.049922) (xy 153.255218 -312.049922)
			(xy 153.254723 -312.074529) (xy 153.246828 -312.123106) (xy 153.231244 -312.169787) (xy 153.208373 -312.213364)
			(xy 153.178808 -312.252708) (xy 153.143315 -312.2868) (xy 153.102812 -312.314756) (xy 153.05835 -312.335854)
			(xy 153.011079 -312.349546) (xy 152.962224 -312.355478) (xy 152.913049 -312.353497) (xy 152.86483 -312.343653)
			(xy 152.818814 -312.326201) (xy 152.776193 -312.301594) (xy 152.738072 -312.270469) (xy 152.705437 -312.233632)
			(xy 152.679134 -312.192036) (xy 152.659843 -312.14676) (xy 152.648066 -312.098976) (xy 152.644106 -312.049922)
			(xy 82.755232 -312.049922) (xy 82.754737 -312.074529) (xy 82.746842 -312.123106) (xy 82.731258 -312.169787)
			(xy 82.708387 -312.213364) (xy 82.678822 -312.252708) (xy 82.643329 -312.2868) (xy 82.602826 -312.314756)
			(xy 82.558364 -312.335854) (xy 82.511093 -312.349546) (xy 82.462238 -312.355478) (xy 82.413063 -312.353497)
			(xy 82.364844 -312.343653) (xy 82.318828 -312.326201) (xy 82.276207 -312.301594) (xy 82.238086 -312.270469)
			(xy 82.205451 -312.233632) (xy 82.179148 -312.192036) (xy 82.159857 -312.14676) (xy 82.14808 -312.098976)
			(xy 82.14412 -312.049922) (xy 81.805272 -312.049922) (xy 81.804777 -312.074529) (xy 81.796882 -312.123106)
			(xy 81.781298 -312.169787) (xy 81.758427 -312.213364) (xy 81.728862 -312.252708) (xy 81.693369 -312.2868)
			(xy 81.652866 -312.314756) (xy 81.608404 -312.335854) (xy 81.561133 -312.349546) (xy 81.512278 -312.355478)
			(xy 81.463103 -312.353497) (xy 81.414884 -312.343653) (xy 81.368868 -312.326201) (xy 81.326247 -312.301594)
			(xy 81.288126 -312.270469) (xy 81.255491 -312.233632) (xy 81.229188 -312.192036) (xy 81.209897 -312.14676)
			(xy 81.19812 -312.098976) (xy 81.19416 -312.049922) (xy 79.905098 -312.049922) (xy 79.904603 -312.074529)
			(xy 79.896708 -312.123106) (xy 79.881124 -312.169787) (xy 79.858253 -312.213364) (xy 79.828688 -312.252708)
			(xy 79.793195 -312.2868) (xy 79.752692 -312.314756) (xy 79.70823 -312.335854) (xy 79.660959 -312.349546)
			(xy 79.612104 -312.355478) (xy 79.562929 -312.353497) (xy 79.51471 -312.343653) (xy 79.468694 -312.326201)
			(xy 79.426073 -312.301594) (xy 79.387952 -312.270469) (xy 79.355317 -312.233632) (xy 79.329014 -312.192036)
			(xy 79.309723 -312.14676) (xy 79.297946 -312.098976) (xy 79.293986 -312.049922) (xy 78.005178 -312.049922)
			(xy 78.004683 -312.074529) (xy 77.996788 -312.123106) (xy 77.981204 -312.169787) (xy 77.958333 -312.213364)
			(xy 77.928768 -312.252708) (xy 77.893275 -312.2868) (xy 77.852772 -312.314756) (xy 77.80831 -312.335854)
			(xy 77.761039 -312.349546) (xy 77.712184 -312.355478) (xy 77.663009 -312.353497) (xy 77.61479 -312.343653)
			(xy 77.568774 -312.326201) (xy 77.526153 -312.301594) (xy 77.488032 -312.270469) (xy 77.455397 -312.233632)
			(xy 77.429094 -312.192036) (xy 77.409803 -312.14676) (xy 77.398026 -312.098976) (xy 77.394066 -312.049922)
			(xy 76.105258 -312.049922) (xy 76.104763 -312.074529) (xy 76.096868 -312.123106) (xy 76.081284 -312.169787)
			(xy 76.058413 -312.213364) (xy 76.028848 -312.252708) (xy 75.993355 -312.2868) (xy 75.952852 -312.314756)
			(xy 75.90839 -312.335854) (xy 75.861119 -312.349546) (xy 75.812264 -312.355478) (xy 75.763089 -312.353497)
			(xy 75.71487 -312.343653) (xy 75.668854 -312.326201) (xy 75.626233 -312.301594) (xy 75.588112 -312.270469)
			(xy 75.555477 -312.233632) (xy 75.529174 -312.192036) (xy 75.509883 -312.14676) (xy 75.498106 -312.098976)
			(xy 75.494146 -312.049922) (xy 74.205084 -312.049922) (xy 74.204589 -312.074529) (xy 74.196694 -312.123106)
			(xy 74.18111 -312.169787) (xy 74.158239 -312.213364) (xy 74.128674 -312.252708) (xy 74.093181 -312.2868)
			(xy 74.052678 -312.314756) (xy 74.008216 -312.335854) (xy 73.960945 -312.349546) (xy 73.91209 -312.355478)
			(xy 73.862915 -312.353497) (xy 73.814696 -312.343653) (xy 73.76868 -312.326201) (xy 73.726059 -312.301594)
			(xy 73.687938 -312.270469) (xy 73.655303 -312.233632) (xy 73.629 -312.192036) (xy 73.609709 -312.14676)
			(xy 73.597932 -312.098976) (xy 73.593972 -312.049922) (xy 72.305164 -312.049922) (xy 72.304669 -312.074529)
			(xy 72.296774 -312.123106) (xy 72.28119 -312.169787) (xy 72.258319 -312.213364) (xy 72.228754 -312.252708)
			(xy 72.193261 -312.2868) (xy 72.152758 -312.314756) (xy 72.108296 -312.335854) (xy 72.061025 -312.349546)
			(xy 72.01217 -312.355478) (xy 71.962995 -312.353497) (xy 71.914776 -312.343653) (xy 71.86876 -312.326201)
			(xy 71.826139 -312.301594) (xy 71.788018 -312.270469) (xy 71.755383 -312.233632) (xy 71.72908 -312.192036)
			(xy 71.709789 -312.14676) (xy 71.698012 -312.098976) (xy 71.694052 -312.049922) (xy 70.405244 -312.049922)
			(xy 70.404749 -312.074529) (xy 70.396854 -312.123106) (xy 70.38127 -312.169787) (xy 70.358399 -312.213364)
			(xy 70.328834 -312.252708) (xy 70.293341 -312.2868) (xy 70.252838 -312.314756) (xy 70.208376 -312.335854)
			(xy 70.161105 -312.349546) (xy 70.11225 -312.355478) (xy 70.063075 -312.353497) (xy 70.014856 -312.343653)
			(xy 69.96884 -312.326201) (xy 69.926219 -312.301594) (xy 69.888098 -312.270469) (xy 69.855463 -312.233632)
			(xy 69.82916 -312.192036) (xy 69.809869 -312.14676) (xy 69.798092 -312.098976) (xy 69.794132 -312.049922)
			(xy 68.50507 -312.049922) (xy 68.504575 -312.074529) (xy 68.49668 -312.123106) (xy 68.481096 -312.169787)
			(xy 68.458225 -312.213364) (xy 68.42866 -312.252708) (xy 68.393167 -312.2868) (xy 68.352664 -312.314756)
			(xy 68.308202 -312.335854) (xy 68.260931 -312.349546) (xy 68.212076 -312.355478) (xy 68.162901 -312.353497)
			(xy 68.114682 -312.343653) (xy 68.068666 -312.326201) (xy 68.026045 -312.301594) (xy 67.987924 -312.270469)
			(xy 67.955289 -312.233632) (xy 67.928986 -312.192036) (xy 67.909695 -312.14676) (xy 67.897918 -312.098976)
			(xy 67.893958 -312.049922) (xy 66.60515 -312.049922) (xy 66.604655 -312.074529) (xy 66.59676 -312.123106)
			(xy 66.581176 -312.169787) (xy 66.558305 -312.213364) (xy 66.52874 -312.252708) (xy 66.493247 -312.2868)
			(xy 66.452744 -312.314756) (xy 66.408282 -312.335854) (xy 66.361011 -312.349546) (xy 66.312156 -312.355478)
			(xy 66.262981 -312.353497) (xy 66.214762 -312.343653) (xy 66.168746 -312.326201) (xy 66.126125 -312.301594)
			(xy 66.088004 -312.270469) (xy 66.055369 -312.233632) (xy 66.029066 -312.192036) (xy 66.009775 -312.14676)
			(xy 65.997998 -312.098976) (xy 65.994038 -312.049922) (xy 64.70523 -312.049922) (xy 64.704735 -312.074529)
			(xy 64.69684 -312.123106) (xy 64.681256 -312.169787) (xy 64.658385 -312.213364) (xy 64.62882 -312.252708)
			(xy 64.593327 -312.2868) (xy 64.552824 -312.314756) (xy 64.508362 -312.335854) (xy 64.461091 -312.349546)
			(xy 64.412236 -312.355478) (xy 64.363061 -312.353497) (xy 64.314842 -312.343653) (xy 64.268826 -312.326201)
			(xy 64.226205 -312.301594) (xy 64.188084 -312.270469) (xy 64.155449 -312.233632) (xy 64.129146 -312.192036)
			(xy 64.109855 -312.14676) (xy 64.098078 -312.098976) (xy 64.094118 -312.049922) (xy 62.805056 -312.049922)
			(xy 62.804561 -312.074529) (xy 62.796666 -312.123106) (xy 62.781082 -312.169787) (xy 62.758211 -312.213364)
			(xy 62.728646 -312.252708) (xy 62.693153 -312.2868) (xy 62.65265 -312.314756) (xy 62.608188 -312.335854)
			(xy 62.560917 -312.349546) (xy 62.512062 -312.355478) (xy 62.462887 -312.353497) (xy 62.414668 -312.343653)
			(xy 62.368652 -312.326201) (xy 62.326031 -312.301594) (xy 62.28791 -312.270469) (xy 62.255275 -312.233632)
			(xy 62.228972 -312.192036) (xy 62.209681 -312.14676) (xy 62.197904 -312.098976) (xy 62.193944 -312.049922)
			(xy 60.905136 -312.049922) (xy 60.904641 -312.074529) (xy 60.896746 -312.123106) (xy 60.881162 -312.169787)
			(xy 60.858291 -312.213364) (xy 60.828726 -312.252708) (xy 60.793233 -312.2868) (xy 60.75273 -312.314756)
			(xy 60.708268 -312.335854) (xy 60.660997 -312.349546) (xy 60.612142 -312.355478) (xy 60.562967 -312.353497)
			(xy 60.514748 -312.343653) (xy 60.468732 -312.326201) (xy 60.426111 -312.301594) (xy 60.38799 -312.270469)
			(xy 60.355355 -312.233632) (xy 60.329052 -312.192036) (xy 60.309761 -312.14676) (xy 60.297984 -312.098976)
			(xy 60.294024 -312.049922) (xy 59.005216 -312.049922) (xy 59.004721 -312.074529) (xy 58.996826 -312.123106)
			(xy 58.981242 -312.169787) (xy 58.958371 -312.213364) (xy 58.928806 -312.252708) (xy 58.893313 -312.2868)
			(xy 58.85281 -312.314756) (xy 58.808348 -312.335854) (xy 58.761077 -312.349546) (xy 58.712222 -312.355478)
			(xy 58.663047 -312.353497) (xy 58.614828 -312.343653) (xy 58.568812 -312.326201) (xy 58.526191 -312.301594)
			(xy 58.48807 -312.270469) (xy 58.455435 -312.233632) (xy 58.429132 -312.192036) (xy 58.409841 -312.14676)
			(xy 58.398064 -312.098976) (xy 58.394104 -312.049922) (xy 57.105296 -312.049922) (xy 57.104801 -312.074529)
			(xy 57.096906 -312.123106) (xy 57.081322 -312.169787) (xy 57.058451 -312.213364) (xy 57.028886 -312.252708)
			(xy 56.993393 -312.2868) (xy 56.95289 -312.314756) (xy 56.908428 -312.335854) (xy 56.861157 -312.349546)
			(xy 56.812302 -312.355478) (xy 56.763127 -312.353497) (xy 56.714908 -312.343653) (xy 56.668892 -312.326201)
			(xy 56.626271 -312.301594) (xy 56.58815 -312.270469) (xy 56.555515 -312.233632) (xy 56.529212 -312.192036)
			(xy 56.509921 -312.14676) (xy 56.498144 -312.098976) (xy 56.494184 -312.049922) (xy 55.205122 -312.049922)
			(xy 55.204627 -312.074529) (xy 55.196732 -312.123106) (xy 55.181148 -312.169787) (xy 55.158277 -312.213364)
			(xy 55.128712 -312.252708) (xy 55.093219 -312.2868) (xy 55.052716 -312.314756) (xy 55.008254 -312.335854)
			(xy 54.960983 -312.349546) (xy 54.912128 -312.355478) (xy 54.862953 -312.353497) (xy 54.814734 -312.343653)
			(xy 54.768718 -312.326201) (xy 54.726097 -312.301594) (xy 54.687976 -312.270469) (xy 54.655341 -312.233632)
			(xy 54.629038 -312.192036) (xy 54.609747 -312.14676) (xy 54.59797 -312.098976) (xy 54.59401 -312.049922)
			(xy 53.305202 -312.049922) (xy 53.304707 -312.074529) (xy 53.296812 -312.123106) (xy 53.281228 -312.169787)
			(xy 53.258357 -312.213364) (xy 53.228792 -312.252708) (xy 53.193299 -312.2868) (xy 53.152796 -312.314756)
			(xy 53.108334 -312.335854) (xy 53.061063 -312.349546) (xy 53.012208 -312.355478) (xy 52.963033 -312.353497)
			(xy 52.914814 -312.343653) (xy 52.868798 -312.326201) (xy 52.826177 -312.301594) (xy 52.788056 -312.270469)
			(xy 52.755421 -312.233632) (xy 52.729118 -312.192036) (xy 52.709827 -312.14676) (xy 52.69805 -312.098976)
			(xy 52.69409 -312.049922) (xy 51.405282 -312.049922) (xy 51.404787 -312.074529) (xy 51.396892 -312.123106)
			(xy 51.381308 -312.169787) (xy 51.358437 -312.213364) (xy 51.328872 -312.252708) (xy 51.293379 -312.2868)
			(xy 51.252876 -312.314756) (xy 51.208414 -312.335854) (xy 51.161143 -312.349546) (xy 51.112288 -312.355478)
			(xy 51.063113 -312.353497) (xy 51.014894 -312.343653) (xy 50.968878 -312.326201) (xy 50.926257 -312.301594)
			(xy 50.888136 -312.270469) (xy 50.855501 -312.233632) (xy 50.829198 -312.192036) (xy 50.809907 -312.14676)
			(xy 50.79813 -312.098976) (xy 50.79417 -312.049922) (xy 49.505108 -312.049922) (xy 49.504613 -312.074529)
			(xy 49.496718 -312.123106) (xy 49.481134 -312.169787) (xy 49.458263 -312.213364) (xy 49.428698 -312.252708)
			(xy 49.393205 -312.2868) (xy 49.352702 -312.314756) (xy 49.30824 -312.335854) (xy 49.260969 -312.349546)
			(xy 49.212114 -312.355478) (xy 49.162939 -312.353497) (xy 49.11472 -312.343653) (xy 49.068704 -312.326201)
			(xy 49.026083 -312.301594) (xy 48.987962 -312.270469) (xy 48.955327 -312.233632) (xy 48.929024 -312.192036)
			(xy 48.909733 -312.14676) (xy 48.897956 -312.098976) (xy 48.893996 -312.049922) (xy 47.605188 -312.049922)
			(xy 47.604693 -312.074529) (xy 47.596798 -312.123106) (xy 47.581214 -312.169787) (xy 47.558343 -312.213364)
			(xy 47.528778 -312.252708) (xy 47.493285 -312.2868) (xy 47.452782 -312.314756) (xy 47.40832 -312.335854)
			(xy 47.361049 -312.349546) (xy 47.312194 -312.355478) (xy 47.263019 -312.353497) (xy 47.2148 -312.343653)
			(xy 47.168784 -312.326201) (xy 47.126163 -312.301594) (xy 47.088042 -312.270469) (xy 47.055407 -312.233632)
			(xy 47.029104 -312.192036) (xy 47.009813 -312.14676) (xy 46.998036 -312.098976) (xy 46.994076 -312.049922)
			(xy 45.705268 -312.049922) (xy 45.704773 -312.074529) (xy 45.696878 -312.123106) (xy 45.681294 -312.169787)
			(xy 45.658423 -312.213364) (xy 45.628858 -312.252708) (xy 45.593365 -312.2868) (xy 45.552862 -312.314756)
			(xy 45.5084 -312.335854) (xy 45.461129 -312.349546) (xy 45.412274 -312.355478) (xy 45.363099 -312.353497)
			(xy 45.31488 -312.343653) (xy 45.268864 -312.326201) (xy 45.226243 -312.301594) (xy 45.188122 -312.270469)
			(xy 45.155487 -312.233632) (xy 45.129184 -312.192036) (xy 45.109893 -312.14676) (xy 45.098116 -312.098976)
			(xy 45.094156 -312.049922) (xy 43.805094 -312.049922) (xy 43.804599 -312.074529) (xy 43.796704 -312.123106)
			(xy 43.78112 -312.169787) (xy 43.758249 -312.213364) (xy 43.728684 -312.252708) (xy 43.693191 -312.2868)
			(xy 43.652688 -312.314756) (xy 43.608226 -312.335854) (xy 43.560955 -312.349546) (xy 43.5121 -312.355478)
			(xy 43.462925 -312.353497) (xy 43.414706 -312.343653) (xy 43.36869 -312.326201) (xy 43.326069 -312.301594)
			(xy 43.287948 -312.270469) (xy 43.255313 -312.233632) (xy 43.22901 -312.192036) (xy 43.209719 -312.14676)
			(xy 43.197942 -312.098976) (xy 43.193982 -312.049922) (xy 41.905174 -312.049922) (xy 41.904679 -312.074529)
			(xy 41.896784 -312.123106) (xy 41.8812 -312.169787) (xy 41.858329 -312.213364) (xy 41.828764 -312.252708)
			(xy 41.793271 -312.2868) (xy 41.752768 -312.314756) (xy 41.708306 -312.335854) (xy 41.661035 -312.349546)
			(xy 41.61218 -312.355478) (xy 41.563005 -312.353497) (xy 41.514786 -312.343653) (xy 41.46877 -312.326201)
			(xy 41.426149 -312.301594) (xy 41.388028 -312.270469) (xy 41.355393 -312.233632) (xy 41.32909 -312.192036)
			(xy 41.309799 -312.14676) (xy 41.298022 -312.098976) (xy 41.294062 -312.049922) (xy 40.005254 -312.049922)
			(xy 40.004759 -312.074529) (xy 39.996864 -312.123106) (xy 39.98128 -312.169787) (xy 39.958409 -312.213364)
			(xy 39.928844 -312.252708) (xy 39.893351 -312.2868) (xy 39.852848 -312.314756) (xy 39.808386 -312.335854)
			(xy 39.761115 -312.349546) (xy 39.71226 -312.355478) (xy 39.663085 -312.353497) (xy 39.614866 -312.343653)
			(xy 39.56885 -312.326201) (xy 39.526229 -312.301594) (xy 39.488108 -312.270469) (xy 39.455473 -312.233632)
			(xy 39.42917 -312.192036) (xy 39.409879 -312.14676) (xy 39.398102 -312.098976) (xy 39.394142 -312.049922)
			(xy 38.10508 -312.049922) (xy 38.104585 -312.074529) (xy 38.09669 -312.123106) (xy 38.081106 -312.169787)
			(xy 38.058235 -312.213364) (xy 38.02867 -312.252708) (xy 37.993177 -312.2868) (xy 37.952674 -312.314756)
			(xy 37.908212 -312.335854) (xy 37.860941 -312.349546) (xy 37.812086 -312.355478) (xy 37.762911 -312.353497)
			(xy 37.714692 -312.343653) (xy 37.668676 -312.326201) (xy 37.626055 -312.301594) (xy 37.587934 -312.270469)
			(xy 37.555299 -312.233632) (xy 37.528996 -312.192036) (xy 37.509705 -312.14676) (xy 37.497928 -312.098976)
			(xy 37.493968 -312.049922) (xy 37.15512 -312.049922) (xy 37.154625 -312.074529) (xy 37.14673 -312.123106)
			(xy 37.131146 -312.169787) (xy 37.108275 -312.213364) (xy 37.07871 -312.252708) (xy 37.043217 -312.2868)
			(xy 37.002714 -312.314756) (xy 36.958252 -312.335854) (xy 36.910981 -312.349546) (xy 36.862126 -312.355478)
			(xy 36.812951 -312.353497) (xy 36.764732 -312.343653) (xy 36.718716 -312.326201) (xy 36.676095 -312.301594)
			(xy 36.637974 -312.270469) (xy 36.605339 -312.233632) (xy 36.579036 -312.192036) (xy 36.559745 -312.14676)
			(xy 36.547968 -312.098976) (xy 36.544008 -312.049922) (xy 0.509016 -312.049922) (xy 0.509016 -312.999882)
			(xy 38.444182 -312.999882) (xy 38.448142 -312.950828) (xy 38.459919 -312.903044) (xy 38.47921 -312.857768)
			(xy 38.505513 -312.816172) (xy 38.538148 -312.779335) (xy 38.576269 -312.74821) (xy 38.61889 -312.723603)
			(xy 38.664906 -312.706151) (xy 38.713125 -312.696307) (xy 38.7623 -312.694326) (xy 38.811155 -312.700258)
			(xy 38.858426 -312.71395) (xy 38.902888 -312.735048) (xy 38.943391 -312.763004) (xy 38.978884 -312.797096)
			(xy 39.008449 -312.83644) (xy 39.03132 -312.880017) (xy 39.046904 -312.926698) (xy 39.054799 -312.975275)
			(xy 39.055294 -312.999882) (xy 40.344102 -312.999882) (xy 40.348062 -312.950828) (xy 40.359839 -312.903044)
			(xy 40.37913 -312.857768) (xy 40.405433 -312.816172) (xy 40.438068 -312.779335) (xy 40.476189 -312.74821)
			(xy 40.51881 -312.723603) (xy 40.564826 -312.706151) (xy 40.613045 -312.696307) (xy 40.66222 -312.694326)
			(xy 40.711075 -312.700258) (xy 40.758346 -312.71395) (xy 40.802808 -312.735048) (xy 40.843311 -312.763004)
			(xy 40.878804 -312.797096) (xy 40.908369 -312.83644) (xy 40.93124 -312.880017) (xy 40.946824 -312.926698)
			(xy 40.954719 -312.975275) (xy 40.955214 -312.999882) (xy 42.244022 -312.999882) (xy 42.247982 -312.950828)
			(xy 42.259759 -312.903044) (xy 42.27905 -312.857768) (xy 42.305353 -312.816172) (xy 42.337988 -312.779335)
			(xy 42.376109 -312.74821) (xy 42.41873 -312.723603) (xy 42.464746 -312.706151) (xy 42.512965 -312.696307)
			(xy 42.56214 -312.694326) (xy 42.610995 -312.700258) (xy 42.658266 -312.71395) (xy 42.702728 -312.735048)
			(xy 42.743231 -312.763004) (xy 42.778724 -312.797096) (xy 42.808289 -312.83644) (xy 42.83116 -312.880017)
			(xy 42.846744 -312.926698) (xy 42.854639 -312.975275) (xy 42.855134 -312.999882) (xy 44.143942 -312.999882)
			(xy 44.147902 -312.950828) (xy 44.159679 -312.903044) (xy 44.17897 -312.857768) (xy 44.205273 -312.816172)
			(xy 44.237908 -312.779335) (xy 44.276029 -312.74821) (xy 44.31865 -312.723603) (xy 44.364666 -312.706151)
			(xy 44.412885 -312.696307) (xy 44.46206 -312.694326) (xy 44.510915 -312.700258) (xy 44.558186 -312.71395)
			(xy 44.602648 -312.735048) (xy 44.643151 -312.763004) (xy 44.678644 -312.797096) (xy 44.708209 -312.83644)
			(xy 44.73108 -312.880017) (xy 44.746664 -312.926698) (xy 44.754559 -312.975275) (xy 44.755054 -312.999882)
			(xy 46.044116 -312.999882) (xy 46.048076 -312.950828) (xy 46.059853 -312.903044) (xy 46.079144 -312.857768)
			(xy 46.105447 -312.816172) (xy 46.138082 -312.779335) (xy 46.176203 -312.74821) (xy 46.218824 -312.723603)
			(xy 46.26484 -312.706151) (xy 46.313059 -312.696307) (xy 46.362234 -312.694326) (xy 46.411089 -312.700258)
			(xy 46.45836 -312.71395) (xy 46.502822 -312.735048) (xy 46.543325 -312.763004) (xy 46.578818 -312.797096)
			(xy 46.608383 -312.83644) (xy 46.631254 -312.880017) (xy 46.646838 -312.926698) (xy 46.654733 -312.975275)
			(xy 46.655228 -312.999882) (xy 47.944036 -312.999882) (xy 47.947996 -312.950828) (xy 47.959773 -312.903044)
			(xy 47.979064 -312.857768) (xy 48.005367 -312.816172) (xy 48.038002 -312.779335) (xy 48.076123 -312.74821)
			(xy 48.118744 -312.723603) (xy 48.16476 -312.706151) (xy 48.212979 -312.696307) (xy 48.262154 -312.694326)
			(xy 48.311009 -312.700258) (xy 48.35828 -312.71395) (xy 48.402742 -312.735048) (xy 48.443245 -312.763004)
			(xy 48.478738 -312.797096) (xy 48.508303 -312.83644) (xy 48.531174 -312.880017) (xy 48.546758 -312.926698)
			(xy 48.554653 -312.975275) (xy 48.555148 -312.999882) (xy 49.843956 -312.999882) (xy 49.847916 -312.950828)
			(xy 49.859693 -312.903044) (xy 49.878984 -312.857768) (xy 49.905287 -312.816172) (xy 49.937922 -312.779335)
			(xy 49.976043 -312.74821) (xy 50.018664 -312.723603) (xy 50.06468 -312.706151) (xy 50.112899 -312.696307)
			(xy 50.162074 -312.694326) (xy 50.210929 -312.700258) (xy 50.2582 -312.71395) (xy 50.302662 -312.735048)
			(xy 50.343165 -312.763004) (xy 50.378658 -312.797096) (xy 50.408223 -312.83644) (xy 50.431094 -312.880017)
			(xy 50.446678 -312.926698) (xy 50.454573 -312.975275) (xy 50.455068 -312.999882) (xy 51.74413 -312.999882)
			(xy 51.74809 -312.950828) (xy 51.759867 -312.903044) (xy 51.779158 -312.857768) (xy 51.805461 -312.816172)
			(xy 51.838096 -312.779335) (xy 51.876217 -312.74821) (xy 51.918838 -312.723603) (xy 51.964854 -312.706151)
			(xy 52.013073 -312.696307) (xy 52.062248 -312.694326) (xy 52.111103 -312.700258) (xy 52.158374 -312.71395)
			(xy 52.202836 -312.735048) (xy 52.243339 -312.763004) (xy 52.278832 -312.797096) (xy 52.308397 -312.83644)
			(xy 52.331268 -312.880017) (xy 52.346852 -312.926698) (xy 52.354747 -312.975275) (xy 52.355242 -312.999882)
			(xy 53.64405 -312.999882) (xy 53.64801 -312.950828) (xy 53.659787 -312.903044) (xy 53.679078 -312.857768)
			(xy 53.705381 -312.816172) (xy 53.738016 -312.779335) (xy 53.776137 -312.74821) (xy 53.818758 -312.723603)
			(xy 53.864774 -312.706151) (xy 53.912993 -312.696307) (xy 53.962168 -312.694326) (xy 54.011023 -312.700258)
			(xy 54.058294 -312.71395) (xy 54.102756 -312.735048) (xy 54.143259 -312.763004) (xy 54.178752 -312.797096)
			(xy 54.208317 -312.83644) (xy 54.231188 -312.880017) (xy 54.246772 -312.926698) (xy 54.254667 -312.975275)
			(xy 54.255162 -312.999882) (xy 55.54397 -312.999882) (xy 55.54793 -312.950828) (xy 55.559707 -312.903044)
			(xy 55.578998 -312.857768) (xy 55.605301 -312.816172) (xy 55.637936 -312.779335) (xy 55.676057 -312.74821)
			(xy 55.718678 -312.723603) (xy 55.764694 -312.706151) (xy 55.812913 -312.696307) (xy 55.862088 -312.694326)
			(xy 55.910943 -312.700258) (xy 55.958214 -312.71395) (xy 56.002676 -312.735048) (xy 56.043179 -312.763004)
			(xy 56.078672 -312.797096) (xy 56.108237 -312.83644) (xy 56.131108 -312.880017) (xy 56.146692 -312.926698)
			(xy 56.154587 -312.975275) (xy 56.155082 -312.999882) (xy 57.444144 -312.999882) (xy 57.448104 -312.950828)
			(xy 57.459881 -312.903044) (xy 57.479172 -312.857768) (xy 57.505475 -312.816172) (xy 57.53811 -312.779335)
			(xy 57.576231 -312.74821) (xy 57.618852 -312.723603) (xy 57.664868 -312.706151) (xy 57.713087 -312.696307)
			(xy 57.762262 -312.694326) (xy 57.811117 -312.700258) (xy 57.858388 -312.71395) (xy 57.90285 -312.735048)
			(xy 57.943353 -312.763004) (xy 57.978846 -312.797096) (xy 58.008411 -312.83644) (xy 58.031282 -312.880017)
			(xy 58.046866 -312.926698) (xy 58.054761 -312.975275) (xy 58.055256 -312.999882) (xy 59.344064 -312.999882)
			(xy 59.348024 -312.950828) (xy 59.359801 -312.903044) (xy 59.379092 -312.857768) (xy 59.405395 -312.816172)
			(xy 59.43803 -312.779335) (xy 59.476151 -312.74821) (xy 59.518772 -312.723603) (xy 59.564788 -312.706151)
			(xy 59.613007 -312.696307) (xy 59.662182 -312.694326) (xy 59.711037 -312.700258) (xy 59.758308 -312.71395)
			(xy 59.80277 -312.735048) (xy 59.843273 -312.763004) (xy 59.878766 -312.797096) (xy 59.908331 -312.83644)
			(xy 59.931202 -312.880017) (xy 59.946786 -312.926698) (xy 59.954681 -312.975275) (xy 59.955176 -312.999882)
			(xy 61.243984 -312.999882) (xy 61.247944 -312.950828) (xy 61.259721 -312.903044) (xy 61.279012 -312.857768)
			(xy 61.305315 -312.816172) (xy 61.33795 -312.779335) (xy 61.376071 -312.74821) (xy 61.418692 -312.723603)
			(xy 61.464708 -312.706151) (xy 61.512927 -312.696307) (xy 61.562102 -312.694326) (xy 61.610957 -312.700258)
			(xy 61.658228 -312.71395) (xy 61.70269 -312.735048) (xy 61.743193 -312.763004) (xy 61.778686 -312.797096)
			(xy 61.808251 -312.83644) (xy 61.831122 -312.880017) (xy 61.846706 -312.926698) (xy 61.854601 -312.975275)
			(xy 61.855096 -312.999882) (xy 63.144158 -312.999882) (xy 63.148118 -312.950828) (xy 63.159895 -312.903044)
			(xy 63.179186 -312.857768) (xy 63.205489 -312.816172) (xy 63.238124 -312.779335) (xy 63.276245 -312.74821)
			(xy 63.318866 -312.723603) (xy 63.364882 -312.706151) (xy 63.413101 -312.696307) (xy 63.462276 -312.694326)
			(xy 63.511131 -312.700258) (xy 63.558402 -312.71395) (xy 63.602864 -312.735048) (xy 63.643367 -312.763004)
			(xy 63.67886 -312.797096) (xy 63.708425 -312.83644) (xy 63.731296 -312.880017) (xy 63.74688 -312.926698)
			(xy 63.754775 -312.975275) (xy 63.75527 -312.999882) (xy 65.044078 -312.999882) (xy 65.048038 -312.950828)
			(xy 65.059815 -312.903044) (xy 65.079106 -312.857768) (xy 65.105409 -312.816172) (xy 65.138044 -312.779335)
			(xy 65.176165 -312.74821) (xy 65.218786 -312.723603) (xy 65.264802 -312.706151) (xy 65.313021 -312.696307)
			(xy 65.362196 -312.694326) (xy 65.411051 -312.700258) (xy 65.458322 -312.71395) (xy 65.502784 -312.735048)
			(xy 65.543287 -312.763004) (xy 65.57878 -312.797096) (xy 65.608345 -312.83644) (xy 65.631216 -312.880017)
			(xy 65.6468 -312.926698) (xy 65.654695 -312.975275) (xy 65.65519 -312.999882) (xy 66.943998 -312.999882)
			(xy 66.947958 -312.950828) (xy 66.959735 -312.903044) (xy 66.979026 -312.857768) (xy 67.005329 -312.816172)
			(xy 67.037964 -312.779335) (xy 67.076085 -312.74821) (xy 67.118706 -312.723603) (xy 67.164722 -312.706151)
			(xy 67.212941 -312.696307) (xy 67.262116 -312.694326) (xy 67.310971 -312.700258) (xy 67.358242 -312.71395)
			(xy 67.402704 -312.735048) (xy 67.443207 -312.763004) (xy 67.4787 -312.797096) (xy 67.508265 -312.83644)
			(xy 67.531136 -312.880017) (xy 67.54672 -312.926698) (xy 67.554615 -312.975275) (xy 67.55511 -312.999882)
			(xy 68.844172 -312.999882) (xy 68.848132 -312.950828) (xy 68.859909 -312.903044) (xy 68.8792 -312.857768)
			(xy 68.905503 -312.816172) (xy 68.938138 -312.779335) (xy 68.976259 -312.74821) (xy 69.01888 -312.723603)
			(xy 69.064896 -312.706151) (xy 69.113115 -312.696307) (xy 69.16229 -312.694326) (xy 69.211145 -312.700258)
			(xy 69.258416 -312.71395) (xy 69.302878 -312.735048) (xy 69.343381 -312.763004) (xy 69.378874 -312.797096)
			(xy 69.408439 -312.83644) (xy 69.43131 -312.880017) (xy 69.446894 -312.926698) (xy 69.454789 -312.975275)
			(xy 69.455284 -312.999882) (xy 70.744092 -312.999882) (xy 70.748052 -312.950828) (xy 70.759829 -312.903044)
			(xy 70.77912 -312.857768) (xy 70.805423 -312.816172) (xy 70.838058 -312.779335) (xy 70.876179 -312.74821)
			(xy 70.9188 -312.723603) (xy 70.964816 -312.706151) (xy 71.013035 -312.696307) (xy 71.06221 -312.694326)
			(xy 71.111065 -312.700258) (xy 71.158336 -312.71395) (xy 71.202798 -312.735048) (xy 71.243301 -312.763004)
			(xy 71.278794 -312.797096) (xy 71.308359 -312.83644) (xy 71.33123 -312.880017) (xy 71.346814 -312.926698)
			(xy 71.354709 -312.975275) (xy 71.355204 -312.999882) (xy 72.644012 -312.999882) (xy 72.647972 -312.950828)
			(xy 72.659749 -312.903044) (xy 72.67904 -312.857768) (xy 72.705343 -312.816172) (xy 72.737978 -312.779335)
			(xy 72.776099 -312.74821) (xy 72.81872 -312.723603) (xy 72.864736 -312.706151) (xy 72.912955 -312.696307)
			(xy 72.96213 -312.694326) (xy 73.010985 -312.700258) (xy 73.058256 -312.71395) (xy 73.102718 -312.735048)
			(xy 73.143221 -312.763004) (xy 73.178714 -312.797096) (xy 73.208279 -312.83644) (xy 73.23115 -312.880017)
			(xy 73.246734 -312.926698) (xy 73.254629 -312.975275) (xy 73.255124 -312.999882) (xy 74.544186 -312.999882)
			(xy 74.548146 -312.950828) (xy 74.559923 -312.903044) (xy 74.579214 -312.857768) (xy 74.605517 -312.816172)
			(xy 74.638152 -312.779335) (xy 74.676273 -312.74821) (xy 74.718894 -312.723603) (xy 74.76491 -312.706151)
			(xy 74.813129 -312.696307) (xy 74.862304 -312.694326) (xy 74.911159 -312.700258) (xy 74.95843 -312.71395)
			(xy 75.002892 -312.735048) (xy 75.043395 -312.763004) (xy 75.078888 -312.797096) (xy 75.108453 -312.83644)
			(xy 75.131324 -312.880017) (xy 75.146908 -312.926698) (xy 75.154803 -312.975275) (xy 75.155298 -312.999882)
			(xy 76.444106 -312.999882) (xy 76.448066 -312.950828) (xy 76.459843 -312.903044) (xy 76.479134 -312.857768)
			(xy 76.505437 -312.816172) (xy 76.538072 -312.779335) (xy 76.576193 -312.74821) (xy 76.618814 -312.723603)
			(xy 76.66483 -312.706151) (xy 76.713049 -312.696307) (xy 76.762224 -312.694326) (xy 76.811079 -312.700258)
			(xy 76.85835 -312.71395) (xy 76.902812 -312.735048) (xy 76.943315 -312.763004) (xy 76.978808 -312.797096)
			(xy 77.008373 -312.83644) (xy 77.031244 -312.880017) (xy 77.046828 -312.926698) (xy 77.054723 -312.975275)
			(xy 77.055218 -312.999882) (xy 78.344026 -312.999882) (xy 78.347986 -312.950828) (xy 78.359763 -312.903044)
			(xy 78.379054 -312.857768) (xy 78.405357 -312.816172) (xy 78.437992 -312.779335) (xy 78.476113 -312.74821)
			(xy 78.518734 -312.723603) (xy 78.56475 -312.706151) (xy 78.612969 -312.696307) (xy 78.662144 -312.694326)
			(xy 78.710999 -312.700258) (xy 78.75827 -312.71395) (xy 78.802732 -312.735048) (xy 78.843235 -312.763004)
			(xy 78.878728 -312.797096) (xy 78.908293 -312.83644) (xy 78.931164 -312.880017) (xy 78.946748 -312.926698)
			(xy 78.954643 -312.975275) (xy 78.955138 -312.999882) (xy 80.243946 -312.999882) (xy 80.247906 -312.950828)
			(xy 80.259683 -312.903044) (xy 80.278974 -312.857768) (xy 80.305277 -312.816172) (xy 80.337912 -312.779335)
			(xy 80.376033 -312.74821) (xy 80.418654 -312.723603) (xy 80.46467 -312.706151) (xy 80.512889 -312.696307)
			(xy 80.562064 -312.694326) (xy 80.610919 -312.700258) (xy 80.65819 -312.71395) (xy 80.702652 -312.735048)
			(xy 80.743155 -312.763004) (xy 80.778648 -312.797096) (xy 80.808213 -312.83644) (xy 80.831084 -312.880017)
			(xy 80.846668 -312.926698) (xy 80.854563 -312.975275) (xy 80.855058 -312.999882) (xy 154.54428 -312.999882)
			(xy 154.54824 -312.950828) (xy 154.560017 -312.903044) (xy 154.579308 -312.857768) (xy 154.605611 -312.816172)
			(xy 154.638246 -312.779335) (xy 154.676367 -312.74821) (xy 154.718988 -312.723603) (xy 154.765004 -312.706151)
			(xy 154.813223 -312.696307) (xy 154.862398 -312.694326) (xy 154.911253 -312.700258) (xy 154.958524 -312.71395)
			(xy 155.002986 -312.735048) (xy 155.043489 -312.763004) (xy 155.078982 -312.797096) (xy 155.108547 -312.83644)
			(xy 155.131418 -312.880017) (xy 155.147002 -312.926698) (xy 155.154897 -312.975275) (xy 155.155392 -312.999882)
			(xy 156.4442 -312.999882) (xy 156.44816 -312.950828) (xy 156.459937 -312.903044) (xy 156.479228 -312.857768)
			(xy 156.505531 -312.816172) (xy 156.538166 -312.779335) (xy 156.576287 -312.74821) (xy 156.618908 -312.723603)
			(xy 156.664924 -312.706151) (xy 156.713143 -312.696307) (xy 156.762318 -312.694326) (xy 156.811173 -312.700258)
			(xy 156.858444 -312.71395) (xy 156.902906 -312.735048) (xy 156.943409 -312.763004) (xy 156.978902 -312.797096)
			(xy 157.008467 -312.83644) (xy 157.031338 -312.880017) (xy 157.046922 -312.926698) (xy 157.054817 -312.975275)
			(xy 157.055312 -312.999882) (xy 158.34412 -312.999882) (xy 158.34808 -312.950828) (xy 158.359857 -312.903044)
			(xy 158.379148 -312.857768) (xy 158.405451 -312.816172) (xy 158.438086 -312.779335) (xy 158.476207 -312.74821)
			(xy 158.518828 -312.723603) (xy 158.564844 -312.706151) (xy 158.613063 -312.696307) (xy 158.662238 -312.694326)
			(xy 158.711093 -312.700258) (xy 158.758364 -312.71395) (xy 158.802826 -312.735048) (xy 158.843329 -312.763004)
			(xy 158.878822 -312.797096) (xy 158.908387 -312.83644) (xy 158.931258 -312.880017) (xy 158.946842 -312.926698)
			(xy 158.954737 -312.975275) (xy 158.955232 -312.999882) (xy 160.24404 -312.999882) (xy 160.248 -312.950828)
			(xy 160.259777 -312.903044) (xy 160.279068 -312.857768) (xy 160.305371 -312.816172) (xy 160.338006 -312.779335)
			(xy 160.376127 -312.74821) (xy 160.418748 -312.723603) (xy 160.464764 -312.706151) (xy 160.512983 -312.696307)
			(xy 160.562158 -312.694326) (xy 160.611013 -312.700258) (xy 160.658284 -312.71395) (xy 160.702746 -312.735048)
			(xy 160.743249 -312.763004) (xy 160.778742 -312.797096) (xy 160.808307 -312.83644) (xy 160.831178 -312.880017)
			(xy 160.846762 -312.926698) (xy 160.854657 -312.975275) (xy 160.855152 -312.999882) (xy 162.144214 -312.999882)
			(xy 162.148174 -312.950828) (xy 162.159951 -312.903044) (xy 162.179242 -312.857768) (xy 162.205545 -312.816172)
			(xy 162.23818 -312.779335) (xy 162.276301 -312.74821) (xy 162.318922 -312.723603) (xy 162.364938 -312.706151)
			(xy 162.413157 -312.696307) (xy 162.462332 -312.694326) (xy 162.511187 -312.700258) (xy 162.558458 -312.71395)
			(xy 162.60292 -312.735048) (xy 162.643423 -312.763004) (xy 162.678916 -312.797096) (xy 162.708481 -312.83644)
			(xy 162.731352 -312.880017) (xy 162.746936 -312.926698) (xy 162.754831 -312.975275) (xy 162.755326 -312.999882)
			(xy 164.044134 -312.999882) (xy 164.048094 -312.950828) (xy 164.059871 -312.903044) (xy 164.079162 -312.857768)
			(xy 164.105465 -312.816172) (xy 164.1381 -312.779335) (xy 164.176221 -312.74821) (xy 164.218842 -312.723603)
			(xy 164.264858 -312.706151) (xy 164.313077 -312.696307) (xy 164.362252 -312.694326) (xy 164.411107 -312.700258)
			(xy 164.458378 -312.71395) (xy 164.50284 -312.735048) (xy 164.543343 -312.763004) (xy 164.578836 -312.797096)
			(xy 164.608401 -312.83644) (xy 164.631272 -312.880017) (xy 164.646856 -312.926698) (xy 164.654751 -312.975275)
			(xy 164.655246 -312.999882) (xy 165.944054 -312.999882) (xy 165.948014 -312.950828) (xy 165.959791 -312.903044)
			(xy 165.979082 -312.857768) (xy 166.005385 -312.816172) (xy 166.03802 -312.779335) (xy 166.076141 -312.74821)
			(xy 166.118762 -312.723603) (xy 166.164778 -312.706151) (xy 166.212997 -312.696307) (xy 166.262172 -312.694326)
			(xy 166.311027 -312.700258) (xy 166.358298 -312.71395) (xy 166.40276 -312.735048) (xy 166.443263 -312.763004)
			(xy 166.478756 -312.797096) (xy 166.508321 -312.83644) (xy 166.531192 -312.880017) (xy 166.546776 -312.926698)
			(xy 166.554671 -312.975275) (xy 166.555166 -312.999882) (xy 167.844228 -312.999882) (xy 167.848188 -312.950828)
			(xy 167.859965 -312.903044) (xy 167.879256 -312.857768) (xy 167.905559 -312.816172) (xy 167.938194 -312.779335)
			(xy 167.976315 -312.74821) (xy 168.018936 -312.723603) (xy 168.064952 -312.706151) (xy 168.113171 -312.696307)
			(xy 168.162346 -312.694326) (xy 168.211201 -312.700258) (xy 168.258472 -312.71395) (xy 168.302934 -312.735048)
			(xy 168.343437 -312.763004) (xy 168.37893 -312.797096) (xy 168.408495 -312.83644) (xy 168.431366 -312.880017)
			(xy 168.44695 -312.926698) (xy 168.454845 -312.975275) (xy 168.45534 -312.999882) (xy 169.744148 -312.999882)
			(xy 169.748108 -312.950828) (xy 169.759885 -312.903044) (xy 169.779176 -312.857768) (xy 169.805479 -312.816172)
			(xy 169.838114 -312.779335) (xy 169.876235 -312.74821) (xy 169.918856 -312.723603) (xy 169.964872 -312.706151)
			(xy 170.013091 -312.696307) (xy 170.062266 -312.694326) (xy 170.111121 -312.700258) (xy 170.158392 -312.71395)
			(xy 170.202854 -312.735048) (xy 170.243357 -312.763004) (xy 170.27885 -312.797096) (xy 170.308415 -312.83644)
			(xy 170.331286 -312.880017) (xy 170.34687 -312.926698) (xy 170.354765 -312.975275) (xy 170.35526 -312.999882)
			(xy 171.644068 -312.999882) (xy 171.648028 -312.950828) (xy 171.659805 -312.903044) (xy 171.679096 -312.857768)
			(xy 171.705399 -312.816172) (xy 171.738034 -312.779335) (xy 171.776155 -312.74821) (xy 171.818776 -312.723603)
			(xy 171.864792 -312.706151) (xy 171.913011 -312.696307) (xy 171.962186 -312.694326) (xy 172.011041 -312.700258)
			(xy 172.058312 -312.71395) (xy 172.102774 -312.735048) (xy 172.143277 -312.763004) (xy 172.17877 -312.797096)
			(xy 172.208335 -312.83644) (xy 172.231206 -312.880017) (xy 172.24679 -312.926698) (xy 172.254685 -312.975275)
			(xy 172.25518 -312.999882) (xy 173.544242 -312.999882) (xy 173.548202 -312.950828) (xy 173.559979 -312.903044)
			(xy 173.57927 -312.857768) (xy 173.605573 -312.816172) (xy 173.638208 -312.779335) (xy 173.676329 -312.74821)
			(xy 173.71895 -312.723603) (xy 173.764966 -312.706151) (xy 173.813185 -312.696307) (xy 173.86236 -312.694326)
			(xy 173.911215 -312.700258) (xy 173.958486 -312.71395) (xy 174.002948 -312.735048) (xy 174.043451 -312.763004)
			(xy 174.078944 -312.797096) (xy 174.108509 -312.83644) (xy 174.13138 -312.880017) (xy 174.146964 -312.926698)
			(xy 174.154859 -312.975275) (xy 174.155354 -312.999882) (xy 175.444162 -312.999882) (xy 175.448122 -312.950828)
			(xy 175.459899 -312.903044) (xy 175.47919 -312.857768) (xy 175.505493 -312.816172) (xy 175.538128 -312.779335)
			(xy 175.576249 -312.74821) (xy 175.61887 -312.723603) (xy 175.664886 -312.706151) (xy 175.713105 -312.696307)
			(xy 175.76228 -312.694326) (xy 175.811135 -312.700258) (xy 175.858406 -312.71395) (xy 175.902868 -312.735048)
			(xy 175.943371 -312.763004) (xy 175.978864 -312.797096) (xy 176.008429 -312.83644) (xy 176.0313 -312.880017)
			(xy 176.046884 -312.926698) (xy 176.054779 -312.975275) (xy 176.055274 -312.999882) (xy 177.344082 -312.999882)
			(xy 177.348042 -312.950828) (xy 177.359819 -312.903044) (xy 177.37911 -312.857768) (xy 177.405413 -312.816172)
			(xy 177.438048 -312.779335) (xy 177.476169 -312.74821) (xy 177.51879 -312.723603) (xy 177.564806 -312.706151)
			(xy 177.613025 -312.696307) (xy 177.6622 -312.694326) (xy 177.711055 -312.700258) (xy 177.758326 -312.71395)
			(xy 177.802788 -312.735048) (xy 177.843291 -312.763004) (xy 177.878784 -312.797096) (xy 177.908349 -312.83644)
			(xy 177.93122 -312.880017) (xy 177.946804 -312.926698) (xy 177.954699 -312.975275) (xy 177.955194 -312.999882)
			(xy 179.244256 -312.999882) (xy 179.248216 -312.950828) (xy 179.259993 -312.903044) (xy 179.279284 -312.857768)
			(xy 179.305587 -312.816172) (xy 179.338222 -312.779335) (xy 179.376343 -312.74821) (xy 179.418964 -312.723603)
			(xy 179.46498 -312.706151) (xy 179.513199 -312.696307) (xy 179.562374 -312.694326) (xy 179.611229 -312.700258)
			(xy 179.6585 -312.71395) (xy 179.702962 -312.735048) (xy 179.743465 -312.763004) (xy 179.778958 -312.797096)
			(xy 179.808523 -312.83644) (xy 179.831394 -312.880017) (xy 179.846978 -312.926698) (xy 179.854873 -312.975275)
			(xy 179.855368 -312.999882) (xy 181.144176 -312.999882) (xy 181.148136 -312.950828) (xy 181.159913 -312.903044)
			(xy 181.179204 -312.857768) (xy 181.205507 -312.816172) (xy 181.238142 -312.779335) (xy 181.276263 -312.74821)
			(xy 181.318884 -312.723603) (xy 181.3649 -312.706151) (xy 181.413119 -312.696307) (xy 181.462294 -312.694326)
			(xy 181.511149 -312.700258) (xy 181.55842 -312.71395) (xy 181.602882 -312.735048) (xy 181.643385 -312.763004)
			(xy 181.678878 -312.797096) (xy 181.708443 -312.83644) (xy 181.731314 -312.880017) (xy 181.746898 -312.926698)
			(xy 181.754793 -312.975275) (xy 181.755288 -312.999882) (xy 183.044096 -312.999882) (xy 183.048056 -312.950828)
			(xy 183.059833 -312.903044) (xy 183.079124 -312.857768) (xy 183.105427 -312.816172) (xy 183.138062 -312.779335)
			(xy 183.176183 -312.74821) (xy 183.218804 -312.723603) (xy 183.26482 -312.706151) (xy 183.313039 -312.696307)
			(xy 183.362214 -312.694326) (xy 183.411069 -312.700258) (xy 183.45834 -312.71395) (xy 183.502802 -312.735048)
			(xy 183.543305 -312.763004) (xy 183.578798 -312.797096) (xy 183.608363 -312.83644) (xy 183.631234 -312.880017)
			(xy 183.646818 -312.926698) (xy 183.654713 -312.975275) (xy 183.655208 -312.999882) (xy 184.94427 -312.999882)
			(xy 184.94823 -312.950828) (xy 184.960007 -312.903044) (xy 184.979298 -312.857768) (xy 185.005601 -312.816172)
			(xy 185.038236 -312.779335) (xy 185.076357 -312.74821) (xy 185.118978 -312.723603) (xy 185.164994 -312.706151)
			(xy 185.213213 -312.696307) (xy 185.262388 -312.694326) (xy 185.311243 -312.700258) (xy 185.358514 -312.71395)
			(xy 185.402976 -312.735048) (xy 185.443479 -312.763004) (xy 185.478972 -312.797096) (xy 185.508537 -312.83644)
			(xy 185.531408 -312.880017) (xy 185.546992 -312.926698) (xy 185.554887 -312.975275) (xy 185.555382 -312.999882)
			(xy 186.84419 -312.999882) (xy 186.84815 -312.950828) (xy 186.859927 -312.903044) (xy 186.879218 -312.857768)
			(xy 186.905521 -312.816172) (xy 186.938156 -312.779335) (xy 186.976277 -312.74821) (xy 187.018898 -312.723603)
			(xy 187.064914 -312.706151) (xy 187.113133 -312.696307) (xy 187.162308 -312.694326) (xy 187.211163 -312.700258)
			(xy 187.258434 -312.71395) (xy 187.302896 -312.735048) (xy 187.343399 -312.763004) (xy 187.378892 -312.797096)
			(xy 187.408457 -312.83644) (xy 187.431328 -312.880017) (xy 187.446912 -312.926698) (xy 187.454807 -312.975275)
			(xy 187.455302 -312.999882) (xy 188.74411 -312.999882) (xy 188.74807 -312.950828) (xy 188.759847 -312.903044)
			(xy 188.779138 -312.857768) (xy 188.805441 -312.816172) (xy 188.838076 -312.779335) (xy 188.876197 -312.74821)
			(xy 188.918818 -312.723603) (xy 188.964834 -312.706151) (xy 189.013053 -312.696307) (xy 189.062228 -312.694326)
			(xy 189.111083 -312.700258) (xy 189.158354 -312.71395) (xy 189.202816 -312.735048) (xy 189.243319 -312.763004)
			(xy 189.278812 -312.797096) (xy 189.308377 -312.83644) (xy 189.331248 -312.880017) (xy 189.346832 -312.926698)
			(xy 189.354727 -312.975275) (xy 189.355222 -312.999882) (xy 190.644284 -312.999882) (xy 190.648244 -312.950828)
			(xy 190.660021 -312.903044) (xy 190.679312 -312.857768) (xy 190.705615 -312.816172) (xy 190.73825 -312.779335)
			(xy 190.776371 -312.74821) (xy 190.818992 -312.723603) (xy 190.865008 -312.706151) (xy 190.913227 -312.696307)
			(xy 190.962402 -312.694326) (xy 191.011257 -312.700258) (xy 191.058528 -312.71395) (xy 191.10299 -312.735048)
			(xy 191.143493 -312.763004) (xy 191.178986 -312.797096) (xy 191.208551 -312.83644) (xy 191.231422 -312.880017)
			(xy 191.247006 -312.926698) (xy 191.254901 -312.975275) (xy 191.255396 -312.999882) (xy 192.544204 -312.999882)
			(xy 192.548164 -312.950828) (xy 192.559941 -312.903044) (xy 192.579232 -312.857768) (xy 192.605535 -312.816172)
			(xy 192.63817 -312.779335) (xy 192.676291 -312.74821) (xy 192.718912 -312.723603) (xy 192.764928 -312.706151)
			(xy 192.813147 -312.696307) (xy 192.862322 -312.694326) (xy 192.911177 -312.700258) (xy 192.958448 -312.71395)
			(xy 193.00291 -312.735048) (xy 193.043413 -312.763004) (xy 193.078906 -312.797096) (xy 193.108471 -312.83644)
			(xy 193.131342 -312.880017) (xy 193.146926 -312.926698) (xy 193.154821 -312.975275) (xy 193.155316 -312.999882)
			(xy 194.444124 -312.999882) (xy 194.448084 -312.950828) (xy 194.459861 -312.903044) (xy 194.479152 -312.857768)
			(xy 194.505455 -312.816172) (xy 194.53809 -312.779335) (xy 194.576211 -312.74821) (xy 194.618832 -312.723603)
			(xy 194.664848 -312.706151) (xy 194.713067 -312.696307) (xy 194.762242 -312.694326) (xy 194.811097 -312.700258)
			(xy 194.858368 -312.71395) (xy 194.90283 -312.735048) (xy 194.943333 -312.763004) (xy 194.978826 -312.797096)
			(xy 195.008391 -312.83644) (xy 195.031262 -312.880017) (xy 195.046846 -312.926698) (xy 195.054741 -312.975275)
			(xy 195.055236 -312.999882) (xy 196.344044 -312.999882) (xy 196.348004 -312.950828) (xy 196.359781 -312.903044)
			(xy 196.379072 -312.857768) (xy 196.405375 -312.816172) (xy 196.43801 -312.779335) (xy 196.476131 -312.74821)
			(xy 196.518752 -312.723603) (xy 196.564768 -312.706151) (xy 196.612987 -312.696307) (xy 196.662162 -312.694326)
			(xy 196.711017 -312.700258) (xy 196.758288 -312.71395) (xy 196.80275 -312.735048) (xy 196.843253 -312.763004)
			(xy 196.878746 -312.797096) (xy 196.908311 -312.83644) (xy 196.931182 -312.880017) (xy 196.946766 -312.926698)
			(xy 196.954661 -312.975275) (xy 196.955156 -312.999882) (xy 270.644124 -312.999882) (xy 270.648084 -312.950828)
			(xy 270.659861 -312.903044) (xy 270.679152 -312.857768) (xy 270.705455 -312.816172) (xy 270.73809 -312.779335)
			(xy 270.776211 -312.74821) (xy 270.818832 -312.723603) (xy 270.864848 -312.706151) (xy 270.913067 -312.696307)
			(xy 270.962242 -312.694326) (xy 271.011097 -312.700258) (xy 271.058368 -312.71395) (xy 271.10283 -312.735048)
			(xy 271.143333 -312.763004) (xy 271.178826 -312.797096) (xy 271.208391 -312.83644) (xy 271.231262 -312.880017)
			(xy 271.246846 -312.926698) (xy 271.254741 -312.975275) (xy 271.255236 -312.999882) (xy 272.544044 -312.999882)
			(xy 272.548004 -312.950828) (xy 272.559781 -312.903044) (xy 272.579072 -312.857768) (xy 272.605375 -312.816172)
			(xy 272.63801 -312.779335) (xy 272.676131 -312.74821) (xy 272.718752 -312.723603) (xy 272.764768 -312.706151)
			(xy 272.812987 -312.696307) (xy 272.862162 -312.694326) (xy 272.911017 -312.700258) (xy 272.958288 -312.71395)
			(xy 273.00275 -312.735048) (xy 273.043253 -312.763004) (xy 273.078746 -312.797096) (xy 273.108311 -312.83644)
			(xy 273.131182 -312.880017) (xy 273.146766 -312.926698) (xy 273.154661 -312.975275) (xy 273.155156 -312.999882)
			(xy 274.443964 -312.999882) (xy 274.447924 -312.950828) (xy 274.459701 -312.903044) (xy 274.478992 -312.857768)
			(xy 274.505295 -312.816172) (xy 274.53793 -312.779335) (xy 274.576051 -312.74821) (xy 274.618672 -312.723603)
			(xy 274.664688 -312.706151) (xy 274.712907 -312.696307) (xy 274.762082 -312.694326) (xy 274.810937 -312.700258)
			(xy 274.858208 -312.71395) (xy 274.90267 -312.735048) (xy 274.943173 -312.763004) (xy 274.978666 -312.797096)
			(xy 275.008231 -312.83644) (xy 275.031102 -312.880017) (xy 275.046686 -312.926698) (xy 275.054581 -312.975275)
			(xy 275.055076 -312.999882) (xy 276.343884 -312.999882) (xy 276.347844 -312.950828) (xy 276.359621 -312.903044)
			(xy 276.378912 -312.857768) (xy 276.405215 -312.816172) (xy 276.43785 -312.779335) (xy 276.475971 -312.74821)
			(xy 276.518592 -312.723603) (xy 276.564608 -312.706151) (xy 276.612827 -312.696307) (xy 276.662002 -312.694326)
			(xy 276.710857 -312.700258) (xy 276.758128 -312.71395) (xy 276.80259 -312.735048) (xy 276.843093 -312.763004)
			(xy 276.878586 -312.797096) (xy 276.908151 -312.83644) (xy 276.931022 -312.880017) (xy 276.946606 -312.926698)
			(xy 276.954501 -312.975275) (xy 276.954996 -312.999882) (xy 278.244058 -312.999882) (xy 278.248018 -312.950828)
			(xy 278.259795 -312.903044) (xy 278.279086 -312.857768) (xy 278.305389 -312.816172) (xy 278.338024 -312.779335)
			(xy 278.376145 -312.74821) (xy 278.418766 -312.723603) (xy 278.464782 -312.706151) (xy 278.513001 -312.696307)
			(xy 278.562176 -312.694326) (xy 278.611031 -312.700258) (xy 278.658302 -312.71395) (xy 278.702764 -312.735048)
			(xy 278.743267 -312.763004) (xy 278.77876 -312.797096) (xy 278.808325 -312.83644) (xy 278.831196 -312.880017)
			(xy 278.84678 -312.926698) (xy 278.854675 -312.975275) (xy 278.85517 -312.999882) (xy 280.143978 -312.999882)
			(xy 280.147938 -312.950828) (xy 280.159715 -312.903044) (xy 280.179006 -312.857768) (xy 280.205309 -312.816172)
			(xy 280.237944 -312.779335) (xy 280.276065 -312.74821) (xy 280.318686 -312.723603) (xy 280.364702 -312.706151)
			(xy 280.412921 -312.696307) (xy 280.462096 -312.694326) (xy 280.510951 -312.700258) (xy 280.558222 -312.71395)
			(xy 280.602684 -312.735048) (xy 280.643187 -312.763004) (xy 280.67868 -312.797096) (xy 280.708245 -312.83644)
			(xy 280.731116 -312.880017) (xy 280.7467 -312.926698) (xy 280.754595 -312.975275) (xy 280.75509 -312.999882)
			(xy 282.043898 -312.999882) (xy 282.047858 -312.950828) (xy 282.059635 -312.903044) (xy 282.078926 -312.857768)
			(xy 282.105229 -312.816172) (xy 282.137864 -312.779335) (xy 282.175985 -312.74821) (xy 282.218606 -312.723603)
			(xy 282.264622 -312.706151) (xy 282.312841 -312.696307) (xy 282.362016 -312.694326) (xy 282.410871 -312.700258)
			(xy 282.458142 -312.71395) (xy 282.502604 -312.735048) (xy 282.543107 -312.763004) (xy 282.5786 -312.797096)
			(xy 282.608165 -312.83644) (xy 282.631036 -312.880017) (xy 282.64662 -312.926698) (xy 282.654515 -312.975275)
			(xy 282.65501 -312.999882) (xy 283.944072 -312.999882) (xy 283.948032 -312.950828) (xy 283.959809 -312.903044)
			(xy 283.9791 -312.857768) (xy 284.005403 -312.816172) (xy 284.038038 -312.779335) (xy 284.076159 -312.74821)
			(xy 284.11878 -312.723603) (xy 284.164796 -312.706151) (xy 284.213015 -312.696307) (xy 284.26219 -312.694326)
			(xy 284.311045 -312.700258) (xy 284.358316 -312.71395) (xy 284.402778 -312.735048) (xy 284.443281 -312.763004)
			(xy 284.478774 -312.797096) (xy 284.508339 -312.83644) (xy 284.53121 -312.880017) (xy 284.546794 -312.926698)
			(xy 284.554689 -312.975275) (xy 284.555184 -312.999882) (xy 285.843992 -312.999882) (xy 285.847952 -312.950828)
			(xy 285.859729 -312.903044) (xy 285.87902 -312.857768) (xy 285.905323 -312.816172) (xy 285.937958 -312.779335)
			(xy 285.976079 -312.74821) (xy 286.0187 -312.723603) (xy 286.064716 -312.706151) (xy 286.112935 -312.696307)
			(xy 286.16211 -312.694326) (xy 286.210965 -312.700258) (xy 286.258236 -312.71395) (xy 286.302698 -312.735048)
			(xy 286.343201 -312.763004) (xy 286.378694 -312.797096) (xy 286.408259 -312.83644) (xy 286.43113 -312.880017)
			(xy 286.446714 -312.926698) (xy 286.454609 -312.975275) (xy 286.455104 -312.999882) (xy 287.743912 -312.999882)
			(xy 287.747872 -312.950828) (xy 287.759649 -312.903044) (xy 287.77894 -312.857768) (xy 287.805243 -312.816172)
			(xy 287.837878 -312.779335) (xy 287.875999 -312.74821) (xy 287.91862 -312.723603) (xy 287.964636 -312.706151)
			(xy 288.012855 -312.696307) (xy 288.06203 -312.694326) (xy 288.110885 -312.700258) (xy 288.158156 -312.71395)
			(xy 288.202618 -312.735048) (xy 288.243121 -312.763004) (xy 288.278614 -312.797096) (xy 288.308179 -312.83644)
			(xy 288.33105 -312.880017) (xy 288.346634 -312.926698) (xy 288.354529 -312.975275) (xy 288.355024 -312.999882)
			(xy 289.644086 -312.999882) (xy 289.648046 -312.950828) (xy 289.659823 -312.903044) (xy 289.679114 -312.857768)
			(xy 289.705417 -312.816172) (xy 289.738052 -312.779335) (xy 289.776173 -312.74821) (xy 289.818794 -312.723603)
			(xy 289.86481 -312.706151) (xy 289.913029 -312.696307) (xy 289.962204 -312.694326) (xy 290.011059 -312.700258)
			(xy 290.05833 -312.71395) (xy 290.102792 -312.735048) (xy 290.143295 -312.763004) (xy 290.178788 -312.797096)
			(xy 290.208353 -312.83644) (xy 290.231224 -312.880017) (xy 290.246808 -312.926698) (xy 290.254703 -312.975275)
			(xy 290.255198 -312.999882) (xy 291.544006 -312.999882) (xy 291.547966 -312.950828) (xy 291.559743 -312.903044)
			(xy 291.579034 -312.857768) (xy 291.605337 -312.816172) (xy 291.637972 -312.779335) (xy 291.676093 -312.74821)
			(xy 291.718714 -312.723603) (xy 291.76473 -312.706151) (xy 291.812949 -312.696307) (xy 291.862124 -312.694326)
			(xy 291.910979 -312.700258) (xy 291.95825 -312.71395) (xy 292.002712 -312.735048) (xy 292.043215 -312.763004)
			(xy 292.078708 -312.797096) (xy 292.108273 -312.83644) (xy 292.131144 -312.880017) (xy 292.146728 -312.926698)
			(xy 292.154623 -312.975275) (xy 292.155118 -312.999882) (xy 293.443926 -312.999882) (xy 293.447886 -312.950828)
			(xy 293.459663 -312.903044) (xy 293.478954 -312.857768) (xy 293.505257 -312.816172) (xy 293.537892 -312.779335)
			(xy 293.576013 -312.74821) (xy 293.618634 -312.723603) (xy 293.66465 -312.706151) (xy 293.712869 -312.696307)
			(xy 293.762044 -312.694326) (xy 293.810899 -312.700258) (xy 293.85817 -312.71395) (xy 293.902632 -312.735048)
			(xy 293.943135 -312.763004) (xy 293.978628 -312.797096) (xy 294.008193 -312.83644) (xy 294.031064 -312.880017)
			(xy 294.046648 -312.926698) (xy 294.054543 -312.975275) (xy 294.055038 -312.999882) (xy 295.3441 -312.999882)
			(xy 295.34806 -312.950828) (xy 295.359837 -312.903044) (xy 295.379128 -312.857768) (xy 295.405431 -312.816172)
			(xy 295.438066 -312.779335) (xy 295.476187 -312.74821) (xy 295.518808 -312.723603) (xy 295.564824 -312.706151)
			(xy 295.613043 -312.696307) (xy 295.662218 -312.694326) (xy 295.711073 -312.700258) (xy 295.758344 -312.71395)
			(xy 295.802806 -312.735048) (xy 295.843309 -312.763004) (xy 295.878802 -312.797096) (xy 295.908367 -312.83644)
			(xy 295.931238 -312.880017) (xy 295.946822 -312.926698) (xy 295.954717 -312.975275) (xy 295.955212 -312.999882)
			(xy 297.24402 -312.999882) (xy 297.24798 -312.950828) (xy 297.259757 -312.903044) (xy 297.279048 -312.857768)
			(xy 297.305351 -312.816172) (xy 297.337986 -312.779335) (xy 297.376107 -312.74821) (xy 297.418728 -312.723603)
			(xy 297.464744 -312.706151) (xy 297.512963 -312.696307) (xy 297.562138 -312.694326) (xy 297.610993 -312.700258)
			(xy 297.658264 -312.71395) (xy 297.702726 -312.735048) (xy 297.743229 -312.763004) (xy 297.778722 -312.797096)
			(xy 297.808287 -312.83644) (xy 297.831158 -312.880017) (xy 297.846742 -312.926698) (xy 297.854637 -312.975275)
			(xy 297.855132 -312.999882) (xy 299.14394 -312.999882) (xy 299.1479 -312.950828) (xy 299.159677 -312.903044)
			(xy 299.178968 -312.857768) (xy 299.205271 -312.816172) (xy 299.237906 -312.779335) (xy 299.276027 -312.74821)
			(xy 299.318648 -312.723603) (xy 299.364664 -312.706151) (xy 299.412883 -312.696307) (xy 299.462058 -312.694326)
			(xy 299.510913 -312.700258) (xy 299.558184 -312.71395) (xy 299.602646 -312.735048) (xy 299.643149 -312.763004)
			(xy 299.678642 -312.797096) (xy 299.708207 -312.83644) (xy 299.731078 -312.880017) (xy 299.746662 -312.926698)
			(xy 299.754557 -312.975275) (xy 299.755052 -312.999882) (xy 301.044114 -312.999882) (xy 301.048074 -312.950828)
			(xy 301.059851 -312.903044) (xy 301.079142 -312.857768) (xy 301.105445 -312.816172) (xy 301.13808 -312.779335)
			(xy 301.176201 -312.74821) (xy 301.218822 -312.723603) (xy 301.264838 -312.706151) (xy 301.313057 -312.696307)
			(xy 301.362232 -312.694326) (xy 301.411087 -312.700258) (xy 301.458358 -312.71395) (xy 301.50282 -312.735048)
			(xy 301.543323 -312.763004) (xy 301.578816 -312.797096) (xy 301.608381 -312.83644) (xy 301.631252 -312.880017)
			(xy 301.646836 -312.926698) (xy 301.654731 -312.975275) (xy 301.655226 -312.999882) (xy 302.944034 -312.999882)
			(xy 302.947994 -312.950828) (xy 302.959771 -312.903044) (xy 302.979062 -312.857768) (xy 303.005365 -312.816172)
			(xy 303.038 -312.779335) (xy 303.076121 -312.74821) (xy 303.118742 -312.723603) (xy 303.164758 -312.706151)
			(xy 303.212977 -312.696307) (xy 303.262152 -312.694326) (xy 303.311007 -312.700258) (xy 303.358278 -312.71395)
			(xy 303.40274 -312.735048) (xy 303.443243 -312.763004) (xy 303.478736 -312.797096) (xy 303.508301 -312.83644)
			(xy 303.531172 -312.880017) (xy 303.546756 -312.926698) (xy 303.554651 -312.975275) (xy 303.555146 -312.999882)
			(xy 304.843954 -312.999882) (xy 304.847914 -312.950828) (xy 304.859691 -312.903044) (xy 304.878982 -312.857768)
			(xy 304.905285 -312.816172) (xy 304.93792 -312.779335) (xy 304.976041 -312.74821) (xy 305.018662 -312.723603)
			(xy 305.064678 -312.706151) (xy 305.112897 -312.696307) (xy 305.162072 -312.694326) (xy 305.210927 -312.700258)
			(xy 305.258198 -312.71395) (xy 305.30266 -312.735048) (xy 305.343163 -312.763004) (xy 305.378656 -312.797096)
			(xy 305.408221 -312.83644) (xy 305.431092 -312.880017) (xy 305.446676 -312.926698) (xy 305.454571 -312.975275)
			(xy 305.455066 -312.999882) (xy 306.744128 -312.999882) (xy 306.748088 -312.950828) (xy 306.759865 -312.903044)
			(xy 306.779156 -312.857768) (xy 306.805459 -312.816172) (xy 306.838094 -312.779335) (xy 306.876215 -312.74821)
			(xy 306.918836 -312.723603) (xy 306.964852 -312.706151) (xy 307.013071 -312.696307) (xy 307.062246 -312.694326)
			(xy 307.111101 -312.700258) (xy 307.158372 -312.71395) (xy 307.202834 -312.735048) (xy 307.243337 -312.763004)
			(xy 307.27883 -312.797096) (xy 307.308395 -312.83644) (xy 307.331266 -312.880017) (xy 307.34685 -312.926698)
			(xy 307.354745 -312.975275) (xy 307.35524 -312.999882) (xy 308.644048 -312.999882) (xy 308.648008 -312.950828)
			(xy 308.659785 -312.903044) (xy 308.679076 -312.857768) (xy 308.705379 -312.816172) (xy 308.738014 -312.779335)
			(xy 308.776135 -312.74821) (xy 308.818756 -312.723603) (xy 308.864772 -312.706151) (xy 308.912991 -312.696307)
			(xy 308.962166 -312.694326) (xy 309.011021 -312.700258) (xy 309.058292 -312.71395) (xy 309.102754 -312.735048)
			(xy 309.143257 -312.763004) (xy 309.17875 -312.797096) (xy 309.208315 -312.83644) (xy 309.231186 -312.880017)
			(xy 309.24677 -312.926698) (xy 309.254665 -312.975275) (xy 309.25516 -312.999882) (xy 310.543968 -312.999882)
			(xy 310.547928 -312.950828) (xy 310.559705 -312.903044) (xy 310.578996 -312.857768) (xy 310.605299 -312.816172)
			(xy 310.637934 -312.779335) (xy 310.676055 -312.74821) (xy 310.718676 -312.723603) (xy 310.764692 -312.706151)
			(xy 310.812911 -312.696307) (xy 310.862086 -312.694326) (xy 310.910941 -312.700258) (xy 310.958212 -312.71395)
			(xy 311.002674 -312.735048) (xy 311.043177 -312.763004) (xy 311.07867 -312.797096) (xy 311.108235 -312.83644)
			(xy 311.131106 -312.880017) (xy 311.14669 -312.926698) (xy 311.154585 -312.975275) (xy 311.15508 -312.999882)
			(xy 312.443888 -312.999882) (xy 312.447848 -312.950828) (xy 312.459625 -312.903044) (xy 312.478916 -312.857768)
			(xy 312.505219 -312.816172) (xy 312.537854 -312.779335) (xy 312.575975 -312.74821) (xy 312.618596 -312.723603)
			(xy 312.664612 -312.706151) (xy 312.712831 -312.696307) (xy 312.762006 -312.694326) (xy 312.810861 -312.700258)
			(xy 312.858132 -312.71395) (xy 312.902594 -312.735048) (xy 312.943097 -312.763004) (xy 312.97859 -312.797096)
			(xy 313.008155 -312.83644) (xy 313.031026 -312.880017) (xy 313.04661 -312.926698) (xy 313.054505 -312.975275)
			(xy 313.055 -312.999882) (xy 386.744222 -312.999882) (xy 386.748182 -312.950828) (xy 386.759959 -312.903044)
			(xy 386.77925 -312.857768) (xy 386.805553 -312.816172) (xy 386.838188 -312.779335) (xy 386.876309 -312.74821)
			(xy 386.91893 -312.723603) (xy 386.964946 -312.706151) (xy 387.013165 -312.696307) (xy 387.06234 -312.694326)
			(xy 387.111195 -312.700258) (xy 387.158466 -312.71395) (xy 387.202928 -312.735048) (xy 387.243431 -312.763004)
			(xy 387.278924 -312.797096) (xy 387.308489 -312.83644) (xy 387.33136 -312.880017) (xy 387.346944 -312.926698)
			(xy 387.354839 -312.975275) (xy 387.355334 -312.999882) (xy 388.644142 -312.999882) (xy 388.648102 -312.950828)
			(xy 388.659879 -312.903044) (xy 388.67917 -312.857768) (xy 388.705473 -312.816172) (xy 388.738108 -312.779335)
			(xy 388.776229 -312.74821) (xy 388.81885 -312.723603) (xy 388.864866 -312.706151) (xy 388.913085 -312.696307)
			(xy 388.96226 -312.694326) (xy 389.011115 -312.700258) (xy 389.058386 -312.71395) (xy 389.102848 -312.735048)
			(xy 389.143351 -312.763004) (xy 389.178844 -312.797096) (xy 389.208409 -312.83644) (xy 389.23128 -312.880017)
			(xy 389.246864 -312.926698) (xy 389.254759 -312.975275) (xy 389.255254 -312.999882) (xy 390.544062 -312.999882)
			(xy 390.548022 -312.950828) (xy 390.559799 -312.903044) (xy 390.57909 -312.857768) (xy 390.605393 -312.816172)
			(xy 390.638028 -312.779335) (xy 390.676149 -312.74821) (xy 390.71877 -312.723603) (xy 390.764786 -312.706151)
			(xy 390.813005 -312.696307) (xy 390.86218 -312.694326) (xy 390.911035 -312.700258) (xy 390.958306 -312.71395)
			(xy 391.002768 -312.735048) (xy 391.043271 -312.763004) (xy 391.078764 -312.797096) (xy 391.108329 -312.83644)
			(xy 391.1312 -312.880017) (xy 391.146784 -312.926698) (xy 391.154679 -312.975275) (xy 391.155174 -312.999882)
			(xy 392.443982 -312.999882) (xy 392.447942 -312.950828) (xy 392.459719 -312.903044) (xy 392.47901 -312.857768)
			(xy 392.505313 -312.816172) (xy 392.537948 -312.779335) (xy 392.576069 -312.74821) (xy 392.61869 -312.723603)
			(xy 392.664706 -312.706151) (xy 392.712925 -312.696307) (xy 392.7621 -312.694326) (xy 392.810955 -312.700258)
			(xy 392.858226 -312.71395) (xy 392.902688 -312.735048) (xy 392.943191 -312.763004) (xy 392.978684 -312.797096)
			(xy 393.008249 -312.83644) (xy 393.03112 -312.880017) (xy 393.046704 -312.926698) (xy 393.054599 -312.975275)
			(xy 393.055094 -312.999882) (xy 394.344156 -312.999882) (xy 394.348116 -312.950828) (xy 394.359893 -312.903044)
			(xy 394.379184 -312.857768) (xy 394.405487 -312.816172) (xy 394.438122 -312.779335) (xy 394.476243 -312.74821)
			(xy 394.518864 -312.723603) (xy 394.56488 -312.706151) (xy 394.613099 -312.696307) (xy 394.662274 -312.694326)
			(xy 394.711129 -312.700258) (xy 394.7584 -312.71395) (xy 394.802862 -312.735048) (xy 394.843365 -312.763004)
			(xy 394.878858 -312.797096) (xy 394.908423 -312.83644) (xy 394.931294 -312.880017) (xy 394.946878 -312.926698)
			(xy 394.954773 -312.975275) (xy 394.955268 -312.999882) (xy 396.244076 -312.999882) (xy 396.248036 -312.950828)
			(xy 396.259813 -312.903044) (xy 396.279104 -312.857768) (xy 396.305407 -312.816172) (xy 396.338042 -312.779335)
			(xy 396.376163 -312.74821) (xy 396.418784 -312.723603) (xy 396.4648 -312.706151) (xy 396.513019 -312.696307)
			(xy 396.562194 -312.694326) (xy 396.611049 -312.700258) (xy 396.65832 -312.71395) (xy 396.702782 -312.735048)
			(xy 396.743285 -312.763004) (xy 396.778778 -312.797096) (xy 396.808343 -312.83644) (xy 396.831214 -312.880017)
			(xy 396.846798 -312.926698) (xy 396.854693 -312.975275) (xy 396.855188 -312.999882) (xy 398.143996 -312.999882)
			(xy 398.147956 -312.950828) (xy 398.159733 -312.903044) (xy 398.179024 -312.857768) (xy 398.205327 -312.816172)
			(xy 398.237962 -312.779335) (xy 398.276083 -312.74821) (xy 398.318704 -312.723603) (xy 398.36472 -312.706151)
			(xy 398.412939 -312.696307) (xy 398.462114 -312.694326) (xy 398.510969 -312.700258) (xy 398.55824 -312.71395)
			(xy 398.602702 -312.735048) (xy 398.643205 -312.763004) (xy 398.678698 -312.797096) (xy 398.708263 -312.83644)
			(xy 398.731134 -312.880017) (xy 398.746718 -312.926698) (xy 398.754613 -312.975275) (xy 398.755108 -312.999882)
			(xy 400.04417 -312.999882) (xy 400.04813 -312.950828) (xy 400.059907 -312.903044) (xy 400.079198 -312.857768)
			(xy 400.105501 -312.816172) (xy 400.138136 -312.779335) (xy 400.176257 -312.74821) (xy 400.218878 -312.723603)
			(xy 400.264894 -312.706151) (xy 400.313113 -312.696307) (xy 400.362288 -312.694326) (xy 400.411143 -312.700258)
			(xy 400.458414 -312.71395) (xy 400.502876 -312.735048) (xy 400.543379 -312.763004) (xy 400.578872 -312.797096)
			(xy 400.608437 -312.83644) (xy 400.631308 -312.880017) (xy 400.646892 -312.926698) (xy 400.654787 -312.975275)
			(xy 400.655282 -312.999882) (xy 401.94409 -312.999882) (xy 401.94805 -312.950828) (xy 401.959827 -312.903044)
			(xy 401.979118 -312.857768) (xy 402.005421 -312.816172) (xy 402.038056 -312.779335) (xy 402.076177 -312.74821)
			(xy 402.118798 -312.723603) (xy 402.164814 -312.706151) (xy 402.213033 -312.696307) (xy 402.262208 -312.694326)
			(xy 402.311063 -312.700258) (xy 402.358334 -312.71395) (xy 402.402796 -312.735048) (xy 402.443299 -312.763004)
			(xy 402.478792 -312.797096) (xy 402.508357 -312.83644) (xy 402.531228 -312.880017) (xy 402.546812 -312.926698)
			(xy 402.554707 -312.975275) (xy 402.555202 -312.999882) (xy 403.84401 -312.999882) (xy 403.84797 -312.950828)
			(xy 403.859747 -312.903044) (xy 403.879038 -312.857768) (xy 403.905341 -312.816172) (xy 403.937976 -312.779335)
			(xy 403.976097 -312.74821) (xy 404.018718 -312.723603) (xy 404.064734 -312.706151) (xy 404.112953 -312.696307)
			(xy 404.162128 -312.694326) (xy 404.210983 -312.700258) (xy 404.258254 -312.71395) (xy 404.302716 -312.735048)
			(xy 404.343219 -312.763004) (xy 404.378712 -312.797096) (xy 404.408277 -312.83644) (xy 404.431148 -312.880017)
			(xy 404.446732 -312.926698) (xy 404.454627 -312.975275) (xy 404.455122 -312.999882) (xy 405.744184 -312.999882)
			(xy 405.748144 -312.950828) (xy 405.759921 -312.903044) (xy 405.779212 -312.857768) (xy 405.805515 -312.816172)
			(xy 405.83815 -312.779335) (xy 405.876271 -312.74821) (xy 405.918892 -312.723603) (xy 405.964908 -312.706151)
			(xy 406.013127 -312.696307) (xy 406.062302 -312.694326) (xy 406.111157 -312.700258) (xy 406.158428 -312.71395)
			(xy 406.20289 -312.735048) (xy 406.243393 -312.763004) (xy 406.278886 -312.797096) (xy 406.308451 -312.83644)
			(xy 406.331322 -312.880017) (xy 406.346906 -312.926698) (xy 406.354801 -312.975275) (xy 406.355296 -312.999882)
			(xy 407.644104 -312.999882) (xy 407.648064 -312.950828) (xy 407.659841 -312.903044) (xy 407.679132 -312.857768)
			(xy 407.705435 -312.816172) (xy 407.73807 -312.779335) (xy 407.776191 -312.74821) (xy 407.818812 -312.723603)
			(xy 407.864828 -312.706151) (xy 407.913047 -312.696307) (xy 407.962222 -312.694326) (xy 408.011077 -312.700258)
			(xy 408.058348 -312.71395) (xy 408.10281 -312.735048) (xy 408.143313 -312.763004) (xy 408.178806 -312.797096)
			(xy 408.208371 -312.83644) (xy 408.231242 -312.880017) (xy 408.246826 -312.926698) (xy 408.254721 -312.975275)
			(xy 408.255216 -312.999882) (xy 409.544024 -312.999882) (xy 409.547984 -312.950828) (xy 409.559761 -312.903044)
			(xy 409.579052 -312.857768) (xy 409.605355 -312.816172) (xy 409.63799 -312.779335) (xy 409.676111 -312.74821)
			(xy 409.718732 -312.723603) (xy 409.764748 -312.706151) (xy 409.812967 -312.696307) (xy 409.862142 -312.694326)
			(xy 409.910997 -312.700258) (xy 409.958268 -312.71395) (xy 410.00273 -312.735048) (xy 410.043233 -312.763004)
			(xy 410.078726 -312.797096) (xy 410.108291 -312.83644) (xy 410.131162 -312.880017) (xy 410.146746 -312.926698)
			(xy 410.154641 -312.975275) (xy 410.155136 -312.999882) (xy 411.444198 -312.999882) (xy 411.448158 -312.950828)
			(xy 411.459935 -312.903044) (xy 411.479226 -312.857768) (xy 411.505529 -312.816172) (xy 411.538164 -312.779335)
			(xy 411.576285 -312.74821) (xy 411.618906 -312.723603) (xy 411.664922 -312.706151) (xy 411.713141 -312.696307)
			(xy 411.762316 -312.694326) (xy 411.811171 -312.700258) (xy 411.858442 -312.71395) (xy 411.902904 -312.735048)
			(xy 411.943407 -312.763004) (xy 411.9789 -312.797096) (xy 412.008465 -312.83644) (xy 412.031336 -312.880017)
			(xy 412.04692 -312.926698) (xy 412.054815 -312.975275) (xy 412.05531 -312.999882) (xy 413.344118 -312.999882)
			(xy 413.348078 -312.950828) (xy 413.359855 -312.903044) (xy 413.379146 -312.857768) (xy 413.405449 -312.816172)
			(xy 413.438084 -312.779335) (xy 413.476205 -312.74821) (xy 413.518826 -312.723603) (xy 413.564842 -312.706151)
			(xy 413.613061 -312.696307) (xy 413.662236 -312.694326) (xy 413.711091 -312.700258) (xy 413.758362 -312.71395)
			(xy 413.802824 -312.735048) (xy 413.843327 -312.763004) (xy 413.87882 -312.797096) (xy 413.908385 -312.83644)
			(xy 413.931256 -312.880017) (xy 413.94684 -312.926698) (xy 413.954735 -312.975275) (xy 413.95523 -312.999882)
			(xy 415.244038 -312.999882) (xy 415.247998 -312.950828) (xy 415.259775 -312.903044) (xy 415.279066 -312.857768)
			(xy 415.305369 -312.816172) (xy 415.338004 -312.779335) (xy 415.376125 -312.74821) (xy 415.418746 -312.723603)
			(xy 415.464762 -312.706151) (xy 415.512981 -312.696307) (xy 415.562156 -312.694326) (xy 415.611011 -312.700258)
			(xy 415.658282 -312.71395) (xy 415.702744 -312.735048) (xy 415.743247 -312.763004) (xy 415.77874 -312.797096)
			(xy 415.808305 -312.83644) (xy 415.831176 -312.880017) (xy 415.84676 -312.926698) (xy 415.854655 -312.975275)
			(xy 415.85515 -312.999882) (xy 417.144212 -312.999882) (xy 417.148172 -312.950828) (xy 417.159949 -312.903044)
			(xy 417.17924 -312.857768) (xy 417.205543 -312.816172) (xy 417.238178 -312.779335) (xy 417.276299 -312.74821)
			(xy 417.31892 -312.723603) (xy 417.364936 -312.706151) (xy 417.413155 -312.696307) (xy 417.46233 -312.694326)
			(xy 417.511185 -312.700258) (xy 417.558456 -312.71395) (xy 417.602918 -312.735048) (xy 417.643421 -312.763004)
			(xy 417.678914 -312.797096) (xy 417.708479 -312.83644) (xy 417.73135 -312.880017) (xy 417.746934 -312.926698)
			(xy 417.754829 -312.975275) (xy 417.755324 -312.999882) (xy 419.044132 -312.999882) (xy 419.048092 -312.950828)
			(xy 419.059869 -312.903044) (xy 419.07916 -312.857768) (xy 419.105463 -312.816172) (xy 419.138098 -312.779335)
			(xy 419.176219 -312.74821) (xy 419.21884 -312.723603) (xy 419.264856 -312.706151) (xy 419.313075 -312.696307)
			(xy 419.36225 -312.694326) (xy 419.411105 -312.700258) (xy 419.458376 -312.71395) (xy 419.502838 -312.735048)
			(xy 419.543341 -312.763004) (xy 419.578834 -312.797096) (xy 419.608399 -312.83644) (xy 419.63127 -312.880017)
			(xy 419.646854 -312.926698) (xy 419.654749 -312.975275) (xy 419.655244 -312.999882) (xy 420.944052 -312.999882)
			(xy 420.948012 -312.950828) (xy 420.959789 -312.903044) (xy 420.97908 -312.857768) (xy 421.005383 -312.816172)
			(xy 421.038018 -312.779335) (xy 421.076139 -312.74821) (xy 421.11876 -312.723603) (xy 421.164776 -312.706151)
			(xy 421.212995 -312.696307) (xy 421.26217 -312.694326) (xy 421.311025 -312.700258) (xy 421.358296 -312.71395)
			(xy 421.402758 -312.735048) (xy 421.443261 -312.763004) (xy 421.478754 -312.797096) (xy 421.508319 -312.83644)
			(xy 421.53119 -312.880017) (xy 421.546774 -312.926698) (xy 421.554669 -312.975275) (xy 421.555164 -312.999882)
			(xy 422.844226 -312.999882) (xy 422.848186 -312.950828) (xy 422.859963 -312.903044) (xy 422.879254 -312.857768)
			(xy 422.905557 -312.816172) (xy 422.938192 -312.779335) (xy 422.976313 -312.74821) (xy 423.018934 -312.723603)
			(xy 423.06495 -312.706151) (xy 423.113169 -312.696307) (xy 423.162344 -312.694326) (xy 423.211199 -312.700258)
			(xy 423.25847 -312.71395) (xy 423.302932 -312.735048) (xy 423.343435 -312.763004) (xy 423.378928 -312.797096)
			(xy 423.408493 -312.83644) (xy 423.431364 -312.880017) (xy 423.446948 -312.926698) (xy 423.454843 -312.975275)
			(xy 423.455338 -312.999882) (xy 424.744146 -312.999882) (xy 424.748106 -312.950828) (xy 424.759883 -312.903044)
			(xy 424.779174 -312.857768) (xy 424.805477 -312.816172) (xy 424.838112 -312.779335) (xy 424.876233 -312.74821)
			(xy 424.918854 -312.723603) (xy 424.96487 -312.706151) (xy 425.013089 -312.696307) (xy 425.062264 -312.694326)
			(xy 425.111119 -312.700258) (xy 425.15839 -312.71395) (xy 425.202852 -312.735048) (xy 425.243355 -312.763004)
			(xy 425.278848 -312.797096) (xy 425.308413 -312.83644) (xy 425.331284 -312.880017) (xy 425.346868 -312.926698)
			(xy 425.354763 -312.975275) (xy 425.355258 -312.999882) (xy 426.644066 -312.999882) (xy 426.648026 -312.950828)
			(xy 426.659803 -312.903044) (xy 426.679094 -312.857768) (xy 426.705397 -312.816172) (xy 426.738032 -312.779335)
			(xy 426.776153 -312.74821) (xy 426.818774 -312.723603) (xy 426.86479 -312.706151) (xy 426.913009 -312.696307)
			(xy 426.962184 -312.694326) (xy 427.011039 -312.700258) (xy 427.05831 -312.71395) (xy 427.102772 -312.735048)
			(xy 427.143275 -312.763004) (xy 427.178768 -312.797096) (xy 427.208333 -312.83644) (xy 427.231204 -312.880017)
			(xy 427.246788 -312.926698) (xy 427.254683 -312.975275) (xy 427.255178 -312.999882) (xy 428.543986 -312.999882)
			(xy 428.547946 -312.950828) (xy 428.559723 -312.903044) (xy 428.579014 -312.857768) (xy 428.605317 -312.816172)
			(xy 428.637952 -312.779335) (xy 428.676073 -312.74821) (xy 428.718694 -312.723603) (xy 428.76471 -312.706151)
			(xy 428.812929 -312.696307) (xy 428.862104 -312.694326) (xy 428.910959 -312.700258) (xy 428.95823 -312.71395)
			(xy 429.002692 -312.735048) (xy 429.043195 -312.763004) (xy 429.078688 -312.797096) (xy 429.108253 -312.83644)
			(xy 429.131124 -312.880017) (xy 429.146708 -312.926698) (xy 429.154603 -312.975275) (xy 429.155098 -312.999882)
			(xy 429.154603 -313.024489) (xy 429.146708 -313.073066) (xy 429.131124 -313.119747) (xy 429.108253 -313.163324)
			(xy 429.078688 -313.202668) (xy 429.043195 -313.23676) (xy 429.002692 -313.264716) (xy 428.95823 -313.285814)
			(xy 428.910959 -313.299506) (xy 428.862104 -313.305438) (xy 428.812929 -313.303457) (xy 428.76471 -313.293613)
			(xy 428.718694 -313.276161) (xy 428.676073 -313.251554) (xy 428.637952 -313.220429) (xy 428.605317 -313.183592)
			(xy 428.579014 -313.141996) (xy 428.559723 -313.09672) (xy 428.547946 -313.048936) (xy 428.543986 -312.999882)
			(xy 427.255178 -312.999882) (xy 427.254683 -313.024489) (xy 427.246788 -313.073066) (xy 427.231204 -313.119747)
			(xy 427.208333 -313.163324) (xy 427.178768 -313.202668) (xy 427.143275 -313.23676) (xy 427.102772 -313.264716)
			(xy 427.05831 -313.285814) (xy 427.011039 -313.299506) (xy 426.962184 -313.305438) (xy 426.913009 -313.303457)
			(xy 426.86479 -313.293613) (xy 426.818774 -313.276161) (xy 426.776153 -313.251554) (xy 426.738032 -313.220429)
			(xy 426.705397 -313.183592) (xy 426.679094 -313.141996) (xy 426.659803 -313.09672) (xy 426.648026 -313.048936)
			(xy 426.644066 -312.999882) (xy 425.355258 -312.999882) (xy 425.354763 -313.024489) (xy 425.346868 -313.073066)
			(xy 425.331284 -313.119747) (xy 425.308413 -313.163324) (xy 425.278848 -313.202668) (xy 425.243355 -313.23676)
			(xy 425.202852 -313.264716) (xy 425.15839 -313.285814) (xy 425.111119 -313.299506) (xy 425.062264 -313.305438)
			(xy 425.013089 -313.303457) (xy 424.96487 -313.293613) (xy 424.918854 -313.276161) (xy 424.876233 -313.251554)
			(xy 424.838112 -313.220429) (xy 424.805477 -313.183592) (xy 424.779174 -313.141996) (xy 424.759883 -313.09672)
			(xy 424.748106 -313.048936) (xy 424.744146 -312.999882) (xy 423.455338 -312.999882) (xy 423.454843 -313.024489)
			(xy 423.446948 -313.073066) (xy 423.431364 -313.119747) (xy 423.408493 -313.163324) (xy 423.378928 -313.202668)
			(xy 423.343435 -313.23676) (xy 423.302932 -313.264716) (xy 423.25847 -313.285814) (xy 423.211199 -313.299506)
			(xy 423.162344 -313.305438) (xy 423.113169 -313.303457) (xy 423.06495 -313.293613) (xy 423.018934 -313.276161)
			(xy 422.976313 -313.251554) (xy 422.938192 -313.220429) (xy 422.905557 -313.183592) (xy 422.879254 -313.141996)
			(xy 422.859963 -313.09672) (xy 422.848186 -313.048936) (xy 422.844226 -312.999882) (xy 421.555164 -312.999882)
			(xy 421.554669 -313.024489) (xy 421.546774 -313.073066) (xy 421.53119 -313.119747) (xy 421.508319 -313.163324)
			(xy 421.478754 -313.202668) (xy 421.443261 -313.23676) (xy 421.402758 -313.264716) (xy 421.358296 -313.285814)
			(xy 421.311025 -313.299506) (xy 421.26217 -313.305438) (xy 421.212995 -313.303457) (xy 421.164776 -313.293613)
			(xy 421.11876 -313.276161) (xy 421.076139 -313.251554) (xy 421.038018 -313.220429) (xy 421.005383 -313.183592)
			(xy 420.97908 -313.141996) (xy 420.959789 -313.09672) (xy 420.948012 -313.048936) (xy 420.944052 -312.999882)
			(xy 419.655244 -312.999882) (xy 419.654749 -313.024489) (xy 419.646854 -313.073066) (xy 419.63127 -313.119747)
			(xy 419.608399 -313.163324) (xy 419.578834 -313.202668) (xy 419.543341 -313.23676) (xy 419.502838 -313.264716)
			(xy 419.458376 -313.285814) (xy 419.411105 -313.299506) (xy 419.36225 -313.305438) (xy 419.313075 -313.303457)
			(xy 419.264856 -313.293613) (xy 419.21884 -313.276161) (xy 419.176219 -313.251554) (xy 419.138098 -313.220429)
			(xy 419.105463 -313.183592) (xy 419.07916 -313.141996) (xy 419.059869 -313.09672) (xy 419.048092 -313.048936)
			(xy 419.044132 -312.999882) (xy 417.755324 -312.999882) (xy 417.754829 -313.024489) (xy 417.746934 -313.073066)
			(xy 417.73135 -313.119747) (xy 417.708479 -313.163324) (xy 417.678914 -313.202668) (xy 417.643421 -313.23676)
			(xy 417.602918 -313.264716) (xy 417.558456 -313.285814) (xy 417.511185 -313.299506) (xy 417.46233 -313.305438)
			(xy 417.413155 -313.303457) (xy 417.364936 -313.293613) (xy 417.31892 -313.276161) (xy 417.276299 -313.251554)
			(xy 417.238178 -313.220429) (xy 417.205543 -313.183592) (xy 417.17924 -313.141996) (xy 417.159949 -313.09672)
			(xy 417.148172 -313.048936) (xy 417.144212 -312.999882) (xy 415.85515 -312.999882) (xy 415.854655 -313.024489)
			(xy 415.84676 -313.073066) (xy 415.831176 -313.119747) (xy 415.808305 -313.163324) (xy 415.77874 -313.202668)
			(xy 415.743247 -313.23676) (xy 415.702744 -313.264716) (xy 415.658282 -313.285814) (xy 415.611011 -313.299506)
			(xy 415.562156 -313.305438) (xy 415.512981 -313.303457) (xy 415.464762 -313.293613) (xy 415.418746 -313.276161)
			(xy 415.376125 -313.251554) (xy 415.338004 -313.220429) (xy 415.305369 -313.183592) (xy 415.279066 -313.141996)
			(xy 415.259775 -313.09672) (xy 415.247998 -313.048936) (xy 415.244038 -312.999882) (xy 413.95523 -312.999882)
			(xy 413.954735 -313.024489) (xy 413.94684 -313.073066) (xy 413.931256 -313.119747) (xy 413.908385 -313.163324)
			(xy 413.87882 -313.202668) (xy 413.843327 -313.23676) (xy 413.802824 -313.264716) (xy 413.758362 -313.285814)
			(xy 413.711091 -313.299506) (xy 413.662236 -313.305438) (xy 413.613061 -313.303457) (xy 413.564842 -313.293613)
			(xy 413.518826 -313.276161) (xy 413.476205 -313.251554) (xy 413.438084 -313.220429) (xy 413.405449 -313.183592)
			(xy 413.379146 -313.141996) (xy 413.359855 -313.09672) (xy 413.348078 -313.048936) (xy 413.344118 -312.999882)
			(xy 412.05531 -312.999882) (xy 412.054815 -313.024489) (xy 412.04692 -313.073066) (xy 412.031336 -313.119747)
			(xy 412.008465 -313.163324) (xy 411.9789 -313.202668) (xy 411.943407 -313.23676) (xy 411.902904 -313.264716)
			(xy 411.858442 -313.285814) (xy 411.811171 -313.299506) (xy 411.762316 -313.305438) (xy 411.713141 -313.303457)
			(xy 411.664922 -313.293613) (xy 411.618906 -313.276161) (xy 411.576285 -313.251554) (xy 411.538164 -313.220429)
			(xy 411.505529 -313.183592) (xy 411.479226 -313.141996) (xy 411.459935 -313.09672) (xy 411.448158 -313.048936)
			(xy 411.444198 -312.999882) (xy 410.155136 -312.999882) (xy 410.154641 -313.024489) (xy 410.146746 -313.073066)
			(xy 410.131162 -313.119747) (xy 410.108291 -313.163324) (xy 410.078726 -313.202668) (xy 410.043233 -313.23676)
			(xy 410.00273 -313.264716) (xy 409.958268 -313.285814) (xy 409.910997 -313.299506) (xy 409.862142 -313.305438)
			(xy 409.812967 -313.303457) (xy 409.764748 -313.293613) (xy 409.718732 -313.276161) (xy 409.676111 -313.251554)
			(xy 409.63799 -313.220429) (xy 409.605355 -313.183592) (xy 409.579052 -313.141996) (xy 409.559761 -313.09672)
			(xy 409.547984 -313.048936) (xy 409.544024 -312.999882) (xy 408.255216 -312.999882) (xy 408.254721 -313.024489)
			(xy 408.246826 -313.073066) (xy 408.231242 -313.119747) (xy 408.208371 -313.163324) (xy 408.178806 -313.202668)
			(xy 408.143313 -313.23676) (xy 408.10281 -313.264716) (xy 408.058348 -313.285814) (xy 408.011077 -313.299506)
			(xy 407.962222 -313.305438) (xy 407.913047 -313.303457) (xy 407.864828 -313.293613) (xy 407.818812 -313.276161)
			(xy 407.776191 -313.251554) (xy 407.73807 -313.220429) (xy 407.705435 -313.183592) (xy 407.679132 -313.141996)
			(xy 407.659841 -313.09672) (xy 407.648064 -313.048936) (xy 407.644104 -312.999882) (xy 406.355296 -312.999882)
			(xy 406.354801 -313.024489) (xy 406.346906 -313.073066) (xy 406.331322 -313.119747) (xy 406.308451 -313.163324)
			(xy 406.278886 -313.202668) (xy 406.243393 -313.23676) (xy 406.20289 -313.264716) (xy 406.158428 -313.285814)
			(xy 406.111157 -313.299506) (xy 406.062302 -313.305438) (xy 406.013127 -313.303457) (xy 405.964908 -313.293613)
			(xy 405.918892 -313.276161) (xy 405.876271 -313.251554) (xy 405.83815 -313.220429) (xy 405.805515 -313.183592)
			(xy 405.779212 -313.141996) (xy 405.759921 -313.09672) (xy 405.748144 -313.048936) (xy 405.744184 -312.999882)
			(xy 404.455122 -312.999882) (xy 404.454627 -313.024489) (xy 404.446732 -313.073066) (xy 404.431148 -313.119747)
			(xy 404.408277 -313.163324) (xy 404.378712 -313.202668) (xy 404.343219 -313.23676) (xy 404.302716 -313.264716)
			(xy 404.258254 -313.285814) (xy 404.210983 -313.299506) (xy 404.162128 -313.305438) (xy 404.112953 -313.303457)
			(xy 404.064734 -313.293613) (xy 404.018718 -313.276161) (xy 403.976097 -313.251554) (xy 403.937976 -313.220429)
			(xy 403.905341 -313.183592) (xy 403.879038 -313.141996) (xy 403.859747 -313.09672) (xy 403.84797 -313.048936)
			(xy 403.84401 -312.999882) (xy 402.555202 -312.999882) (xy 402.554707 -313.024489) (xy 402.546812 -313.073066)
			(xy 402.531228 -313.119747) (xy 402.508357 -313.163324) (xy 402.478792 -313.202668) (xy 402.443299 -313.23676)
			(xy 402.402796 -313.264716) (xy 402.358334 -313.285814) (xy 402.311063 -313.299506) (xy 402.262208 -313.305438)
			(xy 402.213033 -313.303457) (xy 402.164814 -313.293613) (xy 402.118798 -313.276161) (xy 402.076177 -313.251554)
			(xy 402.038056 -313.220429) (xy 402.005421 -313.183592) (xy 401.979118 -313.141996) (xy 401.959827 -313.09672)
			(xy 401.94805 -313.048936) (xy 401.94409 -312.999882) (xy 400.655282 -312.999882) (xy 400.654787 -313.024489)
			(xy 400.646892 -313.073066) (xy 400.631308 -313.119747) (xy 400.608437 -313.163324) (xy 400.578872 -313.202668)
			(xy 400.543379 -313.23676) (xy 400.502876 -313.264716) (xy 400.458414 -313.285814) (xy 400.411143 -313.299506)
			(xy 400.362288 -313.305438) (xy 400.313113 -313.303457) (xy 400.264894 -313.293613) (xy 400.218878 -313.276161)
			(xy 400.176257 -313.251554) (xy 400.138136 -313.220429) (xy 400.105501 -313.183592) (xy 400.079198 -313.141996)
			(xy 400.059907 -313.09672) (xy 400.04813 -313.048936) (xy 400.04417 -312.999882) (xy 398.755108 -312.999882)
			(xy 398.754613 -313.024489) (xy 398.746718 -313.073066) (xy 398.731134 -313.119747) (xy 398.708263 -313.163324)
			(xy 398.678698 -313.202668) (xy 398.643205 -313.23676) (xy 398.602702 -313.264716) (xy 398.55824 -313.285814)
			(xy 398.510969 -313.299506) (xy 398.462114 -313.305438) (xy 398.412939 -313.303457) (xy 398.36472 -313.293613)
			(xy 398.318704 -313.276161) (xy 398.276083 -313.251554) (xy 398.237962 -313.220429) (xy 398.205327 -313.183592)
			(xy 398.179024 -313.141996) (xy 398.159733 -313.09672) (xy 398.147956 -313.048936) (xy 398.143996 -312.999882)
			(xy 396.855188 -312.999882) (xy 396.854693 -313.024489) (xy 396.846798 -313.073066) (xy 396.831214 -313.119747)
			(xy 396.808343 -313.163324) (xy 396.778778 -313.202668) (xy 396.743285 -313.23676) (xy 396.702782 -313.264716)
			(xy 396.65832 -313.285814) (xy 396.611049 -313.299506) (xy 396.562194 -313.305438) (xy 396.513019 -313.303457)
			(xy 396.4648 -313.293613) (xy 396.418784 -313.276161) (xy 396.376163 -313.251554) (xy 396.338042 -313.220429)
			(xy 396.305407 -313.183592) (xy 396.279104 -313.141996) (xy 396.259813 -313.09672) (xy 396.248036 -313.048936)
			(xy 396.244076 -312.999882) (xy 394.955268 -312.999882) (xy 394.954773 -313.024489) (xy 394.946878 -313.073066)
			(xy 394.931294 -313.119747) (xy 394.908423 -313.163324) (xy 394.878858 -313.202668) (xy 394.843365 -313.23676)
			(xy 394.802862 -313.264716) (xy 394.7584 -313.285814) (xy 394.711129 -313.299506) (xy 394.662274 -313.305438)
			(xy 394.613099 -313.303457) (xy 394.56488 -313.293613) (xy 394.518864 -313.276161) (xy 394.476243 -313.251554)
			(xy 394.438122 -313.220429) (xy 394.405487 -313.183592) (xy 394.379184 -313.141996) (xy 394.359893 -313.09672)
			(xy 394.348116 -313.048936) (xy 394.344156 -312.999882) (xy 393.055094 -312.999882) (xy 393.054599 -313.024489)
			(xy 393.046704 -313.073066) (xy 393.03112 -313.119747) (xy 393.008249 -313.163324) (xy 392.978684 -313.202668)
			(xy 392.943191 -313.23676) (xy 392.902688 -313.264716) (xy 392.858226 -313.285814) (xy 392.810955 -313.299506)
			(xy 392.7621 -313.305438) (xy 392.712925 -313.303457) (xy 392.664706 -313.293613) (xy 392.61869 -313.276161)
			(xy 392.576069 -313.251554) (xy 392.537948 -313.220429) (xy 392.505313 -313.183592) (xy 392.47901 -313.141996)
			(xy 392.459719 -313.09672) (xy 392.447942 -313.048936) (xy 392.443982 -312.999882) (xy 391.155174 -312.999882)
			(xy 391.154679 -313.024489) (xy 391.146784 -313.073066) (xy 391.1312 -313.119747) (xy 391.108329 -313.163324)
			(xy 391.078764 -313.202668) (xy 391.043271 -313.23676) (xy 391.002768 -313.264716) (xy 390.958306 -313.285814)
			(xy 390.911035 -313.299506) (xy 390.86218 -313.305438) (xy 390.813005 -313.303457) (xy 390.764786 -313.293613)
			(xy 390.71877 -313.276161) (xy 390.676149 -313.251554) (xy 390.638028 -313.220429) (xy 390.605393 -313.183592)
			(xy 390.57909 -313.141996) (xy 390.559799 -313.09672) (xy 390.548022 -313.048936) (xy 390.544062 -312.999882)
			(xy 389.255254 -312.999882) (xy 389.254759 -313.024489) (xy 389.246864 -313.073066) (xy 389.23128 -313.119747)
			(xy 389.208409 -313.163324) (xy 389.178844 -313.202668) (xy 389.143351 -313.23676) (xy 389.102848 -313.264716)
			(xy 389.058386 -313.285814) (xy 389.011115 -313.299506) (xy 388.96226 -313.305438) (xy 388.913085 -313.303457)
			(xy 388.864866 -313.293613) (xy 388.81885 -313.276161) (xy 388.776229 -313.251554) (xy 388.738108 -313.220429)
			(xy 388.705473 -313.183592) (xy 388.67917 -313.141996) (xy 388.659879 -313.09672) (xy 388.648102 -313.048936)
			(xy 388.644142 -312.999882) (xy 387.355334 -312.999882) (xy 387.354839 -313.024489) (xy 387.346944 -313.073066)
			(xy 387.33136 -313.119747) (xy 387.308489 -313.163324) (xy 387.278924 -313.202668) (xy 387.243431 -313.23676)
			(xy 387.202928 -313.264716) (xy 387.158466 -313.285814) (xy 387.111195 -313.299506) (xy 387.06234 -313.305438)
			(xy 387.013165 -313.303457) (xy 386.964946 -313.293613) (xy 386.91893 -313.276161) (xy 386.876309 -313.251554)
			(xy 386.838188 -313.220429) (xy 386.805553 -313.183592) (xy 386.77925 -313.141996) (xy 386.759959 -313.09672)
			(xy 386.748182 -313.048936) (xy 386.744222 -312.999882) (xy 313.055 -312.999882) (xy 313.054505 -313.024489)
			(xy 313.04661 -313.073066) (xy 313.031026 -313.119747) (xy 313.008155 -313.163324) (xy 312.97859 -313.202668)
			(xy 312.943097 -313.23676) (xy 312.902594 -313.264716) (xy 312.858132 -313.285814) (xy 312.810861 -313.299506)
			(xy 312.762006 -313.305438) (xy 312.712831 -313.303457) (xy 312.664612 -313.293613) (xy 312.618596 -313.276161)
			(xy 312.575975 -313.251554) (xy 312.537854 -313.220429) (xy 312.505219 -313.183592) (xy 312.478916 -313.141996)
			(xy 312.459625 -313.09672) (xy 312.447848 -313.048936) (xy 312.443888 -312.999882) (xy 311.15508 -312.999882)
			(xy 311.154585 -313.024489) (xy 311.14669 -313.073066) (xy 311.131106 -313.119747) (xy 311.108235 -313.163324)
			(xy 311.07867 -313.202668) (xy 311.043177 -313.23676) (xy 311.002674 -313.264716) (xy 310.958212 -313.285814)
			(xy 310.910941 -313.299506) (xy 310.862086 -313.305438) (xy 310.812911 -313.303457) (xy 310.764692 -313.293613)
			(xy 310.718676 -313.276161) (xy 310.676055 -313.251554) (xy 310.637934 -313.220429) (xy 310.605299 -313.183592)
			(xy 310.578996 -313.141996) (xy 310.559705 -313.09672) (xy 310.547928 -313.048936) (xy 310.543968 -312.999882)
			(xy 309.25516 -312.999882) (xy 309.254665 -313.024489) (xy 309.24677 -313.073066) (xy 309.231186 -313.119747)
			(xy 309.208315 -313.163324) (xy 309.17875 -313.202668) (xy 309.143257 -313.23676) (xy 309.102754 -313.264716)
			(xy 309.058292 -313.285814) (xy 309.011021 -313.299506) (xy 308.962166 -313.305438) (xy 308.912991 -313.303457)
			(xy 308.864772 -313.293613) (xy 308.818756 -313.276161) (xy 308.776135 -313.251554) (xy 308.738014 -313.220429)
			(xy 308.705379 -313.183592) (xy 308.679076 -313.141996) (xy 308.659785 -313.09672) (xy 308.648008 -313.048936)
			(xy 308.644048 -312.999882) (xy 307.35524 -312.999882) (xy 307.354745 -313.024489) (xy 307.34685 -313.073066)
			(xy 307.331266 -313.119747) (xy 307.308395 -313.163324) (xy 307.27883 -313.202668) (xy 307.243337 -313.23676)
			(xy 307.202834 -313.264716) (xy 307.158372 -313.285814) (xy 307.111101 -313.299506) (xy 307.062246 -313.305438)
			(xy 307.013071 -313.303457) (xy 306.964852 -313.293613) (xy 306.918836 -313.276161) (xy 306.876215 -313.251554)
			(xy 306.838094 -313.220429) (xy 306.805459 -313.183592) (xy 306.779156 -313.141996) (xy 306.759865 -313.09672)
			(xy 306.748088 -313.048936) (xy 306.744128 -312.999882) (xy 305.455066 -312.999882) (xy 305.454571 -313.024489)
			(xy 305.446676 -313.073066) (xy 305.431092 -313.119747) (xy 305.408221 -313.163324) (xy 305.378656 -313.202668)
			(xy 305.343163 -313.23676) (xy 305.30266 -313.264716) (xy 305.258198 -313.285814) (xy 305.210927 -313.299506)
			(xy 305.162072 -313.305438) (xy 305.112897 -313.303457) (xy 305.064678 -313.293613) (xy 305.018662 -313.276161)
			(xy 304.976041 -313.251554) (xy 304.93792 -313.220429) (xy 304.905285 -313.183592) (xy 304.878982 -313.141996)
			(xy 304.859691 -313.09672) (xy 304.847914 -313.048936) (xy 304.843954 -312.999882) (xy 303.555146 -312.999882)
			(xy 303.554651 -313.024489) (xy 303.546756 -313.073066) (xy 303.531172 -313.119747) (xy 303.508301 -313.163324)
			(xy 303.478736 -313.202668) (xy 303.443243 -313.23676) (xy 303.40274 -313.264716) (xy 303.358278 -313.285814)
			(xy 303.311007 -313.299506) (xy 303.262152 -313.305438) (xy 303.212977 -313.303457) (xy 303.164758 -313.293613)
			(xy 303.118742 -313.276161) (xy 303.076121 -313.251554) (xy 303.038 -313.220429) (xy 303.005365 -313.183592)
			(xy 302.979062 -313.141996) (xy 302.959771 -313.09672) (xy 302.947994 -313.048936) (xy 302.944034 -312.999882)
			(xy 301.655226 -312.999882) (xy 301.654731 -313.024489) (xy 301.646836 -313.073066) (xy 301.631252 -313.119747)
			(xy 301.608381 -313.163324) (xy 301.578816 -313.202668) (xy 301.543323 -313.23676) (xy 301.50282 -313.264716)
			(xy 301.458358 -313.285814) (xy 301.411087 -313.299506) (xy 301.362232 -313.305438) (xy 301.313057 -313.303457)
			(xy 301.264838 -313.293613) (xy 301.218822 -313.276161) (xy 301.176201 -313.251554) (xy 301.13808 -313.220429)
			(xy 301.105445 -313.183592) (xy 301.079142 -313.141996) (xy 301.059851 -313.09672) (xy 301.048074 -313.048936)
			(xy 301.044114 -312.999882) (xy 299.755052 -312.999882) (xy 299.754557 -313.024489) (xy 299.746662 -313.073066)
			(xy 299.731078 -313.119747) (xy 299.708207 -313.163324) (xy 299.678642 -313.202668) (xy 299.643149 -313.23676)
			(xy 299.602646 -313.264716) (xy 299.558184 -313.285814) (xy 299.510913 -313.299506) (xy 299.462058 -313.305438)
			(xy 299.412883 -313.303457) (xy 299.364664 -313.293613) (xy 299.318648 -313.276161) (xy 299.276027 -313.251554)
			(xy 299.237906 -313.220429) (xy 299.205271 -313.183592) (xy 299.178968 -313.141996) (xy 299.159677 -313.09672)
			(xy 299.1479 -313.048936) (xy 299.14394 -312.999882) (xy 297.855132 -312.999882) (xy 297.854637 -313.024489)
			(xy 297.846742 -313.073066) (xy 297.831158 -313.119747) (xy 297.808287 -313.163324) (xy 297.778722 -313.202668)
			(xy 297.743229 -313.23676) (xy 297.702726 -313.264716) (xy 297.658264 -313.285814) (xy 297.610993 -313.299506)
			(xy 297.562138 -313.305438) (xy 297.512963 -313.303457) (xy 297.464744 -313.293613) (xy 297.418728 -313.276161)
			(xy 297.376107 -313.251554) (xy 297.337986 -313.220429) (xy 297.305351 -313.183592) (xy 297.279048 -313.141996)
			(xy 297.259757 -313.09672) (xy 297.24798 -313.048936) (xy 297.24402 -312.999882) (xy 295.955212 -312.999882)
			(xy 295.954717 -313.024489) (xy 295.946822 -313.073066) (xy 295.931238 -313.119747) (xy 295.908367 -313.163324)
			(xy 295.878802 -313.202668) (xy 295.843309 -313.23676) (xy 295.802806 -313.264716) (xy 295.758344 -313.285814)
			(xy 295.711073 -313.299506) (xy 295.662218 -313.305438) (xy 295.613043 -313.303457) (xy 295.564824 -313.293613)
			(xy 295.518808 -313.276161) (xy 295.476187 -313.251554) (xy 295.438066 -313.220429) (xy 295.405431 -313.183592)
			(xy 295.379128 -313.141996) (xy 295.359837 -313.09672) (xy 295.34806 -313.048936) (xy 295.3441 -312.999882)
			(xy 294.055038 -312.999882) (xy 294.054543 -313.024489) (xy 294.046648 -313.073066) (xy 294.031064 -313.119747)
			(xy 294.008193 -313.163324) (xy 293.978628 -313.202668) (xy 293.943135 -313.23676) (xy 293.902632 -313.264716)
			(xy 293.85817 -313.285814) (xy 293.810899 -313.299506) (xy 293.762044 -313.305438) (xy 293.712869 -313.303457)
			(xy 293.66465 -313.293613) (xy 293.618634 -313.276161) (xy 293.576013 -313.251554) (xy 293.537892 -313.220429)
			(xy 293.505257 -313.183592) (xy 293.478954 -313.141996) (xy 293.459663 -313.09672) (xy 293.447886 -313.048936)
			(xy 293.443926 -312.999882) (xy 292.155118 -312.999882) (xy 292.154623 -313.024489) (xy 292.146728 -313.073066)
			(xy 292.131144 -313.119747) (xy 292.108273 -313.163324) (xy 292.078708 -313.202668) (xy 292.043215 -313.23676)
			(xy 292.002712 -313.264716) (xy 291.95825 -313.285814) (xy 291.910979 -313.299506) (xy 291.862124 -313.305438)
			(xy 291.812949 -313.303457) (xy 291.76473 -313.293613) (xy 291.718714 -313.276161) (xy 291.676093 -313.251554)
			(xy 291.637972 -313.220429) (xy 291.605337 -313.183592) (xy 291.579034 -313.141996) (xy 291.559743 -313.09672)
			(xy 291.547966 -313.048936) (xy 291.544006 -312.999882) (xy 290.255198 -312.999882) (xy 290.254703 -313.024489)
			(xy 290.246808 -313.073066) (xy 290.231224 -313.119747) (xy 290.208353 -313.163324) (xy 290.178788 -313.202668)
			(xy 290.143295 -313.23676) (xy 290.102792 -313.264716) (xy 290.05833 -313.285814) (xy 290.011059 -313.299506)
			(xy 289.962204 -313.305438) (xy 289.913029 -313.303457) (xy 289.86481 -313.293613) (xy 289.818794 -313.276161)
			(xy 289.776173 -313.251554) (xy 289.738052 -313.220429) (xy 289.705417 -313.183592) (xy 289.679114 -313.141996)
			(xy 289.659823 -313.09672) (xy 289.648046 -313.048936) (xy 289.644086 -312.999882) (xy 288.355024 -312.999882)
			(xy 288.354529 -313.024489) (xy 288.346634 -313.073066) (xy 288.33105 -313.119747) (xy 288.308179 -313.163324)
			(xy 288.278614 -313.202668) (xy 288.243121 -313.23676) (xy 288.202618 -313.264716) (xy 288.158156 -313.285814)
			(xy 288.110885 -313.299506) (xy 288.06203 -313.305438) (xy 288.012855 -313.303457) (xy 287.964636 -313.293613)
			(xy 287.91862 -313.276161) (xy 287.875999 -313.251554) (xy 287.837878 -313.220429) (xy 287.805243 -313.183592)
			(xy 287.77894 -313.141996) (xy 287.759649 -313.09672) (xy 287.747872 -313.048936) (xy 287.743912 -312.999882)
			(xy 286.455104 -312.999882) (xy 286.454609 -313.024489) (xy 286.446714 -313.073066) (xy 286.43113 -313.119747)
			(xy 286.408259 -313.163324) (xy 286.378694 -313.202668) (xy 286.343201 -313.23676) (xy 286.302698 -313.264716)
			(xy 286.258236 -313.285814) (xy 286.210965 -313.299506) (xy 286.16211 -313.305438) (xy 286.112935 -313.303457)
			(xy 286.064716 -313.293613) (xy 286.0187 -313.276161) (xy 285.976079 -313.251554) (xy 285.937958 -313.220429)
			(xy 285.905323 -313.183592) (xy 285.87902 -313.141996) (xy 285.859729 -313.09672) (xy 285.847952 -313.048936)
			(xy 285.843992 -312.999882) (xy 284.555184 -312.999882) (xy 284.554689 -313.024489) (xy 284.546794 -313.073066)
			(xy 284.53121 -313.119747) (xy 284.508339 -313.163324) (xy 284.478774 -313.202668) (xy 284.443281 -313.23676)
			(xy 284.402778 -313.264716) (xy 284.358316 -313.285814) (xy 284.311045 -313.299506) (xy 284.26219 -313.305438)
			(xy 284.213015 -313.303457) (xy 284.164796 -313.293613) (xy 284.11878 -313.276161) (xy 284.076159 -313.251554)
			(xy 284.038038 -313.220429) (xy 284.005403 -313.183592) (xy 283.9791 -313.141996) (xy 283.959809 -313.09672)
			(xy 283.948032 -313.048936) (xy 283.944072 -312.999882) (xy 282.65501 -312.999882) (xy 282.654515 -313.024489)
			(xy 282.64662 -313.073066) (xy 282.631036 -313.119747) (xy 282.608165 -313.163324) (xy 282.5786 -313.202668)
			(xy 282.543107 -313.23676) (xy 282.502604 -313.264716) (xy 282.458142 -313.285814) (xy 282.410871 -313.299506)
			(xy 282.362016 -313.305438) (xy 282.312841 -313.303457) (xy 282.264622 -313.293613) (xy 282.218606 -313.276161)
			(xy 282.175985 -313.251554) (xy 282.137864 -313.220429) (xy 282.105229 -313.183592) (xy 282.078926 -313.141996)
			(xy 282.059635 -313.09672) (xy 282.047858 -313.048936) (xy 282.043898 -312.999882) (xy 280.75509 -312.999882)
			(xy 280.754595 -313.024489) (xy 280.7467 -313.073066) (xy 280.731116 -313.119747) (xy 280.708245 -313.163324)
			(xy 280.67868 -313.202668) (xy 280.643187 -313.23676) (xy 280.602684 -313.264716) (xy 280.558222 -313.285814)
			(xy 280.510951 -313.299506) (xy 280.462096 -313.305438) (xy 280.412921 -313.303457) (xy 280.364702 -313.293613)
			(xy 280.318686 -313.276161) (xy 280.276065 -313.251554) (xy 280.237944 -313.220429) (xy 280.205309 -313.183592)
			(xy 280.179006 -313.141996) (xy 280.159715 -313.09672) (xy 280.147938 -313.048936) (xy 280.143978 -312.999882)
			(xy 278.85517 -312.999882) (xy 278.854675 -313.024489) (xy 278.84678 -313.073066) (xy 278.831196 -313.119747)
			(xy 278.808325 -313.163324) (xy 278.77876 -313.202668) (xy 278.743267 -313.23676) (xy 278.702764 -313.264716)
			(xy 278.658302 -313.285814) (xy 278.611031 -313.299506) (xy 278.562176 -313.305438) (xy 278.513001 -313.303457)
			(xy 278.464782 -313.293613) (xy 278.418766 -313.276161) (xy 278.376145 -313.251554) (xy 278.338024 -313.220429)
			(xy 278.305389 -313.183592) (xy 278.279086 -313.141996) (xy 278.259795 -313.09672) (xy 278.248018 -313.048936)
			(xy 278.244058 -312.999882) (xy 276.954996 -312.999882) (xy 276.954501 -313.024489) (xy 276.946606 -313.073066)
			(xy 276.931022 -313.119747) (xy 276.908151 -313.163324) (xy 276.878586 -313.202668) (xy 276.843093 -313.23676)
			(xy 276.80259 -313.264716) (xy 276.758128 -313.285814) (xy 276.710857 -313.299506) (xy 276.662002 -313.305438)
			(xy 276.612827 -313.303457) (xy 276.564608 -313.293613) (xy 276.518592 -313.276161) (xy 276.475971 -313.251554)
			(xy 276.43785 -313.220429) (xy 276.405215 -313.183592) (xy 276.378912 -313.141996) (xy 276.359621 -313.09672)
			(xy 276.347844 -313.048936) (xy 276.343884 -312.999882) (xy 275.055076 -312.999882) (xy 275.054581 -313.024489)
			(xy 275.046686 -313.073066) (xy 275.031102 -313.119747) (xy 275.008231 -313.163324) (xy 274.978666 -313.202668)
			(xy 274.943173 -313.23676) (xy 274.90267 -313.264716) (xy 274.858208 -313.285814) (xy 274.810937 -313.299506)
			(xy 274.762082 -313.305438) (xy 274.712907 -313.303457) (xy 274.664688 -313.293613) (xy 274.618672 -313.276161)
			(xy 274.576051 -313.251554) (xy 274.53793 -313.220429) (xy 274.505295 -313.183592) (xy 274.478992 -313.141996)
			(xy 274.459701 -313.09672) (xy 274.447924 -313.048936) (xy 274.443964 -312.999882) (xy 273.155156 -312.999882)
			(xy 273.154661 -313.024489) (xy 273.146766 -313.073066) (xy 273.131182 -313.119747) (xy 273.108311 -313.163324)
			(xy 273.078746 -313.202668) (xy 273.043253 -313.23676) (xy 273.00275 -313.264716) (xy 272.958288 -313.285814)
			(xy 272.911017 -313.299506) (xy 272.862162 -313.305438) (xy 272.812987 -313.303457) (xy 272.764768 -313.293613)
			(xy 272.718752 -313.276161) (xy 272.676131 -313.251554) (xy 272.63801 -313.220429) (xy 272.605375 -313.183592)
			(xy 272.579072 -313.141996) (xy 272.559781 -313.09672) (xy 272.548004 -313.048936) (xy 272.544044 -312.999882)
			(xy 271.255236 -312.999882) (xy 271.254741 -313.024489) (xy 271.246846 -313.073066) (xy 271.231262 -313.119747)
			(xy 271.208391 -313.163324) (xy 271.178826 -313.202668) (xy 271.143333 -313.23676) (xy 271.10283 -313.264716)
			(xy 271.058368 -313.285814) (xy 271.011097 -313.299506) (xy 270.962242 -313.305438) (xy 270.913067 -313.303457)
			(xy 270.864848 -313.293613) (xy 270.818832 -313.276161) (xy 270.776211 -313.251554) (xy 270.73809 -313.220429)
			(xy 270.705455 -313.183592) (xy 270.679152 -313.141996) (xy 270.659861 -313.09672) (xy 270.648084 -313.048936)
			(xy 270.644124 -312.999882) (xy 196.955156 -312.999882) (xy 196.954661 -313.024489) (xy 196.946766 -313.073066)
			(xy 196.931182 -313.119747) (xy 196.908311 -313.163324) (xy 196.878746 -313.202668) (xy 196.843253 -313.23676)
			(xy 196.80275 -313.264716) (xy 196.758288 -313.285814) (xy 196.711017 -313.299506) (xy 196.662162 -313.305438)
			(xy 196.612987 -313.303457) (xy 196.564768 -313.293613) (xy 196.518752 -313.276161) (xy 196.476131 -313.251554)
			(xy 196.43801 -313.220429) (xy 196.405375 -313.183592) (xy 196.379072 -313.141996) (xy 196.359781 -313.09672)
			(xy 196.348004 -313.048936) (xy 196.344044 -312.999882) (xy 195.055236 -312.999882) (xy 195.054741 -313.024489)
			(xy 195.046846 -313.073066) (xy 195.031262 -313.119747) (xy 195.008391 -313.163324) (xy 194.978826 -313.202668)
			(xy 194.943333 -313.23676) (xy 194.90283 -313.264716) (xy 194.858368 -313.285814) (xy 194.811097 -313.299506)
			(xy 194.762242 -313.305438) (xy 194.713067 -313.303457) (xy 194.664848 -313.293613) (xy 194.618832 -313.276161)
			(xy 194.576211 -313.251554) (xy 194.53809 -313.220429) (xy 194.505455 -313.183592) (xy 194.479152 -313.141996)
			(xy 194.459861 -313.09672) (xy 194.448084 -313.048936) (xy 194.444124 -312.999882) (xy 193.155316 -312.999882)
			(xy 193.154821 -313.024489) (xy 193.146926 -313.073066) (xy 193.131342 -313.119747) (xy 193.108471 -313.163324)
			(xy 193.078906 -313.202668) (xy 193.043413 -313.23676) (xy 193.00291 -313.264716) (xy 192.958448 -313.285814)
			(xy 192.911177 -313.299506) (xy 192.862322 -313.305438) (xy 192.813147 -313.303457) (xy 192.764928 -313.293613)
			(xy 192.718912 -313.276161) (xy 192.676291 -313.251554) (xy 192.63817 -313.220429) (xy 192.605535 -313.183592)
			(xy 192.579232 -313.141996) (xy 192.559941 -313.09672) (xy 192.548164 -313.048936) (xy 192.544204 -312.999882)
			(xy 191.255396 -312.999882) (xy 191.254901 -313.024489) (xy 191.247006 -313.073066) (xy 191.231422 -313.119747)
			(xy 191.208551 -313.163324) (xy 191.178986 -313.202668) (xy 191.143493 -313.23676) (xy 191.10299 -313.264716)
			(xy 191.058528 -313.285814) (xy 191.011257 -313.299506) (xy 190.962402 -313.305438) (xy 190.913227 -313.303457)
			(xy 190.865008 -313.293613) (xy 190.818992 -313.276161) (xy 190.776371 -313.251554) (xy 190.73825 -313.220429)
			(xy 190.705615 -313.183592) (xy 190.679312 -313.141996) (xy 190.660021 -313.09672) (xy 190.648244 -313.048936)
			(xy 190.644284 -312.999882) (xy 189.355222 -312.999882) (xy 189.354727 -313.024489) (xy 189.346832 -313.073066)
			(xy 189.331248 -313.119747) (xy 189.308377 -313.163324) (xy 189.278812 -313.202668) (xy 189.243319 -313.23676)
			(xy 189.202816 -313.264716) (xy 189.158354 -313.285814) (xy 189.111083 -313.299506) (xy 189.062228 -313.305438)
			(xy 189.013053 -313.303457) (xy 188.964834 -313.293613) (xy 188.918818 -313.276161) (xy 188.876197 -313.251554)
			(xy 188.838076 -313.220429) (xy 188.805441 -313.183592) (xy 188.779138 -313.141996) (xy 188.759847 -313.09672)
			(xy 188.74807 -313.048936) (xy 188.74411 -312.999882) (xy 187.455302 -312.999882) (xy 187.454807 -313.024489)
			(xy 187.446912 -313.073066) (xy 187.431328 -313.119747) (xy 187.408457 -313.163324) (xy 187.378892 -313.202668)
			(xy 187.343399 -313.23676) (xy 187.302896 -313.264716) (xy 187.258434 -313.285814) (xy 187.211163 -313.299506)
			(xy 187.162308 -313.305438) (xy 187.113133 -313.303457) (xy 187.064914 -313.293613) (xy 187.018898 -313.276161)
			(xy 186.976277 -313.251554) (xy 186.938156 -313.220429) (xy 186.905521 -313.183592) (xy 186.879218 -313.141996)
			(xy 186.859927 -313.09672) (xy 186.84815 -313.048936) (xy 186.84419 -312.999882) (xy 185.555382 -312.999882)
			(xy 185.554887 -313.024489) (xy 185.546992 -313.073066) (xy 185.531408 -313.119747) (xy 185.508537 -313.163324)
			(xy 185.478972 -313.202668) (xy 185.443479 -313.23676) (xy 185.402976 -313.264716) (xy 185.358514 -313.285814)
			(xy 185.311243 -313.299506) (xy 185.262388 -313.305438) (xy 185.213213 -313.303457) (xy 185.164994 -313.293613)
			(xy 185.118978 -313.276161) (xy 185.076357 -313.251554) (xy 185.038236 -313.220429) (xy 185.005601 -313.183592)
			(xy 184.979298 -313.141996) (xy 184.960007 -313.09672) (xy 184.94823 -313.048936) (xy 184.94427 -312.999882)
			(xy 183.655208 -312.999882) (xy 183.654713 -313.024489) (xy 183.646818 -313.073066) (xy 183.631234 -313.119747)
			(xy 183.608363 -313.163324) (xy 183.578798 -313.202668) (xy 183.543305 -313.23676) (xy 183.502802 -313.264716)
			(xy 183.45834 -313.285814) (xy 183.411069 -313.299506) (xy 183.362214 -313.305438) (xy 183.313039 -313.303457)
			(xy 183.26482 -313.293613) (xy 183.218804 -313.276161) (xy 183.176183 -313.251554) (xy 183.138062 -313.220429)
			(xy 183.105427 -313.183592) (xy 183.079124 -313.141996) (xy 183.059833 -313.09672) (xy 183.048056 -313.048936)
			(xy 183.044096 -312.999882) (xy 181.755288 -312.999882) (xy 181.754793 -313.024489) (xy 181.746898 -313.073066)
			(xy 181.731314 -313.119747) (xy 181.708443 -313.163324) (xy 181.678878 -313.202668) (xy 181.643385 -313.23676)
			(xy 181.602882 -313.264716) (xy 181.55842 -313.285814) (xy 181.511149 -313.299506) (xy 181.462294 -313.305438)
			(xy 181.413119 -313.303457) (xy 181.3649 -313.293613) (xy 181.318884 -313.276161) (xy 181.276263 -313.251554)
			(xy 181.238142 -313.220429) (xy 181.205507 -313.183592) (xy 181.179204 -313.141996) (xy 181.159913 -313.09672)
			(xy 181.148136 -313.048936) (xy 181.144176 -312.999882) (xy 179.855368 -312.999882) (xy 179.854873 -313.024489)
			(xy 179.846978 -313.073066) (xy 179.831394 -313.119747) (xy 179.808523 -313.163324) (xy 179.778958 -313.202668)
			(xy 179.743465 -313.23676) (xy 179.702962 -313.264716) (xy 179.6585 -313.285814) (xy 179.611229 -313.299506)
			(xy 179.562374 -313.305438) (xy 179.513199 -313.303457) (xy 179.46498 -313.293613) (xy 179.418964 -313.276161)
			(xy 179.376343 -313.251554) (xy 179.338222 -313.220429) (xy 179.305587 -313.183592) (xy 179.279284 -313.141996)
			(xy 179.259993 -313.09672) (xy 179.248216 -313.048936) (xy 179.244256 -312.999882) (xy 177.955194 -312.999882)
			(xy 177.954699 -313.024489) (xy 177.946804 -313.073066) (xy 177.93122 -313.119747) (xy 177.908349 -313.163324)
			(xy 177.878784 -313.202668) (xy 177.843291 -313.23676) (xy 177.802788 -313.264716) (xy 177.758326 -313.285814)
			(xy 177.711055 -313.299506) (xy 177.6622 -313.305438) (xy 177.613025 -313.303457) (xy 177.564806 -313.293613)
			(xy 177.51879 -313.276161) (xy 177.476169 -313.251554) (xy 177.438048 -313.220429) (xy 177.405413 -313.183592)
			(xy 177.37911 -313.141996) (xy 177.359819 -313.09672) (xy 177.348042 -313.048936) (xy 177.344082 -312.999882)
			(xy 176.055274 -312.999882) (xy 176.054779 -313.024489) (xy 176.046884 -313.073066) (xy 176.0313 -313.119747)
			(xy 176.008429 -313.163324) (xy 175.978864 -313.202668) (xy 175.943371 -313.23676) (xy 175.902868 -313.264716)
			(xy 175.858406 -313.285814) (xy 175.811135 -313.299506) (xy 175.76228 -313.305438) (xy 175.713105 -313.303457)
			(xy 175.664886 -313.293613) (xy 175.61887 -313.276161) (xy 175.576249 -313.251554) (xy 175.538128 -313.220429)
			(xy 175.505493 -313.183592) (xy 175.47919 -313.141996) (xy 175.459899 -313.09672) (xy 175.448122 -313.048936)
			(xy 175.444162 -312.999882) (xy 174.155354 -312.999882) (xy 174.154859 -313.024489) (xy 174.146964 -313.073066)
			(xy 174.13138 -313.119747) (xy 174.108509 -313.163324) (xy 174.078944 -313.202668) (xy 174.043451 -313.23676)
			(xy 174.002948 -313.264716) (xy 173.958486 -313.285814) (xy 173.911215 -313.299506) (xy 173.86236 -313.305438)
			(xy 173.813185 -313.303457) (xy 173.764966 -313.293613) (xy 173.71895 -313.276161) (xy 173.676329 -313.251554)
			(xy 173.638208 -313.220429) (xy 173.605573 -313.183592) (xy 173.57927 -313.141996) (xy 173.559979 -313.09672)
			(xy 173.548202 -313.048936) (xy 173.544242 -312.999882) (xy 172.25518 -312.999882) (xy 172.254685 -313.024489)
			(xy 172.24679 -313.073066) (xy 172.231206 -313.119747) (xy 172.208335 -313.163324) (xy 172.17877 -313.202668)
			(xy 172.143277 -313.23676) (xy 172.102774 -313.264716) (xy 172.058312 -313.285814) (xy 172.011041 -313.299506)
			(xy 171.962186 -313.305438) (xy 171.913011 -313.303457) (xy 171.864792 -313.293613) (xy 171.818776 -313.276161)
			(xy 171.776155 -313.251554) (xy 171.738034 -313.220429) (xy 171.705399 -313.183592) (xy 171.679096 -313.141996)
			(xy 171.659805 -313.09672) (xy 171.648028 -313.048936) (xy 171.644068 -312.999882) (xy 170.35526 -312.999882)
			(xy 170.354765 -313.024489) (xy 170.34687 -313.073066) (xy 170.331286 -313.119747) (xy 170.308415 -313.163324)
			(xy 170.27885 -313.202668) (xy 170.243357 -313.23676) (xy 170.202854 -313.264716) (xy 170.158392 -313.285814)
			(xy 170.111121 -313.299506) (xy 170.062266 -313.305438) (xy 170.013091 -313.303457) (xy 169.964872 -313.293613)
			(xy 169.918856 -313.276161) (xy 169.876235 -313.251554) (xy 169.838114 -313.220429) (xy 169.805479 -313.183592)
			(xy 169.779176 -313.141996) (xy 169.759885 -313.09672) (xy 169.748108 -313.048936) (xy 169.744148 -312.999882)
			(xy 168.45534 -312.999882) (xy 168.454845 -313.024489) (xy 168.44695 -313.073066) (xy 168.431366 -313.119747)
			(xy 168.408495 -313.163324) (xy 168.37893 -313.202668) (xy 168.343437 -313.23676) (xy 168.302934 -313.264716)
			(xy 168.258472 -313.285814) (xy 168.211201 -313.299506) (xy 168.162346 -313.305438) (xy 168.113171 -313.303457)
			(xy 168.064952 -313.293613) (xy 168.018936 -313.276161) (xy 167.976315 -313.251554) (xy 167.938194 -313.220429)
			(xy 167.905559 -313.183592) (xy 167.879256 -313.141996) (xy 167.859965 -313.09672) (xy 167.848188 -313.048936)
			(xy 167.844228 -312.999882) (xy 166.555166 -312.999882) (xy 166.554671 -313.024489) (xy 166.546776 -313.073066)
			(xy 166.531192 -313.119747) (xy 166.508321 -313.163324) (xy 166.478756 -313.202668) (xy 166.443263 -313.23676)
			(xy 166.40276 -313.264716) (xy 166.358298 -313.285814) (xy 166.311027 -313.299506) (xy 166.262172 -313.305438)
			(xy 166.212997 -313.303457) (xy 166.164778 -313.293613) (xy 166.118762 -313.276161) (xy 166.076141 -313.251554)
			(xy 166.03802 -313.220429) (xy 166.005385 -313.183592) (xy 165.979082 -313.141996) (xy 165.959791 -313.09672)
			(xy 165.948014 -313.048936) (xy 165.944054 -312.999882) (xy 164.655246 -312.999882) (xy 164.654751 -313.024489)
			(xy 164.646856 -313.073066) (xy 164.631272 -313.119747) (xy 164.608401 -313.163324) (xy 164.578836 -313.202668)
			(xy 164.543343 -313.23676) (xy 164.50284 -313.264716) (xy 164.458378 -313.285814) (xy 164.411107 -313.299506)
			(xy 164.362252 -313.305438) (xy 164.313077 -313.303457) (xy 164.264858 -313.293613) (xy 164.218842 -313.276161)
			(xy 164.176221 -313.251554) (xy 164.1381 -313.220429) (xy 164.105465 -313.183592) (xy 164.079162 -313.141996)
			(xy 164.059871 -313.09672) (xy 164.048094 -313.048936) (xy 164.044134 -312.999882) (xy 162.755326 -312.999882)
			(xy 162.754831 -313.024489) (xy 162.746936 -313.073066) (xy 162.731352 -313.119747) (xy 162.708481 -313.163324)
			(xy 162.678916 -313.202668) (xy 162.643423 -313.23676) (xy 162.60292 -313.264716) (xy 162.558458 -313.285814)
			(xy 162.511187 -313.299506) (xy 162.462332 -313.305438) (xy 162.413157 -313.303457) (xy 162.364938 -313.293613)
			(xy 162.318922 -313.276161) (xy 162.276301 -313.251554) (xy 162.23818 -313.220429) (xy 162.205545 -313.183592)
			(xy 162.179242 -313.141996) (xy 162.159951 -313.09672) (xy 162.148174 -313.048936) (xy 162.144214 -312.999882)
			(xy 160.855152 -312.999882) (xy 160.854657 -313.024489) (xy 160.846762 -313.073066) (xy 160.831178 -313.119747)
			(xy 160.808307 -313.163324) (xy 160.778742 -313.202668) (xy 160.743249 -313.23676) (xy 160.702746 -313.264716)
			(xy 160.658284 -313.285814) (xy 160.611013 -313.299506) (xy 160.562158 -313.305438) (xy 160.512983 -313.303457)
			(xy 160.464764 -313.293613) (xy 160.418748 -313.276161) (xy 160.376127 -313.251554) (xy 160.338006 -313.220429)
			(xy 160.305371 -313.183592) (xy 160.279068 -313.141996) (xy 160.259777 -313.09672) (xy 160.248 -313.048936)
			(xy 160.24404 -312.999882) (xy 158.955232 -312.999882) (xy 158.954737 -313.024489) (xy 158.946842 -313.073066)
			(xy 158.931258 -313.119747) (xy 158.908387 -313.163324) (xy 158.878822 -313.202668) (xy 158.843329 -313.23676)
			(xy 158.802826 -313.264716) (xy 158.758364 -313.285814) (xy 158.711093 -313.299506) (xy 158.662238 -313.305438)
			(xy 158.613063 -313.303457) (xy 158.564844 -313.293613) (xy 158.518828 -313.276161) (xy 158.476207 -313.251554)
			(xy 158.438086 -313.220429) (xy 158.405451 -313.183592) (xy 158.379148 -313.141996) (xy 158.359857 -313.09672)
			(xy 158.34808 -313.048936) (xy 158.34412 -312.999882) (xy 157.055312 -312.999882) (xy 157.054817 -313.024489)
			(xy 157.046922 -313.073066) (xy 157.031338 -313.119747) (xy 157.008467 -313.163324) (xy 156.978902 -313.202668)
			(xy 156.943409 -313.23676) (xy 156.902906 -313.264716) (xy 156.858444 -313.285814) (xy 156.811173 -313.299506)
			(xy 156.762318 -313.305438) (xy 156.713143 -313.303457) (xy 156.664924 -313.293613) (xy 156.618908 -313.276161)
			(xy 156.576287 -313.251554) (xy 156.538166 -313.220429) (xy 156.505531 -313.183592) (xy 156.479228 -313.141996)
			(xy 156.459937 -313.09672) (xy 156.44816 -313.048936) (xy 156.4442 -312.999882) (xy 155.155392 -312.999882)
			(xy 155.154897 -313.024489) (xy 155.147002 -313.073066) (xy 155.131418 -313.119747) (xy 155.108547 -313.163324)
			(xy 155.078982 -313.202668) (xy 155.043489 -313.23676) (xy 155.002986 -313.264716) (xy 154.958524 -313.285814)
			(xy 154.911253 -313.299506) (xy 154.862398 -313.305438) (xy 154.813223 -313.303457) (xy 154.765004 -313.293613)
			(xy 154.718988 -313.276161) (xy 154.676367 -313.251554) (xy 154.638246 -313.220429) (xy 154.605611 -313.183592)
			(xy 154.579308 -313.141996) (xy 154.560017 -313.09672) (xy 154.54824 -313.048936) (xy 154.54428 -312.999882)
			(xy 80.855058 -312.999882) (xy 80.854563 -313.024489) (xy 80.846668 -313.073066) (xy 80.831084 -313.119747)
			(xy 80.808213 -313.163324) (xy 80.778648 -313.202668) (xy 80.743155 -313.23676) (xy 80.702652 -313.264716)
			(xy 80.65819 -313.285814) (xy 80.610919 -313.299506) (xy 80.562064 -313.305438) (xy 80.512889 -313.303457)
			(xy 80.46467 -313.293613) (xy 80.418654 -313.276161) (xy 80.376033 -313.251554) (xy 80.337912 -313.220429)
			(xy 80.305277 -313.183592) (xy 80.278974 -313.141996) (xy 80.259683 -313.09672) (xy 80.247906 -313.048936)
			(xy 80.243946 -312.999882) (xy 78.955138 -312.999882) (xy 78.954643 -313.024489) (xy 78.946748 -313.073066)
			(xy 78.931164 -313.119747) (xy 78.908293 -313.163324) (xy 78.878728 -313.202668) (xy 78.843235 -313.23676)
			(xy 78.802732 -313.264716) (xy 78.75827 -313.285814) (xy 78.710999 -313.299506) (xy 78.662144 -313.305438)
			(xy 78.612969 -313.303457) (xy 78.56475 -313.293613) (xy 78.518734 -313.276161) (xy 78.476113 -313.251554)
			(xy 78.437992 -313.220429) (xy 78.405357 -313.183592) (xy 78.379054 -313.141996) (xy 78.359763 -313.09672)
			(xy 78.347986 -313.048936) (xy 78.344026 -312.999882) (xy 77.055218 -312.999882) (xy 77.054723 -313.024489)
			(xy 77.046828 -313.073066) (xy 77.031244 -313.119747) (xy 77.008373 -313.163324) (xy 76.978808 -313.202668)
			(xy 76.943315 -313.23676) (xy 76.902812 -313.264716) (xy 76.85835 -313.285814) (xy 76.811079 -313.299506)
			(xy 76.762224 -313.305438) (xy 76.713049 -313.303457) (xy 76.66483 -313.293613) (xy 76.618814 -313.276161)
			(xy 76.576193 -313.251554) (xy 76.538072 -313.220429) (xy 76.505437 -313.183592) (xy 76.479134 -313.141996)
			(xy 76.459843 -313.09672) (xy 76.448066 -313.048936) (xy 76.444106 -312.999882) (xy 75.155298 -312.999882)
			(xy 75.154803 -313.024489) (xy 75.146908 -313.073066) (xy 75.131324 -313.119747) (xy 75.108453 -313.163324)
			(xy 75.078888 -313.202668) (xy 75.043395 -313.23676) (xy 75.002892 -313.264716) (xy 74.95843 -313.285814)
			(xy 74.911159 -313.299506) (xy 74.862304 -313.305438) (xy 74.813129 -313.303457) (xy 74.76491 -313.293613)
			(xy 74.718894 -313.276161) (xy 74.676273 -313.251554) (xy 74.638152 -313.220429) (xy 74.605517 -313.183592)
			(xy 74.579214 -313.141996) (xy 74.559923 -313.09672) (xy 74.548146 -313.048936) (xy 74.544186 -312.999882)
			(xy 73.255124 -312.999882) (xy 73.254629 -313.024489) (xy 73.246734 -313.073066) (xy 73.23115 -313.119747)
			(xy 73.208279 -313.163324) (xy 73.178714 -313.202668) (xy 73.143221 -313.23676) (xy 73.102718 -313.264716)
			(xy 73.058256 -313.285814) (xy 73.010985 -313.299506) (xy 72.96213 -313.305438) (xy 72.912955 -313.303457)
			(xy 72.864736 -313.293613) (xy 72.81872 -313.276161) (xy 72.776099 -313.251554) (xy 72.737978 -313.220429)
			(xy 72.705343 -313.183592) (xy 72.67904 -313.141996) (xy 72.659749 -313.09672) (xy 72.647972 -313.048936)
			(xy 72.644012 -312.999882) (xy 71.355204 -312.999882) (xy 71.354709 -313.024489) (xy 71.346814 -313.073066)
			(xy 71.33123 -313.119747) (xy 71.308359 -313.163324) (xy 71.278794 -313.202668) (xy 71.243301 -313.23676)
			(xy 71.202798 -313.264716) (xy 71.158336 -313.285814) (xy 71.111065 -313.299506) (xy 71.06221 -313.305438)
			(xy 71.013035 -313.303457) (xy 70.964816 -313.293613) (xy 70.9188 -313.276161) (xy 70.876179 -313.251554)
			(xy 70.838058 -313.220429) (xy 70.805423 -313.183592) (xy 70.77912 -313.141996) (xy 70.759829 -313.09672)
			(xy 70.748052 -313.048936) (xy 70.744092 -312.999882) (xy 69.455284 -312.999882) (xy 69.454789 -313.024489)
			(xy 69.446894 -313.073066) (xy 69.43131 -313.119747) (xy 69.408439 -313.163324) (xy 69.378874 -313.202668)
			(xy 69.343381 -313.23676) (xy 69.302878 -313.264716) (xy 69.258416 -313.285814) (xy 69.211145 -313.299506)
			(xy 69.16229 -313.305438) (xy 69.113115 -313.303457) (xy 69.064896 -313.293613) (xy 69.01888 -313.276161)
			(xy 68.976259 -313.251554) (xy 68.938138 -313.220429) (xy 68.905503 -313.183592) (xy 68.8792 -313.141996)
			(xy 68.859909 -313.09672) (xy 68.848132 -313.048936) (xy 68.844172 -312.999882) (xy 67.55511 -312.999882)
			(xy 67.554615 -313.024489) (xy 67.54672 -313.073066) (xy 67.531136 -313.119747) (xy 67.508265 -313.163324)
			(xy 67.4787 -313.202668) (xy 67.443207 -313.23676) (xy 67.402704 -313.264716) (xy 67.358242 -313.285814)
			(xy 67.310971 -313.299506) (xy 67.262116 -313.305438) (xy 67.212941 -313.303457) (xy 67.164722 -313.293613)
			(xy 67.118706 -313.276161) (xy 67.076085 -313.251554) (xy 67.037964 -313.220429) (xy 67.005329 -313.183592)
			(xy 66.979026 -313.141996) (xy 66.959735 -313.09672) (xy 66.947958 -313.048936) (xy 66.943998 -312.999882)
			(xy 65.65519 -312.999882) (xy 65.654695 -313.024489) (xy 65.6468 -313.073066) (xy 65.631216 -313.119747)
			(xy 65.608345 -313.163324) (xy 65.57878 -313.202668) (xy 65.543287 -313.23676) (xy 65.502784 -313.264716)
			(xy 65.458322 -313.285814) (xy 65.411051 -313.299506) (xy 65.362196 -313.305438) (xy 65.313021 -313.303457)
			(xy 65.264802 -313.293613) (xy 65.218786 -313.276161) (xy 65.176165 -313.251554) (xy 65.138044 -313.220429)
			(xy 65.105409 -313.183592) (xy 65.079106 -313.141996) (xy 65.059815 -313.09672) (xy 65.048038 -313.048936)
			(xy 65.044078 -312.999882) (xy 63.75527 -312.999882) (xy 63.754775 -313.024489) (xy 63.74688 -313.073066)
			(xy 63.731296 -313.119747) (xy 63.708425 -313.163324) (xy 63.67886 -313.202668) (xy 63.643367 -313.23676)
			(xy 63.602864 -313.264716) (xy 63.558402 -313.285814) (xy 63.511131 -313.299506) (xy 63.462276 -313.305438)
			(xy 63.413101 -313.303457) (xy 63.364882 -313.293613) (xy 63.318866 -313.276161) (xy 63.276245 -313.251554)
			(xy 63.238124 -313.220429) (xy 63.205489 -313.183592) (xy 63.179186 -313.141996) (xy 63.159895 -313.09672)
			(xy 63.148118 -313.048936) (xy 63.144158 -312.999882) (xy 61.855096 -312.999882) (xy 61.854601 -313.024489)
			(xy 61.846706 -313.073066) (xy 61.831122 -313.119747) (xy 61.808251 -313.163324) (xy 61.778686 -313.202668)
			(xy 61.743193 -313.23676) (xy 61.70269 -313.264716) (xy 61.658228 -313.285814) (xy 61.610957 -313.299506)
			(xy 61.562102 -313.305438) (xy 61.512927 -313.303457) (xy 61.464708 -313.293613) (xy 61.418692 -313.276161)
			(xy 61.376071 -313.251554) (xy 61.33795 -313.220429) (xy 61.305315 -313.183592) (xy 61.279012 -313.141996)
			(xy 61.259721 -313.09672) (xy 61.247944 -313.048936) (xy 61.243984 -312.999882) (xy 59.955176 -312.999882)
			(xy 59.954681 -313.024489) (xy 59.946786 -313.073066) (xy 59.931202 -313.119747) (xy 59.908331 -313.163324)
			(xy 59.878766 -313.202668) (xy 59.843273 -313.23676) (xy 59.80277 -313.264716) (xy 59.758308 -313.285814)
			(xy 59.711037 -313.299506) (xy 59.662182 -313.305438) (xy 59.613007 -313.303457) (xy 59.564788 -313.293613)
			(xy 59.518772 -313.276161) (xy 59.476151 -313.251554) (xy 59.43803 -313.220429) (xy 59.405395 -313.183592)
			(xy 59.379092 -313.141996) (xy 59.359801 -313.09672) (xy 59.348024 -313.048936) (xy 59.344064 -312.999882)
			(xy 58.055256 -312.999882) (xy 58.054761 -313.024489) (xy 58.046866 -313.073066) (xy 58.031282 -313.119747)
			(xy 58.008411 -313.163324) (xy 57.978846 -313.202668) (xy 57.943353 -313.23676) (xy 57.90285 -313.264716)
			(xy 57.858388 -313.285814) (xy 57.811117 -313.299506) (xy 57.762262 -313.305438) (xy 57.713087 -313.303457)
			(xy 57.664868 -313.293613) (xy 57.618852 -313.276161) (xy 57.576231 -313.251554) (xy 57.53811 -313.220429)
			(xy 57.505475 -313.183592) (xy 57.479172 -313.141996) (xy 57.459881 -313.09672) (xy 57.448104 -313.048936)
			(xy 57.444144 -312.999882) (xy 56.155082 -312.999882) (xy 56.154587 -313.024489) (xy 56.146692 -313.073066)
			(xy 56.131108 -313.119747) (xy 56.108237 -313.163324) (xy 56.078672 -313.202668) (xy 56.043179 -313.23676)
			(xy 56.002676 -313.264716) (xy 55.958214 -313.285814) (xy 55.910943 -313.299506) (xy 55.862088 -313.305438)
			(xy 55.812913 -313.303457) (xy 55.764694 -313.293613) (xy 55.718678 -313.276161) (xy 55.676057 -313.251554)
			(xy 55.637936 -313.220429) (xy 55.605301 -313.183592) (xy 55.578998 -313.141996) (xy 55.559707 -313.09672)
			(xy 55.54793 -313.048936) (xy 55.54397 -312.999882) (xy 54.255162 -312.999882) (xy 54.254667 -313.024489)
			(xy 54.246772 -313.073066) (xy 54.231188 -313.119747) (xy 54.208317 -313.163324) (xy 54.178752 -313.202668)
			(xy 54.143259 -313.23676) (xy 54.102756 -313.264716) (xy 54.058294 -313.285814) (xy 54.011023 -313.299506)
			(xy 53.962168 -313.305438) (xy 53.912993 -313.303457) (xy 53.864774 -313.293613) (xy 53.818758 -313.276161)
			(xy 53.776137 -313.251554) (xy 53.738016 -313.220429) (xy 53.705381 -313.183592) (xy 53.679078 -313.141996)
			(xy 53.659787 -313.09672) (xy 53.64801 -313.048936) (xy 53.64405 -312.999882) (xy 52.355242 -312.999882)
			(xy 52.354747 -313.024489) (xy 52.346852 -313.073066) (xy 52.331268 -313.119747) (xy 52.308397 -313.163324)
			(xy 52.278832 -313.202668) (xy 52.243339 -313.23676) (xy 52.202836 -313.264716) (xy 52.158374 -313.285814)
			(xy 52.111103 -313.299506) (xy 52.062248 -313.305438) (xy 52.013073 -313.303457) (xy 51.964854 -313.293613)
			(xy 51.918838 -313.276161) (xy 51.876217 -313.251554) (xy 51.838096 -313.220429) (xy 51.805461 -313.183592)
			(xy 51.779158 -313.141996) (xy 51.759867 -313.09672) (xy 51.74809 -313.048936) (xy 51.74413 -312.999882)
			(xy 50.455068 -312.999882) (xy 50.454573 -313.024489) (xy 50.446678 -313.073066) (xy 50.431094 -313.119747)
			(xy 50.408223 -313.163324) (xy 50.378658 -313.202668) (xy 50.343165 -313.23676) (xy 50.302662 -313.264716)
			(xy 50.2582 -313.285814) (xy 50.210929 -313.299506) (xy 50.162074 -313.305438) (xy 50.112899 -313.303457)
			(xy 50.06468 -313.293613) (xy 50.018664 -313.276161) (xy 49.976043 -313.251554) (xy 49.937922 -313.220429)
			(xy 49.905287 -313.183592) (xy 49.878984 -313.141996) (xy 49.859693 -313.09672) (xy 49.847916 -313.048936)
			(xy 49.843956 -312.999882) (xy 48.555148 -312.999882) (xy 48.554653 -313.024489) (xy 48.546758 -313.073066)
			(xy 48.531174 -313.119747) (xy 48.508303 -313.163324) (xy 48.478738 -313.202668) (xy 48.443245 -313.23676)
			(xy 48.402742 -313.264716) (xy 48.35828 -313.285814) (xy 48.311009 -313.299506) (xy 48.262154 -313.305438)
			(xy 48.212979 -313.303457) (xy 48.16476 -313.293613) (xy 48.118744 -313.276161) (xy 48.076123 -313.251554)
			(xy 48.038002 -313.220429) (xy 48.005367 -313.183592) (xy 47.979064 -313.141996) (xy 47.959773 -313.09672)
			(xy 47.947996 -313.048936) (xy 47.944036 -312.999882) (xy 46.655228 -312.999882) (xy 46.654733 -313.024489)
			(xy 46.646838 -313.073066) (xy 46.631254 -313.119747) (xy 46.608383 -313.163324) (xy 46.578818 -313.202668)
			(xy 46.543325 -313.23676) (xy 46.502822 -313.264716) (xy 46.45836 -313.285814) (xy 46.411089 -313.299506)
			(xy 46.362234 -313.305438) (xy 46.313059 -313.303457) (xy 46.26484 -313.293613) (xy 46.218824 -313.276161)
			(xy 46.176203 -313.251554) (xy 46.138082 -313.220429) (xy 46.105447 -313.183592) (xy 46.079144 -313.141996)
			(xy 46.059853 -313.09672) (xy 46.048076 -313.048936) (xy 46.044116 -312.999882) (xy 44.755054 -312.999882)
			(xy 44.754559 -313.024489) (xy 44.746664 -313.073066) (xy 44.73108 -313.119747) (xy 44.708209 -313.163324)
			(xy 44.678644 -313.202668) (xy 44.643151 -313.23676) (xy 44.602648 -313.264716) (xy 44.558186 -313.285814)
			(xy 44.510915 -313.299506) (xy 44.46206 -313.305438) (xy 44.412885 -313.303457) (xy 44.364666 -313.293613)
			(xy 44.31865 -313.276161) (xy 44.276029 -313.251554) (xy 44.237908 -313.220429) (xy 44.205273 -313.183592)
			(xy 44.17897 -313.141996) (xy 44.159679 -313.09672) (xy 44.147902 -313.048936) (xy 44.143942 -312.999882)
			(xy 42.855134 -312.999882) (xy 42.854639 -313.024489) (xy 42.846744 -313.073066) (xy 42.83116 -313.119747)
			(xy 42.808289 -313.163324) (xy 42.778724 -313.202668) (xy 42.743231 -313.23676) (xy 42.702728 -313.264716)
			(xy 42.658266 -313.285814) (xy 42.610995 -313.299506) (xy 42.56214 -313.305438) (xy 42.512965 -313.303457)
			(xy 42.464746 -313.293613) (xy 42.41873 -313.276161) (xy 42.376109 -313.251554) (xy 42.337988 -313.220429)
			(xy 42.305353 -313.183592) (xy 42.27905 -313.141996) (xy 42.259759 -313.09672) (xy 42.247982 -313.048936)
			(xy 42.244022 -312.999882) (xy 40.955214 -312.999882) (xy 40.954719 -313.024489) (xy 40.946824 -313.073066)
			(xy 40.93124 -313.119747) (xy 40.908369 -313.163324) (xy 40.878804 -313.202668) (xy 40.843311 -313.23676)
			(xy 40.802808 -313.264716) (xy 40.758346 -313.285814) (xy 40.711075 -313.299506) (xy 40.66222 -313.305438)
			(xy 40.613045 -313.303457) (xy 40.564826 -313.293613) (xy 40.51881 -313.276161) (xy 40.476189 -313.251554)
			(xy 40.438068 -313.220429) (xy 40.405433 -313.183592) (xy 40.37913 -313.141996) (xy 40.359839 -313.09672)
			(xy 40.348062 -313.048936) (xy 40.344102 -312.999882) (xy 39.055294 -312.999882) (xy 39.054799 -313.024489)
			(xy 39.046904 -313.073066) (xy 39.03132 -313.119747) (xy 39.008449 -313.163324) (xy 38.978884 -313.202668)
			(xy 38.943391 -313.23676) (xy 38.902888 -313.264716) (xy 38.858426 -313.285814) (xy 38.811155 -313.299506)
			(xy 38.7623 -313.305438) (xy 38.713125 -313.303457) (xy 38.664906 -313.293613) (xy 38.61889 -313.276161)
			(xy 38.576269 -313.251554) (xy 38.538148 -313.220429) (xy 38.505513 -313.183592) (xy 38.47921 -313.141996)
			(xy 38.459919 -313.09672) (xy 38.448142 -313.048936) (xy 38.444182 -312.999882) (xy 0.509016 -312.999882)
			(xy 0.509016 -313.949842) (xy 38.444182 -313.949842) (xy 38.448142 -313.900788) (xy 38.459919 -313.853004)
			(xy 38.47921 -313.807728) (xy 38.505513 -313.766132) (xy 38.538148 -313.729295) (xy 38.576269 -313.69817)
			(xy 38.61889 -313.673563) (xy 38.664906 -313.656111) (xy 38.713125 -313.646267) (xy 38.7623 -313.644286)
			(xy 38.811155 -313.650218) (xy 38.858426 -313.66391) (xy 38.902888 -313.685008) (xy 38.943391 -313.712964)
			(xy 38.978884 -313.747056) (xy 39.008449 -313.7864) (xy 39.03132 -313.829977) (xy 39.046904 -313.876658)
			(xy 39.054799 -313.925235) (xy 39.055294 -313.949842) (xy 40.344102 -313.949842) (xy 40.348062 -313.900788)
			(xy 40.359839 -313.853004) (xy 40.37913 -313.807728) (xy 40.405433 -313.766132) (xy 40.438068 -313.729295)
			(xy 40.476189 -313.69817) (xy 40.51881 -313.673563) (xy 40.564826 -313.656111) (xy 40.613045 -313.646267)
			(xy 40.66222 -313.644286) (xy 40.711075 -313.650218) (xy 40.758346 -313.66391) (xy 40.802808 -313.685008)
			(xy 40.843311 -313.712964) (xy 40.878804 -313.747056) (xy 40.908369 -313.7864) (xy 40.93124 -313.829977)
			(xy 40.946824 -313.876658) (xy 40.954719 -313.925235) (xy 40.955214 -313.949842) (xy 42.244022 -313.949842)
			(xy 42.247982 -313.900788) (xy 42.259759 -313.853004) (xy 42.27905 -313.807728) (xy 42.305353 -313.766132)
			(xy 42.337988 -313.729295) (xy 42.376109 -313.69817) (xy 42.41873 -313.673563) (xy 42.464746 -313.656111)
			(xy 42.512965 -313.646267) (xy 42.56214 -313.644286) (xy 42.610995 -313.650218) (xy 42.658266 -313.66391)
			(xy 42.702728 -313.685008) (xy 42.743231 -313.712964) (xy 42.778724 -313.747056) (xy 42.808289 -313.7864)
			(xy 42.83116 -313.829977) (xy 42.846744 -313.876658) (xy 42.854639 -313.925235) (xy 42.855134 -313.949842)
			(xy 44.143942 -313.949842) (xy 44.147902 -313.900788) (xy 44.159679 -313.853004) (xy 44.17897 -313.807728)
			(xy 44.205273 -313.766132) (xy 44.237908 -313.729295) (xy 44.276029 -313.69817) (xy 44.31865 -313.673563)
			(xy 44.364666 -313.656111) (xy 44.412885 -313.646267) (xy 44.46206 -313.644286) (xy 44.510915 -313.650218)
			(xy 44.558186 -313.66391) (xy 44.602648 -313.685008) (xy 44.643151 -313.712964) (xy 44.678644 -313.747056)
			(xy 44.708209 -313.7864) (xy 44.73108 -313.829977) (xy 44.746664 -313.876658) (xy 44.754559 -313.925235)
			(xy 44.755054 -313.949842) (xy 46.044116 -313.949842) (xy 46.048076 -313.900788) (xy 46.059853 -313.853004)
			(xy 46.079144 -313.807728) (xy 46.105447 -313.766132) (xy 46.138082 -313.729295) (xy 46.176203 -313.69817)
			(xy 46.218824 -313.673563) (xy 46.26484 -313.656111) (xy 46.313059 -313.646267) (xy 46.362234 -313.644286)
			(xy 46.411089 -313.650218) (xy 46.45836 -313.66391) (xy 46.502822 -313.685008) (xy 46.543325 -313.712964)
			(xy 46.578818 -313.747056) (xy 46.608383 -313.7864) (xy 46.631254 -313.829977) (xy 46.646838 -313.876658)
			(xy 46.654733 -313.925235) (xy 46.655228 -313.949842) (xy 47.944036 -313.949842) (xy 47.947996 -313.900788)
			(xy 47.959773 -313.853004) (xy 47.979064 -313.807728) (xy 48.005367 -313.766132) (xy 48.038002 -313.729295)
			(xy 48.076123 -313.69817) (xy 48.118744 -313.673563) (xy 48.16476 -313.656111) (xy 48.212979 -313.646267)
			(xy 48.262154 -313.644286) (xy 48.311009 -313.650218) (xy 48.35828 -313.66391) (xy 48.402742 -313.685008)
			(xy 48.443245 -313.712964) (xy 48.478738 -313.747056) (xy 48.508303 -313.7864) (xy 48.531174 -313.829977)
			(xy 48.546758 -313.876658) (xy 48.554653 -313.925235) (xy 48.555148 -313.949842) (xy 49.843956 -313.949842)
			(xy 49.847916 -313.900788) (xy 49.859693 -313.853004) (xy 49.878984 -313.807728) (xy 49.905287 -313.766132)
			(xy 49.937922 -313.729295) (xy 49.976043 -313.69817) (xy 50.018664 -313.673563) (xy 50.06468 -313.656111)
			(xy 50.112899 -313.646267) (xy 50.162074 -313.644286) (xy 50.210929 -313.650218) (xy 50.2582 -313.66391)
			(xy 50.302662 -313.685008) (xy 50.343165 -313.712964) (xy 50.378658 -313.747056) (xy 50.408223 -313.7864)
			(xy 50.431094 -313.829977) (xy 50.446678 -313.876658) (xy 50.454573 -313.925235) (xy 50.455068 -313.949842)
			(xy 51.74413 -313.949842) (xy 51.74809 -313.900788) (xy 51.759867 -313.853004) (xy 51.779158 -313.807728)
			(xy 51.805461 -313.766132) (xy 51.838096 -313.729295) (xy 51.876217 -313.69817) (xy 51.918838 -313.673563)
			(xy 51.964854 -313.656111) (xy 52.013073 -313.646267) (xy 52.062248 -313.644286) (xy 52.111103 -313.650218)
			(xy 52.158374 -313.66391) (xy 52.202836 -313.685008) (xy 52.243339 -313.712964) (xy 52.278832 -313.747056)
			(xy 52.308397 -313.7864) (xy 52.331268 -313.829977) (xy 52.346852 -313.876658) (xy 52.354747 -313.925235)
			(xy 52.355242 -313.949842) (xy 53.64405 -313.949842) (xy 53.64801 -313.900788) (xy 53.659787 -313.853004)
			(xy 53.679078 -313.807728) (xy 53.705381 -313.766132) (xy 53.738016 -313.729295) (xy 53.776137 -313.69817)
			(xy 53.818758 -313.673563) (xy 53.864774 -313.656111) (xy 53.912993 -313.646267) (xy 53.962168 -313.644286)
			(xy 54.011023 -313.650218) (xy 54.058294 -313.66391) (xy 54.102756 -313.685008) (xy 54.143259 -313.712964)
			(xy 54.178752 -313.747056) (xy 54.208317 -313.7864) (xy 54.231188 -313.829977) (xy 54.246772 -313.876658)
			(xy 54.254667 -313.925235) (xy 54.255162 -313.949842) (xy 55.54397 -313.949842) (xy 55.54793 -313.900788)
			(xy 55.559707 -313.853004) (xy 55.578998 -313.807728) (xy 55.605301 -313.766132) (xy 55.637936 -313.729295)
			(xy 55.676057 -313.69817) (xy 55.718678 -313.673563) (xy 55.764694 -313.656111) (xy 55.812913 -313.646267)
			(xy 55.862088 -313.644286) (xy 55.910943 -313.650218) (xy 55.958214 -313.66391) (xy 56.002676 -313.685008)
			(xy 56.043179 -313.712964) (xy 56.078672 -313.747056) (xy 56.108237 -313.7864) (xy 56.131108 -313.829977)
			(xy 56.146692 -313.876658) (xy 56.154587 -313.925235) (xy 56.155082 -313.949842) (xy 57.444144 -313.949842)
			(xy 57.448104 -313.900788) (xy 57.459881 -313.853004) (xy 57.479172 -313.807728) (xy 57.505475 -313.766132)
			(xy 57.53811 -313.729295) (xy 57.576231 -313.69817) (xy 57.618852 -313.673563) (xy 57.664868 -313.656111)
			(xy 57.713087 -313.646267) (xy 57.762262 -313.644286) (xy 57.811117 -313.650218) (xy 57.858388 -313.66391)
			(xy 57.90285 -313.685008) (xy 57.943353 -313.712964) (xy 57.978846 -313.747056) (xy 58.008411 -313.7864)
			(xy 58.031282 -313.829977) (xy 58.046866 -313.876658) (xy 58.054761 -313.925235) (xy 58.055256 -313.949842)
			(xy 59.344064 -313.949842) (xy 59.348024 -313.900788) (xy 59.359801 -313.853004) (xy 59.379092 -313.807728)
			(xy 59.405395 -313.766132) (xy 59.43803 -313.729295) (xy 59.476151 -313.69817) (xy 59.518772 -313.673563)
			(xy 59.564788 -313.656111) (xy 59.613007 -313.646267) (xy 59.662182 -313.644286) (xy 59.711037 -313.650218)
			(xy 59.758308 -313.66391) (xy 59.80277 -313.685008) (xy 59.843273 -313.712964) (xy 59.878766 -313.747056)
			(xy 59.908331 -313.7864) (xy 59.931202 -313.829977) (xy 59.946786 -313.876658) (xy 59.954681 -313.925235)
			(xy 59.955176 -313.949842) (xy 61.243984 -313.949842) (xy 61.247944 -313.900788) (xy 61.259721 -313.853004)
			(xy 61.279012 -313.807728) (xy 61.305315 -313.766132) (xy 61.33795 -313.729295) (xy 61.376071 -313.69817)
			(xy 61.418692 -313.673563) (xy 61.464708 -313.656111) (xy 61.512927 -313.646267) (xy 61.562102 -313.644286)
			(xy 61.610957 -313.650218) (xy 61.658228 -313.66391) (xy 61.70269 -313.685008) (xy 61.743193 -313.712964)
			(xy 61.778686 -313.747056) (xy 61.808251 -313.7864) (xy 61.831122 -313.829977) (xy 61.846706 -313.876658)
			(xy 61.854601 -313.925235) (xy 61.855096 -313.949842) (xy 63.144158 -313.949842) (xy 63.148118 -313.900788)
			(xy 63.159895 -313.853004) (xy 63.179186 -313.807728) (xy 63.205489 -313.766132) (xy 63.238124 -313.729295)
			(xy 63.276245 -313.69817) (xy 63.318866 -313.673563) (xy 63.364882 -313.656111) (xy 63.413101 -313.646267)
			(xy 63.462276 -313.644286) (xy 63.511131 -313.650218) (xy 63.558402 -313.66391) (xy 63.602864 -313.685008)
			(xy 63.643367 -313.712964) (xy 63.67886 -313.747056) (xy 63.708425 -313.7864) (xy 63.731296 -313.829977)
			(xy 63.74688 -313.876658) (xy 63.754775 -313.925235) (xy 63.75527 -313.949842) (xy 65.044078 -313.949842)
			(xy 65.048038 -313.900788) (xy 65.059815 -313.853004) (xy 65.079106 -313.807728) (xy 65.105409 -313.766132)
			(xy 65.138044 -313.729295) (xy 65.176165 -313.69817) (xy 65.218786 -313.673563) (xy 65.264802 -313.656111)
			(xy 65.313021 -313.646267) (xy 65.362196 -313.644286) (xy 65.411051 -313.650218) (xy 65.458322 -313.66391)
			(xy 65.502784 -313.685008) (xy 65.543287 -313.712964) (xy 65.57878 -313.747056) (xy 65.608345 -313.7864)
			(xy 65.631216 -313.829977) (xy 65.6468 -313.876658) (xy 65.654695 -313.925235) (xy 65.65519 -313.949842)
			(xy 66.943998 -313.949842) (xy 66.947958 -313.900788) (xy 66.959735 -313.853004) (xy 66.979026 -313.807728)
			(xy 67.005329 -313.766132) (xy 67.037964 -313.729295) (xy 67.076085 -313.69817) (xy 67.118706 -313.673563)
			(xy 67.164722 -313.656111) (xy 67.212941 -313.646267) (xy 67.262116 -313.644286) (xy 67.310971 -313.650218)
			(xy 67.358242 -313.66391) (xy 67.402704 -313.685008) (xy 67.443207 -313.712964) (xy 67.4787 -313.747056)
			(xy 67.508265 -313.7864) (xy 67.531136 -313.829977) (xy 67.54672 -313.876658) (xy 67.554615 -313.925235)
			(xy 67.55511 -313.949842) (xy 68.844172 -313.949842) (xy 68.848132 -313.900788) (xy 68.859909 -313.853004)
			(xy 68.8792 -313.807728) (xy 68.905503 -313.766132) (xy 68.938138 -313.729295) (xy 68.976259 -313.69817)
			(xy 69.01888 -313.673563) (xy 69.064896 -313.656111) (xy 69.113115 -313.646267) (xy 69.16229 -313.644286)
			(xy 69.211145 -313.650218) (xy 69.258416 -313.66391) (xy 69.302878 -313.685008) (xy 69.343381 -313.712964)
			(xy 69.378874 -313.747056) (xy 69.408439 -313.7864) (xy 69.43131 -313.829977) (xy 69.446894 -313.876658)
			(xy 69.454789 -313.925235) (xy 69.455284 -313.949842) (xy 70.744092 -313.949842) (xy 70.748052 -313.900788)
			(xy 70.759829 -313.853004) (xy 70.77912 -313.807728) (xy 70.805423 -313.766132) (xy 70.838058 -313.729295)
			(xy 70.876179 -313.69817) (xy 70.9188 -313.673563) (xy 70.964816 -313.656111) (xy 71.013035 -313.646267)
			(xy 71.06221 -313.644286) (xy 71.111065 -313.650218) (xy 71.158336 -313.66391) (xy 71.202798 -313.685008)
			(xy 71.243301 -313.712964) (xy 71.278794 -313.747056) (xy 71.308359 -313.7864) (xy 71.33123 -313.829977)
			(xy 71.346814 -313.876658) (xy 71.354709 -313.925235) (xy 71.355204 -313.949842) (xy 72.644012 -313.949842)
			(xy 72.647972 -313.900788) (xy 72.659749 -313.853004) (xy 72.67904 -313.807728) (xy 72.705343 -313.766132)
			(xy 72.737978 -313.729295) (xy 72.776099 -313.69817) (xy 72.81872 -313.673563) (xy 72.864736 -313.656111)
			(xy 72.912955 -313.646267) (xy 72.96213 -313.644286) (xy 73.010985 -313.650218) (xy 73.058256 -313.66391)
			(xy 73.102718 -313.685008) (xy 73.143221 -313.712964) (xy 73.178714 -313.747056) (xy 73.208279 -313.7864)
			(xy 73.23115 -313.829977) (xy 73.246734 -313.876658) (xy 73.254629 -313.925235) (xy 73.255124 -313.949842)
			(xy 74.544186 -313.949842) (xy 74.548146 -313.900788) (xy 74.559923 -313.853004) (xy 74.579214 -313.807728)
			(xy 74.605517 -313.766132) (xy 74.638152 -313.729295) (xy 74.676273 -313.69817) (xy 74.718894 -313.673563)
			(xy 74.76491 -313.656111) (xy 74.813129 -313.646267) (xy 74.862304 -313.644286) (xy 74.911159 -313.650218)
			(xy 74.95843 -313.66391) (xy 75.002892 -313.685008) (xy 75.043395 -313.712964) (xy 75.078888 -313.747056)
			(xy 75.108453 -313.7864) (xy 75.131324 -313.829977) (xy 75.146908 -313.876658) (xy 75.154803 -313.925235)
			(xy 75.155298 -313.949842) (xy 76.444106 -313.949842) (xy 76.448066 -313.900788) (xy 76.459843 -313.853004)
			(xy 76.479134 -313.807728) (xy 76.505437 -313.766132) (xy 76.538072 -313.729295) (xy 76.576193 -313.69817)
			(xy 76.618814 -313.673563) (xy 76.66483 -313.656111) (xy 76.713049 -313.646267) (xy 76.762224 -313.644286)
			(xy 76.811079 -313.650218) (xy 76.85835 -313.66391) (xy 76.902812 -313.685008) (xy 76.943315 -313.712964)
			(xy 76.978808 -313.747056) (xy 77.008373 -313.7864) (xy 77.031244 -313.829977) (xy 77.046828 -313.876658)
			(xy 77.054723 -313.925235) (xy 77.055218 -313.949842) (xy 78.344026 -313.949842) (xy 78.347986 -313.900788)
			(xy 78.359763 -313.853004) (xy 78.379054 -313.807728) (xy 78.405357 -313.766132) (xy 78.437992 -313.729295)
			(xy 78.476113 -313.69817) (xy 78.518734 -313.673563) (xy 78.56475 -313.656111) (xy 78.612969 -313.646267)
			(xy 78.662144 -313.644286) (xy 78.710999 -313.650218) (xy 78.75827 -313.66391) (xy 78.802732 -313.685008)
			(xy 78.843235 -313.712964) (xy 78.878728 -313.747056) (xy 78.908293 -313.7864) (xy 78.931164 -313.829977)
			(xy 78.946748 -313.876658) (xy 78.954643 -313.925235) (xy 78.955138 -313.949842) (xy 80.243946 -313.949842)
			(xy 80.247906 -313.900788) (xy 80.259683 -313.853004) (xy 80.278974 -313.807728) (xy 80.305277 -313.766132)
			(xy 80.337912 -313.729295) (xy 80.376033 -313.69817) (xy 80.418654 -313.673563) (xy 80.46467 -313.656111)
			(xy 80.512889 -313.646267) (xy 80.562064 -313.644286) (xy 80.610919 -313.650218) (xy 80.65819 -313.66391)
			(xy 80.702652 -313.685008) (xy 80.743155 -313.712964) (xy 80.778648 -313.747056) (xy 80.808213 -313.7864)
			(xy 80.831084 -313.829977) (xy 80.846668 -313.876658) (xy 80.854563 -313.925235) (xy 80.855058 -313.949842)
			(xy 154.54428 -313.949842) (xy 154.54824 -313.900788) (xy 154.560017 -313.853004) (xy 154.579308 -313.807728)
			(xy 154.605611 -313.766132) (xy 154.638246 -313.729295) (xy 154.676367 -313.69817) (xy 154.718988 -313.673563)
			(xy 154.765004 -313.656111) (xy 154.813223 -313.646267) (xy 154.862398 -313.644286) (xy 154.911253 -313.650218)
			(xy 154.958524 -313.66391) (xy 155.002986 -313.685008) (xy 155.043489 -313.712964) (xy 155.078982 -313.747056)
			(xy 155.108547 -313.7864) (xy 155.131418 -313.829977) (xy 155.147002 -313.876658) (xy 155.154897 -313.925235)
			(xy 155.155392 -313.949842) (xy 156.4442 -313.949842) (xy 156.44816 -313.900788) (xy 156.459937 -313.853004)
			(xy 156.479228 -313.807728) (xy 156.505531 -313.766132) (xy 156.538166 -313.729295) (xy 156.576287 -313.69817)
			(xy 156.618908 -313.673563) (xy 156.664924 -313.656111) (xy 156.713143 -313.646267) (xy 156.762318 -313.644286)
			(xy 156.811173 -313.650218) (xy 156.858444 -313.66391) (xy 156.902906 -313.685008) (xy 156.943409 -313.712964)
			(xy 156.978902 -313.747056) (xy 157.008467 -313.7864) (xy 157.031338 -313.829977) (xy 157.046922 -313.876658)
			(xy 157.054817 -313.925235) (xy 157.055312 -313.949842) (xy 158.34412 -313.949842) (xy 158.34808 -313.900788)
			(xy 158.359857 -313.853004) (xy 158.379148 -313.807728) (xy 158.405451 -313.766132) (xy 158.438086 -313.729295)
			(xy 158.476207 -313.69817) (xy 158.518828 -313.673563) (xy 158.564844 -313.656111) (xy 158.613063 -313.646267)
			(xy 158.662238 -313.644286) (xy 158.711093 -313.650218) (xy 158.758364 -313.66391) (xy 158.802826 -313.685008)
			(xy 158.843329 -313.712964) (xy 158.878822 -313.747056) (xy 158.908387 -313.7864) (xy 158.931258 -313.829977)
			(xy 158.946842 -313.876658) (xy 158.954737 -313.925235) (xy 158.955232 -313.949842) (xy 160.24404 -313.949842)
			(xy 160.248 -313.900788) (xy 160.259777 -313.853004) (xy 160.279068 -313.807728) (xy 160.305371 -313.766132)
			(xy 160.338006 -313.729295) (xy 160.376127 -313.69817) (xy 160.418748 -313.673563) (xy 160.464764 -313.656111)
			(xy 160.512983 -313.646267) (xy 160.562158 -313.644286) (xy 160.611013 -313.650218) (xy 160.658284 -313.66391)
			(xy 160.702746 -313.685008) (xy 160.743249 -313.712964) (xy 160.778742 -313.747056) (xy 160.808307 -313.7864)
			(xy 160.831178 -313.829977) (xy 160.846762 -313.876658) (xy 160.854657 -313.925235) (xy 160.855152 -313.949842)
			(xy 162.144214 -313.949842) (xy 162.148174 -313.900788) (xy 162.159951 -313.853004) (xy 162.179242 -313.807728)
			(xy 162.205545 -313.766132) (xy 162.23818 -313.729295) (xy 162.276301 -313.69817) (xy 162.318922 -313.673563)
			(xy 162.364938 -313.656111) (xy 162.413157 -313.646267) (xy 162.462332 -313.644286) (xy 162.511187 -313.650218)
			(xy 162.558458 -313.66391) (xy 162.60292 -313.685008) (xy 162.643423 -313.712964) (xy 162.678916 -313.747056)
			(xy 162.708481 -313.7864) (xy 162.731352 -313.829977) (xy 162.746936 -313.876658) (xy 162.754831 -313.925235)
			(xy 162.755326 -313.949842) (xy 164.044134 -313.949842) (xy 164.048094 -313.900788) (xy 164.059871 -313.853004)
			(xy 164.079162 -313.807728) (xy 164.105465 -313.766132) (xy 164.1381 -313.729295) (xy 164.176221 -313.69817)
			(xy 164.218842 -313.673563) (xy 164.264858 -313.656111) (xy 164.313077 -313.646267) (xy 164.362252 -313.644286)
			(xy 164.411107 -313.650218) (xy 164.458378 -313.66391) (xy 164.50284 -313.685008) (xy 164.543343 -313.712964)
			(xy 164.578836 -313.747056) (xy 164.608401 -313.7864) (xy 164.631272 -313.829977) (xy 164.646856 -313.876658)
			(xy 164.654751 -313.925235) (xy 164.655246 -313.949842) (xy 165.944054 -313.949842) (xy 165.948014 -313.900788)
			(xy 165.959791 -313.853004) (xy 165.979082 -313.807728) (xy 166.005385 -313.766132) (xy 166.03802 -313.729295)
			(xy 166.076141 -313.69817) (xy 166.118762 -313.673563) (xy 166.164778 -313.656111) (xy 166.212997 -313.646267)
			(xy 166.262172 -313.644286) (xy 166.311027 -313.650218) (xy 166.358298 -313.66391) (xy 166.40276 -313.685008)
			(xy 166.443263 -313.712964) (xy 166.478756 -313.747056) (xy 166.508321 -313.7864) (xy 166.531192 -313.829977)
			(xy 166.546776 -313.876658) (xy 166.554671 -313.925235) (xy 166.555166 -313.949842) (xy 167.844228 -313.949842)
			(xy 167.848188 -313.900788) (xy 167.859965 -313.853004) (xy 167.879256 -313.807728) (xy 167.905559 -313.766132)
			(xy 167.938194 -313.729295) (xy 167.976315 -313.69817) (xy 168.018936 -313.673563) (xy 168.064952 -313.656111)
			(xy 168.113171 -313.646267) (xy 168.162346 -313.644286) (xy 168.211201 -313.650218) (xy 168.258472 -313.66391)
			(xy 168.302934 -313.685008) (xy 168.343437 -313.712964) (xy 168.37893 -313.747056) (xy 168.408495 -313.7864)
			(xy 168.431366 -313.829977) (xy 168.44695 -313.876658) (xy 168.454845 -313.925235) (xy 168.45534 -313.949842)
			(xy 169.744148 -313.949842) (xy 169.748108 -313.900788) (xy 169.759885 -313.853004) (xy 169.779176 -313.807728)
			(xy 169.805479 -313.766132) (xy 169.838114 -313.729295) (xy 169.876235 -313.69817) (xy 169.918856 -313.673563)
			(xy 169.964872 -313.656111) (xy 170.013091 -313.646267) (xy 170.062266 -313.644286) (xy 170.111121 -313.650218)
			(xy 170.158392 -313.66391) (xy 170.202854 -313.685008) (xy 170.243357 -313.712964) (xy 170.27885 -313.747056)
			(xy 170.308415 -313.7864) (xy 170.331286 -313.829977) (xy 170.34687 -313.876658) (xy 170.354765 -313.925235)
			(xy 170.35526 -313.949842) (xy 171.644068 -313.949842) (xy 171.648028 -313.900788) (xy 171.659805 -313.853004)
			(xy 171.679096 -313.807728) (xy 171.705399 -313.766132) (xy 171.738034 -313.729295) (xy 171.776155 -313.69817)
			(xy 171.818776 -313.673563) (xy 171.864792 -313.656111) (xy 171.913011 -313.646267) (xy 171.962186 -313.644286)
			(xy 172.011041 -313.650218) (xy 172.058312 -313.66391) (xy 172.102774 -313.685008) (xy 172.143277 -313.712964)
			(xy 172.17877 -313.747056) (xy 172.208335 -313.7864) (xy 172.231206 -313.829977) (xy 172.24679 -313.876658)
			(xy 172.254685 -313.925235) (xy 172.25518 -313.949842) (xy 173.544242 -313.949842) (xy 173.548202 -313.900788)
			(xy 173.559979 -313.853004) (xy 173.57927 -313.807728) (xy 173.605573 -313.766132) (xy 173.638208 -313.729295)
			(xy 173.676329 -313.69817) (xy 173.71895 -313.673563) (xy 173.764966 -313.656111) (xy 173.813185 -313.646267)
			(xy 173.86236 -313.644286) (xy 173.911215 -313.650218) (xy 173.958486 -313.66391) (xy 174.002948 -313.685008)
			(xy 174.043451 -313.712964) (xy 174.078944 -313.747056) (xy 174.108509 -313.7864) (xy 174.13138 -313.829977)
			(xy 174.146964 -313.876658) (xy 174.154859 -313.925235) (xy 174.155354 -313.949842) (xy 175.444162 -313.949842)
			(xy 175.448122 -313.900788) (xy 175.459899 -313.853004) (xy 175.47919 -313.807728) (xy 175.505493 -313.766132)
			(xy 175.538128 -313.729295) (xy 175.576249 -313.69817) (xy 175.61887 -313.673563) (xy 175.664886 -313.656111)
			(xy 175.713105 -313.646267) (xy 175.76228 -313.644286) (xy 175.811135 -313.650218) (xy 175.858406 -313.66391)
			(xy 175.902868 -313.685008) (xy 175.943371 -313.712964) (xy 175.978864 -313.747056) (xy 176.008429 -313.7864)
			(xy 176.0313 -313.829977) (xy 176.046884 -313.876658) (xy 176.054779 -313.925235) (xy 176.055274 -313.949842)
			(xy 177.344082 -313.949842) (xy 177.348042 -313.900788) (xy 177.359819 -313.853004) (xy 177.37911 -313.807728)
			(xy 177.405413 -313.766132) (xy 177.438048 -313.729295) (xy 177.476169 -313.69817) (xy 177.51879 -313.673563)
			(xy 177.564806 -313.656111) (xy 177.613025 -313.646267) (xy 177.6622 -313.644286) (xy 177.711055 -313.650218)
			(xy 177.758326 -313.66391) (xy 177.802788 -313.685008) (xy 177.843291 -313.712964) (xy 177.878784 -313.747056)
			(xy 177.908349 -313.7864) (xy 177.93122 -313.829977) (xy 177.946804 -313.876658) (xy 177.954699 -313.925235)
			(xy 177.955194 -313.949842) (xy 179.244256 -313.949842) (xy 179.248216 -313.900788) (xy 179.259993 -313.853004)
			(xy 179.279284 -313.807728) (xy 179.305587 -313.766132) (xy 179.338222 -313.729295) (xy 179.376343 -313.69817)
			(xy 179.418964 -313.673563) (xy 179.46498 -313.656111) (xy 179.513199 -313.646267) (xy 179.562374 -313.644286)
			(xy 179.611229 -313.650218) (xy 179.6585 -313.66391) (xy 179.702962 -313.685008) (xy 179.743465 -313.712964)
			(xy 179.778958 -313.747056) (xy 179.808523 -313.7864) (xy 179.831394 -313.829977) (xy 179.846978 -313.876658)
			(xy 179.854873 -313.925235) (xy 179.855368 -313.949842) (xy 181.144176 -313.949842) (xy 181.148136 -313.900788)
			(xy 181.159913 -313.853004) (xy 181.179204 -313.807728) (xy 181.205507 -313.766132) (xy 181.238142 -313.729295)
			(xy 181.276263 -313.69817) (xy 181.318884 -313.673563) (xy 181.3649 -313.656111) (xy 181.413119 -313.646267)
			(xy 181.462294 -313.644286) (xy 181.511149 -313.650218) (xy 181.55842 -313.66391) (xy 181.602882 -313.685008)
			(xy 181.643385 -313.712964) (xy 181.678878 -313.747056) (xy 181.708443 -313.7864) (xy 181.731314 -313.829977)
			(xy 181.746898 -313.876658) (xy 181.754793 -313.925235) (xy 181.755288 -313.949842) (xy 183.044096 -313.949842)
			(xy 183.048056 -313.900788) (xy 183.059833 -313.853004) (xy 183.079124 -313.807728) (xy 183.105427 -313.766132)
			(xy 183.138062 -313.729295) (xy 183.176183 -313.69817) (xy 183.218804 -313.673563) (xy 183.26482 -313.656111)
			(xy 183.313039 -313.646267) (xy 183.362214 -313.644286) (xy 183.411069 -313.650218) (xy 183.45834 -313.66391)
			(xy 183.502802 -313.685008) (xy 183.543305 -313.712964) (xy 183.578798 -313.747056) (xy 183.608363 -313.7864)
			(xy 183.631234 -313.829977) (xy 183.646818 -313.876658) (xy 183.654713 -313.925235) (xy 183.655208 -313.949842)
			(xy 184.94427 -313.949842) (xy 184.94823 -313.900788) (xy 184.960007 -313.853004) (xy 184.979298 -313.807728)
			(xy 185.005601 -313.766132) (xy 185.038236 -313.729295) (xy 185.076357 -313.69817) (xy 185.118978 -313.673563)
			(xy 185.164994 -313.656111) (xy 185.213213 -313.646267) (xy 185.262388 -313.644286) (xy 185.311243 -313.650218)
			(xy 185.358514 -313.66391) (xy 185.402976 -313.685008) (xy 185.443479 -313.712964) (xy 185.478972 -313.747056)
			(xy 185.508537 -313.7864) (xy 185.531408 -313.829977) (xy 185.546992 -313.876658) (xy 185.554887 -313.925235)
			(xy 185.555382 -313.949842) (xy 186.84419 -313.949842) (xy 186.84815 -313.900788) (xy 186.859927 -313.853004)
			(xy 186.879218 -313.807728) (xy 186.905521 -313.766132) (xy 186.938156 -313.729295) (xy 186.976277 -313.69817)
			(xy 187.018898 -313.673563) (xy 187.064914 -313.656111) (xy 187.113133 -313.646267) (xy 187.162308 -313.644286)
			(xy 187.211163 -313.650218) (xy 187.258434 -313.66391) (xy 187.302896 -313.685008) (xy 187.343399 -313.712964)
			(xy 187.378892 -313.747056) (xy 187.408457 -313.7864) (xy 187.431328 -313.829977) (xy 187.446912 -313.876658)
			(xy 187.454807 -313.925235) (xy 187.455302 -313.949842) (xy 188.74411 -313.949842) (xy 188.74807 -313.900788)
			(xy 188.759847 -313.853004) (xy 188.779138 -313.807728) (xy 188.805441 -313.766132) (xy 188.838076 -313.729295)
			(xy 188.876197 -313.69817) (xy 188.918818 -313.673563) (xy 188.964834 -313.656111) (xy 189.013053 -313.646267)
			(xy 189.062228 -313.644286) (xy 189.111083 -313.650218) (xy 189.158354 -313.66391) (xy 189.202816 -313.685008)
			(xy 189.243319 -313.712964) (xy 189.278812 -313.747056) (xy 189.308377 -313.7864) (xy 189.331248 -313.829977)
			(xy 189.346832 -313.876658) (xy 189.354727 -313.925235) (xy 189.355222 -313.949842) (xy 190.644284 -313.949842)
			(xy 190.648244 -313.900788) (xy 190.660021 -313.853004) (xy 190.679312 -313.807728) (xy 190.705615 -313.766132)
			(xy 190.73825 -313.729295) (xy 190.776371 -313.69817) (xy 190.818992 -313.673563) (xy 190.865008 -313.656111)
			(xy 190.913227 -313.646267) (xy 190.962402 -313.644286) (xy 191.011257 -313.650218) (xy 191.058528 -313.66391)
			(xy 191.10299 -313.685008) (xy 191.143493 -313.712964) (xy 191.178986 -313.747056) (xy 191.208551 -313.7864)
			(xy 191.231422 -313.829977) (xy 191.247006 -313.876658) (xy 191.254901 -313.925235) (xy 191.255396 -313.949842)
			(xy 192.544204 -313.949842) (xy 192.548164 -313.900788) (xy 192.559941 -313.853004) (xy 192.579232 -313.807728)
			(xy 192.605535 -313.766132) (xy 192.63817 -313.729295) (xy 192.676291 -313.69817) (xy 192.718912 -313.673563)
			(xy 192.764928 -313.656111) (xy 192.813147 -313.646267) (xy 192.862322 -313.644286) (xy 192.911177 -313.650218)
			(xy 192.958448 -313.66391) (xy 193.00291 -313.685008) (xy 193.043413 -313.712964) (xy 193.078906 -313.747056)
			(xy 193.108471 -313.7864) (xy 193.131342 -313.829977) (xy 193.146926 -313.876658) (xy 193.154821 -313.925235)
			(xy 193.155316 -313.949842) (xy 194.444124 -313.949842) (xy 194.448084 -313.900788) (xy 194.459861 -313.853004)
			(xy 194.479152 -313.807728) (xy 194.505455 -313.766132) (xy 194.53809 -313.729295) (xy 194.576211 -313.69817)
			(xy 194.618832 -313.673563) (xy 194.664848 -313.656111) (xy 194.713067 -313.646267) (xy 194.762242 -313.644286)
			(xy 194.811097 -313.650218) (xy 194.858368 -313.66391) (xy 194.90283 -313.685008) (xy 194.943333 -313.712964)
			(xy 194.978826 -313.747056) (xy 195.008391 -313.7864) (xy 195.031262 -313.829977) (xy 195.046846 -313.876658)
			(xy 195.054741 -313.925235) (xy 195.055236 -313.949842) (xy 196.344044 -313.949842) (xy 196.348004 -313.900788)
			(xy 196.359781 -313.853004) (xy 196.379072 -313.807728) (xy 196.405375 -313.766132) (xy 196.43801 -313.729295)
			(xy 196.476131 -313.69817) (xy 196.518752 -313.673563) (xy 196.564768 -313.656111) (xy 196.612987 -313.646267)
			(xy 196.662162 -313.644286) (xy 196.711017 -313.650218) (xy 196.758288 -313.66391) (xy 196.80275 -313.685008)
			(xy 196.843253 -313.712964) (xy 196.878746 -313.747056) (xy 196.908311 -313.7864) (xy 196.931182 -313.829977)
			(xy 196.946766 -313.876658) (xy 196.954661 -313.925235) (xy 196.955156 -313.949842) (xy 270.644124 -313.949842)
			(xy 270.648084 -313.900788) (xy 270.659861 -313.853004) (xy 270.679152 -313.807728) (xy 270.705455 -313.766132)
			(xy 270.73809 -313.729295) (xy 270.776211 -313.69817) (xy 270.818832 -313.673563) (xy 270.864848 -313.656111)
			(xy 270.913067 -313.646267) (xy 270.962242 -313.644286) (xy 271.011097 -313.650218) (xy 271.058368 -313.66391)
			(xy 271.10283 -313.685008) (xy 271.143333 -313.712964) (xy 271.178826 -313.747056) (xy 271.208391 -313.7864)
			(xy 271.231262 -313.829977) (xy 271.246846 -313.876658) (xy 271.254741 -313.925235) (xy 271.255236 -313.949842)
			(xy 272.544044 -313.949842) (xy 272.548004 -313.900788) (xy 272.559781 -313.853004) (xy 272.579072 -313.807728)
			(xy 272.605375 -313.766132) (xy 272.63801 -313.729295) (xy 272.676131 -313.69817) (xy 272.718752 -313.673563)
			(xy 272.764768 -313.656111) (xy 272.812987 -313.646267) (xy 272.862162 -313.644286) (xy 272.911017 -313.650218)
			(xy 272.958288 -313.66391) (xy 273.00275 -313.685008) (xy 273.043253 -313.712964) (xy 273.078746 -313.747056)
			(xy 273.108311 -313.7864) (xy 273.131182 -313.829977) (xy 273.146766 -313.876658) (xy 273.154661 -313.925235)
			(xy 273.155156 -313.949842) (xy 274.443964 -313.949842) (xy 274.447924 -313.900788) (xy 274.459701 -313.853004)
			(xy 274.478992 -313.807728) (xy 274.505295 -313.766132) (xy 274.53793 -313.729295) (xy 274.576051 -313.69817)
			(xy 274.618672 -313.673563) (xy 274.664688 -313.656111) (xy 274.712907 -313.646267) (xy 274.762082 -313.644286)
			(xy 274.810937 -313.650218) (xy 274.858208 -313.66391) (xy 274.90267 -313.685008) (xy 274.943173 -313.712964)
			(xy 274.978666 -313.747056) (xy 275.008231 -313.7864) (xy 275.031102 -313.829977) (xy 275.046686 -313.876658)
			(xy 275.054581 -313.925235) (xy 275.055076 -313.949842) (xy 276.343884 -313.949842) (xy 276.347844 -313.900788)
			(xy 276.359621 -313.853004) (xy 276.378912 -313.807728) (xy 276.405215 -313.766132) (xy 276.43785 -313.729295)
			(xy 276.475971 -313.69817) (xy 276.518592 -313.673563) (xy 276.564608 -313.656111) (xy 276.612827 -313.646267)
			(xy 276.662002 -313.644286) (xy 276.710857 -313.650218) (xy 276.758128 -313.66391) (xy 276.80259 -313.685008)
			(xy 276.843093 -313.712964) (xy 276.878586 -313.747056) (xy 276.908151 -313.7864) (xy 276.931022 -313.829977)
			(xy 276.946606 -313.876658) (xy 276.954501 -313.925235) (xy 276.954996 -313.949842) (xy 278.244058 -313.949842)
			(xy 278.248018 -313.900788) (xy 278.259795 -313.853004) (xy 278.279086 -313.807728) (xy 278.305389 -313.766132)
			(xy 278.338024 -313.729295) (xy 278.376145 -313.69817) (xy 278.418766 -313.673563) (xy 278.464782 -313.656111)
			(xy 278.513001 -313.646267) (xy 278.562176 -313.644286) (xy 278.611031 -313.650218) (xy 278.658302 -313.66391)
			(xy 278.702764 -313.685008) (xy 278.743267 -313.712964) (xy 278.77876 -313.747056) (xy 278.808325 -313.7864)
			(xy 278.831196 -313.829977) (xy 278.84678 -313.876658) (xy 278.854675 -313.925235) (xy 278.85517 -313.949842)
			(xy 280.143978 -313.949842) (xy 280.147938 -313.900788) (xy 280.159715 -313.853004) (xy 280.179006 -313.807728)
			(xy 280.205309 -313.766132) (xy 280.237944 -313.729295) (xy 280.276065 -313.69817) (xy 280.318686 -313.673563)
			(xy 280.364702 -313.656111) (xy 280.412921 -313.646267) (xy 280.462096 -313.644286) (xy 280.510951 -313.650218)
			(xy 280.558222 -313.66391) (xy 280.602684 -313.685008) (xy 280.643187 -313.712964) (xy 280.67868 -313.747056)
			(xy 280.708245 -313.7864) (xy 280.731116 -313.829977) (xy 280.7467 -313.876658) (xy 280.754595 -313.925235)
			(xy 280.75509 -313.949842) (xy 282.043898 -313.949842) (xy 282.047858 -313.900788) (xy 282.059635 -313.853004)
			(xy 282.078926 -313.807728) (xy 282.105229 -313.766132) (xy 282.137864 -313.729295) (xy 282.175985 -313.69817)
			(xy 282.218606 -313.673563) (xy 282.264622 -313.656111) (xy 282.312841 -313.646267) (xy 282.362016 -313.644286)
			(xy 282.410871 -313.650218) (xy 282.458142 -313.66391) (xy 282.502604 -313.685008) (xy 282.543107 -313.712964)
			(xy 282.5786 -313.747056) (xy 282.608165 -313.7864) (xy 282.631036 -313.829977) (xy 282.64662 -313.876658)
			(xy 282.654515 -313.925235) (xy 282.65501 -313.949842) (xy 283.944072 -313.949842) (xy 283.948032 -313.900788)
			(xy 283.959809 -313.853004) (xy 283.9791 -313.807728) (xy 284.005403 -313.766132) (xy 284.038038 -313.729295)
			(xy 284.076159 -313.69817) (xy 284.11878 -313.673563) (xy 284.164796 -313.656111) (xy 284.213015 -313.646267)
			(xy 284.26219 -313.644286) (xy 284.311045 -313.650218) (xy 284.358316 -313.66391) (xy 284.402778 -313.685008)
			(xy 284.443281 -313.712964) (xy 284.478774 -313.747056) (xy 284.508339 -313.7864) (xy 284.53121 -313.829977)
			(xy 284.546794 -313.876658) (xy 284.554689 -313.925235) (xy 284.555184 -313.949842) (xy 285.843992 -313.949842)
			(xy 285.847952 -313.900788) (xy 285.859729 -313.853004) (xy 285.87902 -313.807728) (xy 285.905323 -313.766132)
			(xy 285.937958 -313.729295) (xy 285.976079 -313.69817) (xy 286.0187 -313.673563) (xy 286.064716 -313.656111)
			(xy 286.112935 -313.646267) (xy 286.16211 -313.644286) (xy 286.210965 -313.650218) (xy 286.258236 -313.66391)
			(xy 286.302698 -313.685008) (xy 286.343201 -313.712964) (xy 286.378694 -313.747056) (xy 286.408259 -313.7864)
			(xy 286.43113 -313.829977) (xy 286.446714 -313.876658) (xy 286.454609 -313.925235) (xy 286.455104 -313.949842)
			(xy 287.743912 -313.949842) (xy 287.747872 -313.900788) (xy 287.759649 -313.853004) (xy 287.77894 -313.807728)
			(xy 287.805243 -313.766132) (xy 287.837878 -313.729295) (xy 287.875999 -313.69817) (xy 287.91862 -313.673563)
			(xy 287.964636 -313.656111) (xy 288.012855 -313.646267) (xy 288.06203 -313.644286) (xy 288.110885 -313.650218)
			(xy 288.158156 -313.66391) (xy 288.202618 -313.685008) (xy 288.243121 -313.712964) (xy 288.278614 -313.747056)
			(xy 288.308179 -313.7864) (xy 288.33105 -313.829977) (xy 288.346634 -313.876658) (xy 288.354529 -313.925235)
			(xy 288.355024 -313.949842) (xy 289.644086 -313.949842) (xy 289.648046 -313.900788) (xy 289.659823 -313.853004)
			(xy 289.679114 -313.807728) (xy 289.705417 -313.766132) (xy 289.738052 -313.729295) (xy 289.776173 -313.69817)
			(xy 289.818794 -313.673563) (xy 289.86481 -313.656111) (xy 289.913029 -313.646267) (xy 289.962204 -313.644286)
			(xy 290.011059 -313.650218) (xy 290.05833 -313.66391) (xy 290.102792 -313.685008) (xy 290.143295 -313.712964)
			(xy 290.178788 -313.747056) (xy 290.208353 -313.7864) (xy 290.231224 -313.829977) (xy 290.246808 -313.876658)
			(xy 290.254703 -313.925235) (xy 290.255198 -313.949842) (xy 291.544006 -313.949842) (xy 291.547966 -313.900788)
			(xy 291.559743 -313.853004) (xy 291.579034 -313.807728) (xy 291.605337 -313.766132) (xy 291.637972 -313.729295)
			(xy 291.676093 -313.69817) (xy 291.718714 -313.673563) (xy 291.76473 -313.656111) (xy 291.812949 -313.646267)
			(xy 291.862124 -313.644286) (xy 291.910979 -313.650218) (xy 291.95825 -313.66391) (xy 292.002712 -313.685008)
			(xy 292.043215 -313.712964) (xy 292.078708 -313.747056) (xy 292.108273 -313.7864) (xy 292.131144 -313.829977)
			(xy 292.146728 -313.876658) (xy 292.154623 -313.925235) (xy 292.155118 -313.949842) (xy 293.443926 -313.949842)
			(xy 293.447886 -313.900788) (xy 293.459663 -313.853004) (xy 293.478954 -313.807728) (xy 293.505257 -313.766132)
			(xy 293.537892 -313.729295) (xy 293.576013 -313.69817) (xy 293.618634 -313.673563) (xy 293.66465 -313.656111)
			(xy 293.712869 -313.646267) (xy 293.762044 -313.644286) (xy 293.810899 -313.650218) (xy 293.85817 -313.66391)
			(xy 293.902632 -313.685008) (xy 293.943135 -313.712964) (xy 293.978628 -313.747056) (xy 294.008193 -313.7864)
			(xy 294.031064 -313.829977) (xy 294.046648 -313.876658) (xy 294.054543 -313.925235) (xy 294.055038 -313.949842)
			(xy 295.3441 -313.949842) (xy 295.34806 -313.900788) (xy 295.359837 -313.853004) (xy 295.379128 -313.807728)
			(xy 295.405431 -313.766132) (xy 295.438066 -313.729295) (xy 295.476187 -313.69817) (xy 295.518808 -313.673563)
			(xy 295.564824 -313.656111) (xy 295.613043 -313.646267) (xy 295.662218 -313.644286) (xy 295.711073 -313.650218)
			(xy 295.758344 -313.66391) (xy 295.802806 -313.685008) (xy 295.843309 -313.712964) (xy 295.878802 -313.747056)
			(xy 295.908367 -313.7864) (xy 295.931238 -313.829977) (xy 295.946822 -313.876658) (xy 295.954717 -313.925235)
			(xy 295.955212 -313.949842) (xy 297.24402 -313.949842) (xy 297.24798 -313.900788) (xy 297.259757 -313.853004)
			(xy 297.279048 -313.807728) (xy 297.305351 -313.766132) (xy 297.337986 -313.729295) (xy 297.376107 -313.69817)
			(xy 297.418728 -313.673563) (xy 297.464744 -313.656111) (xy 297.512963 -313.646267) (xy 297.562138 -313.644286)
			(xy 297.610993 -313.650218) (xy 297.658264 -313.66391) (xy 297.702726 -313.685008) (xy 297.743229 -313.712964)
			(xy 297.778722 -313.747056) (xy 297.808287 -313.7864) (xy 297.831158 -313.829977) (xy 297.846742 -313.876658)
			(xy 297.854637 -313.925235) (xy 297.855132 -313.949842) (xy 299.14394 -313.949842) (xy 299.1479 -313.900788)
			(xy 299.159677 -313.853004) (xy 299.178968 -313.807728) (xy 299.205271 -313.766132) (xy 299.237906 -313.729295)
			(xy 299.276027 -313.69817) (xy 299.318648 -313.673563) (xy 299.364664 -313.656111) (xy 299.412883 -313.646267)
			(xy 299.462058 -313.644286) (xy 299.510913 -313.650218) (xy 299.558184 -313.66391) (xy 299.602646 -313.685008)
			(xy 299.643149 -313.712964) (xy 299.678642 -313.747056) (xy 299.708207 -313.7864) (xy 299.731078 -313.829977)
			(xy 299.746662 -313.876658) (xy 299.754557 -313.925235) (xy 299.755052 -313.949842) (xy 301.044114 -313.949842)
			(xy 301.048074 -313.900788) (xy 301.059851 -313.853004) (xy 301.079142 -313.807728) (xy 301.105445 -313.766132)
			(xy 301.13808 -313.729295) (xy 301.176201 -313.69817) (xy 301.218822 -313.673563) (xy 301.264838 -313.656111)
			(xy 301.313057 -313.646267) (xy 301.362232 -313.644286) (xy 301.411087 -313.650218) (xy 301.458358 -313.66391)
			(xy 301.50282 -313.685008) (xy 301.543323 -313.712964) (xy 301.578816 -313.747056) (xy 301.608381 -313.7864)
			(xy 301.631252 -313.829977) (xy 301.646836 -313.876658) (xy 301.654731 -313.925235) (xy 301.655226 -313.949842)
			(xy 302.944034 -313.949842) (xy 302.947994 -313.900788) (xy 302.959771 -313.853004) (xy 302.979062 -313.807728)
			(xy 303.005365 -313.766132) (xy 303.038 -313.729295) (xy 303.076121 -313.69817) (xy 303.118742 -313.673563)
			(xy 303.164758 -313.656111) (xy 303.212977 -313.646267) (xy 303.262152 -313.644286) (xy 303.311007 -313.650218)
			(xy 303.358278 -313.66391) (xy 303.40274 -313.685008) (xy 303.443243 -313.712964) (xy 303.478736 -313.747056)
			(xy 303.508301 -313.7864) (xy 303.531172 -313.829977) (xy 303.546756 -313.876658) (xy 303.554651 -313.925235)
			(xy 303.555146 -313.949842) (xy 304.843954 -313.949842) (xy 304.847914 -313.900788) (xy 304.859691 -313.853004)
			(xy 304.878982 -313.807728) (xy 304.905285 -313.766132) (xy 304.93792 -313.729295) (xy 304.976041 -313.69817)
			(xy 305.018662 -313.673563) (xy 305.064678 -313.656111) (xy 305.112897 -313.646267) (xy 305.162072 -313.644286)
			(xy 305.210927 -313.650218) (xy 305.258198 -313.66391) (xy 305.30266 -313.685008) (xy 305.343163 -313.712964)
			(xy 305.378656 -313.747056) (xy 305.408221 -313.7864) (xy 305.431092 -313.829977) (xy 305.446676 -313.876658)
			(xy 305.454571 -313.925235) (xy 305.455066 -313.949842) (xy 306.744128 -313.949842) (xy 306.748088 -313.900788)
			(xy 306.759865 -313.853004) (xy 306.779156 -313.807728) (xy 306.805459 -313.766132) (xy 306.838094 -313.729295)
			(xy 306.876215 -313.69817) (xy 306.918836 -313.673563) (xy 306.964852 -313.656111) (xy 307.013071 -313.646267)
			(xy 307.062246 -313.644286) (xy 307.111101 -313.650218) (xy 307.158372 -313.66391) (xy 307.202834 -313.685008)
			(xy 307.243337 -313.712964) (xy 307.27883 -313.747056) (xy 307.308395 -313.7864) (xy 307.331266 -313.829977)
			(xy 307.34685 -313.876658) (xy 307.354745 -313.925235) (xy 307.35524 -313.949842) (xy 308.644048 -313.949842)
			(xy 308.648008 -313.900788) (xy 308.659785 -313.853004) (xy 308.679076 -313.807728) (xy 308.705379 -313.766132)
			(xy 308.738014 -313.729295) (xy 308.776135 -313.69817) (xy 308.818756 -313.673563) (xy 308.864772 -313.656111)
			(xy 308.912991 -313.646267) (xy 308.962166 -313.644286) (xy 309.011021 -313.650218) (xy 309.058292 -313.66391)
			(xy 309.102754 -313.685008) (xy 309.143257 -313.712964) (xy 309.17875 -313.747056) (xy 309.208315 -313.7864)
			(xy 309.231186 -313.829977) (xy 309.24677 -313.876658) (xy 309.254665 -313.925235) (xy 309.25516 -313.949842)
			(xy 310.543968 -313.949842) (xy 310.547928 -313.900788) (xy 310.559705 -313.853004) (xy 310.578996 -313.807728)
			(xy 310.605299 -313.766132) (xy 310.637934 -313.729295) (xy 310.676055 -313.69817) (xy 310.718676 -313.673563)
			(xy 310.764692 -313.656111) (xy 310.812911 -313.646267) (xy 310.862086 -313.644286) (xy 310.910941 -313.650218)
			(xy 310.958212 -313.66391) (xy 311.002674 -313.685008) (xy 311.043177 -313.712964) (xy 311.07867 -313.747056)
			(xy 311.108235 -313.7864) (xy 311.131106 -313.829977) (xy 311.14669 -313.876658) (xy 311.154585 -313.925235)
			(xy 311.15508 -313.949842) (xy 312.443888 -313.949842) (xy 312.447848 -313.900788) (xy 312.459625 -313.853004)
			(xy 312.478916 -313.807728) (xy 312.505219 -313.766132) (xy 312.537854 -313.729295) (xy 312.575975 -313.69817)
			(xy 312.618596 -313.673563) (xy 312.664612 -313.656111) (xy 312.712831 -313.646267) (xy 312.762006 -313.644286)
			(xy 312.810861 -313.650218) (xy 312.858132 -313.66391) (xy 312.902594 -313.685008) (xy 312.943097 -313.712964)
			(xy 312.97859 -313.747056) (xy 313.008155 -313.7864) (xy 313.031026 -313.829977) (xy 313.04661 -313.876658)
			(xy 313.054505 -313.925235) (xy 313.055 -313.949842) (xy 386.744222 -313.949842) (xy 386.748182 -313.900788)
			(xy 386.759959 -313.853004) (xy 386.77925 -313.807728) (xy 386.805553 -313.766132) (xy 386.838188 -313.729295)
			(xy 386.876309 -313.69817) (xy 386.91893 -313.673563) (xy 386.964946 -313.656111) (xy 387.013165 -313.646267)
			(xy 387.06234 -313.644286) (xy 387.111195 -313.650218) (xy 387.158466 -313.66391) (xy 387.202928 -313.685008)
			(xy 387.243431 -313.712964) (xy 387.278924 -313.747056) (xy 387.308489 -313.7864) (xy 387.33136 -313.829977)
			(xy 387.346944 -313.876658) (xy 387.354839 -313.925235) (xy 387.355334 -313.949842) (xy 388.644142 -313.949842)
			(xy 388.648102 -313.900788) (xy 388.659879 -313.853004) (xy 388.67917 -313.807728) (xy 388.705473 -313.766132)
			(xy 388.738108 -313.729295) (xy 388.776229 -313.69817) (xy 388.81885 -313.673563) (xy 388.864866 -313.656111)
			(xy 388.913085 -313.646267) (xy 388.96226 -313.644286) (xy 389.011115 -313.650218) (xy 389.058386 -313.66391)
			(xy 389.102848 -313.685008) (xy 389.143351 -313.712964) (xy 389.178844 -313.747056) (xy 389.208409 -313.7864)
			(xy 389.23128 -313.829977) (xy 389.246864 -313.876658) (xy 389.254759 -313.925235) (xy 389.255254 -313.949842)
			(xy 390.544062 -313.949842) (xy 390.548022 -313.900788) (xy 390.559799 -313.853004) (xy 390.57909 -313.807728)
			(xy 390.605393 -313.766132) (xy 390.638028 -313.729295) (xy 390.676149 -313.69817) (xy 390.71877 -313.673563)
			(xy 390.764786 -313.656111) (xy 390.813005 -313.646267) (xy 390.86218 -313.644286) (xy 390.911035 -313.650218)
			(xy 390.958306 -313.66391) (xy 391.002768 -313.685008) (xy 391.043271 -313.712964) (xy 391.078764 -313.747056)
			(xy 391.108329 -313.7864) (xy 391.1312 -313.829977) (xy 391.146784 -313.876658) (xy 391.154679 -313.925235)
			(xy 391.155174 -313.949842) (xy 392.443982 -313.949842) (xy 392.447942 -313.900788) (xy 392.459719 -313.853004)
			(xy 392.47901 -313.807728) (xy 392.505313 -313.766132) (xy 392.537948 -313.729295) (xy 392.576069 -313.69817)
			(xy 392.61869 -313.673563) (xy 392.664706 -313.656111) (xy 392.712925 -313.646267) (xy 392.7621 -313.644286)
			(xy 392.810955 -313.650218) (xy 392.858226 -313.66391) (xy 392.902688 -313.685008) (xy 392.943191 -313.712964)
			(xy 392.978684 -313.747056) (xy 393.008249 -313.7864) (xy 393.03112 -313.829977) (xy 393.046704 -313.876658)
			(xy 393.054599 -313.925235) (xy 393.055094 -313.949842) (xy 394.344156 -313.949842) (xy 394.348116 -313.900788)
			(xy 394.359893 -313.853004) (xy 394.379184 -313.807728) (xy 394.405487 -313.766132) (xy 394.438122 -313.729295)
			(xy 394.476243 -313.69817) (xy 394.518864 -313.673563) (xy 394.56488 -313.656111) (xy 394.613099 -313.646267)
			(xy 394.662274 -313.644286) (xy 394.711129 -313.650218) (xy 394.7584 -313.66391) (xy 394.802862 -313.685008)
			(xy 394.843365 -313.712964) (xy 394.878858 -313.747056) (xy 394.908423 -313.7864) (xy 394.931294 -313.829977)
			(xy 394.946878 -313.876658) (xy 394.954773 -313.925235) (xy 394.955268 -313.949842) (xy 396.244076 -313.949842)
			(xy 396.248036 -313.900788) (xy 396.259813 -313.853004) (xy 396.279104 -313.807728) (xy 396.305407 -313.766132)
			(xy 396.338042 -313.729295) (xy 396.376163 -313.69817) (xy 396.418784 -313.673563) (xy 396.4648 -313.656111)
			(xy 396.513019 -313.646267) (xy 396.562194 -313.644286) (xy 396.611049 -313.650218) (xy 396.65832 -313.66391)
			(xy 396.702782 -313.685008) (xy 396.743285 -313.712964) (xy 396.778778 -313.747056) (xy 396.808343 -313.7864)
			(xy 396.831214 -313.829977) (xy 396.846798 -313.876658) (xy 396.854693 -313.925235) (xy 396.855188 -313.949842)
			(xy 398.143996 -313.949842) (xy 398.147956 -313.900788) (xy 398.159733 -313.853004) (xy 398.179024 -313.807728)
			(xy 398.205327 -313.766132) (xy 398.237962 -313.729295) (xy 398.276083 -313.69817) (xy 398.318704 -313.673563)
			(xy 398.36472 -313.656111) (xy 398.412939 -313.646267) (xy 398.462114 -313.644286) (xy 398.510969 -313.650218)
			(xy 398.55824 -313.66391) (xy 398.602702 -313.685008) (xy 398.643205 -313.712964) (xy 398.678698 -313.747056)
			(xy 398.708263 -313.7864) (xy 398.731134 -313.829977) (xy 398.746718 -313.876658) (xy 398.754613 -313.925235)
			(xy 398.755108 -313.949842) (xy 400.04417 -313.949842) (xy 400.04813 -313.900788) (xy 400.059907 -313.853004)
			(xy 400.079198 -313.807728) (xy 400.105501 -313.766132) (xy 400.138136 -313.729295) (xy 400.176257 -313.69817)
			(xy 400.218878 -313.673563) (xy 400.264894 -313.656111) (xy 400.313113 -313.646267) (xy 400.362288 -313.644286)
			(xy 400.411143 -313.650218) (xy 400.458414 -313.66391) (xy 400.502876 -313.685008) (xy 400.543379 -313.712964)
			(xy 400.578872 -313.747056) (xy 400.608437 -313.7864) (xy 400.631308 -313.829977) (xy 400.646892 -313.876658)
			(xy 400.654787 -313.925235) (xy 400.655282 -313.949842) (xy 401.94409 -313.949842) (xy 401.94805 -313.900788)
			(xy 401.959827 -313.853004) (xy 401.979118 -313.807728) (xy 402.005421 -313.766132) (xy 402.038056 -313.729295)
			(xy 402.076177 -313.69817) (xy 402.118798 -313.673563) (xy 402.164814 -313.656111) (xy 402.213033 -313.646267)
			(xy 402.262208 -313.644286) (xy 402.311063 -313.650218) (xy 402.358334 -313.66391) (xy 402.402796 -313.685008)
			(xy 402.443299 -313.712964) (xy 402.478792 -313.747056) (xy 402.508357 -313.7864) (xy 402.531228 -313.829977)
			(xy 402.546812 -313.876658) (xy 402.554707 -313.925235) (xy 402.555202 -313.949842) (xy 403.84401 -313.949842)
			(xy 403.84797 -313.900788) (xy 403.859747 -313.853004) (xy 403.879038 -313.807728) (xy 403.905341 -313.766132)
			(xy 403.937976 -313.729295) (xy 403.976097 -313.69817) (xy 404.018718 -313.673563) (xy 404.064734 -313.656111)
			(xy 404.112953 -313.646267) (xy 404.162128 -313.644286) (xy 404.210983 -313.650218) (xy 404.258254 -313.66391)
			(xy 404.302716 -313.685008) (xy 404.343219 -313.712964) (xy 404.378712 -313.747056) (xy 404.408277 -313.7864)
			(xy 404.431148 -313.829977) (xy 404.446732 -313.876658) (xy 404.454627 -313.925235) (xy 404.455122 -313.949842)
			(xy 405.744184 -313.949842) (xy 405.748144 -313.900788) (xy 405.759921 -313.853004) (xy 405.779212 -313.807728)
			(xy 405.805515 -313.766132) (xy 405.83815 -313.729295) (xy 405.876271 -313.69817) (xy 405.918892 -313.673563)
			(xy 405.964908 -313.656111) (xy 406.013127 -313.646267) (xy 406.062302 -313.644286) (xy 406.111157 -313.650218)
			(xy 406.158428 -313.66391) (xy 406.20289 -313.685008) (xy 406.243393 -313.712964) (xy 406.278886 -313.747056)
			(xy 406.308451 -313.7864) (xy 406.331322 -313.829977) (xy 406.346906 -313.876658) (xy 406.354801 -313.925235)
			(xy 406.355296 -313.949842) (xy 407.644104 -313.949842) (xy 407.648064 -313.900788) (xy 407.659841 -313.853004)
			(xy 407.679132 -313.807728) (xy 407.705435 -313.766132) (xy 407.73807 -313.729295) (xy 407.776191 -313.69817)
			(xy 407.818812 -313.673563) (xy 407.864828 -313.656111) (xy 407.913047 -313.646267) (xy 407.962222 -313.644286)
			(xy 408.011077 -313.650218) (xy 408.058348 -313.66391) (xy 408.10281 -313.685008) (xy 408.143313 -313.712964)
			(xy 408.178806 -313.747056) (xy 408.208371 -313.7864) (xy 408.231242 -313.829977) (xy 408.246826 -313.876658)
			(xy 408.254721 -313.925235) (xy 408.255216 -313.949842) (xy 409.544024 -313.949842) (xy 409.547984 -313.900788)
			(xy 409.559761 -313.853004) (xy 409.579052 -313.807728) (xy 409.605355 -313.766132) (xy 409.63799 -313.729295)
			(xy 409.676111 -313.69817) (xy 409.718732 -313.673563) (xy 409.764748 -313.656111) (xy 409.812967 -313.646267)
			(xy 409.862142 -313.644286) (xy 409.910997 -313.650218) (xy 409.958268 -313.66391) (xy 410.00273 -313.685008)
			(xy 410.043233 -313.712964) (xy 410.078726 -313.747056) (xy 410.108291 -313.7864) (xy 410.131162 -313.829977)
			(xy 410.146746 -313.876658) (xy 410.154641 -313.925235) (xy 410.155136 -313.949842) (xy 411.444198 -313.949842)
			(xy 411.448158 -313.900788) (xy 411.459935 -313.853004) (xy 411.479226 -313.807728) (xy 411.505529 -313.766132)
			(xy 411.538164 -313.729295) (xy 411.576285 -313.69817) (xy 411.618906 -313.673563) (xy 411.664922 -313.656111)
			(xy 411.713141 -313.646267) (xy 411.762316 -313.644286) (xy 411.811171 -313.650218) (xy 411.858442 -313.66391)
			(xy 411.902904 -313.685008) (xy 411.943407 -313.712964) (xy 411.9789 -313.747056) (xy 412.008465 -313.7864)
			(xy 412.031336 -313.829977) (xy 412.04692 -313.876658) (xy 412.054815 -313.925235) (xy 412.05531 -313.949842)
			(xy 413.344118 -313.949842) (xy 413.348078 -313.900788) (xy 413.359855 -313.853004) (xy 413.379146 -313.807728)
			(xy 413.405449 -313.766132) (xy 413.438084 -313.729295) (xy 413.476205 -313.69817) (xy 413.518826 -313.673563)
			(xy 413.564842 -313.656111) (xy 413.613061 -313.646267) (xy 413.662236 -313.644286) (xy 413.711091 -313.650218)
			(xy 413.758362 -313.66391) (xy 413.802824 -313.685008) (xy 413.843327 -313.712964) (xy 413.87882 -313.747056)
			(xy 413.908385 -313.7864) (xy 413.931256 -313.829977) (xy 413.94684 -313.876658) (xy 413.954735 -313.925235)
			(xy 413.95523 -313.949842) (xy 415.244038 -313.949842) (xy 415.247998 -313.900788) (xy 415.259775 -313.853004)
			(xy 415.279066 -313.807728) (xy 415.305369 -313.766132) (xy 415.338004 -313.729295) (xy 415.376125 -313.69817)
			(xy 415.418746 -313.673563) (xy 415.464762 -313.656111) (xy 415.512981 -313.646267) (xy 415.562156 -313.644286)
			(xy 415.611011 -313.650218) (xy 415.658282 -313.66391) (xy 415.702744 -313.685008) (xy 415.743247 -313.712964)
			(xy 415.77874 -313.747056) (xy 415.808305 -313.7864) (xy 415.831176 -313.829977) (xy 415.84676 -313.876658)
			(xy 415.854655 -313.925235) (xy 415.85515 -313.949842) (xy 417.144212 -313.949842) (xy 417.148172 -313.900788)
			(xy 417.159949 -313.853004) (xy 417.17924 -313.807728) (xy 417.205543 -313.766132) (xy 417.238178 -313.729295)
			(xy 417.276299 -313.69817) (xy 417.31892 -313.673563) (xy 417.364936 -313.656111) (xy 417.413155 -313.646267)
			(xy 417.46233 -313.644286) (xy 417.511185 -313.650218) (xy 417.558456 -313.66391) (xy 417.602918 -313.685008)
			(xy 417.643421 -313.712964) (xy 417.678914 -313.747056) (xy 417.708479 -313.7864) (xy 417.73135 -313.829977)
			(xy 417.746934 -313.876658) (xy 417.754829 -313.925235) (xy 417.755324 -313.949842) (xy 419.044132 -313.949842)
			(xy 419.048092 -313.900788) (xy 419.059869 -313.853004) (xy 419.07916 -313.807728) (xy 419.105463 -313.766132)
			(xy 419.138098 -313.729295) (xy 419.176219 -313.69817) (xy 419.21884 -313.673563) (xy 419.264856 -313.656111)
			(xy 419.313075 -313.646267) (xy 419.36225 -313.644286) (xy 419.411105 -313.650218) (xy 419.458376 -313.66391)
			(xy 419.502838 -313.685008) (xy 419.543341 -313.712964) (xy 419.578834 -313.747056) (xy 419.608399 -313.7864)
			(xy 419.63127 -313.829977) (xy 419.646854 -313.876658) (xy 419.654749 -313.925235) (xy 419.655244 -313.949842)
			(xy 420.944052 -313.949842) (xy 420.948012 -313.900788) (xy 420.959789 -313.853004) (xy 420.97908 -313.807728)
			(xy 421.005383 -313.766132) (xy 421.038018 -313.729295) (xy 421.076139 -313.69817) (xy 421.11876 -313.673563)
			(xy 421.164776 -313.656111) (xy 421.212995 -313.646267) (xy 421.26217 -313.644286) (xy 421.311025 -313.650218)
			(xy 421.358296 -313.66391) (xy 421.402758 -313.685008) (xy 421.443261 -313.712964) (xy 421.478754 -313.747056)
			(xy 421.508319 -313.7864) (xy 421.53119 -313.829977) (xy 421.546774 -313.876658) (xy 421.554669 -313.925235)
			(xy 421.555164 -313.949842) (xy 422.844226 -313.949842) (xy 422.848186 -313.900788) (xy 422.859963 -313.853004)
			(xy 422.879254 -313.807728) (xy 422.905557 -313.766132) (xy 422.938192 -313.729295) (xy 422.976313 -313.69817)
			(xy 423.018934 -313.673563) (xy 423.06495 -313.656111) (xy 423.113169 -313.646267) (xy 423.162344 -313.644286)
			(xy 423.211199 -313.650218) (xy 423.25847 -313.66391) (xy 423.302932 -313.685008) (xy 423.343435 -313.712964)
			(xy 423.378928 -313.747056) (xy 423.408493 -313.7864) (xy 423.431364 -313.829977) (xy 423.446948 -313.876658)
			(xy 423.454843 -313.925235) (xy 423.455338 -313.949842) (xy 424.744146 -313.949842) (xy 424.748106 -313.900788)
			(xy 424.759883 -313.853004) (xy 424.779174 -313.807728) (xy 424.805477 -313.766132) (xy 424.838112 -313.729295)
			(xy 424.876233 -313.69817) (xy 424.918854 -313.673563) (xy 424.96487 -313.656111) (xy 425.013089 -313.646267)
			(xy 425.062264 -313.644286) (xy 425.111119 -313.650218) (xy 425.15839 -313.66391) (xy 425.202852 -313.685008)
			(xy 425.243355 -313.712964) (xy 425.278848 -313.747056) (xy 425.308413 -313.7864) (xy 425.331284 -313.829977)
			(xy 425.346868 -313.876658) (xy 425.354763 -313.925235) (xy 425.355258 -313.949842) (xy 426.644066 -313.949842)
			(xy 426.648026 -313.900788) (xy 426.659803 -313.853004) (xy 426.679094 -313.807728) (xy 426.705397 -313.766132)
			(xy 426.738032 -313.729295) (xy 426.776153 -313.69817) (xy 426.818774 -313.673563) (xy 426.86479 -313.656111)
			(xy 426.913009 -313.646267) (xy 426.962184 -313.644286) (xy 427.011039 -313.650218) (xy 427.05831 -313.66391)
			(xy 427.102772 -313.685008) (xy 427.143275 -313.712964) (xy 427.178768 -313.747056) (xy 427.208333 -313.7864)
			(xy 427.231204 -313.829977) (xy 427.246788 -313.876658) (xy 427.254683 -313.925235) (xy 427.255178 -313.949842)
			(xy 428.543986 -313.949842) (xy 428.547946 -313.900788) (xy 428.559723 -313.853004) (xy 428.579014 -313.807728)
			(xy 428.605317 -313.766132) (xy 428.637952 -313.729295) (xy 428.676073 -313.69817) (xy 428.718694 -313.673563)
			(xy 428.76471 -313.656111) (xy 428.812929 -313.646267) (xy 428.862104 -313.644286) (xy 428.910959 -313.650218)
			(xy 428.95823 -313.66391) (xy 429.002692 -313.685008) (xy 429.043195 -313.712964) (xy 429.078688 -313.747056)
			(xy 429.108253 -313.7864) (xy 429.131124 -313.829977) (xy 429.146708 -313.876658) (xy 429.154603 -313.925235)
			(xy 429.155098 -313.949842) (xy 429.154603 -313.974449) (xy 429.146708 -314.023026) (xy 429.131124 -314.069707)
			(xy 429.108253 -314.113284) (xy 429.078688 -314.152628) (xy 429.043195 -314.18672) (xy 429.002692 -314.214676)
			(xy 428.95823 -314.235774) (xy 428.910959 -314.249466) (xy 428.862104 -314.255398) (xy 428.812929 -314.253417)
			(xy 428.76471 -314.243573) (xy 428.718694 -314.226121) (xy 428.676073 -314.201514) (xy 428.637952 -314.170389)
			(xy 428.605317 -314.133552) (xy 428.579014 -314.091956) (xy 428.559723 -314.04668) (xy 428.547946 -313.998896)
			(xy 428.543986 -313.949842) (xy 427.255178 -313.949842) (xy 427.254683 -313.974449) (xy 427.246788 -314.023026)
			(xy 427.231204 -314.069707) (xy 427.208333 -314.113284) (xy 427.178768 -314.152628) (xy 427.143275 -314.18672)
			(xy 427.102772 -314.214676) (xy 427.05831 -314.235774) (xy 427.011039 -314.249466) (xy 426.962184 -314.255398)
			(xy 426.913009 -314.253417) (xy 426.86479 -314.243573) (xy 426.818774 -314.226121) (xy 426.776153 -314.201514)
			(xy 426.738032 -314.170389) (xy 426.705397 -314.133552) (xy 426.679094 -314.091956) (xy 426.659803 -314.04668)
			(xy 426.648026 -313.998896) (xy 426.644066 -313.949842) (xy 425.355258 -313.949842) (xy 425.354763 -313.974449)
			(xy 425.346868 -314.023026) (xy 425.331284 -314.069707) (xy 425.308413 -314.113284) (xy 425.278848 -314.152628)
			(xy 425.243355 -314.18672) (xy 425.202852 -314.214676) (xy 425.15839 -314.235774) (xy 425.111119 -314.249466)
			(xy 425.062264 -314.255398) (xy 425.013089 -314.253417) (xy 424.96487 -314.243573) (xy 424.918854 -314.226121)
			(xy 424.876233 -314.201514) (xy 424.838112 -314.170389) (xy 424.805477 -314.133552) (xy 424.779174 -314.091956)
			(xy 424.759883 -314.04668) (xy 424.748106 -313.998896) (xy 424.744146 -313.949842) (xy 423.455338 -313.949842)
			(xy 423.454843 -313.974449) (xy 423.446948 -314.023026) (xy 423.431364 -314.069707) (xy 423.408493 -314.113284)
			(xy 423.378928 -314.152628) (xy 423.343435 -314.18672) (xy 423.302932 -314.214676) (xy 423.25847 -314.235774)
			(xy 423.211199 -314.249466) (xy 423.162344 -314.255398) (xy 423.113169 -314.253417) (xy 423.06495 -314.243573)
			(xy 423.018934 -314.226121) (xy 422.976313 -314.201514) (xy 422.938192 -314.170389) (xy 422.905557 -314.133552)
			(xy 422.879254 -314.091956) (xy 422.859963 -314.04668) (xy 422.848186 -313.998896) (xy 422.844226 -313.949842)
			(xy 421.555164 -313.949842) (xy 421.554669 -313.974449) (xy 421.546774 -314.023026) (xy 421.53119 -314.069707)
			(xy 421.508319 -314.113284) (xy 421.478754 -314.152628) (xy 421.443261 -314.18672) (xy 421.402758 -314.214676)
			(xy 421.358296 -314.235774) (xy 421.311025 -314.249466) (xy 421.26217 -314.255398) (xy 421.212995 -314.253417)
			(xy 421.164776 -314.243573) (xy 421.11876 -314.226121) (xy 421.076139 -314.201514) (xy 421.038018 -314.170389)
			(xy 421.005383 -314.133552) (xy 420.97908 -314.091956) (xy 420.959789 -314.04668) (xy 420.948012 -313.998896)
			(xy 420.944052 -313.949842) (xy 419.655244 -313.949842) (xy 419.654749 -313.974449) (xy 419.646854 -314.023026)
			(xy 419.63127 -314.069707) (xy 419.608399 -314.113284) (xy 419.578834 -314.152628) (xy 419.543341 -314.18672)
			(xy 419.502838 -314.214676) (xy 419.458376 -314.235774) (xy 419.411105 -314.249466) (xy 419.36225 -314.255398)
			(xy 419.313075 -314.253417) (xy 419.264856 -314.243573) (xy 419.21884 -314.226121) (xy 419.176219 -314.201514)
			(xy 419.138098 -314.170389) (xy 419.105463 -314.133552) (xy 419.07916 -314.091956) (xy 419.059869 -314.04668)
			(xy 419.048092 -313.998896) (xy 419.044132 -313.949842) (xy 417.755324 -313.949842) (xy 417.754829 -313.974449)
			(xy 417.746934 -314.023026) (xy 417.73135 -314.069707) (xy 417.708479 -314.113284) (xy 417.678914 -314.152628)
			(xy 417.643421 -314.18672) (xy 417.602918 -314.214676) (xy 417.558456 -314.235774) (xy 417.511185 -314.249466)
			(xy 417.46233 -314.255398) (xy 417.413155 -314.253417) (xy 417.364936 -314.243573) (xy 417.31892 -314.226121)
			(xy 417.276299 -314.201514) (xy 417.238178 -314.170389) (xy 417.205543 -314.133552) (xy 417.17924 -314.091956)
			(xy 417.159949 -314.04668) (xy 417.148172 -313.998896) (xy 417.144212 -313.949842) (xy 415.85515 -313.949842)
			(xy 415.854655 -313.974449) (xy 415.84676 -314.023026) (xy 415.831176 -314.069707) (xy 415.808305 -314.113284)
			(xy 415.77874 -314.152628) (xy 415.743247 -314.18672) (xy 415.702744 -314.214676) (xy 415.658282 -314.235774)
			(xy 415.611011 -314.249466) (xy 415.562156 -314.255398) (xy 415.512981 -314.253417) (xy 415.464762 -314.243573)
			(xy 415.418746 -314.226121) (xy 415.376125 -314.201514) (xy 415.338004 -314.170389) (xy 415.305369 -314.133552)
			(xy 415.279066 -314.091956) (xy 415.259775 -314.04668) (xy 415.247998 -313.998896) (xy 415.244038 -313.949842)
			(xy 413.95523 -313.949842) (xy 413.954735 -313.974449) (xy 413.94684 -314.023026) (xy 413.931256 -314.069707)
			(xy 413.908385 -314.113284) (xy 413.87882 -314.152628) (xy 413.843327 -314.18672) (xy 413.802824 -314.214676)
			(xy 413.758362 -314.235774) (xy 413.711091 -314.249466) (xy 413.662236 -314.255398) (xy 413.613061 -314.253417)
			(xy 413.564842 -314.243573) (xy 413.518826 -314.226121) (xy 413.476205 -314.201514) (xy 413.438084 -314.170389)
			(xy 413.405449 -314.133552) (xy 413.379146 -314.091956) (xy 413.359855 -314.04668) (xy 413.348078 -313.998896)
			(xy 413.344118 -313.949842) (xy 412.05531 -313.949842) (xy 412.054815 -313.974449) (xy 412.04692 -314.023026)
			(xy 412.031336 -314.069707) (xy 412.008465 -314.113284) (xy 411.9789 -314.152628) (xy 411.943407 -314.18672)
			(xy 411.902904 -314.214676) (xy 411.858442 -314.235774) (xy 411.811171 -314.249466) (xy 411.762316 -314.255398)
			(xy 411.713141 -314.253417) (xy 411.664922 -314.243573) (xy 411.618906 -314.226121) (xy 411.576285 -314.201514)
			(xy 411.538164 -314.170389) (xy 411.505529 -314.133552) (xy 411.479226 -314.091956) (xy 411.459935 -314.04668)
			(xy 411.448158 -313.998896) (xy 411.444198 -313.949842) (xy 410.155136 -313.949842) (xy 410.154641 -313.974449)
			(xy 410.146746 -314.023026) (xy 410.131162 -314.069707) (xy 410.108291 -314.113284) (xy 410.078726 -314.152628)
			(xy 410.043233 -314.18672) (xy 410.00273 -314.214676) (xy 409.958268 -314.235774) (xy 409.910997 -314.249466)
			(xy 409.862142 -314.255398) (xy 409.812967 -314.253417) (xy 409.764748 -314.243573) (xy 409.718732 -314.226121)
			(xy 409.676111 -314.201514) (xy 409.63799 -314.170389) (xy 409.605355 -314.133552) (xy 409.579052 -314.091956)
			(xy 409.559761 -314.04668) (xy 409.547984 -313.998896) (xy 409.544024 -313.949842) (xy 408.255216 -313.949842)
			(xy 408.254721 -313.974449) (xy 408.246826 -314.023026) (xy 408.231242 -314.069707) (xy 408.208371 -314.113284)
			(xy 408.178806 -314.152628) (xy 408.143313 -314.18672) (xy 408.10281 -314.214676) (xy 408.058348 -314.235774)
			(xy 408.011077 -314.249466) (xy 407.962222 -314.255398) (xy 407.913047 -314.253417) (xy 407.864828 -314.243573)
			(xy 407.818812 -314.226121) (xy 407.776191 -314.201514) (xy 407.73807 -314.170389) (xy 407.705435 -314.133552)
			(xy 407.679132 -314.091956) (xy 407.659841 -314.04668) (xy 407.648064 -313.998896) (xy 407.644104 -313.949842)
			(xy 406.355296 -313.949842) (xy 406.354801 -313.974449) (xy 406.346906 -314.023026) (xy 406.331322 -314.069707)
			(xy 406.308451 -314.113284) (xy 406.278886 -314.152628) (xy 406.243393 -314.18672) (xy 406.20289 -314.214676)
			(xy 406.158428 -314.235774) (xy 406.111157 -314.249466) (xy 406.062302 -314.255398) (xy 406.013127 -314.253417)
			(xy 405.964908 -314.243573) (xy 405.918892 -314.226121) (xy 405.876271 -314.201514) (xy 405.83815 -314.170389)
			(xy 405.805515 -314.133552) (xy 405.779212 -314.091956) (xy 405.759921 -314.04668) (xy 405.748144 -313.998896)
			(xy 405.744184 -313.949842) (xy 404.455122 -313.949842) (xy 404.454627 -313.974449) (xy 404.446732 -314.023026)
			(xy 404.431148 -314.069707) (xy 404.408277 -314.113284) (xy 404.378712 -314.152628) (xy 404.343219 -314.18672)
			(xy 404.302716 -314.214676) (xy 404.258254 -314.235774) (xy 404.210983 -314.249466) (xy 404.162128 -314.255398)
			(xy 404.112953 -314.253417) (xy 404.064734 -314.243573) (xy 404.018718 -314.226121) (xy 403.976097 -314.201514)
			(xy 403.937976 -314.170389) (xy 403.905341 -314.133552) (xy 403.879038 -314.091956) (xy 403.859747 -314.04668)
			(xy 403.84797 -313.998896) (xy 403.84401 -313.949842) (xy 402.555202 -313.949842) (xy 402.554707 -313.974449)
			(xy 402.546812 -314.023026) (xy 402.531228 -314.069707) (xy 402.508357 -314.113284) (xy 402.478792 -314.152628)
			(xy 402.443299 -314.18672) (xy 402.402796 -314.214676) (xy 402.358334 -314.235774) (xy 402.311063 -314.249466)
			(xy 402.262208 -314.255398) (xy 402.213033 -314.253417) (xy 402.164814 -314.243573) (xy 402.118798 -314.226121)
			(xy 402.076177 -314.201514) (xy 402.038056 -314.170389) (xy 402.005421 -314.133552) (xy 401.979118 -314.091956)
			(xy 401.959827 -314.04668) (xy 401.94805 -313.998896) (xy 401.94409 -313.949842) (xy 400.655282 -313.949842)
			(xy 400.654787 -313.974449) (xy 400.646892 -314.023026) (xy 400.631308 -314.069707) (xy 400.608437 -314.113284)
			(xy 400.578872 -314.152628) (xy 400.543379 -314.18672) (xy 400.502876 -314.214676) (xy 400.458414 -314.235774)
			(xy 400.411143 -314.249466) (xy 400.362288 -314.255398) (xy 400.313113 -314.253417) (xy 400.264894 -314.243573)
			(xy 400.218878 -314.226121) (xy 400.176257 -314.201514) (xy 400.138136 -314.170389) (xy 400.105501 -314.133552)
			(xy 400.079198 -314.091956) (xy 400.059907 -314.04668) (xy 400.04813 -313.998896) (xy 400.04417 -313.949842)
			(xy 398.755108 -313.949842) (xy 398.754613 -313.974449) (xy 398.746718 -314.023026) (xy 398.731134 -314.069707)
			(xy 398.708263 -314.113284) (xy 398.678698 -314.152628) (xy 398.643205 -314.18672) (xy 398.602702 -314.214676)
			(xy 398.55824 -314.235774) (xy 398.510969 -314.249466) (xy 398.462114 -314.255398) (xy 398.412939 -314.253417)
			(xy 398.36472 -314.243573) (xy 398.318704 -314.226121) (xy 398.276083 -314.201514) (xy 398.237962 -314.170389)
			(xy 398.205327 -314.133552) (xy 398.179024 -314.091956) (xy 398.159733 -314.04668) (xy 398.147956 -313.998896)
			(xy 398.143996 -313.949842) (xy 396.855188 -313.949842) (xy 396.854693 -313.974449) (xy 396.846798 -314.023026)
			(xy 396.831214 -314.069707) (xy 396.808343 -314.113284) (xy 396.778778 -314.152628) (xy 396.743285 -314.18672)
			(xy 396.702782 -314.214676) (xy 396.65832 -314.235774) (xy 396.611049 -314.249466) (xy 396.562194 -314.255398)
			(xy 396.513019 -314.253417) (xy 396.4648 -314.243573) (xy 396.418784 -314.226121) (xy 396.376163 -314.201514)
			(xy 396.338042 -314.170389) (xy 396.305407 -314.133552) (xy 396.279104 -314.091956) (xy 396.259813 -314.04668)
			(xy 396.248036 -313.998896) (xy 396.244076 -313.949842) (xy 394.955268 -313.949842) (xy 394.954773 -313.974449)
			(xy 394.946878 -314.023026) (xy 394.931294 -314.069707) (xy 394.908423 -314.113284) (xy 394.878858 -314.152628)
			(xy 394.843365 -314.18672) (xy 394.802862 -314.214676) (xy 394.7584 -314.235774) (xy 394.711129 -314.249466)
			(xy 394.662274 -314.255398) (xy 394.613099 -314.253417) (xy 394.56488 -314.243573) (xy 394.518864 -314.226121)
			(xy 394.476243 -314.201514) (xy 394.438122 -314.170389) (xy 394.405487 -314.133552) (xy 394.379184 -314.091956)
			(xy 394.359893 -314.04668) (xy 394.348116 -313.998896) (xy 394.344156 -313.949842) (xy 393.055094 -313.949842)
			(xy 393.054599 -313.974449) (xy 393.046704 -314.023026) (xy 393.03112 -314.069707) (xy 393.008249 -314.113284)
			(xy 392.978684 -314.152628) (xy 392.943191 -314.18672) (xy 392.902688 -314.214676) (xy 392.858226 -314.235774)
			(xy 392.810955 -314.249466) (xy 392.7621 -314.255398) (xy 392.712925 -314.253417) (xy 392.664706 -314.243573)
			(xy 392.61869 -314.226121) (xy 392.576069 -314.201514) (xy 392.537948 -314.170389) (xy 392.505313 -314.133552)
			(xy 392.47901 -314.091956) (xy 392.459719 -314.04668) (xy 392.447942 -313.998896) (xy 392.443982 -313.949842)
			(xy 391.155174 -313.949842) (xy 391.154679 -313.974449) (xy 391.146784 -314.023026) (xy 391.1312 -314.069707)
			(xy 391.108329 -314.113284) (xy 391.078764 -314.152628) (xy 391.043271 -314.18672) (xy 391.002768 -314.214676)
			(xy 390.958306 -314.235774) (xy 390.911035 -314.249466) (xy 390.86218 -314.255398) (xy 390.813005 -314.253417)
			(xy 390.764786 -314.243573) (xy 390.71877 -314.226121) (xy 390.676149 -314.201514) (xy 390.638028 -314.170389)
			(xy 390.605393 -314.133552) (xy 390.57909 -314.091956) (xy 390.559799 -314.04668) (xy 390.548022 -313.998896)
			(xy 390.544062 -313.949842) (xy 389.255254 -313.949842) (xy 389.254759 -313.974449) (xy 389.246864 -314.023026)
			(xy 389.23128 -314.069707) (xy 389.208409 -314.113284) (xy 389.178844 -314.152628) (xy 389.143351 -314.18672)
			(xy 389.102848 -314.214676) (xy 389.058386 -314.235774) (xy 389.011115 -314.249466) (xy 388.96226 -314.255398)
			(xy 388.913085 -314.253417) (xy 388.864866 -314.243573) (xy 388.81885 -314.226121) (xy 388.776229 -314.201514)
			(xy 388.738108 -314.170389) (xy 388.705473 -314.133552) (xy 388.67917 -314.091956) (xy 388.659879 -314.04668)
			(xy 388.648102 -313.998896) (xy 388.644142 -313.949842) (xy 387.355334 -313.949842) (xy 387.354839 -313.974449)
			(xy 387.346944 -314.023026) (xy 387.33136 -314.069707) (xy 387.308489 -314.113284) (xy 387.278924 -314.152628)
			(xy 387.243431 -314.18672) (xy 387.202928 -314.214676) (xy 387.158466 -314.235774) (xy 387.111195 -314.249466)
			(xy 387.06234 -314.255398) (xy 387.013165 -314.253417) (xy 386.964946 -314.243573) (xy 386.91893 -314.226121)
			(xy 386.876309 -314.201514) (xy 386.838188 -314.170389) (xy 386.805553 -314.133552) (xy 386.77925 -314.091956)
			(xy 386.759959 -314.04668) (xy 386.748182 -313.998896) (xy 386.744222 -313.949842) (xy 313.055 -313.949842)
			(xy 313.054505 -313.974449) (xy 313.04661 -314.023026) (xy 313.031026 -314.069707) (xy 313.008155 -314.113284)
			(xy 312.97859 -314.152628) (xy 312.943097 -314.18672) (xy 312.902594 -314.214676) (xy 312.858132 -314.235774)
			(xy 312.810861 -314.249466) (xy 312.762006 -314.255398) (xy 312.712831 -314.253417) (xy 312.664612 -314.243573)
			(xy 312.618596 -314.226121) (xy 312.575975 -314.201514) (xy 312.537854 -314.170389) (xy 312.505219 -314.133552)
			(xy 312.478916 -314.091956) (xy 312.459625 -314.04668) (xy 312.447848 -313.998896) (xy 312.443888 -313.949842)
			(xy 311.15508 -313.949842) (xy 311.154585 -313.974449) (xy 311.14669 -314.023026) (xy 311.131106 -314.069707)
			(xy 311.108235 -314.113284) (xy 311.07867 -314.152628) (xy 311.043177 -314.18672) (xy 311.002674 -314.214676)
			(xy 310.958212 -314.235774) (xy 310.910941 -314.249466) (xy 310.862086 -314.255398) (xy 310.812911 -314.253417)
			(xy 310.764692 -314.243573) (xy 310.718676 -314.226121) (xy 310.676055 -314.201514) (xy 310.637934 -314.170389)
			(xy 310.605299 -314.133552) (xy 310.578996 -314.091956) (xy 310.559705 -314.04668) (xy 310.547928 -313.998896)
			(xy 310.543968 -313.949842) (xy 309.25516 -313.949842) (xy 309.254665 -313.974449) (xy 309.24677 -314.023026)
			(xy 309.231186 -314.069707) (xy 309.208315 -314.113284) (xy 309.17875 -314.152628) (xy 309.143257 -314.18672)
			(xy 309.102754 -314.214676) (xy 309.058292 -314.235774) (xy 309.011021 -314.249466) (xy 308.962166 -314.255398)
			(xy 308.912991 -314.253417) (xy 308.864772 -314.243573) (xy 308.818756 -314.226121) (xy 308.776135 -314.201514)
			(xy 308.738014 -314.170389) (xy 308.705379 -314.133552) (xy 308.679076 -314.091956) (xy 308.659785 -314.04668)
			(xy 308.648008 -313.998896) (xy 308.644048 -313.949842) (xy 307.35524 -313.949842) (xy 307.354745 -313.974449)
			(xy 307.34685 -314.023026) (xy 307.331266 -314.069707) (xy 307.308395 -314.113284) (xy 307.27883 -314.152628)
			(xy 307.243337 -314.18672) (xy 307.202834 -314.214676) (xy 307.158372 -314.235774) (xy 307.111101 -314.249466)
			(xy 307.062246 -314.255398) (xy 307.013071 -314.253417) (xy 306.964852 -314.243573) (xy 306.918836 -314.226121)
			(xy 306.876215 -314.201514) (xy 306.838094 -314.170389) (xy 306.805459 -314.133552) (xy 306.779156 -314.091956)
			(xy 306.759865 -314.04668) (xy 306.748088 -313.998896) (xy 306.744128 -313.949842) (xy 305.455066 -313.949842)
			(xy 305.454571 -313.974449) (xy 305.446676 -314.023026) (xy 305.431092 -314.069707) (xy 305.408221 -314.113284)
			(xy 305.378656 -314.152628) (xy 305.343163 -314.18672) (xy 305.30266 -314.214676) (xy 305.258198 -314.235774)
			(xy 305.210927 -314.249466) (xy 305.162072 -314.255398) (xy 305.112897 -314.253417) (xy 305.064678 -314.243573)
			(xy 305.018662 -314.226121) (xy 304.976041 -314.201514) (xy 304.93792 -314.170389) (xy 304.905285 -314.133552)
			(xy 304.878982 -314.091956) (xy 304.859691 -314.04668) (xy 304.847914 -313.998896) (xy 304.843954 -313.949842)
			(xy 303.555146 -313.949842) (xy 303.554651 -313.974449) (xy 303.546756 -314.023026) (xy 303.531172 -314.069707)
			(xy 303.508301 -314.113284) (xy 303.478736 -314.152628) (xy 303.443243 -314.18672) (xy 303.40274 -314.214676)
			(xy 303.358278 -314.235774) (xy 303.311007 -314.249466) (xy 303.262152 -314.255398) (xy 303.212977 -314.253417)
			(xy 303.164758 -314.243573) (xy 303.118742 -314.226121) (xy 303.076121 -314.201514) (xy 303.038 -314.170389)
			(xy 303.005365 -314.133552) (xy 302.979062 -314.091956) (xy 302.959771 -314.04668) (xy 302.947994 -313.998896)
			(xy 302.944034 -313.949842) (xy 301.655226 -313.949842) (xy 301.654731 -313.974449) (xy 301.646836 -314.023026)
			(xy 301.631252 -314.069707) (xy 301.608381 -314.113284) (xy 301.578816 -314.152628) (xy 301.543323 -314.18672)
			(xy 301.50282 -314.214676) (xy 301.458358 -314.235774) (xy 301.411087 -314.249466) (xy 301.362232 -314.255398)
			(xy 301.313057 -314.253417) (xy 301.264838 -314.243573) (xy 301.218822 -314.226121) (xy 301.176201 -314.201514)
			(xy 301.13808 -314.170389) (xy 301.105445 -314.133552) (xy 301.079142 -314.091956) (xy 301.059851 -314.04668)
			(xy 301.048074 -313.998896) (xy 301.044114 -313.949842) (xy 299.755052 -313.949842) (xy 299.754557 -313.974449)
			(xy 299.746662 -314.023026) (xy 299.731078 -314.069707) (xy 299.708207 -314.113284) (xy 299.678642 -314.152628)
			(xy 299.643149 -314.18672) (xy 299.602646 -314.214676) (xy 299.558184 -314.235774) (xy 299.510913 -314.249466)
			(xy 299.462058 -314.255398) (xy 299.412883 -314.253417) (xy 299.364664 -314.243573) (xy 299.318648 -314.226121)
			(xy 299.276027 -314.201514) (xy 299.237906 -314.170389) (xy 299.205271 -314.133552) (xy 299.178968 -314.091956)
			(xy 299.159677 -314.04668) (xy 299.1479 -313.998896) (xy 299.14394 -313.949842) (xy 297.855132 -313.949842)
			(xy 297.854637 -313.974449) (xy 297.846742 -314.023026) (xy 297.831158 -314.069707) (xy 297.808287 -314.113284)
			(xy 297.778722 -314.152628) (xy 297.743229 -314.18672) (xy 297.702726 -314.214676) (xy 297.658264 -314.235774)
			(xy 297.610993 -314.249466) (xy 297.562138 -314.255398) (xy 297.512963 -314.253417) (xy 297.464744 -314.243573)
			(xy 297.418728 -314.226121) (xy 297.376107 -314.201514) (xy 297.337986 -314.170389) (xy 297.305351 -314.133552)
			(xy 297.279048 -314.091956) (xy 297.259757 -314.04668) (xy 297.24798 -313.998896) (xy 297.24402 -313.949842)
			(xy 295.955212 -313.949842) (xy 295.954717 -313.974449) (xy 295.946822 -314.023026) (xy 295.931238 -314.069707)
			(xy 295.908367 -314.113284) (xy 295.878802 -314.152628) (xy 295.843309 -314.18672) (xy 295.802806 -314.214676)
			(xy 295.758344 -314.235774) (xy 295.711073 -314.249466) (xy 295.662218 -314.255398) (xy 295.613043 -314.253417)
			(xy 295.564824 -314.243573) (xy 295.518808 -314.226121) (xy 295.476187 -314.201514) (xy 295.438066 -314.170389)
			(xy 295.405431 -314.133552) (xy 295.379128 -314.091956) (xy 295.359837 -314.04668) (xy 295.34806 -313.998896)
			(xy 295.3441 -313.949842) (xy 294.055038 -313.949842) (xy 294.054543 -313.974449) (xy 294.046648 -314.023026)
			(xy 294.031064 -314.069707) (xy 294.008193 -314.113284) (xy 293.978628 -314.152628) (xy 293.943135 -314.18672)
			(xy 293.902632 -314.214676) (xy 293.85817 -314.235774) (xy 293.810899 -314.249466) (xy 293.762044 -314.255398)
			(xy 293.712869 -314.253417) (xy 293.66465 -314.243573) (xy 293.618634 -314.226121) (xy 293.576013 -314.201514)
			(xy 293.537892 -314.170389) (xy 293.505257 -314.133552) (xy 293.478954 -314.091956) (xy 293.459663 -314.04668)
			(xy 293.447886 -313.998896) (xy 293.443926 -313.949842) (xy 292.155118 -313.949842) (xy 292.154623 -313.974449)
			(xy 292.146728 -314.023026) (xy 292.131144 -314.069707) (xy 292.108273 -314.113284) (xy 292.078708 -314.152628)
			(xy 292.043215 -314.18672) (xy 292.002712 -314.214676) (xy 291.95825 -314.235774) (xy 291.910979 -314.249466)
			(xy 291.862124 -314.255398) (xy 291.812949 -314.253417) (xy 291.76473 -314.243573) (xy 291.718714 -314.226121)
			(xy 291.676093 -314.201514) (xy 291.637972 -314.170389) (xy 291.605337 -314.133552) (xy 291.579034 -314.091956)
			(xy 291.559743 -314.04668) (xy 291.547966 -313.998896) (xy 291.544006 -313.949842) (xy 290.255198 -313.949842)
			(xy 290.254703 -313.974449) (xy 290.246808 -314.023026) (xy 290.231224 -314.069707) (xy 290.208353 -314.113284)
			(xy 290.178788 -314.152628) (xy 290.143295 -314.18672) (xy 290.102792 -314.214676) (xy 290.05833 -314.235774)
			(xy 290.011059 -314.249466) (xy 289.962204 -314.255398) (xy 289.913029 -314.253417) (xy 289.86481 -314.243573)
			(xy 289.818794 -314.226121) (xy 289.776173 -314.201514) (xy 289.738052 -314.170389) (xy 289.705417 -314.133552)
			(xy 289.679114 -314.091956) (xy 289.659823 -314.04668) (xy 289.648046 -313.998896) (xy 289.644086 -313.949842)
			(xy 288.355024 -313.949842) (xy 288.354529 -313.974449) (xy 288.346634 -314.023026) (xy 288.33105 -314.069707)
			(xy 288.308179 -314.113284) (xy 288.278614 -314.152628) (xy 288.243121 -314.18672) (xy 288.202618 -314.214676)
			(xy 288.158156 -314.235774) (xy 288.110885 -314.249466) (xy 288.06203 -314.255398) (xy 288.012855 -314.253417)
			(xy 287.964636 -314.243573) (xy 287.91862 -314.226121) (xy 287.875999 -314.201514) (xy 287.837878 -314.170389)
			(xy 287.805243 -314.133552) (xy 287.77894 -314.091956) (xy 287.759649 -314.04668) (xy 287.747872 -313.998896)
			(xy 287.743912 -313.949842) (xy 286.455104 -313.949842) (xy 286.454609 -313.974449) (xy 286.446714 -314.023026)
			(xy 286.43113 -314.069707) (xy 286.408259 -314.113284) (xy 286.378694 -314.152628) (xy 286.343201 -314.18672)
			(xy 286.302698 -314.214676) (xy 286.258236 -314.235774) (xy 286.210965 -314.249466) (xy 286.16211 -314.255398)
			(xy 286.112935 -314.253417) (xy 286.064716 -314.243573) (xy 286.0187 -314.226121) (xy 285.976079 -314.201514)
			(xy 285.937958 -314.170389) (xy 285.905323 -314.133552) (xy 285.87902 -314.091956) (xy 285.859729 -314.04668)
			(xy 285.847952 -313.998896) (xy 285.843992 -313.949842) (xy 284.555184 -313.949842) (xy 284.554689 -313.974449)
			(xy 284.546794 -314.023026) (xy 284.53121 -314.069707) (xy 284.508339 -314.113284) (xy 284.478774 -314.152628)
			(xy 284.443281 -314.18672) (xy 284.402778 -314.214676) (xy 284.358316 -314.235774) (xy 284.311045 -314.249466)
			(xy 284.26219 -314.255398) (xy 284.213015 -314.253417) (xy 284.164796 -314.243573) (xy 284.11878 -314.226121)
			(xy 284.076159 -314.201514) (xy 284.038038 -314.170389) (xy 284.005403 -314.133552) (xy 283.9791 -314.091956)
			(xy 283.959809 -314.04668) (xy 283.948032 -313.998896) (xy 283.944072 -313.949842) (xy 282.65501 -313.949842)
			(xy 282.654515 -313.974449) (xy 282.64662 -314.023026) (xy 282.631036 -314.069707) (xy 282.608165 -314.113284)
			(xy 282.5786 -314.152628) (xy 282.543107 -314.18672) (xy 282.502604 -314.214676) (xy 282.458142 -314.235774)
			(xy 282.410871 -314.249466) (xy 282.362016 -314.255398) (xy 282.312841 -314.253417) (xy 282.264622 -314.243573)
			(xy 282.218606 -314.226121) (xy 282.175985 -314.201514) (xy 282.137864 -314.170389) (xy 282.105229 -314.133552)
			(xy 282.078926 -314.091956) (xy 282.059635 -314.04668) (xy 282.047858 -313.998896) (xy 282.043898 -313.949842)
			(xy 280.75509 -313.949842) (xy 280.754595 -313.974449) (xy 280.7467 -314.023026) (xy 280.731116 -314.069707)
			(xy 280.708245 -314.113284) (xy 280.67868 -314.152628) (xy 280.643187 -314.18672) (xy 280.602684 -314.214676)
			(xy 280.558222 -314.235774) (xy 280.510951 -314.249466) (xy 280.462096 -314.255398) (xy 280.412921 -314.253417)
			(xy 280.364702 -314.243573) (xy 280.318686 -314.226121) (xy 280.276065 -314.201514) (xy 280.237944 -314.170389)
			(xy 280.205309 -314.133552) (xy 280.179006 -314.091956) (xy 280.159715 -314.04668) (xy 280.147938 -313.998896)
			(xy 280.143978 -313.949842) (xy 278.85517 -313.949842) (xy 278.854675 -313.974449) (xy 278.84678 -314.023026)
			(xy 278.831196 -314.069707) (xy 278.808325 -314.113284) (xy 278.77876 -314.152628) (xy 278.743267 -314.18672)
			(xy 278.702764 -314.214676) (xy 278.658302 -314.235774) (xy 278.611031 -314.249466) (xy 278.562176 -314.255398)
			(xy 278.513001 -314.253417) (xy 278.464782 -314.243573) (xy 278.418766 -314.226121) (xy 278.376145 -314.201514)
			(xy 278.338024 -314.170389) (xy 278.305389 -314.133552) (xy 278.279086 -314.091956) (xy 278.259795 -314.04668)
			(xy 278.248018 -313.998896) (xy 278.244058 -313.949842) (xy 276.954996 -313.949842) (xy 276.954501 -313.974449)
			(xy 276.946606 -314.023026) (xy 276.931022 -314.069707) (xy 276.908151 -314.113284) (xy 276.878586 -314.152628)
			(xy 276.843093 -314.18672) (xy 276.80259 -314.214676) (xy 276.758128 -314.235774) (xy 276.710857 -314.249466)
			(xy 276.662002 -314.255398) (xy 276.612827 -314.253417) (xy 276.564608 -314.243573) (xy 276.518592 -314.226121)
			(xy 276.475971 -314.201514) (xy 276.43785 -314.170389) (xy 276.405215 -314.133552) (xy 276.378912 -314.091956)
			(xy 276.359621 -314.04668) (xy 276.347844 -313.998896) (xy 276.343884 -313.949842) (xy 275.055076 -313.949842)
			(xy 275.054581 -313.974449) (xy 275.046686 -314.023026) (xy 275.031102 -314.069707) (xy 275.008231 -314.113284)
			(xy 274.978666 -314.152628) (xy 274.943173 -314.18672) (xy 274.90267 -314.214676) (xy 274.858208 -314.235774)
			(xy 274.810937 -314.249466) (xy 274.762082 -314.255398) (xy 274.712907 -314.253417) (xy 274.664688 -314.243573)
			(xy 274.618672 -314.226121) (xy 274.576051 -314.201514) (xy 274.53793 -314.170389) (xy 274.505295 -314.133552)
			(xy 274.478992 -314.091956) (xy 274.459701 -314.04668) (xy 274.447924 -313.998896) (xy 274.443964 -313.949842)
			(xy 273.155156 -313.949842) (xy 273.154661 -313.974449) (xy 273.146766 -314.023026) (xy 273.131182 -314.069707)
			(xy 273.108311 -314.113284) (xy 273.078746 -314.152628) (xy 273.043253 -314.18672) (xy 273.00275 -314.214676)
			(xy 272.958288 -314.235774) (xy 272.911017 -314.249466) (xy 272.862162 -314.255398) (xy 272.812987 -314.253417)
			(xy 272.764768 -314.243573) (xy 272.718752 -314.226121) (xy 272.676131 -314.201514) (xy 272.63801 -314.170389)
			(xy 272.605375 -314.133552) (xy 272.579072 -314.091956) (xy 272.559781 -314.04668) (xy 272.548004 -313.998896)
			(xy 272.544044 -313.949842) (xy 271.255236 -313.949842) (xy 271.254741 -313.974449) (xy 271.246846 -314.023026)
			(xy 271.231262 -314.069707) (xy 271.208391 -314.113284) (xy 271.178826 -314.152628) (xy 271.143333 -314.18672)
			(xy 271.10283 -314.214676) (xy 271.058368 -314.235774) (xy 271.011097 -314.249466) (xy 270.962242 -314.255398)
			(xy 270.913067 -314.253417) (xy 270.864848 -314.243573) (xy 270.818832 -314.226121) (xy 270.776211 -314.201514)
			(xy 270.73809 -314.170389) (xy 270.705455 -314.133552) (xy 270.679152 -314.091956) (xy 270.659861 -314.04668)
			(xy 270.648084 -313.998896) (xy 270.644124 -313.949842) (xy 196.955156 -313.949842) (xy 196.954661 -313.974449)
			(xy 196.946766 -314.023026) (xy 196.931182 -314.069707) (xy 196.908311 -314.113284) (xy 196.878746 -314.152628)
			(xy 196.843253 -314.18672) (xy 196.80275 -314.214676) (xy 196.758288 -314.235774) (xy 196.711017 -314.249466)
			(xy 196.662162 -314.255398) (xy 196.612987 -314.253417) (xy 196.564768 -314.243573) (xy 196.518752 -314.226121)
			(xy 196.476131 -314.201514) (xy 196.43801 -314.170389) (xy 196.405375 -314.133552) (xy 196.379072 -314.091956)
			(xy 196.359781 -314.04668) (xy 196.348004 -313.998896) (xy 196.344044 -313.949842) (xy 195.055236 -313.949842)
			(xy 195.054741 -313.974449) (xy 195.046846 -314.023026) (xy 195.031262 -314.069707) (xy 195.008391 -314.113284)
			(xy 194.978826 -314.152628) (xy 194.943333 -314.18672) (xy 194.90283 -314.214676) (xy 194.858368 -314.235774)
			(xy 194.811097 -314.249466) (xy 194.762242 -314.255398) (xy 194.713067 -314.253417) (xy 194.664848 -314.243573)
			(xy 194.618832 -314.226121) (xy 194.576211 -314.201514) (xy 194.53809 -314.170389) (xy 194.505455 -314.133552)
			(xy 194.479152 -314.091956) (xy 194.459861 -314.04668) (xy 194.448084 -313.998896) (xy 194.444124 -313.949842)
			(xy 193.155316 -313.949842) (xy 193.154821 -313.974449) (xy 193.146926 -314.023026) (xy 193.131342 -314.069707)
			(xy 193.108471 -314.113284) (xy 193.078906 -314.152628) (xy 193.043413 -314.18672) (xy 193.00291 -314.214676)
			(xy 192.958448 -314.235774) (xy 192.911177 -314.249466) (xy 192.862322 -314.255398) (xy 192.813147 -314.253417)
			(xy 192.764928 -314.243573) (xy 192.718912 -314.226121) (xy 192.676291 -314.201514) (xy 192.63817 -314.170389)
			(xy 192.605535 -314.133552) (xy 192.579232 -314.091956) (xy 192.559941 -314.04668) (xy 192.548164 -313.998896)
			(xy 192.544204 -313.949842) (xy 191.255396 -313.949842) (xy 191.254901 -313.974449) (xy 191.247006 -314.023026)
			(xy 191.231422 -314.069707) (xy 191.208551 -314.113284) (xy 191.178986 -314.152628) (xy 191.143493 -314.18672)
			(xy 191.10299 -314.214676) (xy 191.058528 -314.235774) (xy 191.011257 -314.249466) (xy 190.962402 -314.255398)
			(xy 190.913227 -314.253417) (xy 190.865008 -314.243573) (xy 190.818992 -314.226121) (xy 190.776371 -314.201514)
			(xy 190.73825 -314.170389) (xy 190.705615 -314.133552) (xy 190.679312 -314.091956) (xy 190.660021 -314.04668)
			(xy 190.648244 -313.998896) (xy 190.644284 -313.949842) (xy 189.355222 -313.949842) (xy 189.354727 -313.974449)
			(xy 189.346832 -314.023026) (xy 189.331248 -314.069707) (xy 189.308377 -314.113284) (xy 189.278812 -314.152628)
			(xy 189.243319 -314.18672) (xy 189.202816 -314.214676) (xy 189.158354 -314.235774) (xy 189.111083 -314.249466)
			(xy 189.062228 -314.255398) (xy 189.013053 -314.253417) (xy 188.964834 -314.243573) (xy 188.918818 -314.226121)
			(xy 188.876197 -314.201514) (xy 188.838076 -314.170389) (xy 188.805441 -314.133552) (xy 188.779138 -314.091956)
			(xy 188.759847 -314.04668) (xy 188.74807 -313.998896) (xy 188.74411 -313.949842) (xy 187.455302 -313.949842)
			(xy 187.454807 -313.974449) (xy 187.446912 -314.023026) (xy 187.431328 -314.069707) (xy 187.408457 -314.113284)
			(xy 187.378892 -314.152628) (xy 187.343399 -314.18672) (xy 187.302896 -314.214676) (xy 187.258434 -314.235774)
			(xy 187.211163 -314.249466) (xy 187.162308 -314.255398) (xy 187.113133 -314.253417) (xy 187.064914 -314.243573)
			(xy 187.018898 -314.226121) (xy 186.976277 -314.201514) (xy 186.938156 -314.170389) (xy 186.905521 -314.133552)
			(xy 186.879218 -314.091956) (xy 186.859927 -314.04668) (xy 186.84815 -313.998896) (xy 186.84419 -313.949842)
			(xy 185.555382 -313.949842) (xy 185.554887 -313.974449) (xy 185.546992 -314.023026) (xy 185.531408 -314.069707)
			(xy 185.508537 -314.113284) (xy 185.478972 -314.152628) (xy 185.443479 -314.18672) (xy 185.402976 -314.214676)
			(xy 185.358514 -314.235774) (xy 185.311243 -314.249466) (xy 185.262388 -314.255398) (xy 185.213213 -314.253417)
			(xy 185.164994 -314.243573) (xy 185.118978 -314.226121) (xy 185.076357 -314.201514) (xy 185.038236 -314.170389)
			(xy 185.005601 -314.133552) (xy 184.979298 -314.091956) (xy 184.960007 -314.04668) (xy 184.94823 -313.998896)
			(xy 184.94427 -313.949842) (xy 183.655208 -313.949842) (xy 183.654713 -313.974449) (xy 183.646818 -314.023026)
			(xy 183.631234 -314.069707) (xy 183.608363 -314.113284) (xy 183.578798 -314.152628) (xy 183.543305 -314.18672)
			(xy 183.502802 -314.214676) (xy 183.45834 -314.235774) (xy 183.411069 -314.249466) (xy 183.362214 -314.255398)
			(xy 183.313039 -314.253417) (xy 183.26482 -314.243573) (xy 183.218804 -314.226121) (xy 183.176183 -314.201514)
			(xy 183.138062 -314.170389) (xy 183.105427 -314.133552) (xy 183.079124 -314.091956) (xy 183.059833 -314.04668)
			(xy 183.048056 -313.998896) (xy 183.044096 -313.949842) (xy 181.755288 -313.949842) (xy 181.754793 -313.974449)
			(xy 181.746898 -314.023026) (xy 181.731314 -314.069707) (xy 181.708443 -314.113284) (xy 181.678878 -314.152628)
			(xy 181.643385 -314.18672) (xy 181.602882 -314.214676) (xy 181.55842 -314.235774) (xy 181.511149 -314.249466)
			(xy 181.462294 -314.255398) (xy 181.413119 -314.253417) (xy 181.3649 -314.243573) (xy 181.318884 -314.226121)
			(xy 181.276263 -314.201514) (xy 181.238142 -314.170389) (xy 181.205507 -314.133552) (xy 181.179204 -314.091956)
			(xy 181.159913 -314.04668) (xy 181.148136 -313.998896) (xy 181.144176 -313.949842) (xy 179.855368 -313.949842)
			(xy 179.854873 -313.974449) (xy 179.846978 -314.023026) (xy 179.831394 -314.069707) (xy 179.808523 -314.113284)
			(xy 179.778958 -314.152628) (xy 179.743465 -314.18672) (xy 179.702962 -314.214676) (xy 179.6585 -314.235774)
			(xy 179.611229 -314.249466) (xy 179.562374 -314.255398) (xy 179.513199 -314.253417) (xy 179.46498 -314.243573)
			(xy 179.418964 -314.226121) (xy 179.376343 -314.201514) (xy 179.338222 -314.170389) (xy 179.305587 -314.133552)
			(xy 179.279284 -314.091956) (xy 179.259993 -314.04668) (xy 179.248216 -313.998896) (xy 179.244256 -313.949842)
			(xy 177.955194 -313.949842) (xy 177.954699 -313.974449) (xy 177.946804 -314.023026) (xy 177.93122 -314.069707)
			(xy 177.908349 -314.113284) (xy 177.878784 -314.152628) (xy 177.843291 -314.18672) (xy 177.802788 -314.214676)
			(xy 177.758326 -314.235774) (xy 177.711055 -314.249466) (xy 177.6622 -314.255398) (xy 177.613025 -314.253417)
			(xy 177.564806 -314.243573) (xy 177.51879 -314.226121) (xy 177.476169 -314.201514) (xy 177.438048 -314.170389)
			(xy 177.405413 -314.133552) (xy 177.37911 -314.091956) (xy 177.359819 -314.04668) (xy 177.348042 -313.998896)
			(xy 177.344082 -313.949842) (xy 176.055274 -313.949842) (xy 176.054779 -313.974449) (xy 176.046884 -314.023026)
			(xy 176.0313 -314.069707) (xy 176.008429 -314.113284) (xy 175.978864 -314.152628) (xy 175.943371 -314.18672)
			(xy 175.902868 -314.214676) (xy 175.858406 -314.235774) (xy 175.811135 -314.249466) (xy 175.76228 -314.255398)
			(xy 175.713105 -314.253417) (xy 175.664886 -314.243573) (xy 175.61887 -314.226121) (xy 175.576249 -314.201514)
			(xy 175.538128 -314.170389) (xy 175.505493 -314.133552) (xy 175.47919 -314.091956) (xy 175.459899 -314.04668)
			(xy 175.448122 -313.998896) (xy 175.444162 -313.949842) (xy 174.155354 -313.949842) (xy 174.154859 -313.974449)
			(xy 174.146964 -314.023026) (xy 174.13138 -314.069707) (xy 174.108509 -314.113284) (xy 174.078944 -314.152628)
			(xy 174.043451 -314.18672) (xy 174.002948 -314.214676) (xy 173.958486 -314.235774) (xy 173.911215 -314.249466)
			(xy 173.86236 -314.255398) (xy 173.813185 -314.253417) (xy 173.764966 -314.243573) (xy 173.71895 -314.226121)
			(xy 173.676329 -314.201514) (xy 173.638208 -314.170389) (xy 173.605573 -314.133552) (xy 173.57927 -314.091956)
			(xy 173.559979 -314.04668) (xy 173.548202 -313.998896) (xy 173.544242 -313.949842) (xy 172.25518 -313.949842)
			(xy 172.254685 -313.974449) (xy 172.24679 -314.023026) (xy 172.231206 -314.069707) (xy 172.208335 -314.113284)
			(xy 172.17877 -314.152628) (xy 172.143277 -314.18672) (xy 172.102774 -314.214676) (xy 172.058312 -314.235774)
			(xy 172.011041 -314.249466) (xy 171.962186 -314.255398) (xy 171.913011 -314.253417) (xy 171.864792 -314.243573)
			(xy 171.818776 -314.226121) (xy 171.776155 -314.201514) (xy 171.738034 -314.170389) (xy 171.705399 -314.133552)
			(xy 171.679096 -314.091956) (xy 171.659805 -314.04668) (xy 171.648028 -313.998896) (xy 171.644068 -313.949842)
			(xy 170.35526 -313.949842) (xy 170.354765 -313.974449) (xy 170.34687 -314.023026) (xy 170.331286 -314.069707)
			(xy 170.308415 -314.113284) (xy 170.27885 -314.152628) (xy 170.243357 -314.18672) (xy 170.202854 -314.214676)
			(xy 170.158392 -314.235774) (xy 170.111121 -314.249466) (xy 170.062266 -314.255398) (xy 170.013091 -314.253417)
			(xy 169.964872 -314.243573) (xy 169.918856 -314.226121) (xy 169.876235 -314.201514) (xy 169.838114 -314.170389)
			(xy 169.805479 -314.133552) (xy 169.779176 -314.091956) (xy 169.759885 -314.04668) (xy 169.748108 -313.998896)
			(xy 169.744148 -313.949842) (xy 168.45534 -313.949842) (xy 168.454845 -313.974449) (xy 168.44695 -314.023026)
			(xy 168.431366 -314.069707) (xy 168.408495 -314.113284) (xy 168.37893 -314.152628) (xy 168.343437 -314.18672)
			(xy 168.302934 -314.214676) (xy 168.258472 -314.235774) (xy 168.211201 -314.249466) (xy 168.162346 -314.255398)
			(xy 168.113171 -314.253417) (xy 168.064952 -314.243573) (xy 168.018936 -314.226121) (xy 167.976315 -314.201514)
			(xy 167.938194 -314.170389) (xy 167.905559 -314.133552) (xy 167.879256 -314.091956) (xy 167.859965 -314.04668)
			(xy 167.848188 -313.998896) (xy 167.844228 -313.949842) (xy 166.555166 -313.949842) (xy 166.554671 -313.974449)
			(xy 166.546776 -314.023026) (xy 166.531192 -314.069707) (xy 166.508321 -314.113284) (xy 166.478756 -314.152628)
			(xy 166.443263 -314.18672) (xy 166.40276 -314.214676) (xy 166.358298 -314.235774) (xy 166.311027 -314.249466)
			(xy 166.262172 -314.255398) (xy 166.212997 -314.253417) (xy 166.164778 -314.243573) (xy 166.118762 -314.226121)
			(xy 166.076141 -314.201514) (xy 166.03802 -314.170389) (xy 166.005385 -314.133552) (xy 165.979082 -314.091956)
			(xy 165.959791 -314.04668) (xy 165.948014 -313.998896) (xy 165.944054 -313.949842) (xy 164.655246 -313.949842)
			(xy 164.654751 -313.974449) (xy 164.646856 -314.023026) (xy 164.631272 -314.069707) (xy 164.608401 -314.113284)
			(xy 164.578836 -314.152628) (xy 164.543343 -314.18672) (xy 164.50284 -314.214676) (xy 164.458378 -314.235774)
			(xy 164.411107 -314.249466) (xy 164.362252 -314.255398) (xy 164.313077 -314.253417) (xy 164.264858 -314.243573)
			(xy 164.218842 -314.226121) (xy 164.176221 -314.201514) (xy 164.1381 -314.170389) (xy 164.105465 -314.133552)
			(xy 164.079162 -314.091956) (xy 164.059871 -314.04668) (xy 164.048094 -313.998896) (xy 164.044134 -313.949842)
			(xy 162.755326 -313.949842) (xy 162.754831 -313.974449) (xy 162.746936 -314.023026) (xy 162.731352 -314.069707)
			(xy 162.708481 -314.113284) (xy 162.678916 -314.152628) (xy 162.643423 -314.18672) (xy 162.60292 -314.214676)
			(xy 162.558458 -314.235774) (xy 162.511187 -314.249466) (xy 162.462332 -314.255398) (xy 162.413157 -314.253417)
			(xy 162.364938 -314.243573) (xy 162.318922 -314.226121) (xy 162.276301 -314.201514) (xy 162.23818 -314.170389)
			(xy 162.205545 -314.133552) (xy 162.179242 -314.091956) (xy 162.159951 -314.04668) (xy 162.148174 -313.998896)
			(xy 162.144214 -313.949842) (xy 160.855152 -313.949842) (xy 160.854657 -313.974449) (xy 160.846762 -314.023026)
			(xy 160.831178 -314.069707) (xy 160.808307 -314.113284) (xy 160.778742 -314.152628) (xy 160.743249 -314.18672)
			(xy 160.702746 -314.214676) (xy 160.658284 -314.235774) (xy 160.611013 -314.249466) (xy 160.562158 -314.255398)
			(xy 160.512983 -314.253417) (xy 160.464764 -314.243573) (xy 160.418748 -314.226121) (xy 160.376127 -314.201514)
			(xy 160.338006 -314.170389) (xy 160.305371 -314.133552) (xy 160.279068 -314.091956) (xy 160.259777 -314.04668)
			(xy 160.248 -313.998896) (xy 160.24404 -313.949842) (xy 158.955232 -313.949842) (xy 158.954737 -313.974449)
			(xy 158.946842 -314.023026) (xy 158.931258 -314.069707) (xy 158.908387 -314.113284) (xy 158.878822 -314.152628)
			(xy 158.843329 -314.18672) (xy 158.802826 -314.214676) (xy 158.758364 -314.235774) (xy 158.711093 -314.249466)
			(xy 158.662238 -314.255398) (xy 158.613063 -314.253417) (xy 158.564844 -314.243573) (xy 158.518828 -314.226121)
			(xy 158.476207 -314.201514) (xy 158.438086 -314.170389) (xy 158.405451 -314.133552) (xy 158.379148 -314.091956)
			(xy 158.359857 -314.04668) (xy 158.34808 -313.998896) (xy 158.34412 -313.949842) (xy 157.055312 -313.949842)
			(xy 157.054817 -313.974449) (xy 157.046922 -314.023026) (xy 157.031338 -314.069707) (xy 157.008467 -314.113284)
			(xy 156.978902 -314.152628) (xy 156.943409 -314.18672) (xy 156.902906 -314.214676) (xy 156.858444 -314.235774)
			(xy 156.811173 -314.249466) (xy 156.762318 -314.255398) (xy 156.713143 -314.253417) (xy 156.664924 -314.243573)
			(xy 156.618908 -314.226121) (xy 156.576287 -314.201514) (xy 156.538166 -314.170389) (xy 156.505531 -314.133552)
			(xy 156.479228 -314.091956) (xy 156.459937 -314.04668) (xy 156.44816 -313.998896) (xy 156.4442 -313.949842)
			(xy 155.155392 -313.949842) (xy 155.154897 -313.974449) (xy 155.147002 -314.023026) (xy 155.131418 -314.069707)
			(xy 155.108547 -314.113284) (xy 155.078982 -314.152628) (xy 155.043489 -314.18672) (xy 155.002986 -314.214676)
			(xy 154.958524 -314.235774) (xy 154.911253 -314.249466) (xy 154.862398 -314.255398) (xy 154.813223 -314.253417)
			(xy 154.765004 -314.243573) (xy 154.718988 -314.226121) (xy 154.676367 -314.201514) (xy 154.638246 -314.170389)
			(xy 154.605611 -314.133552) (xy 154.579308 -314.091956) (xy 154.560017 -314.04668) (xy 154.54824 -313.998896)
			(xy 154.54428 -313.949842) (xy 80.855058 -313.949842) (xy 80.854563 -313.974449) (xy 80.846668 -314.023026)
			(xy 80.831084 -314.069707) (xy 80.808213 -314.113284) (xy 80.778648 -314.152628) (xy 80.743155 -314.18672)
			(xy 80.702652 -314.214676) (xy 80.65819 -314.235774) (xy 80.610919 -314.249466) (xy 80.562064 -314.255398)
			(xy 80.512889 -314.253417) (xy 80.46467 -314.243573) (xy 80.418654 -314.226121) (xy 80.376033 -314.201514)
			(xy 80.337912 -314.170389) (xy 80.305277 -314.133552) (xy 80.278974 -314.091956) (xy 80.259683 -314.04668)
			(xy 80.247906 -313.998896) (xy 80.243946 -313.949842) (xy 78.955138 -313.949842) (xy 78.954643 -313.974449)
			(xy 78.946748 -314.023026) (xy 78.931164 -314.069707) (xy 78.908293 -314.113284) (xy 78.878728 -314.152628)
			(xy 78.843235 -314.18672) (xy 78.802732 -314.214676) (xy 78.75827 -314.235774) (xy 78.710999 -314.249466)
			(xy 78.662144 -314.255398) (xy 78.612969 -314.253417) (xy 78.56475 -314.243573) (xy 78.518734 -314.226121)
			(xy 78.476113 -314.201514) (xy 78.437992 -314.170389) (xy 78.405357 -314.133552) (xy 78.379054 -314.091956)
			(xy 78.359763 -314.04668) (xy 78.347986 -313.998896) (xy 78.344026 -313.949842) (xy 77.055218 -313.949842)
			(xy 77.054723 -313.974449) (xy 77.046828 -314.023026) (xy 77.031244 -314.069707) (xy 77.008373 -314.113284)
			(xy 76.978808 -314.152628) (xy 76.943315 -314.18672) (xy 76.902812 -314.214676) (xy 76.85835 -314.235774)
			(xy 76.811079 -314.249466) (xy 76.762224 -314.255398) (xy 76.713049 -314.253417) (xy 76.66483 -314.243573)
			(xy 76.618814 -314.226121) (xy 76.576193 -314.201514) (xy 76.538072 -314.170389) (xy 76.505437 -314.133552)
			(xy 76.479134 -314.091956) (xy 76.459843 -314.04668) (xy 76.448066 -313.998896) (xy 76.444106 -313.949842)
			(xy 75.155298 -313.949842) (xy 75.154803 -313.974449) (xy 75.146908 -314.023026) (xy 75.131324 -314.069707)
			(xy 75.108453 -314.113284) (xy 75.078888 -314.152628) (xy 75.043395 -314.18672) (xy 75.002892 -314.214676)
			(xy 74.95843 -314.235774) (xy 74.911159 -314.249466) (xy 74.862304 -314.255398) (xy 74.813129 -314.253417)
			(xy 74.76491 -314.243573) (xy 74.718894 -314.226121) (xy 74.676273 -314.201514) (xy 74.638152 -314.170389)
			(xy 74.605517 -314.133552) (xy 74.579214 -314.091956) (xy 74.559923 -314.04668) (xy 74.548146 -313.998896)
			(xy 74.544186 -313.949842) (xy 73.255124 -313.949842) (xy 73.254629 -313.974449) (xy 73.246734 -314.023026)
			(xy 73.23115 -314.069707) (xy 73.208279 -314.113284) (xy 73.178714 -314.152628) (xy 73.143221 -314.18672)
			(xy 73.102718 -314.214676) (xy 73.058256 -314.235774) (xy 73.010985 -314.249466) (xy 72.96213 -314.255398)
			(xy 72.912955 -314.253417) (xy 72.864736 -314.243573) (xy 72.81872 -314.226121) (xy 72.776099 -314.201514)
			(xy 72.737978 -314.170389) (xy 72.705343 -314.133552) (xy 72.67904 -314.091956) (xy 72.659749 -314.04668)
			(xy 72.647972 -313.998896) (xy 72.644012 -313.949842) (xy 71.355204 -313.949842) (xy 71.354709 -313.974449)
			(xy 71.346814 -314.023026) (xy 71.33123 -314.069707) (xy 71.308359 -314.113284) (xy 71.278794 -314.152628)
			(xy 71.243301 -314.18672) (xy 71.202798 -314.214676) (xy 71.158336 -314.235774) (xy 71.111065 -314.249466)
			(xy 71.06221 -314.255398) (xy 71.013035 -314.253417) (xy 70.964816 -314.243573) (xy 70.9188 -314.226121)
			(xy 70.876179 -314.201514) (xy 70.838058 -314.170389) (xy 70.805423 -314.133552) (xy 70.77912 -314.091956)
			(xy 70.759829 -314.04668) (xy 70.748052 -313.998896) (xy 70.744092 -313.949842) (xy 69.455284 -313.949842)
			(xy 69.454789 -313.974449) (xy 69.446894 -314.023026) (xy 69.43131 -314.069707) (xy 69.408439 -314.113284)
			(xy 69.378874 -314.152628) (xy 69.343381 -314.18672) (xy 69.302878 -314.214676) (xy 69.258416 -314.235774)
			(xy 69.211145 -314.249466) (xy 69.16229 -314.255398) (xy 69.113115 -314.253417) (xy 69.064896 -314.243573)
			(xy 69.01888 -314.226121) (xy 68.976259 -314.201514) (xy 68.938138 -314.170389) (xy 68.905503 -314.133552)
			(xy 68.8792 -314.091956) (xy 68.859909 -314.04668) (xy 68.848132 -313.998896) (xy 68.844172 -313.949842)
			(xy 67.55511 -313.949842) (xy 67.554615 -313.974449) (xy 67.54672 -314.023026) (xy 67.531136 -314.069707)
			(xy 67.508265 -314.113284) (xy 67.4787 -314.152628) (xy 67.443207 -314.18672) (xy 67.402704 -314.214676)
			(xy 67.358242 -314.235774) (xy 67.310971 -314.249466) (xy 67.262116 -314.255398) (xy 67.212941 -314.253417)
			(xy 67.164722 -314.243573) (xy 67.118706 -314.226121) (xy 67.076085 -314.201514) (xy 67.037964 -314.170389)
			(xy 67.005329 -314.133552) (xy 66.979026 -314.091956) (xy 66.959735 -314.04668) (xy 66.947958 -313.998896)
			(xy 66.943998 -313.949842) (xy 65.65519 -313.949842) (xy 65.654695 -313.974449) (xy 65.6468 -314.023026)
			(xy 65.631216 -314.069707) (xy 65.608345 -314.113284) (xy 65.57878 -314.152628) (xy 65.543287 -314.18672)
			(xy 65.502784 -314.214676) (xy 65.458322 -314.235774) (xy 65.411051 -314.249466) (xy 65.362196 -314.255398)
			(xy 65.313021 -314.253417) (xy 65.264802 -314.243573) (xy 65.218786 -314.226121) (xy 65.176165 -314.201514)
			(xy 65.138044 -314.170389) (xy 65.105409 -314.133552) (xy 65.079106 -314.091956) (xy 65.059815 -314.04668)
			(xy 65.048038 -313.998896) (xy 65.044078 -313.949842) (xy 63.75527 -313.949842) (xy 63.754775 -313.974449)
			(xy 63.74688 -314.023026) (xy 63.731296 -314.069707) (xy 63.708425 -314.113284) (xy 63.67886 -314.152628)
			(xy 63.643367 -314.18672) (xy 63.602864 -314.214676) (xy 63.558402 -314.235774) (xy 63.511131 -314.249466)
			(xy 63.462276 -314.255398) (xy 63.413101 -314.253417) (xy 63.364882 -314.243573) (xy 63.318866 -314.226121)
			(xy 63.276245 -314.201514) (xy 63.238124 -314.170389) (xy 63.205489 -314.133552) (xy 63.179186 -314.091956)
			(xy 63.159895 -314.04668) (xy 63.148118 -313.998896) (xy 63.144158 -313.949842) (xy 61.855096 -313.949842)
			(xy 61.854601 -313.974449) (xy 61.846706 -314.023026) (xy 61.831122 -314.069707) (xy 61.808251 -314.113284)
			(xy 61.778686 -314.152628) (xy 61.743193 -314.18672) (xy 61.70269 -314.214676) (xy 61.658228 -314.235774)
			(xy 61.610957 -314.249466) (xy 61.562102 -314.255398) (xy 61.512927 -314.253417) (xy 61.464708 -314.243573)
			(xy 61.418692 -314.226121) (xy 61.376071 -314.201514) (xy 61.33795 -314.170389) (xy 61.305315 -314.133552)
			(xy 61.279012 -314.091956) (xy 61.259721 -314.04668) (xy 61.247944 -313.998896) (xy 61.243984 -313.949842)
			(xy 59.955176 -313.949842) (xy 59.954681 -313.974449) (xy 59.946786 -314.023026) (xy 59.931202 -314.069707)
			(xy 59.908331 -314.113284) (xy 59.878766 -314.152628) (xy 59.843273 -314.18672) (xy 59.80277 -314.214676)
			(xy 59.758308 -314.235774) (xy 59.711037 -314.249466) (xy 59.662182 -314.255398) (xy 59.613007 -314.253417)
			(xy 59.564788 -314.243573) (xy 59.518772 -314.226121) (xy 59.476151 -314.201514) (xy 59.43803 -314.170389)
			(xy 59.405395 -314.133552) (xy 59.379092 -314.091956) (xy 59.359801 -314.04668) (xy 59.348024 -313.998896)
			(xy 59.344064 -313.949842) (xy 58.055256 -313.949842) (xy 58.054761 -313.974449) (xy 58.046866 -314.023026)
			(xy 58.031282 -314.069707) (xy 58.008411 -314.113284) (xy 57.978846 -314.152628) (xy 57.943353 -314.18672)
			(xy 57.90285 -314.214676) (xy 57.858388 -314.235774) (xy 57.811117 -314.249466) (xy 57.762262 -314.255398)
			(xy 57.713087 -314.253417) (xy 57.664868 -314.243573) (xy 57.618852 -314.226121) (xy 57.576231 -314.201514)
			(xy 57.53811 -314.170389) (xy 57.505475 -314.133552) (xy 57.479172 -314.091956) (xy 57.459881 -314.04668)
			(xy 57.448104 -313.998896) (xy 57.444144 -313.949842) (xy 56.155082 -313.949842) (xy 56.154587 -313.974449)
			(xy 56.146692 -314.023026) (xy 56.131108 -314.069707) (xy 56.108237 -314.113284) (xy 56.078672 -314.152628)
			(xy 56.043179 -314.18672) (xy 56.002676 -314.214676) (xy 55.958214 -314.235774) (xy 55.910943 -314.249466)
			(xy 55.862088 -314.255398) (xy 55.812913 -314.253417) (xy 55.764694 -314.243573) (xy 55.718678 -314.226121)
			(xy 55.676057 -314.201514) (xy 55.637936 -314.170389) (xy 55.605301 -314.133552) (xy 55.578998 -314.091956)
			(xy 55.559707 -314.04668) (xy 55.54793 -313.998896) (xy 55.54397 -313.949842) (xy 54.255162 -313.949842)
			(xy 54.254667 -313.974449) (xy 54.246772 -314.023026) (xy 54.231188 -314.069707) (xy 54.208317 -314.113284)
			(xy 54.178752 -314.152628) (xy 54.143259 -314.18672) (xy 54.102756 -314.214676) (xy 54.058294 -314.235774)
			(xy 54.011023 -314.249466) (xy 53.962168 -314.255398) (xy 53.912993 -314.253417) (xy 53.864774 -314.243573)
			(xy 53.818758 -314.226121) (xy 53.776137 -314.201514) (xy 53.738016 -314.170389) (xy 53.705381 -314.133552)
			(xy 53.679078 -314.091956) (xy 53.659787 -314.04668) (xy 53.64801 -313.998896) (xy 53.64405 -313.949842)
			(xy 52.355242 -313.949842) (xy 52.354747 -313.974449) (xy 52.346852 -314.023026) (xy 52.331268 -314.069707)
			(xy 52.308397 -314.113284) (xy 52.278832 -314.152628) (xy 52.243339 -314.18672) (xy 52.202836 -314.214676)
			(xy 52.158374 -314.235774) (xy 52.111103 -314.249466) (xy 52.062248 -314.255398) (xy 52.013073 -314.253417)
			(xy 51.964854 -314.243573) (xy 51.918838 -314.226121) (xy 51.876217 -314.201514) (xy 51.838096 -314.170389)
			(xy 51.805461 -314.133552) (xy 51.779158 -314.091956) (xy 51.759867 -314.04668) (xy 51.74809 -313.998896)
			(xy 51.74413 -313.949842) (xy 50.455068 -313.949842) (xy 50.454573 -313.974449) (xy 50.446678 -314.023026)
			(xy 50.431094 -314.069707) (xy 50.408223 -314.113284) (xy 50.378658 -314.152628) (xy 50.343165 -314.18672)
			(xy 50.302662 -314.214676) (xy 50.2582 -314.235774) (xy 50.210929 -314.249466) (xy 50.162074 -314.255398)
			(xy 50.112899 -314.253417) (xy 50.06468 -314.243573) (xy 50.018664 -314.226121) (xy 49.976043 -314.201514)
			(xy 49.937922 -314.170389) (xy 49.905287 -314.133552) (xy 49.878984 -314.091956) (xy 49.859693 -314.04668)
			(xy 49.847916 -313.998896) (xy 49.843956 -313.949842) (xy 48.555148 -313.949842) (xy 48.554653 -313.974449)
			(xy 48.546758 -314.023026) (xy 48.531174 -314.069707) (xy 48.508303 -314.113284) (xy 48.478738 -314.152628)
			(xy 48.443245 -314.18672) (xy 48.402742 -314.214676) (xy 48.35828 -314.235774) (xy 48.311009 -314.249466)
			(xy 48.262154 -314.255398) (xy 48.212979 -314.253417) (xy 48.16476 -314.243573) (xy 48.118744 -314.226121)
			(xy 48.076123 -314.201514) (xy 48.038002 -314.170389) (xy 48.005367 -314.133552) (xy 47.979064 -314.091956)
			(xy 47.959773 -314.04668) (xy 47.947996 -313.998896) (xy 47.944036 -313.949842) (xy 46.655228 -313.949842)
			(xy 46.654733 -313.974449) (xy 46.646838 -314.023026) (xy 46.631254 -314.069707) (xy 46.608383 -314.113284)
			(xy 46.578818 -314.152628) (xy 46.543325 -314.18672) (xy 46.502822 -314.214676) (xy 46.45836 -314.235774)
			(xy 46.411089 -314.249466) (xy 46.362234 -314.255398) (xy 46.313059 -314.253417) (xy 46.26484 -314.243573)
			(xy 46.218824 -314.226121) (xy 46.176203 -314.201514) (xy 46.138082 -314.170389) (xy 46.105447 -314.133552)
			(xy 46.079144 -314.091956) (xy 46.059853 -314.04668) (xy 46.048076 -313.998896) (xy 46.044116 -313.949842)
			(xy 44.755054 -313.949842) (xy 44.754559 -313.974449) (xy 44.746664 -314.023026) (xy 44.73108 -314.069707)
			(xy 44.708209 -314.113284) (xy 44.678644 -314.152628) (xy 44.643151 -314.18672) (xy 44.602648 -314.214676)
			(xy 44.558186 -314.235774) (xy 44.510915 -314.249466) (xy 44.46206 -314.255398) (xy 44.412885 -314.253417)
			(xy 44.364666 -314.243573) (xy 44.31865 -314.226121) (xy 44.276029 -314.201514) (xy 44.237908 -314.170389)
			(xy 44.205273 -314.133552) (xy 44.17897 -314.091956) (xy 44.159679 -314.04668) (xy 44.147902 -313.998896)
			(xy 44.143942 -313.949842) (xy 42.855134 -313.949842) (xy 42.854639 -313.974449) (xy 42.846744 -314.023026)
			(xy 42.83116 -314.069707) (xy 42.808289 -314.113284) (xy 42.778724 -314.152628) (xy 42.743231 -314.18672)
			(xy 42.702728 -314.214676) (xy 42.658266 -314.235774) (xy 42.610995 -314.249466) (xy 42.56214 -314.255398)
			(xy 42.512965 -314.253417) (xy 42.464746 -314.243573) (xy 42.41873 -314.226121) (xy 42.376109 -314.201514)
			(xy 42.337988 -314.170389) (xy 42.305353 -314.133552) (xy 42.27905 -314.091956) (xy 42.259759 -314.04668)
			(xy 42.247982 -313.998896) (xy 42.244022 -313.949842) (xy 40.955214 -313.949842) (xy 40.954719 -313.974449)
			(xy 40.946824 -314.023026) (xy 40.93124 -314.069707) (xy 40.908369 -314.113284) (xy 40.878804 -314.152628)
			(xy 40.843311 -314.18672) (xy 40.802808 -314.214676) (xy 40.758346 -314.235774) (xy 40.711075 -314.249466)
			(xy 40.66222 -314.255398) (xy 40.613045 -314.253417) (xy 40.564826 -314.243573) (xy 40.51881 -314.226121)
			(xy 40.476189 -314.201514) (xy 40.438068 -314.170389) (xy 40.405433 -314.133552) (xy 40.37913 -314.091956)
			(xy 40.359839 -314.04668) (xy 40.348062 -313.998896) (xy 40.344102 -313.949842) (xy 39.055294 -313.949842)
			(xy 39.054799 -313.974449) (xy 39.046904 -314.023026) (xy 39.03132 -314.069707) (xy 39.008449 -314.113284)
			(xy 38.978884 -314.152628) (xy 38.943391 -314.18672) (xy 38.902888 -314.214676) (xy 38.858426 -314.235774)
			(xy 38.811155 -314.249466) (xy 38.7623 -314.255398) (xy 38.713125 -314.253417) (xy 38.664906 -314.243573)
			(xy 38.61889 -314.226121) (xy 38.576269 -314.201514) (xy 38.538148 -314.170389) (xy 38.505513 -314.133552)
			(xy 38.47921 -314.091956) (xy 38.459919 -314.04668) (xy 38.448142 -313.998896) (xy 38.444182 -313.949842)
			(xy 0.509016 -313.949842) (xy 0.509016 -314.899802) (xy 36.544008 -314.899802) (xy 36.547968 -314.850748)
			(xy 36.559745 -314.802964) (xy 36.579036 -314.757688) (xy 36.605339 -314.716092) (xy 36.637974 -314.679255)
			(xy 36.676095 -314.64813) (xy 36.718716 -314.623523) (xy 36.764732 -314.606071) (xy 36.812951 -314.596227)
			(xy 36.862126 -314.594246) (xy 36.910981 -314.600178) (xy 36.958252 -314.61387) (xy 37.002714 -314.634968)
			(xy 37.043217 -314.662924) (xy 37.07871 -314.697016) (xy 37.108275 -314.73636) (xy 37.131146 -314.779937)
			(xy 37.14673 -314.826618) (xy 37.154625 -314.875195) (xy 37.15512 -314.899802) (xy 37.493968 -314.899802)
			(xy 37.497928 -314.850748) (xy 37.509705 -314.802964) (xy 37.528996 -314.757688) (xy 37.555299 -314.716092)
			(xy 37.587934 -314.679255) (xy 37.626055 -314.64813) (xy 37.668676 -314.623523) (xy 37.714692 -314.606071)
			(xy 37.762911 -314.596227) (xy 37.812086 -314.594246) (xy 37.860941 -314.600178) (xy 37.908212 -314.61387)
			(xy 37.952674 -314.634968) (xy 37.993177 -314.662924) (xy 38.02867 -314.697016) (xy 38.058235 -314.73636)
			(xy 38.081106 -314.779937) (xy 38.09669 -314.826618) (xy 38.104585 -314.875195) (xy 38.10508 -314.899802)
			(xy 81.19416 -314.899802) (xy 81.19812 -314.850748) (xy 81.209897 -314.802964) (xy 81.229188 -314.757688)
			(xy 81.255491 -314.716092) (xy 81.288126 -314.679255) (xy 81.326247 -314.64813) (xy 81.368868 -314.623523)
			(xy 81.414884 -314.606071) (xy 81.463103 -314.596227) (xy 81.512278 -314.594246) (xy 81.561133 -314.600178)
			(xy 81.608404 -314.61387) (xy 81.652866 -314.634968) (xy 81.693369 -314.662924) (xy 81.728862 -314.697016)
			(xy 81.758427 -314.73636) (xy 81.781298 -314.779937) (xy 81.796882 -314.826618) (xy 81.804777 -314.875195)
			(xy 81.805272 -314.899802) (xy 82.14412 -314.899802) (xy 82.14808 -314.850748) (xy 82.159857 -314.802964)
			(xy 82.179148 -314.757688) (xy 82.205451 -314.716092) (xy 82.238086 -314.679255) (xy 82.276207 -314.64813)
			(xy 82.318828 -314.623523) (xy 82.364844 -314.606071) (xy 82.413063 -314.596227) (xy 82.462238 -314.594246)
			(xy 82.511093 -314.600178) (xy 82.558364 -314.61387) (xy 82.602826 -314.634968) (xy 82.643329 -314.662924)
			(xy 82.678822 -314.697016) (xy 82.708387 -314.73636) (xy 82.731258 -314.779937) (xy 82.746842 -314.826618)
			(xy 82.754737 -314.875195) (xy 82.755232 -314.899802) (xy 152.644106 -314.899802) (xy 152.648066 -314.850748)
			(xy 152.659843 -314.802964) (xy 152.679134 -314.757688) (xy 152.705437 -314.716092) (xy 152.738072 -314.679255)
			(xy 152.776193 -314.64813) (xy 152.818814 -314.623523) (xy 152.86483 -314.606071) (xy 152.913049 -314.596227)
			(xy 152.962224 -314.594246) (xy 153.011079 -314.600178) (xy 153.05835 -314.61387) (xy 153.102812 -314.634968)
			(xy 153.143315 -314.662924) (xy 153.178808 -314.697016) (xy 153.208373 -314.73636) (xy 153.231244 -314.779937)
			(xy 153.246828 -314.826618) (xy 153.254723 -314.875195) (xy 153.255218 -314.899802) (xy 153.594066 -314.899802)
			(xy 153.598026 -314.850748) (xy 153.609803 -314.802964) (xy 153.629094 -314.757688) (xy 153.655397 -314.716092)
			(xy 153.688032 -314.679255) (xy 153.726153 -314.64813) (xy 153.768774 -314.623523) (xy 153.81479 -314.606071)
			(xy 153.863009 -314.596227) (xy 153.912184 -314.594246) (xy 153.961039 -314.600178) (xy 154.00831 -314.61387)
			(xy 154.052772 -314.634968) (xy 154.093275 -314.662924) (xy 154.128768 -314.697016) (xy 154.158333 -314.73636)
			(xy 154.181204 -314.779937) (xy 154.196788 -314.826618) (xy 154.204683 -314.875195) (xy 154.205178 -314.899802)
			(xy 197.294258 -314.899802) (xy 197.298218 -314.850748) (xy 197.309995 -314.802964) (xy 197.329286 -314.757688)
			(xy 197.355589 -314.716092) (xy 197.388224 -314.679255) (xy 197.426345 -314.64813) (xy 197.468966 -314.623523)
			(xy 197.514982 -314.606071) (xy 197.563201 -314.596227) (xy 197.612376 -314.594246) (xy 197.661231 -314.600178)
			(xy 197.708502 -314.61387) (xy 197.752964 -314.634968) (xy 197.793467 -314.662924) (xy 197.82896 -314.697016)
			(xy 197.858525 -314.73636) (xy 197.881396 -314.779937) (xy 197.89698 -314.826618) (xy 197.904875 -314.875195)
			(xy 197.90537 -314.899802) (xy 198.244218 -314.899802) (xy 198.248178 -314.850748) (xy 198.259955 -314.802964)
			(xy 198.279246 -314.757688) (xy 198.305549 -314.716092) (xy 198.338184 -314.679255) (xy 198.376305 -314.64813)
			(xy 198.418926 -314.623523) (xy 198.464942 -314.606071) (xy 198.513161 -314.596227) (xy 198.562336 -314.594246)
			(xy 198.611191 -314.600178) (xy 198.658462 -314.61387) (xy 198.702924 -314.634968) (xy 198.743427 -314.662924)
			(xy 198.77892 -314.697016) (xy 198.808485 -314.73636) (xy 198.831356 -314.779937) (xy 198.84694 -314.826618)
			(xy 198.854835 -314.875195) (xy 198.85533 -314.899802) (xy 268.74395 -314.899802) (xy 268.74791 -314.850748)
			(xy 268.759687 -314.802964) (xy 268.778978 -314.757688) (xy 268.805281 -314.716092) (xy 268.837916 -314.679255)
			(xy 268.876037 -314.64813) (xy 268.918658 -314.623523) (xy 268.964674 -314.606071) (xy 269.012893 -314.596227)
			(xy 269.062068 -314.594246) (xy 269.110923 -314.600178) (xy 269.158194 -314.61387) (xy 269.202656 -314.634968)
			(xy 269.243159 -314.662924) (xy 269.278652 -314.697016) (xy 269.308217 -314.73636) (xy 269.331088 -314.779937)
			(xy 269.346672 -314.826618) (xy 269.354567 -314.875195) (xy 269.355062 -314.899802) (xy 269.69391 -314.899802)
			(xy 269.69787 -314.850748) (xy 269.709647 -314.802964) (xy 269.728938 -314.757688) (xy 269.755241 -314.716092)
			(xy 269.787876 -314.679255) (xy 269.825997 -314.64813) (xy 269.868618 -314.623523) (xy 269.914634 -314.606071)
			(xy 269.962853 -314.596227) (xy 270.012028 -314.594246) (xy 270.060883 -314.600178) (xy 270.108154 -314.61387)
			(xy 270.152616 -314.634968) (xy 270.193119 -314.662924) (xy 270.228612 -314.697016) (xy 270.258177 -314.73636)
			(xy 270.281048 -314.779937) (xy 270.296632 -314.826618) (xy 270.304527 -314.875195) (xy 270.305022 -314.899802)
			(xy 313.394102 -314.899802) (xy 313.398062 -314.850748) (xy 313.409839 -314.802964) (xy 313.42913 -314.757688)
			(xy 313.455433 -314.716092) (xy 313.488068 -314.679255) (xy 313.526189 -314.64813) (xy 313.56881 -314.623523)
			(xy 313.614826 -314.606071) (xy 313.663045 -314.596227) (xy 313.71222 -314.594246) (xy 313.761075 -314.600178)
			(xy 313.808346 -314.61387) (xy 313.852808 -314.634968) (xy 313.893311 -314.662924) (xy 313.928804 -314.697016)
			(xy 313.958369 -314.73636) (xy 313.98124 -314.779937) (xy 313.996824 -314.826618) (xy 314.004719 -314.875195)
			(xy 314.005214 -314.899802) (xy 314.344062 -314.899802) (xy 314.348022 -314.850748) (xy 314.359799 -314.802964)
			(xy 314.37909 -314.757688) (xy 314.405393 -314.716092) (xy 314.438028 -314.679255) (xy 314.476149 -314.64813)
			(xy 314.51877 -314.623523) (xy 314.564786 -314.606071) (xy 314.613005 -314.596227) (xy 314.66218 -314.594246)
			(xy 314.711035 -314.600178) (xy 314.758306 -314.61387) (xy 314.802768 -314.634968) (xy 314.843271 -314.662924)
			(xy 314.878764 -314.697016) (xy 314.908329 -314.73636) (xy 314.9312 -314.779937) (xy 314.946784 -314.826618)
			(xy 314.954679 -314.875195) (xy 314.955174 -314.899802) (xy 384.844048 -314.899802) (xy 384.848008 -314.850748)
			(xy 384.859785 -314.802964) (xy 384.879076 -314.757688) (xy 384.905379 -314.716092) (xy 384.938014 -314.679255)
			(xy 384.976135 -314.64813) (xy 385.018756 -314.623523) (xy 385.064772 -314.606071) (xy 385.112991 -314.596227)
			(xy 385.162166 -314.594246) (xy 385.211021 -314.600178) (xy 385.258292 -314.61387) (xy 385.302754 -314.634968)
			(xy 385.343257 -314.662924) (xy 385.37875 -314.697016) (xy 385.408315 -314.73636) (xy 385.431186 -314.779937)
			(xy 385.44677 -314.826618) (xy 385.454665 -314.875195) (xy 385.45516 -314.899802) (xy 385.794008 -314.899802)
			(xy 385.797968 -314.850748) (xy 385.809745 -314.802964) (xy 385.829036 -314.757688) (xy 385.855339 -314.716092)
			(xy 385.887974 -314.679255) (xy 385.926095 -314.64813) (xy 385.968716 -314.623523) (xy 386.014732 -314.606071)
			(xy 386.062951 -314.596227) (xy 386.112126 -314.594246) (xy 386.160981 -314.600178) (xy 386.208252 -314.61387)
			(xy 386.252714 -314.634968) (xy 386.293217 -314.662924) (xy 386.32871 -314.697016) (xy 386.358275 -314.73636)
			(xy 386.381146 -314.779937) (xy 386.39673 -314.826618) (xy 386.404625 -314.875195) (xy 386.40512 -314.899802)
			(xy 429.4942 -314.899802) (xy 429.49816 -314.850748) (xy 429.509937 -314.802964) (xy 429.529228 -314.757688)
			(xy 429.555531 -314.716092) (xy 429.588166 -314.679255) (xy 429.626287 -314.64813) (xy 429.668908 -314.623523)
			(xy 429.714924 -314.606071) (xy 429.763143 -314.596227) (xy 429.812318 -314.594246) (xy 429.861173 -314.600178)
			(xy 429.908444 -314.61387) (xy 429.952906 -314.634968) (xy 429.993409 -314.662924) (xy 430.028902 -314.697016)
			(xy 430.058467 -314.73636) (xy 430.081338 -314.779937) (xy 430.096922 -314.826618) (xy 430.104817 -314.875195)
			(xy 430.105312 -314.899802) (xy 430.44416 -314.899802) (xy 430.44812 -314.850748) (xy 430.459897 -314.802964)
			(xy 430.479188 -314.757688) (xy 430.505491 -314.716092) (xy 430.538126 -314.679255) (xy 430.576247 -314.64813)
			(xy 430.618868 -314.623523) (xy 430.664884 -314.606071) (xy 430.713103 -314.596227) (xy 430.762278 -314.594246)
			(xy 430.811133 -314.600178) (xy 430.858404 -314.61387) (xy 430.902866 -314.634968) (xy 430.943369 -314.662924)
			(xy 430.978862 -314.697016) (xy 431.008427 -314.73636) (xy 431.031298 -314.779937) (xy 431.046882 -314.826618)
			(xy 431.054777 -314.875195) (xy 431.055272 -314.899802) (xy 431.054777 -314.924409) (xy 431.046882 -314.972986)
			(xy 431.031298 -315.019667) (xy 431.008427 -315.063244) (xy 430.978862 -315.102588) (xy 430.943369 -315.13668)
			(xy 430.902866 -315.164636) (xy 430.858404 -315.185734) (xy 430.811133 -315.199426) (xy 430.762278 -315.205358)
			(xy 430.713103 -315.203377) (xy 430.664884 -315.193533) (xy 430.618868 -315.176081) (xy 430.576247 -315.151474)
			(xy 430.538126 -315.120349) (xy 430.505491 -315.083512) (xy 430.479188 -315.041916) (xy 430.459897 -314.99664)
			(xy 430.44812 -314.948856) (xy 430.44416 -314.899802) (xy 430.105312 -314.899802) (xy 430.104817 -314.924409)
			(xy 430.096922 -314.972986) (xy 430.081338 -315.019667) (xy 430.058467 -315.063244) (xy 430.028902 -315.102588)
			(xy 429.993409 -315.13668) (xy 429.952906 -315.164636) (xy 429.908444 -315.185734) (xy 429.861173 -315.199426)
			(xy 429.812318 -315.205358) (xy 429.763143 -315.203377) (xy 429.714924 -315.193533) (xy 429.668908 -315.176081)
			(xy 429.626287 -315.151474) (xy 429.588166 -315.120349) (xy 429.555531 -315.083512) (xy 429.529228 -315.041916)
			(xy 429.509937 -314.99664) (xy 429.49816 -314.948856) (xy 429.4942 -314.899802) (xy 386.40512 -314.899802)
			(xy 386.404625 -314.924409) (xy 386.39673 -314.972986) (xy 386.381146 -315.019667) (xy 386.358275 -315.063244)
			(xy 386.32871 -315.102588) (xy 386.293217 -315.13668) (xy 386.252714 -315.164636) (xy 386.208252 -315.185734)
			(xy 386.160981 -315.199426) (xy 386.112126 -315.205358) (xy 386.062951 -315.203377) (xy 386.014732 -315.193533)
			(xy 385.968716 -315.176081) (xy 385.926095 -315.151474) (xy 385.887974 -315.120349) (xy 385.855339 -315.083512)
			(xy 385.829036 -315.041916) (xy 385.809745 -314.99664) (xy 385.797968 -314.948856) (xy 385.794008 -314.899802)
			(xy 385.45516 -314.899802) (xy 385.454665 -314.924409) (xy 385.44677 -314.972986) (xy 385.431186 -315.019667)
			(xy 385.408315 -315.063244) (xy 385.37875 -315.102588) (xy 385.343257 -315.13668) (xy 385.302754 -315.164636)
			(xy 385.258292 -315.185734) (xy 385.211021 -315.199426) (xy 385.162166 -315.205358) (xy 385.112991 -315.203377)
			(xy 385.064772 -315.193533) (xy 385.018756 -315.176081) (xy 384.976135 -315.151474) (xy 384.938014 -315.120349)
			(xy 384.905379 -315.083512) (xy 384.879076 -315.041916) (xy 384.859785 -314.99664) (xy 384.848008 -314.948856)
			(xy 384.844048 -314.899802) (xy 314.955174 -314.899802) (xy 314.954679 -314.924409) (xy 314.946784 -314.972986)
			(xy 314.9312 -315.019667) (xy 314.908329 -315.063244) (xy 314.878764 -315.102588) (xy 314.843271 -315.13668)
			(xy 314.802768 -315.164636) (xy 314.758306 -315.185734) (xy 314.711035 -315.199426) (xy 314.66218 -315.205358)
			(xy 314.613005 -315.203377) (xy 314.564786 -315.193533) (xy 314.51877 -315.176081) (xy 314.476149 -315.151474)
			(xy 314.438028 -315.120349) (xy 314.405393 -315.083512) (xy 314.37909 -315.041916) (xy 314.359799 -314.99664)
			(xy 314.348022 -314.948856) (xy 314.344062 -314.899802) (xy 314.005214 -314.899802) (xy 314.004719 -314.924409)
			(xy 313.996824 -314.972986) (xy 313.98124 -315.019667) (xy 313.958369 -315.063244) (xy 313.928804 -315.102588)
			(xy 313.893311 -315.13668) (xy 313.852808 -315.164636) (xy 313.808346 -315.185734) (xy 313.761075 -315.199426)
			(xy 313.71222 -315.205358) (xy 313.663045 -315.203377) (xy 313.614826 -315.193533) (xy 313.56881 -315.176081)
			(xy 313.526189 -315.151474) (xy 313.488068 -315.120349) (xy 313.455433 -315.083512) (xy 313.42913 -315.041916)
			(xy 313.409839 -314.99664) (xy 313.398062 -314.948856) (xy 313.394102 -314.899802) (xy 270.305022 -314.899802)
			(xy 270.304527 -314.924409) (xy 270.296632 -314.972986) (xy 270.281048 -315.019667) (xy 270.258177 -315.063244)
			(xy 270.228612 -315.102588) (xy 270.193119 -315.13668) (xy 270.152616 -315.164636) (xy 270.108154 -315.185734)
			(xy 270.060883 -315.199426) (xy 270.012028 -315.205358) (xy 269.962853 -315.203377) (xy 269.914634 -315.193533)
			(xy 269.868618 -315.176081) (xy 269.825997 -315.151474) (xy 269.787876 -315.120349) (xy 269.755241 -315.083512)
			(xy 269.728938 -315.041916) (xy 269.709647 -314.99664) (xy 269.69787 -314.948856) (xy 269.69391 -314.899802)
			(xy 269.355062 -314.899802) (xy 269.354567 -314.924409) (xy 269.346672 -314.972986) (xy 269.331088 -315.019667)
			(xy 269.308217 -315.063244) (xy 269.278652 -315.102588) (xy 269.243159 -315.13668) (xy 269.202656 -315.164636)
			(xy 269.158194 -315.185734) (xy 269.110923 -315.199426) (xy 269.062068 -315.205358) (xy 269.012893 -315.203377)
			(xy 268.964674 -315.193533) (xy 268.918658 -315.176081) (xy 268.876037 -315.151474) (xy 268.837916 -315.120349)
			(xy 268.805281 -315.083512) (xy 268.778978 -315.041916) (xy 268.759687 -314.99664) (xy 268.74791 -314.948856)
			(xy 268.74395 -314.899802) (xy 198.85533 -314.899802) (xy 198.854835 -314.924409) (xy 198.84694 -314.972986)
			(xy 198.831356 -315.019667) (xy 198.808485 -315.063244) (xy 198.77892 -315.102588) (xy 198.743427 -315.13668)
			(xy 198.702924 -315.164636) (xy 198.658462 -315.185734) (xy 198.611191 -315.199426) (xy 198.562336 -315.205358)
			(xy 198.513161 -315.203377) (xy 198.464942 -315.193533) (xy 198.418926 -315.176081) (xy 198.376305 -315.151474)
			(xy 198.338184 -315.120349) (xy 198.305549 -315.083512) (xy 198.279246 -315.041916) (xy 198.259955 -314.99664)
			(xy 198.248178 -314.948856) (xy 198.244218 -314.899802) (xy 197.90537 -314.899802) (xy 197.904875 -314.924409)
			(xy 197.89698 -314.972986) (xy 197.881396 -315.019667) (xy 197.858525 -315.063244) (xy 197.82896 -315.102588)
			(xy 197.793467 -315.13668) (xy 197.752964 -315.164636) (xy 197.708502 -315.185734) (xy 197.661231 -315.199426)
			(xy 197.612376 -315.205358) (xy 197.563201 -315.203377) (xy 197.514982 -315.193533) (xy 197.468966 -315.176081)
			(xy 197.426345 -315.151474) (xy 197.388224 -315.120349) (xy 197.355589 -315.083512) (xy 197.329286 -315.041916)
			(xy 197.309995 -314.99664) (xy 197.298218 -314.948856) (xy 197.294258 -314.899802) (xy 154.205178 -314.899802)
			(xy 154.204683 -314.924409) (xy 154.196788 -314.972986) (xy 154.181204 -315.019667) (xy 154.158333 -315.063244)
			(xy 154.128768 -315.102588) (xy 154.093275 -315.13668) (xy 154.052772 -315.164636) (xy 154.00831 -315.185734)
			(xy 153.961039 -315.199426) (xy 153.912184 -315.205358) (xy 153.863009 -315.203377) (xy 153.81479 -315.193533)
			(xy 153.768774 -315.176081) (xy 153.726153 -315.151474) (xy 153.688032 -315.120349) (xy 153.655397 -315.083512)
			(xy 153.629094 -315.041916) (xy 153.609803 -314.99664) (xy 153.598026 -314.948856) (xy 153.594066 -314.899802)
			(xy 153.255218 -314.899802) (xy 153.254723 -314.924409) (xy 153.246828 -314.972986) (xy 153.231244 -315.019667)
			(xy 153.208373 -315.063244) (xy 153.178808 -315.102588) (xy 153.143315 -315.13668) (xy 153.102812 -315.164636)
			(xy 153.05835 -315.185734) (xy 153.011079 -315.199426) (xy 152.962224 -315.205358) (xy 152.913049 -315.203377)
			(xy 152.86483 -315.193533) (xy 152.818814 -315.176081) (xy 152.776193 -315.151474) (xy 152.738072 -315.120349)
			(xy 152.705437 -315.083512) (xy 152.679134 -315.041916) (xy 152.659843 -314.99664) (xy 152.648066 -314.948856)
			(xy 152.644106 -314.899802) (xy 82.755232 -314.899802) (xy 82.754737 -314.924409) (xy 82.746842 -314.972986)
			(xy 82.731258 -315.019667) (xy 82.708387 -315.063244) (xy 82.678822 -315.102588) (xy 82.643329 -315.13668)
			(xy 82.602826 -315.164636) (xy 82.558364 -315.185734) (xy 82.511093 -315.199426) (xy 82.462238 -315.205358)
			(xy 82.413063 -315.203377) (xy 82.364844 -315.193533) (xy 82.318828 -315.176081) (xy 82.276207 -315.151474)
			(xy 82.238086 -315.120349) (xy 82.205451 -315.083512) (xy 82.179148 -315.041916) (xy 82.159857 -314.99664)
			(xy 82.14808 -314.948856) (xy 82.14412 -314.899802) (xy 81.805272 -314.899802) (xy 81.804777 -314.924409)
			(xy 81.796882 -314.972986) (xy 81.781298 -315.019667) (xy 81.758427 -315.063244) (xy 81.728862 -315.102588)
			(xy 81.693369 -315.13668) (xy 81.652866 -315.164636) (xy 81.608404 -315.185734) (xy 81.561133 -315.199426)
			(xy 81.512278 -315.205358) (xy 81.463103 -315.203377) (xy 81.414884 -315.193533) (xy 81.368868 -315.176081)
			(xy 81.326247 -315.151474) (xy 81.288126 -315.120349) (xy 81.255491 -315.083512) (xy 81.229188 -315.041916)
			(xy 81.209897 -314.99664) (xy 81.19812 -314.948856) (xy 81.19416 -314.899802) (xy 38.10508 -314.899802)
			(xy 38.104585 -314.924409) (xy 38.09669 -314.972986) (xy 38.081106 -315.019667) (xy 38.058235 -315.063244)
			(xy 38.02867 -315.102588) (xy 37.993177 -315.13668) (xy 37.952674 -315.164636) (xy 37.908212 -315.185734)
			(xy 37.860941 -315.199426) (xy 37.812086 -315.205358) (xy 37.762911 -315.203377) (xy 37.714692 -315.193533)
			(xy 37.668676 -315.176081) (xy 37.626055 -315.151474) (xy 37.587934 -315.120349) (xy 37.555299 -315.083512)
			(xy 37.528996 -315.041916) (xy 37.509705 -314.99664) (xy 37.497928 -314.948856) (xy 37.493968 -314.899802)
			(xy 37.15512 -314.899802) (xy 37.154625 -314.924409) (xy 37.14673 -314.972986) (xy 37.131146 -315.019667)
			(xy 37.108275 -315.063244) (xy 37.07871 -315.102588) (xy 37.043217 -315.13668) (xy 37.002714 -315.164636)
			(xy 36.958252 -315.185734) (xy 36.910981 -315.199426) (xy 36.862126 -315.205358) (xy 36.812951 -315.203377)
			(xy 36.764732 -315.193533) (xy 36.718716 -315.176081) (xy 36.676095 -315.151474) (xy 36.637974 -315.120349)
			(xy 36.605339 -315.083512) (xy 36.579036 -315.041916) (xy 36.559745 -314.99664) (xy 36.547968 -314.948856)
			(xy 36.544008 -314.899802) (xy 0.509016 -314.899802) (xy 0.509016 -315.849762) (xy 39.394142 -315.849762)
			(xy 39.398102 -315.800708) (xy 39.409879 -315.752924) (xy 39.42917 -315.707648) (xy 39.455473 -315.666052)
			(xy 39.488108 -315.629215) (xy 39.526229 -315.59809) (xy 39.56885 -315.573483) (xy 39.614866 -315.556031)
			(xy 39.663085 -315.546187) (xy 39.71226 -315.544206) (xy 39.761115 -315.550138) (xy 39.808386 -315.56383)
			(xy 39.852848 -315.584928) (xy 39.893351 -315.612884) (xy 39.928844 -315.646976) (xy 39.958409 -315.68632)
			(xy 39.98128 -315.729897) (xy 39.996864 -315.776578) (xy 40.004759 -315.825155) (xy 40.005254 -315.849762)
			(xy 41.294062 -315.849762) (xy 41.298022 -315.800708) (xy 41.309799 -315.752924) (xy 41.32909 -315.707648)
			(xy 41.355393 -315.666052) (xy 41.388028 -315.629215) (xy 41.426149 -315.59809) (xy 41.46877 -315.573483)
			(xy 41.514786 -315.556031) (xy 41.563005 -315.546187) (xy 41.61218 -315.544206) (xy 41.661035 -315.550138)
			(xy 41.708306 -315.56383) (xy 41.752768 -315.584928) (xy 41.793271 -315.612884) (xy 41.828764 -315.646976)
			(xy 41.858329 -315.68632) (xy 41.8812 -315.729897) (xy 41.896784 -315.776578) (xy 41.904679 -315.825155)
			(xy 41.905174 -315.849762) (xy 43.193982 -315.849762) (xy 43.197942 -315.800708) (xy 43.209719 -315.752924)
			(xy 43.22901 -315.707648) (xy 43.255313 -315.666052) (xy 43.287948 -315.629215) (xy 43.326069 -315.59809)
			(xy 43.36869 -315.573483) (xy 43.414706 -315.556031) (xy 43.462925 -315.546187) (xy 43.5121 -315.544206)
			(xy 43.560955 -315.550138) (xy 43.608226 -315.56383) (xy 43.652688 -315.584928) (xy 43.693191 -315.612884)
			(xy 43.728684 -315.646976) (xy 43.758249 -315.68632) (xy 43.78112 -315.729897) (xy 43.796704 -315.776578)
			(xy 43.804599 -315.825155) (xy 43.805094 -315.849762) (xy 45.094156 -315.849762) (xy 45.098116 -315.800708)
			(xy 45.109893 -315.752924) (xy 45.129184 -315.707648) (xy 45.155487 -315.666052) (xy 45.188122 -315.629215)
			(xy 45.226243 -315.59809) (xy 45.268864 -315.573483) (xy 45.31488 -315.556031) (xy 45.363099 -315.546187)
			(xy 45.412274 -315.544206) (xy 45.461129 -315.550138) (xy 45.5084 -315.56383) (xy 45.552862 -315.584928)
			(xy 45.593365 -315.612884) (xy 45.628858 -315.646976) (xy 45.658423 -315.68632) (xy 45.681294 -315.729897)
			(xy 45.696878 -315.776578) (xy 45.704773 -315.825155) (xy 45.705268 -315.849762) (xy 46.994076 -315.849762)
			(xy 46.998036 -315.800708) (xy 47.009813 -315.752924) (xy 47.029104 -315.707648) (xy 47.055407 -315.666052)
			(xy 47.088042 -315.629215) (xy 47.126163 -315.59809) (xy 47.168784 -315.573483) (xy 47.2148 -315.556031)
			(xy 47.263019 -315.546187) (xy 47.312194 -315.544206) (xy 47.361049 -315.550138) (xy 47.40832 -315.56383)
			(xy 47.452782 -315.584928) (xy 47.493285 -315.612884) (xy 47.528778 -315.646976) (xy 47.558343 -315.68632)
			(xy 47.581214 -315.729897) (xy 47.596798 -315.776578) (xy 47.604693 -315.825155) (xy 47.605188 -315.849762)
			(xy 48.893996 -315.849762) (xy 48.897956 -315.800708) (xy 48.909733 -315.752924) (xy 48.929024 -315.707648)
			(xy 48.955327 -315.666052) (xy 48.987962 -315.629215) (xy 49.026083 -315.59809) (xy 49.068704 -315.573483)
			(xy 49.11472 -315.556031) (xy 49.162939 -315.546187) (xy 49.212114 -315.544206) (xy 49.260969 -315.550138)
			(xy 49.30824 -315.56383) (xy 49.352702 -315.584928) (xy 49.393205 -315.612884) (xy 49.428698 -315.646976)
			(xy 49.458263 -315.68632) (xy 49.481134 -315.729897) (xy 49.496718 -315.776578) (xy 49.504613 -315.825155)
			(xy 49.505108 -315.849762) (xy 50.79417 -315.849762) (xy 50.79813 -315.800708) (xy 50.809907 -315.752924)
			(xy 50.829198 -315.707648) (xy 50.855501 -315.666052) (xy 50.888136 -315.629215) (xy 50.926257 -315.59809)
			(xy 50.968878 -315.573483) (xy 51.014894 -315.556031) (xy 51.063113 -315.546187) (xy 51.112288 -315.544206)
			(xy 51.161143 -315.550138) (xy 51.208414 -315.56383) (xy 51.252876 -315.584928) (xy 51.293379 -315.612884)
			(xy 51.328872 -315.646976) (xy 51.358437 -315.68632) (xy 51.381308 -315.729897) (xy 51.396892 -315.776578)
			(xy 51.404787 -315.825155) (xy 51.405282 -315.849762) (xy 52.69409 -315.849762) (xy 52.69805 -315.800708)
			(xy 52.709827 -315.752924) (xy 52.729118 -315.707648) (xy 52.755421 -315.666052) (xy 52.788056 -315.629215)
			(xy 52.826177 -315.59809) (xy 52.868798 -315.573483) (xy 52.914814 -315.556031) (xy 52.963033 -315.546187)
			(xy 53.012208 -315.544206) (xy 53.061063 -315.550138) (xy 53.108334 -315.56383) (xy 53.152796 -315.584928)
			(xy 53.193299 -315.612884) (xy 53.228792 -315.646976) (xy 53.258357 -315.68632) (xy 53.281228 -315.729897)
			(xy 53.296812 -315.776578) (xy 53.304707 -315.825155) (xy 53.305202 -315.849762) (xy 54.59401 -315.849762)
			(xy 54.59797 -315.800708) (xy 54.609747 -315.752924) (xy 54.629038 -315.707648) (xy 54.655341 -315.666052)
			(xy 54.687976 -315.629215) (xy 54.726097 -315.59809) (xy 54.768718 -315.573483) (xy 54.814734 -315.556031)
			(xy 54.862953 -315.546187) (xy 54.912128 -315.544206) (xy 54.960983 -315.550138) (xy 55.008254 -315.56383)
			(xy 55.052716 -315.584928) (xy 55.093219 -315.612884) (xy 55.128712 -315.646976) (xy 55.158277 -315.68632)
			(xy 55.181148 -315.729897) (xy 55.196732 -315.776578) (xy 55.204627 -315.825155) (xy 55.205122 -315.849762)
			(xy 56.494184 -315.849762) (xy 56.498144 -315.800708) (xy 56.509921 -315.752924) (xy 56.529212 -315.707648)
			(xy 56.555515 -315.666052) (xy 56.58815 -315.629215) (xy 56.626271 -315.59809) (xy 56.668892 -315.573483)
			(xy 56.714908 -315.556031) (xy 56.763127 -315.546187) (xy 56.812302 -315.544206) (xy 56.861157 -315.550138)
			(xy 56.908428 -315.56383) (xy 56.95289 -315.584928) (xy 56.993393 -315.612884) (xy 57.028886 -315.646976)
			(xy 57.058451 -315.68632) (xy 57.081322 -315.729897) (xy 57.096906 -315.776578) (xy 57.104801 -315.825155)
			(xy 57.105296 -315.849762) (xy 58.394104 -315.849762) (xy 58.398064 -315.800708) (xy 58.409841 -315.752924)
			(xy 58.429132 -315.707648) (xy 58.455435 -315.666052) (xy 58.48807 -315.629215) (xy 58.526191 -315.59809)
			(xy 58.568812 -315.573483) (xy 58.614828 -315.556031) (xy 58.663047 -315.546187) (xy 58.712222 -315.544206)
			(xy 58.761077 -315.550138) (xy 58.808348 -315.56383) (xy 58.85281 -315.584928) (xy 58.893313 -315.612884)
			(xy 58.928806 -315.646976) (xy 58.958371 -315.68632) (xy 58.981242 -315.729897) (xy 58.996826 -315.776578)
			(xy 59.004721 -315.825155) (xy 59.005216 -315.849762) (xy 60.294024 -315.849762) (xy 60.297984 -315.800708)
			(xy 60.309761 -315.752924) (xy 60.329052 -315.707648) (xy 60.355355 -315.666052) (xy 60.38799 -315.629215)
			(xy 60.426111 -315.59809) (xy 60.468732 -315.573483) (xy 60.514748 -315.556031) (xy 60.562967 -315.546187)
			(xy 60.612142 -315.544206) (xy 60.660997 -315.550138) (xy 60.708268 -315.56383) (xy 60.75273 -315.584928)
			(xy 60.793233 -315.612884) (xy 60.828726 -315.646976) (xy 60.858291 -315.68632) (xy 60.881162 -315.729897)
			(xy 60.896746 -315.776578) (xy 60.904641 -315.825155) (xy 60.905136 -315.849762) (xy 62.193944 -315.849762)
			(xy 62.197904 -315.800708) (xy 62.209681 -315.752924) (xy 62.228972 -315.707648) (xy 62.255275 -315.666052)
			(xy 62.28791 -315.629215) (xy 62.326031 -315.59809) (xy 62.368652 -315.573483) (xy 62.414668 -315.556031)
			(xy 62.462887 -315.546187) (xy 62.512062 -315.544206) (xy 62.560917 -315.550138) (xy 62.608188 -315.56383)
			(xy 62.65265 -315.584928) (xy 62.693153 -315.612884) (xy 62.728646 -315.646976) (xy 62.758211 -315.68632)
			(xy 62.781082 -315.729897) (xy 62.796666 -315.776578) (xy 62.804561 -315.825155) (xy 62.805056 -315.849762)
			(xy 64.094118 -315.849762) (xy 64.098078 -315.800708) (xy 64.109855 -315.752924) (xy 64.129146 -315.707648)
			(xy 64.155449 -315.666052) (xy 64.188084 -315.629215) (xy 64.226205 -315.59809) (xy 64.268826 -315.573483)
			(xy 64.314842 -315.556031) (xy 64.363061 -315.546187) (xy 64.412236 -315.544206) (xy 64.461091 -315.550138)
			(xy 64.508362 -315.56383) (xy 64.552824 -315.584928) (xy 64.593327 -315.612884) (xy 64.62882 -315.646976)
			(xy 64.658385 -315.68632) (xy 64.681256 -315.729897) (xy 64.69684 -315.776578) (xy 64.704735 -315.825155)
			(xy 64.70523 -315.849762) (xy 65.994038 -315.849762) (xy 65.997998 -315.800708) (xy 66.009775 -315.752924)
			(xy 66.029066 -315.707648) (xy 66.055369 -315.666052) (xy 66.088004 -315.629215) (xy 66.126125 -315.59809)
			(xy 66.168746 -315.573483) (xy 66.214762 -315.556031) (xy 66.262981 -315.546187) (xy 66.312156 -315.544206)
			(xy 66.361011 -315.550138) (xy 66.408282 -315.56383) (xy 66.452744 -315.584928) (xy 66.493247 -315.612884)
			(xy 66.52874 -315.646976) (xy 66.558305 -315.68632) (xy 66.581176 -315.729897) (xy 66.59676 -315.776578)
			(xy 66.604655 -315.825155) (xy 66.60515 -315.849762) (xy 67.893958 -315.849762) (xy 67.897918 -315.800708)
			(xy 67.909695 -315.752924) (xy 67.928986 -315.707648) (xy 67.955289 -315.666052) (xy 67.987924 -315.629215)
			(xy 68.026045 -315.59809) (xy 68.068666 -315.573483) (xy 68.114682 -315.556031) (xy 68.162901 -315.546187)
			(xy 68.212076 -315.544206) (xy 68.260931 -315.550138) (xy 68.308202 -315.56383) (xy 68.352664 -315.584928)
			(xy 68.393167 -315.612884) (xy 68.42866 -315.646976) (xy 68.458225 -315.68632) (xy 68.481096 -315.729897)
			(xy 68.49668 -315.776578) (xy 68.504575 -315.825155) (xy 68.50507 -315.849762) (xy 69.794132 -315.849762)
			(xy 69.798092 -315.800708) (xy 69.809869 -315.752924) (xy 69.82916 -315.707648) (xy 69.855463 -315.666052)
			(xy 69.888098 -315.629215) (xy 69.926219 -315.59809) (xy 69.96884 -315.573483) (xy 70.014856 -315.556031)
			(xy 70.063075 -315.546187) (xy 70.11225 -315.544206) (xy 70.161105 -315.550138) (xy 70.208376 -315.56383)
			(xy 70.252838 -315.584928) (xy 70.293341 -315.612884) (xy 70.328834 -315.646976) (xy 70.358399 -315.68632)
			(xy 70.38127 -315.729897) (xy 70.396854 -315.776578) (xy 70.404749 -315.825155) (xy 70.405244 -315.849762)
			(xy 71.694052 -315.849762) (xy 71.698012 -315.800708) (xy 71.709789 -315.752924) (xy 71.72908 -315.707648)
			(xy 71.755383 -315.666052) (xy 71.788018 -315.629215) (xy 71.826139 -315.59809) (xy 71.86876 -315.573483)
			(xy 71.914776 -315.556031) (xy 71.962995 -315.546187) (xy 72.01217 -315.544206) (xy 72.061025 -315.550138)
			(xy 72.108296 -315.56383) (xy 72.152758 -315.584928) (xy 72.193261 -315.612884) (xy 72.228754 -315.646976)
			(xy 72.258319 -315.68632) (xy 72.28119 -315.729897) (xy 72.296774 -315.776578) (xy 72.304669 -315.825155)
			(xy 72.305164 -315.849762) (xy 73.593972 -315.849762) (xy 73.597932 -315.800708) (xy 73.609709 -315.752924)
			(xy 73.629 -315.707648) (xy 73.655303 -315.666052) (xy 73.687938 -315.629215) (xy 73.726059 -315.59809)
			(xy 73.76868 -315.573483) (xy 73.814696 -315.556031) (xy 73.862915 -315.546187) (xy 73.91209 -315.544206)
			(xy 73.960945 -315.550138) (xy 74.008216 -315.56383) (xy 74.052678 -315.584928) (xy 74.093181 -315.612884)
			(xy 74.128674 -315.646976) (xy 74.158239 -315.68632) (xy 74.18111 -315.729897) (xy 74.196694 -315.776578)
			(xy 74.204589 -315.825155) (xy 74.205084 -315.849762) (xy 75.494146 -315.849762) (xy 75.498106 -315.800708)
			(xy 75.509883 -315.752924) (xy 75.529174 -315.707648) (xy 75.555477 -315.666052) (xy 75.588112 -315.629215)
			(xy 75.626233 -315.59809) (xy 75.668854 -315.573483) (xy 75.71487 -315.556031) (xy 75.763089 -315.546187)
			(xy 75.812264 -315.544206) (xy 75.861119 -315.550138) (xy 75.90839 -315.56383) (xy 75.952852 -315.584928)
			(xy 75.993355 -315.612884) (xy 76.028848 -315.646976) (xy 76.058413 -315.68632) (xy 76.081284 -315.729897)
			(xy 76.096868 -315.776578) (xy 76.104763 -315.825155) (xy 76.105258 -315.849762) (xy 77.394066 -315.849762)
			(xy 77.398026 -315.800708) (xy 77.409803 -315.752924) (xy 77.429094 -315.707648) (xy 77.455397 -315.666052)
			(xy 77.488032 -315.629215) (xy 77.526153 -315.59809) (xy 77.568774 -315.573483) (xy 77.61479 -315.556031)
			(xy 77.663009 -315.546187) (xy 77.712184 -315.544206) (xy 77.761039 -315.550138) (xy 77.80831 -315.56383)
			(xy 77.852772 -315.584928) (xy 77.893275 -315.612884) (xy 77.928768 -315.646976) (xy 77.958333 -315.68632)
			(xy 77.981204 -315.729897) (xy 77.996788 -315.776578) (xy 78.004683 -315.825155) (xy 78.005178 -315.849762)
			(xy 79.293986 -315.849762) (xy 79.297946 -315.800708) (xy 79.309723 -315.752924) (xy 79.329014 -315.707648)
			(xy 79.355317 -315.666052) (xy 79.387952 -315.629215) (xy 79.426073 -315.59809) (xy 79.468694 -315.573483)
			(xy 79.51471 -315.556031) (xy 79.562929 -315.546187) (xy 79.612104 -315.544206) (xy 79.660959 -315.550138)
			(xy 79.70823 -315.56383) (xy 79.752692 -315.584928) (xy 79.793195 -315.612884) (xy 79.828688 -315.646976)
			(xy 79.858253 -315.68632) (xy 79.881124 -315.729897) (xy 79.896708 -315.776578) (xy 79.904603 -315.825155)
			(xy 79.905098 -315.849762) (xy 155.49424 -315.849762) (xy 155.4982 -315.800708) (xy 155.509977 -315.752924)
			(xy 155.529268 -315.707648) (xy 155.555571 -315.666052) (xy 155.588206 -315.629215) (xy 155.626327 -315.59809)
			(xy 155.668948 -315.573483) (xy 155.714964 -315.556031) (xy 155.763183 -315.546187) (xy 155.812358 -315.544206)
			(xy 155.861213 -315.550138) (xy 155.908484 -315.56383) (xy 155.952946 -315.584928) (xy 155.993449 -315.612884)
			(xy 156.028942 -315.646976) (xy 156.058507 -315.68632) (xy 156.081378 -315.729897) (xy 156.096962 -315.776578)
			(xy 156.104857 -315.825155) (xy 156.105352 -315.849762) (xy 157.39416 -315.849762) (xy 157.39812 -315.800708)
			(xy 157.409897 -315.752924) (xy 157.429188 -315.707648) (xy 157.455491 -315.666052) (xy 157.488126 -315.629215)
			(xy 157.526247 -315.59809) (xy 157.568868 -315.573483) (xy 157.614884 -315.556031) (xy 157.663103 -315.546187)
			(xy 157.712278 -315.544206) (xy 157.761133 -315.550138) (xy 157.808404 -315.56383) (xy 157.852866 -315.584928)
			(xy 157.893369 -315.612884) (xy 157.928862 -315.646976) (xy 157.958427 -315.68632) (xy 157.981298 -315.729897)
			(xy 157.996882 -315.776578) (xy 158.004777 -315.825155) (xy 158.005272 -315.849762) (xy 159.29408 -315.849762)
			(xy 159.29804 -315.800708) (xy 159.309817 -315.752924) (xy 159.329108 -315.707648) (xy 159.355411 -315.666052)
			(xy 159.388046 -315.629215) (xy 159.426167 -315.59809) (xy 159.468788 -315.573483) (xy 159.514804 -315.556031)
			(xy 159.563023 -315.546187) (xy 159.612198 -315.544206) (xy 159.661053 -315.550138) (xy 159.708324 -315.56383)
			(xy 159.752786 -315.584928) (xy 159.793289 -315.612884) (xy 159.828782 -315.646976) (xy 159.858347 -315.68632)
			(xy 159.881218 -315.729897) (xy 159.896802 -315.776578) (xy 159.904697 -315.825155) (xy 159.905192 -315.849762)
			(xy 161.194254 -315.849762) (xy 161.198214 -315.800708) (xy 161.209991 -315.752924) (xy 161.229282 -315.707648)
			(xy 161.255585 -315.666052) (xy 161.28822 -315.629215) (xy 161.326341 -315.59809) (xy 161.368962 -315.573483)
			(xy 161.414978 -315.556031) (xy 161.463197 -315.546187) (xy 161.512372 -315.544206) (xy 161.561227 -315.550138)
			(xy 161.608498 -315.56383) (xy 161.65296 -315.584928) (xy 161.693463 -315.612884) (xy 161.728956 -315.646976)
			(xy 161.758521 -315.68632) (xy 161.781392 -315.729897) (xy 161.796976 -315.776578) (xy 161.804871 -315.825155)
			(xy 161.805366 -315.849762) (xy 163.094174 -315.849762) (xy 163.098134 -315.800708) (xy 163.109911 -315.752924)
			(xy 163.129202 -315.707648) (xy 163.155505 -315.666052) (xy 163.18814 -315.629215) (xy 163.226261 -315.59809)
			(xy 163.268882 -315.573483) (xy 163.314898 -315.556031) (xy 163.363117 -315.546187) (xy 163.412292 -315.544206)
			(xy 163.461147 -315.550138) (xy 163.508418 -315.56383) (xy 163.55288 -315.584928) (xy 163.593383 -315.612884)
			(xy 163.628876 -315.646976) (xy 163.658441 -315.68632) (xy 163.681312 -315.729897) (xy 163.696896 -315.776578)
			(xy 163.704791 -315.825155) (xy 163.705286 -315.849762) (xy 164.994094 -315.849762) (xy 164.998054 -315.800708)
			(xy 165.009831 -315.752924) (xy 165.029122 -315.707648) (xy 165.055425 -315.666052) (xy 165.08806 -315.629215)
			(xy 165.126181 -315.59809) (xy 165.168802 -315.573483) (xy 165.214818 -315.556031) (xy 165.263037 -315.546187)
			(xy 165.312212 -315.544206) (xy 165.361067 -315.550138) (xy 165.408338 -315.56383) (xy 165.4528 -315.584928)
			(xy 165.493303 -315.612884) (xy 165.528796 -315.646976) (xy 165.558361 -315.68632) (xy 165.581232 -315.729897)
			(xy 165.596816 -315.776578) (xy 165.604711 -315.825155) (xy 165.605206 -315.849762) (xy 166.894268 -315.849762)
			(xy 166.898228 -315.800708) (xy 166.910005 -315.752924) (xy 166.929296 -315.707648) (xy 166.955599 -315.666052)
			(xy 166.988234 -315.629215) (xy 167.026355 -315.59809) (xy 167.068976 -315.573483) (xy 167.114992 -315.556031)
			(xy 167.163211 -315.546187) (xy 167.212386 -315.544206) (xy 167.261241 -315.550138) (xy 167.308512 -315.56383)
			(xy 167.352974 -315.584928) (xy 167.393477 -315.612884) (xy 167.42897 -315.646976) (xy 167.458535 -315.68632)
			(xy 167.481406 -315.729897) (xy 167.49699 -315.776578) (xy 167.504885 -315.825155) (xy 167.50538 -315.849762)
			(xy 168.794188 -315.849762) (xy 168.798148 -315.800708) (xy 168.809925 -315.752924) (xy 168.829216 -315.707648)
			(xy 168.855519 -315.666052) (xy 168.888154 -315.629215) (xy 168.926275 -315.59809) (xy 168.968896 -315.573483)
			(xy 169.014912 -315.556031) (xy 169.063131 -315.546187) (xy 169.112306 -315.544206) (xy 169.161161 -315.550138)
			(xy 169.208432 -315.56383) (xy 169.252894 -315.584928) (xy 169.293397 -315.612884) (xy 169.32889 -315.646976)
			(xy 169.358455 -315.68632) (xy 169.381326 -315.729897) (xy 169.39691 -315.776578) (xy 169.404805 -315.825155)
			(xy 169.4053 -315.849762) (xy 170.694108 -315.849762) (xy 170.698068 -315.800708) (xy 170.709845 -315.752924)
			(xy 170.729136 -315.707648) (xy 170.755439 -315.666052) (xy 170.788074 -315.629215) (xy 170.826195 -315.59809)
			(xy 170.868816 -315.573483) (xy 170.914832 -315.556031) (xy 170.963051 -315.546187) (xy 171.012226 -315.544206)
			(xy 171.061081 -315.550138) (xy 171.108352 -315.56383) (xy 171.152814 -315.584928) (xy 171.193317 -315.612884)
			(xy 171.22881 -315.646976) (xy 171.258375 -315.68632) (xy 171.281246 -315.729897) (xy 171.29683 -315.776578)
			(xy 171.304725 -315.825155) (xy 171.30522 -315.849762) (xy 172.594282 -315.849762) (xy 172.598242 -315.800708)
			(xy 172.610019 -315.752924) (xy 172.62931 -315.707648) (xy 172.655613 -315.666052) (xy 172.688248 -315.629215)
			(xy 172.726369 -315.59809) (xy 172.76899 -315.573483) (xy 172.815006 -315.556031) (xy 172.863225 -315.546187)
			(xy 172.9124 -315.544206) (xy 172.961255 -315.550138) (xy 173.008526 -315.56383) (xy 173.052988 -315.584928)
			(xy 173.093491 -315.612884) (xy 173.128984 -315.646976) (xy 173.158549 -315.68632) (xy 173.18142 -315.729897)
			(xy 173.197004 -315.776578) (xy 173.204899 -315.825155) (xy 173.205394 -315.849762) (xy 174.494202 -315.849762)
			(xy 174.498162 -315.800708) (xy 174.509939 -315.752924) (xy 174.52923 -315.707648) (xy 174.555533 -315.666052)
			(xy 174.588168 -315.629215) (xy 174.626289 -315.59809) (xy 174.66891 -315.573483) (xy 174.714926 -315.556031)
			(xy 174.763145 -315.546187) (xy 174.81232 -315.544206) (xy 174.861175 -315.550138) (xy 174.908446 -315.56383)
			(xy 174.952908 -315.584928) (xy 174.993411 -315.612884) (xy 175.028904 -315.646976) (xy 175.058469 -315.68632)
			(xy 175.08134 -315.729897) (xy 175.096924 -315.776578) (xy 175.104819 -315.825155) (xy 175.105314 -315.849762)
			(xy 176.394122 -315.849762) (xy 176.398082 -315.800708) (xy 176.409859 -315.752924) (xy 176.42915 -315.707648)
			(xy 176.455453 -315.666052) (xy 176.488088 -315.629215) (xy 176.526209 -315.59809) (xy 176.56883 -315.573483)
			(xy 176.614846 -315.556031) (xy 176.663065 -315.546187) (xy 176.71224 -315.544206) (xy 176.761095 -315.550138)
			(xy 176.808366 -315.56383) (xy 176.852828 -315.584928) (xy 176.893331 -315.612884) (xy 176.928824 -315.646976)
			(xy 176.958389 -315.68632) (xy 176.98126 -315.729897) (xy 176.996844 -315.776578) (xy 177.004739 -315.825155)
			(xy 177.005234 -315.849762) (xy 178.294042 -315.849762) (xy 178.298002 -315.800708) (xy 178.309779 -315.752924)
			(xy 178.32907 -315.707648) (xy 178.355373 -315.666052) (xy 178.388008 -315.629215) (xy 178.426129 -315.59809)
			(xy 178.46875 -315.573483) (xy 178.514766 -315.556031) (xy 178.562985 -315.546187) (xy 178.61216 -315.544206)
			(xy 178.661015 -315.550138) (xy 178.708286 -315.56383) (xy 178.752748 -315.584928) (xy 178.793251 -315.612884)
			(xy 178.828744 -315.646976) (xy 178.858309 -315.68632) (xy 178.88118 -315.729897) (xy 178.896764 -315.776578)
			(xy 178.904659 -315.825155) (xy 178.905154 -315.849762) (xy 180.194216 -315.849762) (xy 180.198176 -315.800708)
			(xy 180.209953 -315.752924) (xy 180.229244 -315.707648) (xy 180.255547 -315.666052) (xy 180.288182 -315.629215)
			(xy 180.326303 -315.59809) (xy 180.368924 -315.573483) (xy 180.41494 -315.556031) (xy 180.463159 -315.546187)
			(xy 180.512334 -315.544206) (xy 180.561189 -315.550138) (xy 180.60846 -315.56383) (xy 180.652922 -315.584928)
			(xy 180.693425 -315.612884) (xy 180.728918 -315.646976) (xy 180.758483 -315.68632) (xy 180.781354 -315.729897)
			(xy 180.796938 -315.776578) (xy 180.804833 -315.825155) (xy 180.805328 -315.849762) (xy 182.094136 -315.849762)
			(xy 182.098096 -315.800708) (xy 182.109873 -315.752924) (xy 182.129164 -315.707648) (xy 182.155467 -315.666052)
			(xy 182.188102 -315.629215) (xy 182.226223 -315.59809) (xy 182.268844 -315.573483) (xy 182.31486 -315.556031)
			(xy 182.363079 -315.546187) (xy 182.412254 -315.544206) (xy 182.461109 -315.550138) (xy 182.50838 -315.56383)
			(xy 182.552842 -315.584928) (xy 182.593345 -315.612884) (xy 182.628838 -315.646976) (xy 182.658403 -315.68632)
			(xy 182.681274 -315.729897) (xy 182.696858 -315.776578) (xy 182.704753 -315.825155) (xy 182.705248 -315.849762)
			(xy 183.994056 -315.849762) (xy 183.998016 -315.800708) (xy 184.009793 -315.752924) (xy 184.029084 -315.707648)
			(xy 184.055387 -315.666052) (xy 184.088022 -315.629215) (xy 184.126143 -315.59809) (xy 184.168764 -315.573483)
			(xy 184.21478 -315.556031) (xy 184.262999 -315.546187) (xy 184.312174 -315.544206) (xy 184.361029 -315.550138)
			(xy 184.4083 -315.56383) (xy 184.452762 -315.584928) (xy 184.493265 -315.612884) (xy 184.528758 -315.646976)
			(xy 184.558323 -315.68632) (xy 184.581194 -315.729897) (xy 184.596778 -315.776578) (xy 184.604673 -315.825155)
			(xy 184.605168 -315.849762) (xy 185.89423 -315.849762) (xy 185.89819 -315.800708) (xy 185.909967 -315.752924)
			(xy 185.929258 -315.707648) (xy 185.955561 -315.666052) (xy 185.988196 -315.629215) (xy 186.026317 -315.59809)
			(xy 186.068938 -315.573483) (xy 186.114954 -315.556031) (xy 186.163173 -315.546187) (xy 186.212348 -315.544206)
			(xy 186.261203 -315.550138) (xy 186.308474 -315.56383) (xy 186.352936 -315.584928) (xy 186.393439 -315.612884)
			(xy 186.428932 -315.646976) (xy 186.458497 -315.68632) (xy 186.481368 -315.729897) (xy 186.496952 -315.776578)
			(xy 186.504847 -315.825155) (xy 186.505342 -315.849762) (xy 187.79415 -315.849762) (xy 187.79811 -315.800708)
			(xy 187.809887 -315.752924) (xy 187.829178 -315.707648) (xy 187.855481 -315.666052) (xy 187.888116 -315.629215)
			(xy 187.926237 -315.59809) (xy 187.968858 -315.573483) (xy 188.014874 -315.556031) (xy 188.063093 -315.546187)
			(xy 188.112268 -315.544206) (xy 188.161123 -315.550138) (xy 188.208394 -315.56383) (xy 188.252856 -315.584928)
			(xy 188.293359 -315.612884) (xy 188.328852 -315.646976) (xy 188.358417 -315.68632) (xy 188.381288 -315.729897)
			(xy 188.396872 -315.776578) (xy 188.404767 -315.825155) (xy 188.405262 -315.849762) (xy 189.69407 -315.849762)
			(xy 189.69803 -315.800708) (xy 189.709807 -315.752924) (xy 189.729098 -315.707648) (xy 189.755401 -315.666052)
			(xy 189.788036 -315.629215) (xy 189.826157 -315.59809) (xy 189.868778 -315.573483) (xy 189.914794 -315.556031)
			(xy 189.963013 -315.546187) (xy 190.012188 -315.544206) (xy 190.061043 -315.550138) (xy 190.108314 -315.56383)
			(xy 190.152776 -315.584928) (xy 190.193279 -315.612884) (xy 190.228772 -315.646976) (xy 190.258337 -315.68632)
			(xy 190.281208 -315.729897) (xy 190.296792 -315.776578) (xy 190.304687 -315.825155) (xy 190.305182 -315.849762)
			(xy 191.594244 -315.849762) (xy 191.598204 -315.800708) (xy 191.609981 -315.752924) (xy 191.629272 -315.707648)
			(xy 191.655575 -315.666052) (xy 191.68821 -315.629215) (xy 191.726331 -315.59809) (xy 191.768952 -315.573483)
			(xy 191.814968 -315.556031) (xy 191.863187 -315.546187) (xy 191.912362 -315.544206) (xy 191.961217 -315.550138)
			(xy 192.008488 -315.56383) (xy 192.05295 -315.584928) (xy 192.093453 -315.612884) (xy 192.128946 -315.646976)
			(xy 192.158511 -315.68632) (xy 192.181382 -315.729897) (xy 192.196966 -315.776578) (xy 192.204861 -315.825155)
			(xy 192.205356 -315.849762) (xy 193.494164 -315.849762) (xy 193.498124 -315.800708) (xy 193.509901 -315.752924)
			(xy 193.529192 -315.707648) (xy 193.555495 -315.666052) (xy 193.58813 -315.629215) (xy 193.626251 -315.59809)
			(xy 193.668872 -315.573483) (xy 193.714888 -315.556031) (xy 193.763107 -315.546187) (xy 193.812282 -315.544206)
			(xy 193.861137 -315.550138) (xy 193.908408 -315.56383) (xy 193.95287 -315.584928) (xy 193.993373 -315.612884)
			(xy 194.028866 -315.646976) (xy 194.058431 -315.68632) (xy 194.081302 -315.729897) (xy 194.096886 -315.776578)
			(xy 194.104781 -315.825155) (xy 194.105276 -315.849762) (xy 195.394084 -315.849762) (xy 195.398044 -315.800708)
			(xy 195.409821 -315.752924) (xy 195.429112 -315.707648) (xy 195.455415 -315.666052) (xy 195.48805 -315.629215)
			(xy 195.526171 -315.59809) (xy 195.568792 -315.573483) (xy 195.614808 -315.556031) (xy 195.663027 -315.546187)
			(xy 195.712202 -315.544206) (xy 195.761057 -315.550138) (xy 195.808328 -315.56383) (xy 195.85279 -315.584928)
			(xy 195.893293 -315.612884) (xy 195.928786 -315.646976) (xy 195.958351 -315.68632) (xy 195.981222 -315.729897)
			(xy 195.996806 -315.776578) (xy 196.004701 -315.825155) (xy 196.005196 -315.849762) (xy 271.594084 -315.849762)
			(xy 271.598044 -315.800708) (xy 271.609821 -315.752924) (xy 271.629112 -315.707648) (xy 271.655415 -315.666052)
			(xy 271.68805 -315.629215) (xy 271.726171 -315.59809) (xy 271.768792 -315.573483) (xy 271.814808 -315.556031)
			(xy 271.863027 -315.546187) (xy 271.912202 -315.544206) (xy 271.961057 -315.550138) (xy 272.008328 -315.56383)
			(xy 272.05279 -315.584928) (xy 272.093293 -315.612884) (xy 272.128786 -315.646976) (xy 272.158351 -315.68632)
			(xy 272.181222 -315.729897) (xy 272.196806 -315.776578) (xy 272.204701 -315.825155) (xy 272.205196 -315.849762)
			(xy 273.494004 -315.849762) (xy 273.497964 -315.800708) (xy 273.509741 -315.752924) (xy 273.529032 -315.707648)
			(xy 273.555335 -315.666052) (xy 273.58797 -315.629215) (xy 273.626091 -315.59809) (xy 273.668712 -315.573483)
			(xy 273.714728 -315.556031) (xy 273.762947 -315.546187) (xy 273.812122 -315.544206) (xy 273.860977 -315.550138)
			(xy 273.908248 -315.56383) (xy 273.95271 -315.584928) (xy 273.993213 -315.612884) (xy 274.028706 -315.646976)
			(xy 274.058271 -315.68632) (xy 274.081142 -315.729897) (xy 274.096726 -315.776578) (xy 274.104621 -315.825155)
			(xy 274.105116 -315.849762) (xy 275.393924 -315.849762) (xy 275.397884 -315.800708) (xy 275.409661 -315.752924)
			(xy 275.428952 -315.707648) (xy 275.455255 -315.666052) (xy 275.48789 -315.629215) (xy 275.526011 -315.59809)
			(xy 275.568632 -315.573483) (xy 275.614648 -315.556031) (xy 275.662867 -315.546187) (xy 275.712042 -315.544206)
			(xy 275.760897 -315.550138) (xy 275.808168 -315.56383) (xy 275.85263 -315.584928) (xy 275.893133 -315.612884)
			(xy 275.928626 -315.646976) (xy 275.958191 -315.68632) (xy 275.981062 -315.729897) (xy 275.996646 -315.776578)
			(xy 276.004541 -315.825155) (xy 276.005036 -315.849762) (xy 277.294098 -315.849762) (xy 277.298058 -315.800708)
			(xy 277.309835 -315.752924) (xy 277.329126 -315.707648) (xy 277.355429 -315.666052) (xy 277.388064 -315.629215)
			(xy 277.426185 -315.59809) (xy 277.468806 -315.573483) (xy 277.514822 -315.556031) (xy 277.563041 -315.546187)
			(xy 277.612216 -315.544206) (xy 277.661071 -315.550138) (xy 277.708342 -315.56383) (xy 277.752804 -315.584928)
			(xy 277.793307 -315.612884) (xy 277.8288 -315.646976) (xy 277.858365 -315.68632) (xy 277.881236 -315.729897)
			(xy 277.89682 -315.776578) (xy 277.904715 -315.825155) (xy 277.90521 -315.849762) (xy 279.194018 -315.849762)
			(xy 279.197978 -315.800708) (xy 279.209755 -315.752924) (xy 279.229046 -315.707648) (xy 279.255349 -315.666052)
			(xy 279.287984 -315.629215) (xy 279.326105 -315.59809) (xy 279.368726 -315.573483) (xy 279.414742 -315.556031)
			(xy 279.462961 -315.546187) (xy 279.512136 -315.544206) (xy 279.560991 -315.550138) (xy 279.608262 -315.56383)
			(xy 279.652724 -315.584928) (xy 279.693227 -315.612884) (xy 279.72872 -315.646976) (xy 279.758285 -315.68632)
			(xy 279.781156 -315.729897) (xy 279.79674 -315.776578) (xy 279.804635 -315.825155) (xy 279.80513 -315.849762)
			(xy 281.093938 -315.849762) (xy 281.097898 -315.800708) (xy 281.109675 -315.752924) (xy 281.128966 -315.707648)
			(xy 281.155269 -315.666052) (xy 281.187904 -315.629215) (xy 281.226025 -315.59809) (xy 281.268646 -315.573483)
			(xy 281.314662 -315.556031) (xy 281.362881 -315.546187) (xy 281.412056 -315.544206) (xy 281.460911 -315.550138)
			(xy 281.508182 -315.56383) (xy 281.552644 -315.584928) (xy 281.593147 -315.612884) (xy 281.62864 -315.646976)
			(xy 281.658205 -315.68632) (xy 281.681076 -315.729897) (xy 281.69666 -315.776578) (xy 281.704555 -315.825155)
			(xy 281.70505 -315.849762) (xy 282.994112 -315.849762) (xy 282.998072 -315.800708) (xy 283.009849 -315.752924)
			(xy 283.02914 -315.707648) (xy 283.055443 -315.666052) (xy 283.088078 -315.629215) (xy 283.126199 -315.59809)
			(xy 283.16882 -315.573483) (xy 283.214836 -315.556031) (xy 283.263055 -315.546187) (xy 283.31223 -315.544206)
			(xy 283.361085 -315.550138) (xy 283.408356 -315.56383) (xy 283.452818 -315.584928) (xy 283.493321 -315.612884)
			(xy 283.528814 -315.646976) (xy 283.558379 -315.68632) (xy 283.58125 -315.729897) (xy 283.596834 -315.776578)
			(xy 283.604729 -315.825155) (xy 283.605224 -315.849762) (xy 284.894032 -315.849762) (xy 284.897992 -315.800708)
			(xy 284.909769 -315.752924) (xy 284.92906 -315.707648) (xy 284.955363 -315.666052) (xy 284.987998 -315.629215)
			(xy 285.026119 -315.59809) (xy 285.06874 -315.573483) (xy 285.114756 -315.556031) (xy 285.162975 -315.546187)
			(xy 285.21215 -315.544206) (xy 285.261005 -315.550138) (xy 285.308276 -315.56383) (xy 285.352738 -315.584928)
			(xy 285.393241 -315.612884) (xy 285.428734 -315.646976) (xy 285.458299 -315.68632) (xy 285.48117 -315.729897)
			(xy 285.496754 -315.776578) (xy 285.504649 -315.825155) (xy 285.505144 -315.849762) (xy 286.793952 -315.849762)
			(xy 286.797912 -315.800708) (xy 286.809689 -315.752924) (xy 286.82898 -315.707648) (xy 286.855283 -315.666052)
			(xy 286.887918 -315.629215) (xy 286.926039 -315.59809) (xy 286.96866 -315.573483) (xy 287.014676 -315.556031)
			(xy 287.062895 -315.546187) (xy 287.11207 -315.544206) (xy 287.160925 -315.550138) (xy 287.208196 -315.56383)
			(xy 287.252658 -315.584928) (xy 287.293161 -315.612884) (xy 287.328654 -315.646976) (xy 287.358219 -315.68632)
			(xy 287.38109 -315.729897) (xy 287.396674 -315.776578) (xy 287.404569 -315.825155) (xy 287.405064 -315.849762)
			(xy 288.694126 -315.849762) (xy 288.698086 -315.800708) (xy 288.709863 -315.752924) (xy 288.729154 -315.707648)
			(xy 288.755457 -315.666052) (xy 288.788092 -315.629215) (xy 288.826213 -315.59809) (xy 288.868834 -315.573483)
			(xy 288.91485 -315.556031) (xy 288.963069 -315.546187) (xy 289.012244 -315.544206) (xy 289.061099 -315.550138)
			(xy 289.10837 -315.56383) (xy 289.152832 -315.584928) (xy 289.193335 -315.612884) (xy 289.228828 -315.646976)
			(xy 289.258393 -315.68632) (xy 289.281264 -315.729897) (xy 289.296848 -315.776578) (xy 289.304743 -315.825155)
			(xy 289.305238 -315.849762) (xy 290.594046 -315.849762) (xy 290.598006 -315.800708) (xy 290.609783 -315.752924)
			(xy 290.629074 -315.707648) (xy 290.655377 -315.666052) (xy 290.688012 -315.629215) (xy 290.726133 -315.59809)
			(xy 290.768754 -315.573483) (xy 290.81477 -315.556031) (xy 290.862989 -315.546187) (xy 290.912164 -315.544206)
			(xy 290.961019 -315.550138) (xy 291.00829 -315.56383) (xy 291.052752 -315.584928) (xy 291.093255 -315.612884)
			(xy 291.128748 -315.646976) (xy 291.158313 -315.68632) (xy 291.181184 -315.729897) (xy 291.196768 -315.776578)
			(xy 291.204663 -315.825155) (xy 291.205158 -315.849762) (xy 292.493966 -315.849762) (xy 292.497926 -315.800708)
			(xy 292.509703 -315.752924) (xy 292.528994 -315.707648) (xy 292.555297 -315.666052) (xy 292.587932 -315.629215)
			(xy 292.626053 -315.59809) (xy 292.668674 -315.573483) (xy 292.71469 -315.556031) (xy 292.762909 -315.546187)
			(xy 292.812084 -315.544206) (xy 292.860939 -315.550138) (xy 292.90821 -315.56383) (xy 292.952672 -315.584928)
			(xy 292.993175 -315.612884) (xy 293.028668 -315.646976) (xy 293.058233 -315.68632) (xy 293.081104 -315.729897)
			(xy 293.096688 -315.776578) (xy 293.104583 -315.825155) (xy 293.105078 -315.849762) (xy 294.393886 -315.849762)
			(xy 294.397846 -315.800708) (xy 294.409623 -315.752924) (xy 294.428914 -315.707648) (xy 294.455217 -315.666052)
			(xy 294.487852 -315.629215) (xy 294.525973 -315.59809) (xy 294.568594 -315.573483) (xy 294.61461 -315.556031)
			(xy 294.662829 -315.546187) (xy 294.712004 -315.544206) (xy 294.760859 -315.550138) (xy 294.80813 -315.56383)
			(xy 294.852592 -315.584928) (xy 294.893095 -315.612884) (xy 294.928588 -315.646976) (xy 294.958153 -315.68632)
			(xy 294.981024 -315.729897) (xy 294.996608 -315.776578) (xy 295.004503 -315.825155) (xy 295.004998 -315.849762)
			(xy 296.29406 -315.849762) (xy 296.29802 -315.800708) (xy 296.309797 -315.752924) (xy 296.329088 -315.707648)
			(xy 296.355391 -315.666052) (xy 296.388026 -315.629215) (xy 296.426147 -315.59809) (xy 296.468768 -315.573483)
			(xy 296.514784 -315.556031) (xy 296.563003 -315.546187) (xy 296.612178 -315.544206) (xy 296.661033 -315.550138)
			(xy 296.708304 -315.56383) (xy 296.752766 -315.584928) (xy 296.793269 -315.612884) (xy 296.828762 -315.646976)
			(xy 296.858327 -315.68632) (xy 296.881198 -315.729897) (xy 296.896782 -315.776578) (xy 296.904677 -315.825155)
			(xy 296.905172 -315.849762) (xy 298.19398 -315.849762) (xy 298.19794 -315.800708) (xy 298.209717 -315.752924)
			(xy 298.229008 -315.707648) (xy 298.255311 -315.666052) (xy 298.287946 -315.629215) (xy 298.326067 -315.59809)
			(xy 298.368688 -315.573483) (xy 298.414704 -315.556031) (xy 298.462923 -315.546187) (xy 298.512098 -315.544206)
			(xy 298.560953 -315.550138) (xy 298.608224 -315.56383) (xy 298.652686 -315.584928) (xy 298.693189 -315.612884)
			(xy 298.728682 -315.646976) (xy 298.758247 -315.68632) (xy 298.781118 -315.729897) (xy 298.796702 -315.776578)
			(xy 298.804597 -315.825155) (xy 298.805092 -315.849762) (xy 300.0939 -315.849762) (xy 300.09786 -315.800708)
			(xy 300.109637 -315.752924) (xy 300.128928 -315.707648) (xy 300.155231 -315.666052) (xy 300.187866 -315.629215)
			(xy 300.225987 -315.59809) (xy 300.268608 -315.573483) (xy 300.314624 -315.556031) (xy 300.362843 -315.546187)
			(xy 300.412018 -315.544206) (xy 300.460873 -315.550138) (xy 300.508144 -315.56383) (xy 300.552606 -315.584928)
			(xy 300.593109 -315.612884) (xy 300.628602 -315.646976) (xy 300.658167 -315.68632) (xy 300.681038 -315.729897)
			(xy 300.696622 -315.776578) (xy 300.704517 -315.825155) (xy 300.705012 -315.849762) (xy 301.994074 -315.849762)
			(xy 301.998034 -315.800708) (xy 302.009811 -315.752924) (xy 302.029102 -315.707648) (xy 302.055405 -315.666052)
			(xy 302.08804 -315.629215) (xy 302.126161 -315.59809) (xy 302.168782 -315.573483) (xy 302.214798 -315.556031)
			(xy 302.263017 -315.546187) (xy 302.312192 -315.544206) (xy 302.361047 -315.550138) (xy 302.408318 -315.56383)
			(xy 302.45278 -315.584928) (xy 302.493283 -315.612884) (xy 302.528776 -315.646976) (xy 302.558341 -315.68632)
			(xy 302.581212 -315.729897) (xy 302.596796 -315.776578) (xy 302.604691 -315.825155) (xy 302.605186 -315.849762)
			(xy 303.893994 -315.849762) (xy 303.897954 -315.800708) (xy 303.909731 -315.752924) (xy 303.929022 -315.707648)
			(xy 303.955325 -315.666052) (xy 303.98796 -315.629215) (xy 304.026081 -315.59809) (xy 304.068702 -315.573483)
			(xy 304.114718 -315.556031) (xy 304.162937 -315.546187) (xy 304.212112 -315.544206) (xy 304.260967 -315.550138)
			(xy 304.308238 -315.56383) (xy 304.3527 -315.584928) (xy 304.393203 -315.612884) (xy 304.428696 -315.646976)
			(xy 304.458261 -315.68632) (xy 304.481132 -315.729897) (xy 304.496716 -315.776578) (xy 304.504611 -315.825155)
			(xy 304.505106 -315.849762) (xy 305.793914 -315.849762) (xy 305.797874 -315.800708) (xy 305.809651 -315.752924)
			(xy 305.828942 -315.707648) (xy 305.855245 -315.666052) (xy 305.88788 -315.629215) (xy 305.926001 -315.59809)
			(xy 305.968622 -315.573483) (xy 306.014638 -315.556031) (xy 306.062857 -315.546187) (xy 306.112032 -315.544206)
			(xy 306.160887 -315.550138) (xy 306.208158 -315.56383) (xy 306.25262 -315.584928) (xy 306.293123 -315.612884)
			(xy 306.328616 -315.646976) (xy 306.358181 -315.68632) (xy 306.381052 -315.729897) (xy 306.396636 -315.776578)
			(xy 306.404531 -315.825155) (xy 306.405026 -315.849762) (xy 307.694088 -315.849762) (xy 307.698048 -315.800708)
			(xy 307.709825 -315.752924) (xy 307.729116 -315.707648) (xy 307.755419 -315.666052) (xy 307.788054 -315.629215)
			(xy 307.826175 -315.59809) (xy 307.868796 -315.573483) (xy 307.914812 -315.556031) (xy 307.963031 -315.546187)
			(xy 308.012206 -315.544206) (xy 308.061061 -315.550138) (xy 308.108332 -315.56383) (xy 308.152794 -315.584928)
			(xy 308.193297 -315.612884) (xy 308.22879 -315.646976) (xy 308.258355 -315.68632) (xy 308.281226 -315.729897)
			(xy 308.29681 -315.776578) (xy 308.304705 -315.825155) (xy 308.3052 -315.849762) (xy 309.594008 -315.849762)
			(xy 309.597968 -315.800708) (xy 309.609745 -315.752924) (xy 309.629036 -315.707648) (xy 309.655339 -315.666052)
			(xy 309.687974 -315.629215) (xy 309.726095 -315.59809) (xy 309.768716 -315.573483) (xy 309.814732 -315.556031)
			(xy 309.862951 -315.546187) (xy 309.912126 -315.544206) (xy 309.960981 -315.550138) (xy 310.008252 -315.56383)
			(xy 310.052714 -315.584928) (xy 310.093217 -315.612884) (xy 310.12871 -315.646976) (xy 310.158275 -315.68632)
			(xy 310.181146 -315.729897) (xy 310.19673 -315.776578) (xy 310.204625 -315.825155) (xy 310.20512 -315.849762)
			(xy 311.493928 -315.849762) (xy 311.497888 -315.800708) (xy 311.509665 -315.752924) (xy 311.528956 -315.707648)
			(xy 311.555259 -315.666052) (xy 311.587894 -315.629215) (xy 311.626015 -315.59809) (xy 311.668636 -315.573483)
			(xy 311.714652 -315.556031) (xy 311.762871 -315.546187) (xy 311.812046 -315.544206) (xy 311.860901 -315.550138)
			(xy 311.908172 -315.56383) (xy 311.952634 -315.584928) (xy 311.993137 -315.612884) (xy 312.02863 -315.646976)
			(xy 312.058195 -315.68632) (xy 312.081066 -315.729897) (xy 312.09665 -315.776578) (xy 312.104545 -315.825155)
			(xy 312.10504 -315.849762) (xy 387.694182 -315.849762) (xy 387.698142 -315.800708) (xy 387.709919 -315.752924)
			(xy 387.72921 -315.707648) (xy 387.755513 -315.666052) (xy 387.788148 -315.629215) (xy 387.826269 -315.59809)
			(xy 387.86889 -315.573483) (xy 387.914906 -315.556031) (xy 387.963125 -315.546187) (xy 388.0123 -315.544206)
			(xy 388.061155 -315.550138) (xy 388.108426 -315.56383) (xy 388.152888 -315.584928) (xy 388.193391 -315.612884)
			(xy 388.228884 -315.646976) (xy 388.258449 -315.68632) (xy 388.28132 -315.729897) (xy 388.296904 -315.776578)
			(xy 388.304799 -315.825155) (xy 388.305294 -315.849762) (xy 389.594102 -315.849762) (xy 389.598062 -315.800708)
			(xy 389.609839 -315.752924) (xy 389.62913 -315.707648) (xy 389.655433 -315.666052) (xy 389.688068 -315.629215)
			(xy 389.726189 -315.59809) (xy 389.76881 -315.573483) (xy 389.814826 -315.556031) (xy 389.863045 -315.546187)
			(xy 389.91222 -315.544206) (xy 389.961075 -315.550138) (xy 390.008346 -315.56383) (xy 390.052808 -315.584928)
			(xy 390.093311 -315.612884) (xy 390.128804 -315.646976) (xy 390.158369 -315.68632) (xy 390.18124 -315.729897)
			(xy 390.196824 -315.776578) (xy 390.204719 -315.825155) (xy 390.205214 -315.849762) (xy 391.494022 -315.849762)
			(xy 391.497982 -315.800708) (xy 391.509759 -315.752924) (xy 391.52905 -315.707648) (xy 391.555353 -315.666052)
			(xy 391.587988 -315.629215) (xy 391.626109 -315.59809) (xy 391.66873 -315.573483) (xy 391.714746 -315.556031)
			(xy 391.762965 -315.546187) (xy 391.81214 -315.544206) (xy 391.860995 -315.550138) (xy 391.908266 -315.56383)
			(xy 391.952728 -315.584928) (xy 391.993231 -315.612884) (xy 392.028724 -315.646976) (xy 392.058289 -315.68632)
			(xy 392.08116 -315.729897) (xy 392.096744 -315.776578) (xy 392.104639 -315.825155) (xy 392.105134 -315.849762)
			(xy 393.394196 -315.849762) (xy 393.398156 -315.800708) (xy 393.409933 -315.752924) (xy 393.429224 -315.707648)
			(xy 393.455527 -315.666052) (xy 393.488162 -315.629215) (xy 393.526283 -315.59809) (xy 393.568904 -315.573483)
			(xy 393.61492 -315.556031) (xy 393.663139 -315.546187) (xy 393.712314 -315.544206) (xy 393.761169 -315.550138)
			(xy 393.80844 -315.56383) (xy 393.852902 -315.584928) (xy 393.893405 -315.612884) (xy 393.928898 -315.646976)
			(xy 393.958463 -315.68632) (xy 393.981334 -315.729897) (xy 393.996918 -315.776578) (xy 394.004813 -315.825155)
			(xy 394.005308 -315.849762) (xy 395.294116 -315.849762) (xy 395.298076 -315.800708) (xy 395.309853 -315.752924)
			(xy 395.329144 -315.707648) (xy 395.355447 -315.666052) (xy 395.388082 -315.629215) (xy 395.426203 -315.59809)
			(xy 395.468824 -315.573483) (xy 395.51484 -315.556031) (xy 395.563059 -315.546187) (xy 395.612234 -315.544206)
			(xy 395.661089 -315.550138) (xy 395.70836 -315.56383) (xy 395.752822 -315.584928) (xy 395.793325 -315.612884)
			(xy 395.828818 -315.646976) (xy 395.858383 -315.68632) (xy 395.881254 -315.729897) (xy 395.896838 -315.776578)
			(xy 395.904733 -315.825155) (xy 395.905228 -315.849762) (xy 397.194036 -315.849762) (xy 397.197996 -315.800708)
			(xy 397.209773 -315.752924) (xy 397.229064 -315.707648) (xy 397.255367 -315.666052) (xy 397.288002 -315.629215)
			(xy 397.326123 -315.59809) (xy 397.368744 -315.573483) (xy 397.41476 -315.556031) (xy 397.462979 -315.546187)
			(xy 397.512154 -315.544206) (xy 397.561009 -315.550138) (xy 397.60828 -315.56383) (xy 397.652742 -315.584928)
			(xy 397.693245 -315.612884) (xy 397.728738 -315.646976) (xy 397.758303 -315.68632) (xy 397.781174 -315.729897)
			(xy 397.796758 -315.776578) (xy 397.804653 -315.825155) (xy 397.805148 -315.849762) (xy 399.09421 -315.849762)
			(xy 399.09817 -315.800708) (xy 399.109947 -315.752924) (xy 399.129238 -315.707648) (xy 399.155541 -315.666052)
			(xy 399.188176 -315.629215) (xy 399.226297 -315.59809) (xy 399.268918 -315.573483) (xy 399.314934 -315.556031)
			(xy 399.363153 -315.546187) (xy 399.412328 -315.544206) (xy 399.461183 -315.550138) (xy 399.508454 -315.56383)
			(xy 399.552916 -315.584928) (xy 399.593419 -315.612884) (xy 399.628912 -315.646976) (xy 399.658477 -315.68632)
			(xy 399.681348 -315.729897) (xy 399.696932 -315.776578) (xy 399.704827 -315.825155) (xy 399.705322 -315.849762)
			(xy 400.99413 -315.849762) (xy 400.99809 -315.800708) (xy 401.009867 -315.752924) (xy 401.029158 -315.707648)
			(xy 401.055461 -315.666052) (xy 401.088096 -315.629215) (xy 401.126217 -315.59809) (xy 401.168838 -315.573483)
			(xy 401.214854 -315.556031) (xy 401.263073 -315.546187) (xy 401.312248 -315.544206) (xy 401.361103 -315.550138)
			(xy 401.408374 -315.56383) (xy 401.452836 -315.584928) (xy 401.493339 -315.612884) (xy 401.528832 -315.646976)
			(xy 401.558397 -315.68632) (xy 401.581268 -315.729897) (xy 401.596852 -315.776578) (xy 401.604747 -315.825155)
			(xy 401.605242 -315.849762) (xy 402.89405 -315.849762) (xy 402.89801 -315.800708) (xy 402.909787 -315.752924)
			(xy 402.929078 -315.707648) (xy 402.955381 -315.666052) (xy 402.988016 -315.629215) (xy 403.026137 -315.59809)
			(xy 403.068758 -315.573483) (xy 403.114774 -315.556031) (xy 403.162993 -315.546187) (xy 403.212168 -315.544206)
			(xy 403.261023 -315.550138) (xy 403.308294 -315.56383) (xy 403.352756 -315.584928) (xy 403.393259 -315.612884)
			(xy 403.428752 -315.646976) (xy 403.458317 -315.68632) (xy 403.481188 -315.729897) (xy 403.496772 -315.776578)
			(xy 403.504667 -315.825155) (xy 403.505162 -315.849762) (xy 404.794224 -315.849762) (xy 404.798184 -315.800708)
			(xy 404.809961 -315.752924) (xy 404.829252 -315.707648) (xy 404.855555 -315.666052) (xy 404.88819 -315.629215)
			(xy 404.926311 -315.59809) (xy 404.968932 -315.573483) (xy 405.014948 -315.556031) (xy 405.063167 -315.546187)
			(xy 405.112342 -315.544206) (xy 405.161197 -315.550138) (xy 405.208468 -315.56383) (xy 405.25293 -315.584928)
			(xy 405.293433 -315.612884) (xy 405.328926 -315.646976) (xy 405.358491 -315.68632) (xy 405.381362 -315.729897)
			(xy 405.396946 -315.776578) (xy 405.404841 -315.825155) (xy 405.405336 -315.849762) (xy 406.694144 -315.849762)
			(xy 406.698104 -315.800708) (xy 406.709881 -315.752924) (xy 406.729172 -315.707648) (xy 406.755475 -315.666052)
			(xy 406.78811 -315.629215) (xy 406.826231 -315.59809) (xy 406.868852 -315.573483) (xy 406.914868 -315.556031)
			(xy 406.963087 -315.546187) (xy 407.012262 -315.544206) (xy 407.061117 -315.550138) (xy 407.108388 -315.56383)
			(xy 407.15285 -315.584928) (xy 407.193353 -315.612884) (xy 407.228846 -315.646976) (xy 407.258411 -315.68632)
			(xy 407.281282 -315.729897) (xy 407.296866 -315.776578) (xy 407.304761 -315.825155) (xy 407.305256 -315.849762)
			(xy 408.594064 -315.849762) (xy 408.598024 -315.800708) (xy 408.609801 -315.752924) (xy 408.629092 -315.707648)
			(xy 408.655395 -315.666052) (xy 408.68803 -315.629215) (xy 408.726151 -315.59809) (xy 408.768772 -315.573483)
			(xy 408.814788 -315.556031) (xy 408.863007 -315.546187) (xy 408.912182 -315.544206) (xy 408.961037 -315.550138)
			(xy 409.008308 -315.56383) (xy 409.05277 -315.584928) (xy 409.093273 -315.612884) (xy 409.128766 -315.646976)
			(xy 409.158331 -315.68632) (xy 409.181202 -315.729897) (xy 409.196786 -315.776578) (xy 409.204681 -315.825155)
			(xy 409.205176 -315.849762) (xy 410.493984 -315.849762) (xy 410.497944 -315.800708) (xy 410.509721 -315.752924)
			(xy 410.529012 -315.707648) (xy 410.555315 -315.666052) (xy 410.58795 -315.629215) (xy 410.626071 -315.59809)
			(xy 410.668692 -315.573483) (xy 410.714708 -315.556031) (xy 410.762927 -315.546187) (xy 410.812102 -315.544206)
			(xy 410.860957 -315.550138) (xy 410.908228 -315.56383) (xy 410.95269 -315.584928) (xy 410.993193 -315.612884)
			(xy 411.028686 -315.646976) (xy 411.058251 -315.68632) (xy 411.081122 -315.729897) (xy 411.096706 -315.776578)
			(xy 411.104601 -315.825155) (xy 411.105096 -315.849762) (xy 412.394158 -315.849762) (xy 412.398118 -315.800708)
			(xy 412.409895 -315.752924) (xy 412.429186 -315.707648) (xy 412.455489 -315.666052) (xy 412.488124 -315.629215)
			(xy 412.526245 -315.59809) (xy 412.568866 -315.573483) (xy 412.614882 -315.556031) (xy 412.663101 -315.546187)
			(xy 412.712276 -315.544206) (xy 412.761131 -315.550138) (xy 412.808402 -315.56383) (xy 412.852864 -315.584928)
			(xy 412.893367 -315.612884) (xy 412.92886 -315.646976) (xy 412.958425 -315.68632) (xy 412.981296 -315.729897)
			(xy 412.99688 -315.776578) (xy 413.004775 -315.825155) (xy 413.00527 -315.849762) (xy 414.294078 -315.849762)
			(xy 414.298038 -315.800708) (xy 414.309815 -315.752924) (xy 414.329106 -315.707648) (xy 414.355409 -315.666052)
			(xy 414.388044 -315.629215) (xy 414.426165 -315.59809) (xy 414.468786 -315.573483) (xy 414.514802 -315.556031)
			(xy 414.563021 -315.546187) (xy 414.612196 -315.544206) (xy 414.661051 -315.550138) (xy 414.708322 -315.56383)
			(xy 414.752784 -315.584928) (xy 414.793287 -315.612884) (xy 414.82878 -315.646976) (xy 414.858345 -315.68632)
			(xy 414.881216 -315.729897) (xy 414.8968 -315.776578) (xy 414.904695 -315.825155) (xy 414.90519 -315.849762)
			(xy 416.193998 -315.849762) (xy 416.197958 -315.800708) (xy 416.209735 -315.752924) (xy 416.229026 -315.707648)
			(xy 416.255329 -315.666052) (xy 416.287964 -315.629215) (xy 416.326085 -315.59809) (xy 416.368706 -315.573483)
			(xy 416.414722 -315.556031) (xy 416.462941 -315.546187) (xy 416.512116 -315.544206) (xy 416.560971 -315.550138)
			(xy 416.608242 -315.56383) (xy 416.652704 -315.584928) (xy 416.693207 -315.612884) (xy 416.7287 -315.646976)
			(xy 416.758265 -315.68632) (xy 416.781136 -315.729897) (xy 416.79672 -315.776578) (xy 416.804615 -315.825155)
			(xy 416.80511 -315.849762) (xy 418.094172 -315.849762) (xy 418.098132 -315.800708) (xy 418.109909 -315.752924)
			(xy 418.1292 -315.707648) (xy 418.155503 -315.666052) (xy 418.188138 -315.629215) (xy 418.226259 -315.59809)
			(xy 418.26888 -315.573483) (xy 418.314896 -315.556031) (xy 418.363115 -315.546187) (xy 418.41229 -315.544206)
			(xy 418.461145 -315.550138) (xy 418.508416 -315.56383) (xy 418.552878 -315.584928) (xy 418.593381 -315.612884)
			(xy 418.628874 -315.646976) (xy 418.658439 -315.68632) (xy 418.68131 -315.729897) (xy 418.696894 -315.776578)
			(xy 418.704789 -315.825155) (xy 418.705284 -315.849762) (xy 419.994092 -315.849762) (xy 419.998052 -315.800708)
			(xy 420.009829 -315.752924) (xy 420.02912 -315.707648) (xy 420.055423 -315.666052) (xy 420.088058 -315.629215)
			(xy 420.126179 -315.59809) (xy 420.1688 -315.573483) (xy 420.214816 -315.556031) (xy 420.263035 -315.546187)
			(xy 420.31221 -315.544206) (xy 420.361065 -315.550138) (xy 420.408336 -315.56383) (xy 420.452798 -315.584928)
			(xy 420.493301 -315.612884) (xy 420.528794 -315.646976) (xy 420.558359 -315.68632) (xy 420.58123 -315.729897)
			(xy 420.596814 -315.776578) (xy 420.604709 -315.825155) (xy 420.605204 -315.849762) (xy 421.894012 -315.849762)
			(xy 421.897972 -315.800708) (xy 421.909749 -315.752924) (xy 421.92904 -315.707648) (xy 421.955343 -315.666052)
			(xy 421.987978 -315.629215) (xy 422.026099 -315.59809) (xy 422.06872 -315.573483) (xy 422.114736 -315.556031)
			(xy 422.162955 -315.546187) (xy 422.21213 -315.544206) (xy 422.260985 -315.550138) (xy 422.308256 -315.56383)
			(xy 422.352718 -315.584928) (xy 422.393221 -315.612884) (xy 422.428714 -315.646976) (xy 422.458279 -315.68632)
			(xy 422.48115 -315.729897) (xy 422.496734 -315.776578) (xy 422.504629 -315.825155) (xy 422.505124 -315.849762)
			(xy 423.794186 -315.849762) (xy 423.798146 -315.800708) (xy 423.809923 -315.752924) (xy 423.829214 -315.707648)
			(xy 423.855517 -315.666052) (xy 423.888152 -315.629215) (xy 423.926273 -315.59809) (xy 423.968894 -315.573483)
			(xy 424.01491 -315.556031) (xy 424.063129 -315.546187) (xy 424.112304 -315.544206) (xy 424.161159 -315.550138)
			(xy 424.20843 -315.56383) (xy 424.252892 -315.584928) (xy 424.293395 -315.612884) (xy 424.328888 -315.646976)
			(xy 424.358453 -315.68632) (xy 424.381324 -315.729897) (xy 424.396908 -315.776578) (xy 424.404803 -315.825155)
			(xy 424.405298 -315.849762) (xy 425.694106 -315.849762) (xy 425.698066 -315.800708) (xy 425.709843 -315.752924)
			(xy 425.729134 -315.707648) (xy 425.755437 -315.666052) (xy 425.788072 -315.629215) (xy 425.826193 -315.59809)
			(xy 425.868814 -315.573483) (xy 425.91483 -315.556031) (xy 425.963049 -315.546187) (xy 426.012224 -315.544206)
			(xy 426.061079 -315.550138) (xy 426.10835 -315.56383) (xy 426.152812 -315.584928) (xy 426.193315 -315.612884)
			(xy 426.228808 -315.646976) (xy 426.258373 -315.68632) (xy 426.281244 -315.729897) (xy 426.296828 -315.776578)
			(xy 426.304723 -315.825155) (xy 426.305218 -315.849762) (xy 427.594026 -315.849762) (xy 427.597986 -315.800708)
			(xy 427.609763 -315.752924) (xy 427.629054 -315.707648) (xy 427.655357 -315.666052) (xy 427.687992 -315.629215)
			(xy 427.726113 -315.59809) (xy 427.768734 -315.573483) (xy 427.81475 -315.556031) (xy 427.862969 -315.546187)
			(xy 427.912144 -315.544206) (xy 427.960999 -315.550138) (xy 428.00827 -315.56383) (xy 428.052732 -315.584928)
			(xy 428.093235 -315.612884) (xy 428.128728 -315.646976) (xy 428.158293 -315.68632) (xy 428.181164 -315.729897)
			(xy 428.196748 -315.776578) (xy 428.204643 -315.825155) (xy 428.205138 -315.849762) (xy 428.204643 -315.874369)
			(xy 428.196748 -315.922946) (xy 428.181164 -315.969627) (xy 428.158293 -316.013204) (xy 428.128728 -316.052548)
			(xy 428.093235 -316.08664) (xy 428.052732 -316.114596) (xy 428.00827 -316.135694) (xy 427.960999 -316.149386)
			(xy 427.912144 -316.155318) (xy 427.862969 -316.153337) (xy 427.81475 -316.143493) (xy 427.768734 -316.126041)
			(xy 427.726113 -316.101434) (xy 427.687992 -316.070309) (xy 427.655357 -316.033472) (xy 427.629054 -315.991876)
			(xy 427.609763 -315.9466) (xy 427.597986 -315.898816) (xy 427.594026 -315.849762) (xy 426.305218 -315.849762)
			(xy 426.304723 -315.874369) (xy 426.296828 -315.922946) (xy 426.281244 -315.969627) (xy 426.258373 -316.013204)
			(xy 426.228808 -316.052548) (xy 426.193315 -316.08664) (xy 426.152812 -316.114596) (xy 426.10835 -316.135694)
			(xy 426.061079 -316.149386) (xy 426.012224 -316.155318) (xy 425.963049 -316.153337) (xy 425.91483 -316.143493)
			(xy 425.868814 -316.126041) (xy 425.826193 -316.101434) (xy 425.788072 -316.070309) (xy 425.755437 -316.033472)
			(xy 425.729134 -315.991876) (xy 425.709843 -315.9466) (xy 425.698066 -315.898816) (xy 425.694106 -315.849762)
			(xy 424.405298 -315.849762) (xy 424.404803 -315.874369) (xy 424.396908 -315.922946) (xy 424.381324 -315.969627)
			(xy 424.358453 -316.013204) (xy 424.328888 -316.052548) (xy 424.293395 -316.08664) (xy 424.252892 -316.114596)
			(xy 424.20843 -316.135694) (xy 424.161159 -316.149386) (xy 424.112304 -316.155318) (xy 424.063129 -316.153337)
			(xy 424.01491 -316.143493) (xy 423.968894 -316.126041) (xy 423.926273 -316.101434) (xy 423.888152 -316.070309)
			(xy 423.855517 -316.033472) (xy 423.829214 -315.991876) (xy 423.809923 -315.9466) (xy 423.798146 -315.898816)
			(xy 423.794186 -315.849762) (xy 422.505124 -315.849762) (xy 422.504629 -315.874369) (xy 422.496734 -315.922946)
			(xy 422.48115 -315.969627) (xy 422.458279 -316.013204) (xy 422.428714 -316.052548) (xy 422.393221 -316.08664)
			(xy 422.352718 -316.114596) (xy 422.308256 -316.135694) (xy 422.260985 -316.149386) (xy 422.21213 -316.155318)
			(xy 422.162955 -316.153337) (xy 422.114736 -316.143493) (xy 422.06872 -316.126041) (xy 422.026099 -316.101434)
			(xy 421.987978 -316.070309) (xy 421.955343 -316.033472) (xy 421.92904 -315.991876) (xy 421.909749 -315.9466)
			(xy 421.897972 -315.898816) (xy 421.894012 -315.849762) (xy 420.605204 -315.849762) (xy 420.604709 -315.874369)
			(xy 420.596814 -315.922946) (xy 420.58123 -315.969627) (xy 420.558359 -316.013204) (xy 420.528794 -316.052548)
			(xy 420.493301 -316.08664) (xy 420.452798 -316.114596) (xy 420.408336 -316.135694) (xy 420.361065 -316.149386)
			(xy 420.31221 -316.155318) (xy 420.263035 -316.153337) (xy 420.214816 -316.143493) (xy 420.1688 -316.126041)
			(xy 420.126179 -316.101434) (xy 420.088058 -316.070309) (xy 420.055423 -316.033472) (xy 420.02912 -315.991876)
			(xy 420.009829 -315.9466) (xy 419.998052 -315.898816) (xy 419.994092 -315.849762) (xy 418.705284 -315.849762)
			(xy 418.704789 -315.874369) (xy 418.696894 -315.922946) (xy 418.68131 -315.969627) (xy 418.658439 -316.013204)
			(xy 418.628874 -316.052548) (xy 418.593381 -316.08664) (xy 418.552878 -316.114596) (xy 418.508416 -316.135694)
			(xy 418.461145 -316.149386) (xy 418.41229 -316.155318) (xy 418.363115 -316.153337) (xy 418.314896 -316.143493)
			(xy 418.26888 -316.126041) (xy 418.226259 -316.101434) (xy 418.188138 -316.070309) (xy 418.155503 -316.033472)
			(xy 418.1292 -315.991876) (xy 418.109909 -315.9466) (xy 418.098132 -315.898816) (xy 418.094172 -315.849762)
			(xy 416.80511 -315.849762) (xy 416.804615 -315.874369) (xy 416.79672 -315.922946) (xy 416.781136 -315.969627)
			(xy 416.758265 -316.013204) (xy 416.7287 -316.052548) (xy 416.693207 -316.08664) (xy 416.652704 -316.114596)
			(xy 416.608242 -316.135694) (xy 416.560971 -316.149386) (xy 416.512116 -316.155318) (xy 416.462941 -316.153337)
			(xy 416.414722 -316.143493) (xy 416.368706 -316.126041) (xy 416.326085 -316.101434) (xy 416.287964 -316.070309)
			(xy 416.255329 -316.033472) (xy 416.229026 -315.991876) (xy 416.209735 -315.9466) (xy 416.197958 -315.898816)
			(xy 416.193998 -315.849762) (xy 414.90519 -315.849762) (xy 414.904695 -315.874369) (xy 414.8968 -315.922946)
			(xy 414.881216 -315.969627) (xy 414.858345 -316.013204) (xy 414.82878 -316.052548) (xy 414.793287 -316.08664)
			(xy 414.752784 -316.114596) (xy 414.708322 -316.135694) (xy 414.661051 -316.149386) (xy 414.612196 -316.155318)
			(xy 414.563021 -316.153337) (xy 414.514802 -316.143493) (xy 414.468786 -316.126041) (xy 414.426165 -316.101434)
			(xy 414.388044 -316.070309) (xy 414.355409 -316.033472) (xy 414.329106 -315.991876) (xy 414.309815 -315.9466)
			(xy 414.298038 -315.898816) (xy 414.294078 -315.849762) (xy 413.00527 -315.849762) (xy 413.004775 -315.874369)
			(xy 412.99688 -315.922946) (xy 412.981296 -315.969627) (xy 412.958425 -316.013204) (xy 412.92886 -316.052548)
			(xy 412.893367 -316.08664) (xy 412.852864 -316.114596) (xy 412.808402 -316.135694) (xy 412.761131 -316.149386)
			(xy 412.712276 -316.155318) (xy 412.663101 -316.153337) (xy 412.614882 -316.143493) (xy 412.568866 -316.126041)
			(xy 412.526245 -316.101434) (xy 412.488124 -316.070309) (xy 412.455489 -316.033472) (xy 412.429186 -315.991876)
			(xy 412.409895 -315.9466) (xy 412.398118 -315.898816) (xy 412.394158 -315.849762) (xy 411.105096 -315.849762)
			(xy 411.104601 -315.874369) (xy 411.096706 -315.922946) (xy 411.081122 -315.969627) (xy 411.058251 -316.013204)
			(xy 411.028686 -316.052548) (xy 410.993193 -316.08664) (xy 410.95269 -316.114596) (xy 410.908228 -316.135694)
			(xy 410.860957 -316.149386) (xy 410.812102 -316.155318) (xy 410.762927 -316.153337) (xy 410.714708 -316.143493)
			(xy 410.668692 -316.126041) (xy 410.626071 -316.101434) (xy 410.58795 -316.070309) (xy 410.555315 -316.033472)
			(xy 410.529012 -315.991876) (xy 410.509721 -315.9466) (xy 410.497944 -315.898816) (xy 410.493984 -315.849762)
			(xy 409.205176 -315.849762) (xy 409.204681 -315.874369) (xy 409.196786 -315.922946) (xy 409.181202 -315.969627)
			(xy 409.158331 -316.013204) (xy 409.128766 -316.052548) (xy 409.093273 -316.08664) (xy 409.05277 -316.114596)
			(xy 409.008308 -316.135694) (xy 408.961037 -316.149386) (xy 408.912182 -316.155318) (xy 408.863007 -316.153337)
			(xy 408.814788 -316.143493) (xy 408.768772 -316.126041) (xy 408.726151 -316.101434) (xy 408.68803 -316.070309)
			(xy 408.655395 -316.033472) (xy 408.629092 -315.991876) (xy 408.609801 -315.9466) (xy 408.598024 -315.898816)
			(xy 408.594064 -315.849762) (xy 407.305256 -315.849762) (xy 407.304761 -315.874369) (xy 407.296866 -315.922946)
			(xy 407.281282 -315.969627) (xy 407.258411 -316.013204) (xy 407.228846 -316.052548) (xy 407.193353 -316.08664)
			(xy 407.15285 -316.114596) (xy 407.108388 -316.135694) (xy 407.061117 -316.149386) (xy 407.012262 -316.155318)
			(xy 406.963087 -316.153337) (xy 406.914868 -316.143493) (xy 406.868852 -316.126041) (xy 406.826231 -316.101434)
			(xy 406.78811 -316.070309) (xy 406.755475 -316.033472) (xy 406.729172 -315.991876) (xy 406.709881 -315.9466)
			(xy 406.698104 -315.898816) (xy 406.694144 -315.849762) (xy 405.405336 -315.849762) (xy 405.404841 -315.874369)
			(xy 405.396946 -315.922946) (xy 405.381362 -315.969627) (xy 405.358491 -316.013204) (xy 405.328926 -316.052548)
			(xy 405.293433 -316.08664) (xy 405.25293 -316.114596) (xy 405.208468 -316.135694) (xy 405.161197 -316.149386)
			(xy 405.112342 -316.155318) (xy 405.063167 -316.153337) (xy 405.014948 -316.143493) (xy 404.968932 -316.126041)
			(xy 404.926311 -316.101434) (xy 404.88819 -316.070309) (xy 404.855555 -316.033472) (xy 404.829252 -315.991876)
			(xy 404.809961 -315.9466) (xy 404.798184 -315.898816) (xy 404.794224 -315.849762) (xy 403.505162 -315.849762)
			(xy 403.504667 -315.874369) (xy 403.496772 -315.922946) (xy 403.481188 -315.969627) (xy 403.458317 -316.013204)
			(xy 403.428752 -316.052548) (xy 403.393259 -316.08664) (xy 403.352756 -316.114596) (xy 403.308294 -316.135694)
			(xy 403.261023 -316.149386) (xy 403.212168 -316.155318) (xy 403.162993 -316.153337) (xy 403.114774 -316.143493)
			(xy 403.068758 -316.126041) (xy 403.026137 -316.101434) (xy 402.988016 -316.070309) (xy 402.955381 -316.033472)
			(xy 402.929078 -315.991876) (xy 402.909787 -315.9466) (xy 402.89801 -315.898816) (xy 402.89405 -315.849762)
			(xy 401.605242 -315.849762) (xy 401.604747 -315.874369) (xy 401.596852 -315.922946) (xy 401.581268 -315.969627)
			(xy 401.558397 -316.013204) (xy 401.528832 -316.052548) (xy 401.493339 -316.08664) (xy 401.452836 -316.114596)
			(xy 401.408374 -316.135694) (xy 401.361103 -316.149386) (xy 401.312248 -316.155318) (xy 401.263073 -316.153337)
			(xy 401.214854 -316.143493) (xy 401.168838 -316.126041) (xy 401.126217 -316.101434) (xy 401.088096 -316.070309)
			(xy 401.055461 -316.033472) (xy 401.029158 -315.991876) (xy 401.009867 -315.9466) (xy 400.99809 -315.898816)
			(xy 400.99413 -315.849762) (xy 399.705322 -315.849762) (xy 399.704827 -315.874369) (xy 399.696932 -315.922946)
			(xy 399.681348 -315.969627) (xy 399.658477 -316.013204) (xy 399.628912 -316.052548) (xy 399.593419 -316.08664)
			(xy 399.552916 -316.114596) (xy 399.508454 -316.135694) (xy 399.461183 -316.149386) (xy 399.412328 -316.155318)
			(xy 399.363153 -316.153337) (xy 399.314934 -316.143493) (xy 399.268918 -316.126041) (xy 399.226297 -316.101434)
			(xy 399.188176 -316.070309) (xy 399.155541 -316.033472) (xy 399.129238 -315.991876) (xy 399.109947 -315.9466)
			(xy 399.09817 -315.898816) (xy 399.09421 -315.849762) (xy 397.805148 -315.849762) (xy 397.804653 -315.874369)
			(xy 397.796758 -315.922946) (xy 397.781174 -315.969627) (xy 397.758303 -316.013204) (xy 397.728738 -316.052548)
			(xy 397.693245 -316.08664) (xy 397.652742 -316.114596) (xy 397.60828 -316.135694) (xy 397.561009 -316.149386)
			(xy 397.512154 -316.155318) (xy 397.462979 -316.153337) (xy 397.41476 -316.143493) (xy 397.368744 -316.126041)
			(xy 397.326123 -316.101434) (xy 397.288002 -316.070309) (xy 397.255367 -316.033472) (xy 397.229064 -315.991876)
			(xy 397.209773 -315.9466) (xy 397.197996 -315.898816) (xy 397.194036 -315.849762) (xy 395.905228 -315.849762)
			(xy 395.904733 -315.874369) (xy 395.896838 -315.922946) (xy 395.881254 -315.969627) (xy 395.858383 -316.013204)
			(xy 395.828818 -316.052548) (xy 395.793325 -316.08664) (xy 395.752822 -316.114596) (xy 395.70836 -316.135694)
			(xy 395.661089 -316.149386) (xy 395.612234 -316.155318) (xy 395.563059 -316.153337) (xy 395.51484 -316.143493)
			(xy 395.468824 -316.126041) (xy 395.426203 -316.101434) (xy 395.388082 -316.070309) (xy 395.355447 -316.033472)
			(xy 395.329144 -315.991876) (xy 395.309853 -315.9466) (xy 395.298076 -315.898816) (xy 395.294116 -315.849762)
			(xy 394.005308 -315.849762) (xy 394.004813 -315.874369) (xy 393.996918 -315.922946) (xy 393.981334 -315.969627)
			(xy 393.958463 -316.013204) (xy 393.928898 -316.052548) (xy 393.893405 -316.08664) (xy 393.852902 -316.114596)
			(xy 393.80844 -316.135694) (xy 393.761169 -316.149386) (xy 393.712314 -316.155318) (xy 393.663139 -316.153337)
			(xy 393.61492 -316.143493) (xy 393.568904 -316.126041) (xy 393.526283 -316.101434) (xy 393.488162 -316.070309)
			(xy 393.455527 -316.033472) (xy 393.429224 -315.991876) (xy 393.409933 -315.9466) (xy 393.398156 -315.898816)
			(xy 393.394196 -315.849762) (xy 392.105134 -315.849762) (xy 392.104639 -315.874369) (xy 392.096744 -315.922946)
			(xy 392.08116 -315.969627) (xy 392.058289 -316.013204) (xy 392.028724 -316.052548) (xy 391.993231 -316.08664)
			(xy 391.952728 -316.114596) (xy 391.908266 -316.135694) (xy 391.860995 -316.149386) (xy 391.81214 -316.155318)
			(xy 391.762965 -316.153337) (xy 391.714746 -316.143493) (xy 391.66873 -316.126041) (xy 391.626109 -316.101434)
			(xy 391.587988 -316.070309) (xy 391.555353 -316.033472) (xy 391.52905 -315.991876) (xy 391.509759 -315.9466)
			(xy 391.497982 -315.898816) (xy 391.494022 -315.849762) (xy 390.205214 -315.849762) (xy 390.204719 -315.874369)
			(xy 390.196824 -315.922946) (xy 390.18124 -315.969627) (xy 390.158369 -316.013204) (xy 390.128804 -316.052548)
			(xy 390.093311 -316.08664) (xy 390.052808 -316.114596) (xy 390.008346 -316.135694) (xy 389.961075 -316.149386)
			(xy 389.91222 -316.155318) (xy 389.863045 -316.153337) (xy 389.814826 -316.143493) (xy 389.76881 -316.126041)
			(xy 389.726189 -316.101434) (xy 389.688068 -316.070309) (xy 389.655433 -316.033472) (xy 389.62913 -315.991876)
			(xy 389.609839 -315.9466) (xy 389.598062 -315.898816) (xy 389.594102 -315.849762) (xy 388.305294 -315.849762)
			(xy 388.304799 -315.874369) (xy 388.296904 -315.922946) (xy 388.28132 -315.969627) (xy 388.258449 -316.013204)
			(xy 388.228884 -316.052548) (xy 388.193391 -316.08664) (xy 388.152888 -316.114596) (xy 388.108426 -316.135694)
			(xy 388.061155 -316.149386) (xy 388.0123 -316.155318) (xy 387.963125 -316.153337) (xy 387.914906 -316.143493)
			(xy 387.86889 -316.126041) (xy 387.826269 -316.101434) (xy 387.788148 -316.070309) (xy 387.755513 -316.033472)
			(xy 387.72921 -315.991876) (xy 387.709919 -315.9466) (xy 387.698142 -315.898816) (xy 387.694182 -315.849762)
			(xy 312.10504 -315.849762) (xy 312.104545 -315.874369) (xy 312.09665 -315.922946) (xy 312.081066 -315.969627)
			(xy 312.058195 -316.013204) (xy 312.02863 -316.052548) (xy 311.993137 -316.08664) (xy 311.952634 -316.114596)
			(xy 311.908172 -316.135694) (xy 311.860901 -316.149386) (xy 311.812046 -316.155318) (xy 311.762871 -316.153337)
			(xy 311.714652 -316.143493) (xy 311.668636 -316.126041) (xy 311.626015 -316.101434) (xy 311.587894 -316.070309)
			(xy 311.555259 -316.033472) (xy 311.528956 -315.991876) (xy 311.509665 -315.9466) (xy 311.497888 -315.898816)
			(xy 311.493928 -315.849762) (xy 310.20512 -315.849762) (xy 310.204625 -315.874369) (xy 310.19673 -315.922946)
			(xy 310.181146 -315.969627) (xy 310.158275 -316.013204) (xy 310.12871 -316.052548) (xy 310.093217 -316.08664)
			(xy 310.052714 -316.114596) (xy 310.008252 -316.135694) (xy 309.960981 -316.149386) (xy 309.912126 -316.155318)
			(xy 309.862951 -316.153337) (xy 309.814732 -316.143493) (xy 309.768716 -316.126041) (xy 309.726095 -316.101434)
			(xy 309.687974 -316.070309) (xy 309.655339 -316.033472) (xy 309.629036 -315.991876) (xy 309.609745 -315.9466)
			(xy 309.597968 -315.898816) (xy 309.594008 -315.849762) (xy 308.3052 -315.849762) (xy 308.304705 -315.874369)
			(xy 308.29681 -315.922946) (xy 308.281226 -315.969627) (xy 308.258355 -316.013204) (xy 308.22879 -316.052548)
			(xy 308.193297 -316.08664) (xy 308.152794 -316.114596) (xy 308.108332 -316.135694) (xy 308.061061 -316.149386)
			(xy 308.012206 -316.155318) (xy 307.963031 -316.153337) (xy 307.914812 -316.143493) (xy 307.868796 -316.126041)
			(xy 307.826175 -316.101434) (xy 307.788054 -316.070309) (xy 307.755419 -316.033472) (xy 307.729116 -315.991876)
			(xy 307.709825 -315.9466) (xy 307.698048 -315.898816) (xy 307.694088 -315.849762) (xy 306.405026 -315.849762)
			(xy 306.404531 -315.874369) (xy 306.396636 -315.922946) (xy 306.381052 -315.969627) (xy 306.358181 -316.013204)
			(xy 306.328616 -316.052548) (xy 306.293123 -316.08664) (xy 306.25262 -316.114596) (xy 306.208158 -316.135694)
			(xy 306.160887 -316.149386) (xy 306.112032 -316.155318) (xy 306.062857 -316.153337) (xy 306.014638 -316.143493)
			(xy 305.968622 -316.126041) (xy 305.926001 -316.101434) (xy 305.88788 -316.070309) (xy 305.855245 -316.033472)
			(xy 305.828942 -315.991876) (xy 305.809651 -315.9466) (xy 305.797874 -315.898816) (xy 305.793914 -315.849762)
			(xy 304.505106 -315.849762) (xy 304.504611 -315.874369) (xy 304.496716 -315.922946) (xy 304.481132 -315.969627)
			(xy 304.458261 -316.013204) (xy 304.428696 -316.052548) (xy 304.393203 -316.08664) (xy 304.3527 -316.114596)
			(xy 304.308238 -316.135694) (xy 304.260967 -316.149386) (xy 304.212112 -316.155318) (xy 304.162937 -316.153337)
			(xy 304.114718 -316.143493) (xy 304.068702 -316.126041) (xy 304.026081 -316.101434) (xy 303.98796 -316.070309)
			(xy 303.955325 -316.033472) (xy 303.929022 -315.991876) (xy 303.909731 -315.9466) (xy 303.897954 -315.898816)
			(xy 303.893994 -315.849762) (xy 302.605186 -315.849762) (xy 302.604691 -315.874369) (xy 302.596796 -315.922946)
			(xy 302.581212 -315.969627) (xy 302.558341 -316.013204) (xy 302.528776 -316.052548) (xy 302.493283 -316.08664)
			(xy 302.45278 -316.114596) (xy 302.408318 -316.135694) (xy 302.361047 -316.149386) (xy 302.312192 -316.155318)
			(xy 302.263017 -316.153337) (xy 302.214798 -316.143493) (xy 302.168782 -316.126041) (xy 302.126161 -316.101434)
			(xy 302.08804 -316.070309) (xy 302.055405 -316.033472) (xy 302.029102 -315.991876) (xy 302.009811 -315.9466)
			(xy 301.998034 -315.898816) (xy 301.994074 -315.849762) (xy 300.705012 -315.849762) (xy 300.704517 -315.874369)
			(xy 300.696622 -315.922946) (xy 300.681038 -315.969627) (xy 300.658167 -316.013204) (xy 300.628602 -316.052548)
			(xy 300.593109 -316.08664) (xy 300.552606 -316.114596) (xy 300.508144 -316.135694) (xy 300.460873 -316.149386)
			(xy 300.412018 -316.155318) (xy 300.362843 -316.153337) (xy 300.314624 -316.143493) (xy 300.268608 -316.126041)
			(xy 300.225987 -316.101434) (xy 300.187866 -316.070309) (xy 300.155231 -316.033472) (xy 300.128928 -315.991876)
			(xy 300.109637 -315.9466) (xy 300.09786 -315.898816) (xy 300.0939 -315.849762) (xy 298.805092 -315.849762)
			(xy 298.804597 -315.874369) (xy 298.796702 -315.922946) (xy 298.781118 -315.969627) (xy 298.758247 -316.013204)
			(xy 298.728682 -316.052548) (xy 298.693189 -316.08664) (xy 298.652686 -316.114596) (xy 298.608224 -316.135694)
			(xy 298.560953 -316.149386) (xy 298.512098 -316.155318) (xy 298.462923 -316.153337) (xy 298.414704 -316.143493)
			(xy 298.368688 -316.126041) (xy 298.326067 -316.101434) (xy 298.287946 -316.070309) (xy 298.255311 -316.033472)
			(xy 298.229008 -315.991876) (xy 298.209717 -315.9466) (xy 298.19794 -315.898816) (xy 298.19398 -315.849762)
			(xy 296.905172 -315.849762) (xy 296.904677 -315.874369) (xy 296.896782 -315.922946) (xy 296.881198 -315.969627)
			(xy 296.858327 -316.013204) (xy 296.828762 -316.052548) (xy 296.793269 -316.08664) (xy 296.752766 -316.114596)
			(xy 296.708304 -316.135694) (xy 296.661033 -316.149386) (xy 296.612178 -316.155318) (xy 296.563003 -316.153337)
			(xy 296.514784 -316.143493) (xy 296.468768 -316.126041) (xy 296.426147 -316.101434) (xy 296.388026 -316.070309)
			(xy 296.355391 -316.033472) (xy 296.329088 -315.991876) (xy 296.309797 -315.9466) (xy 296.29802 -315.898816)
			(xy 296.29406 -315.849762) (xy 295.004998 -315.849762) (xy 295.004503 -315.874369) (xy 294.996608 -315.922946)
			(xy 294.981024 -315.969627) (xy 294.958153 -316.013204) (xy 294.928588 -316.052548) (xy 294.893095 -316.08664)
			(xy 294.852592 -316.114596) (xy 294.80813 -316.135694) (xy 294.760859 -316.149386) (xy 294.712004 -316.155318)
			(xy 294.662829 -316.153337) (xy 294.61461 -316.143493) (xy 294.568594 -316.126041) (xy 294.525973 -316.101434)
			(xy 294.487852 -316.070309) (xy 294.455217 -316.033472) (xy 294.428914 -315.991876) (xy 294.409623 -315.9466)
			(xy 294.397846 -315.898816) (xy 294.393886 -315.849762) (xy 293.105078 -315.849762) (xy 293.104583 -315.874369)
			(xy 293.096688 -315.922946) (xy 293.081104 -315.969627) (xy 293.058233 -316.013204) (xy 293.028668 -316.052548)
			(xy 292.993175 -316.08664) (xy 292.952672 -316.114596) (xy 292.90821 -316.135694) (xy 292.860939 -316.149386)
			(xy 292.812084 -316.155318) (xy 292.762909 -316.153337) (xy 292.71469 -316.143493) (xy 292.668674 -316.126041)
			(xy 292.626053 -316.101434) (xy 292.587932 -316.070309) (xy 292.555297 -316.033472) (xy 292.528994 -315.991876)
			(xy 292.509703 -315.9466) (xy 292.497926 -315.898816) (xy 292.493966 -315.849762) (xy 291.205158 -315.849762)
			(xy 291.204663 -315.874369) (xy 291.196768 -315.922946) (xy 291.181184 -315.969627) (xy 291.158313 -316.013204)
			(xy 291.128748 -316.052548) (xy 291.093255 -316.08664) (xy 291.052752 -316.114596) (xy 291.00829 -316.135694)
			(xy 290.961019 -316.149386) (xy 290.912164 -316.155318) (xy 290.862989 -316.153337) (xy 290.81477 -316.143493)
			(xy 290.768754 -316.126041) (xy 290.726133 -316.101434) (xy 290.688012 -316.070309) (xy 290.655377 -316.033472)
			(xy 290.629074 -315.991876) (xy 290.609783 -315.9466) (xy 290.598006 -315.898816) (xy 290.594046 -315.849762)
			(xy 289.305238 -315.849762) (xy 289.304743 -315.874369) (xy 289.296848 -315.922946) (xy 289.281264 -315.969627)
			(xy 289.258393 -316.013204) (xy 289.228828 -316.052548) (xy 289.193335 -316.08664) (xy 289.152832 -316.114596)
			(xy 289.10837 -316.135694) (xy 289.061099 -316.149386) (xy 289.012244 -316.155318) (xy 288.963069 -316.153337)
			(xy 288.91485 -316.143493) (xy 288.868834 -316.126041) (xy 288.826213 -316.101434) (xy 288.788092 -316.070309)
			(xy 288.755457 -316.033472) (xy 288.729154 -315.991876) (xy 288.709863 -315.9466) (xy 288.698086 -315.898816)
			(xy 288.694126 -315.849762) (xy 287.405064 -315.849762) (xy 287.404569 -315.874369) (xy 287.396674 -315.922946)
			(xy 287.38109 -315.969627) (xy 287.358219 -316.013204) (xy 287.328654 -316.052548) (xy 287.293161 -316.08664)
			(xy 287.252658 -316.114596) (xy 287.208196 -316.135694) (xy 287.160925 -316.149386) (xy 287.11207 -316.155318)
			(xy 287.062895 -316.153337) (xy 287.014676 -316.143493) (xy 286.96866 -316.126041) (xy 286.926039 -316.101434)
			(xy 286.887918 -316.070309) (xy 286.855283 -316.033472) (xy 286.82898 -315.991876) (xy 286.809689 -315.9466)
			(xy 286.797912 -315.898816) (xy 286.793952 -315.849762) (xy 285.505144 -315.849762) (xy 285.504649 -315.874369)
			(xy 285.496754 -315.922946) (xy 285.48117 -315.969627) (xy 285.458299 -316.013204) (xy 285.428734 -316.052548)
			(xy 285.393241 -316.08664) (xy 285.352738 -316.114596) (xy 285.308276 -316.135694) (xy 285.261005 -316.149386)
			(xy 285.21215 -316.155318) (xy 285.162975 -316.153337) (xy 285.114756 -316.143493) (xy 285.06874 -316.126041)
			(xy 285.026119 -316.101434) (xy 284.987998 -316.070309) (xy 284.955363 -316.033472) (xy 284.92906 -315.991876)
			(xy 284.909769 -315.9466) (xy 284.897992 -315.898816) (xy 284.894032 -315.849762) (xy 283.605224 -315.849762)
			(xy 283.604729 -315.874369) (xy 283.596834 -315.922946) (xy 283.58125 -315.969627) (xy 283.558379 -316.013204)
			(xy 283.528814 -316.052548) (xy 283.493321 -316.08664) (xy 283.452818 -316.114596) (xy 283.408356 -316.135694)
			(xy 283.361085 -316.149386) (xy 283.31223 -316.155318) (xy 283.263055 -316.153337) (xy 283.214836 -316.143493)
			(xy 283.16882 -316.126041) (xy 283.126199 -316.101434) (xy 283.088078 -316.070309) (xy 283.055443 -316.033472)
			(xy 283.02914 -315.991876) (xy 283.009849 -315.9466) (xy 282.998072 -315.898816) (xy 282.994112 -315.849762)
			(xy 281.70505 -315.849762) (xy 281.704555 -315.874369) (xy 281.69666 -315.922946) (xy 281.681076 -315.969627)
			(xy 281.658205 -316.013204) (xy 281.62864 -316.052548) (xy 281.593147 -316.08664) (xy 281.552644 -316.114596)
			(xy 281.508182 -316.135694) (xy 281.460911 -316.149386) (xy 281.412056 -316.155318) (xy 281.362881 -316.153337)
			(xy 281.314662 -316.143493) (xy 281.268646 -316.126041) (xy 281.226025 -316.101434) (xy 281.187904 -316.070309)
			(xy 281.155269 -316.033472) (xy 281.128966 -315.991876) (xy 281.109675 -315.9466) (xy 281.097898 -315.898816)
			(xy 281.093938 -315.849762) (xy 279.80513 -315.849762) (xy 279.804635 -315.874369) (xy 279.79674 -315.922946)
			(xy 279.781156 -315.969627) (xy 279.758285 -316.013204) (xy 279.72872 -316.052548) (xy 279.693227 -316.08664)
			(xy 279.652724 -316.114596) (xy 279.608262 -316.135694) (xy 279.560991 -316.149386) (xy 279.512136 -316.155318)
			(xy 279.462961 -316.153337) (xy 279.414742 -316.143493) (xy 279.368726 -316.126041) (xy 279.326105 -316.101434)
			(xy 279.287984 -316.070309) (xy 279.255349 -316.033472) (xy 279.229046 -315.991876) (xy 279.209755 -315.9466)
			(xy 279.197978 -315.898816) (xy 279.194018 -315.849762) (xy 277.90521 -315.849762) (xy 277.904715 -315.874369)
			(xy 277.89682 -315.922946) (xy 277.881236 -315.969627) (xy 277.858365 -316.013204) (xy 277.8288 -316.052548)
			(xy 277.793307 -316.08664) (xy 277.752804 -316.114596) (xy 277.708342 -316.135694) (xy 277.661071 -316.149386)
			(xy 277.612216 -316.155318) (xy 277.563041 -316.153337) (xy 277.514822 -316.143493) (xy 277.468806 -316.126041)
			(xy 277.426185 -316.101434) (xy 277.388064 -316.070309) (xy 277.355429 -316.033472) (xy 277.329126 -315.991876)
			(xy 277.309835 -315.9466) (xy 277.298058 -315.898816) (xy 277.294098 -315.849762) (xy 276.005036 -315.849762)
			(xy 276.004541 -315.874369) (xy 275.996646 -315.922946) (xy 275.981062 -315.969627) (xy 275.958191 -316.013204)
			(xy 275.928626 -316.052548) (xy 275.893133 -316.08664) (xy 275.85263 -316.114596) (xy 275.808168 -316.135694)
			(xy 275.760897 -316.149386) (xy 275.712042 -316.155318) (xy 275.662867 -316.153337) (xy 275.614648 -316.143493)
			(xy 275.568632 -316.126041) (xy 275.526011 -316.101434) (xy 275.48789 -316.070309) (xy 275.455255 -316.033472)
			(xy 275.428952 -315.991876) (xy 275.409661 -315.9466) (xy 275.397884 -315.898816) (xy 275.393924 -315.849762)
			(xy 274.105116 -315.849762) (xy 274.104621 -315.874369) (xy 274.096726 -315.922946) (xy 274.081142 -315.969627)
			(xy 274.058271 -316.013204) (xy 274.028706 -316.052548) (xy 273.993213 -316.08664) (xy 273.95271 -316.114596)
			(xy 273.908248 -316.135694) (xy 273.860977 -316.149386) (xy 273.812122 -316.155318) (xy 273.762947 -316.153337)
			(xy 273.714728 -316.143493) (xy 273.668712 -316.126041) (xy 273.626091 -316.101434) (xy 273.58797 -316.070309)
			(xy 273.555335 -316.033472) (xy 273.529032 -315.991876) (xy 273.509741 -315.9466) (xy 273.497964 -315.898816)
			(xy 273.494004 -315.849762) (xy 272.205196 -315.849762) (xy 272.204701 -315.874369) (xy 272.196806 -315.922946)
			(xy 272.181222 -315.969627) (xy 272.158351 -316.013204) (xy 272.128786 -316.052548) (xy 272.093293 -316.08664)
			(xy 272.05279 -316.114596) (xy 272.008328 -316.135694) (xy 271.961057 -316.149386) (xy 271.912202 -316.155318)
			(xy 271.863027 -316.153337) (xy 271.814808 -316.143493) (xy 271.768792 -316.126041) (xy 271.726171 -316.101434)
			(xy 271.68805 -316.070309) (xy 271.655415 -316.033472) (xy 271.629112 -315.991876) (xy 271.609821 -315.9466)
			(xy 271.598044 -315.898816) (xy 271.594084 -315.849762) (xy 196.005196 -315.849762) (xy 196.004701 -315.874369)
			(xy 195.996806 -315.922946) (xy 195.981222 -315.969627) (xy 195.958351 -316.013204) (xy 195.928786 -316.052548)
			(xy 195.893293 -316.08664) (xy 195.85279 -316.114596) (xy 195.808328 -316.135694) (xy 195.761057 -316.149386)
			(xy 195.712202 -316.155318) (xy 195.663027 -316.153337) (xy 195.614808 -316.143493) (xy 195.568792 -316.126041)
			(xy 195.526171 -316.101434) (xy 195.48805 -316.070309) (xy 195.455415 -316.033472) (xy 195.429112 -315.991876)
			(xy 195.409821 -315.9466) (xy 195.398044 -315.898816) (xy 195.394084 -315.849762) (xy 194.105276 -315.849762)
			(xy 194.104781 -315.874369) (xy 194.096886 -315.922946) (xy 194.081302 -315.969627) (xy 194.058431 -316.013204)
			(xy 194.028866 -316.052548) (xy 193.993373 -316.08664) (xy 193.95287 -316.114596) (xy 193.908408 -316.135694)
			(xy 193.861137 -316.149386) (xy 193.812282 -316.155318) (xy 193.763107 -316.153337) (xy 193.714888 -316.143493)
			(xy 193.668872 -316.126041) (xy 193.626251 -316.101434) (xy 193.58813 -316.070309) (xy 193.555495 -316.033472)
			(xy 193.529192 -315.991876) (xy 193.509901 -315.9466) (xy 193.498124 -315.898816) (xy 193.494164 -315.849762)
			(xy 192.205356 -315.849762) (xy 192.204861 -315.874369) (xy 192.196966 -315.922946) (xy 192.181382 -315.969627)
			(xy 192.158511 -316.013204) (xy 192.128946 -316.052548) (xy 192.093453 -316.08664) (xy 192.05295 -316.114596)
			(xy 192.008488 -316.135694) (xy 191.961217 -316.149386) (xy 191.912362 -316.155318) (xy 191.863187 -316.153337)
			(xy 191.814968 -316.143493) (xy 191.768952 -316.126041) (xy 191.726331 -316.101434) (xy 191.68821 -316.070309)
			(xy 191.655575 -316.033472) (xy 191.629272 -315.991876) (xy 191.609981 -315.9466) (xy 191.598204 -315.898816)
			(xy 191.594244 -315.849762) (xy 190.305182 -315.849762) (xy 190.304687 -315.874369) (xy 190.296792 -315.922946)
			(xy 190.281208 -315.969627) (xy 190.258337 -316.013204) (xy 190.228772 -316.052548) (xy 190.193279 -316.08664)
			(xy 190.152776 -316.114596) (xy 190.108314 -316.135694) (xy 190.061043 -316.149386) (xy 190.012188 -316.155318)
			(xy 189.963013 -316.153337) (xy 189.914794 -316.143493) (xy 189.868778 -316.126041) (xy 189.826157 -316.101434)
			(xy 189.788036 -316.070309) (xy 189.755401 -316.033472) (xy 189.729098 -315.991876) (xy 189.709807 -315.9466)
			(xy 189.69803 -315.898816) (xy 189.69407 -315.849762) (xy 188.405262 -315.849762) (xy 188.404767 -315.874369)
			(xy 188.396872 -315.922946) (xy 188.381288 -315.969627) (xy 188.358417 -316.013204) (xy 188.328852 -316.052548)
			(xy 188.293359 -316.08664) (xy 188.252856 -316.114596) (xy 188.208394 -316.135694) (xy 188.161123 -316.149386)
			(xy 188.112268 -316.155318) (xy 188.063093 -316.153337) (xy 188.014874 -316.143493) (xy 187.968858 -316.126041)
			(xy 187.926237 -316.101434) (xy 187.888116 -316.070309) (xy 187.855481 -316.033472) (xy 187.829178 -315.991876)
			(xy 187.809887 -315.9466) (xy 187.79811 -315.898816) (xy 187.79415 -315.849762) (xy 186.505342 -315.849762)
			(xy 186.504847 -315.874369) (xy 186.496952 -315.922946) (xy 186.481368 -315.969627) (xy 186.458497 -316.013204)
			(xy 186.428932 -316.052548) (xy 186.393439 -316.08664) (xy 186.352936 -316.114596) (xy 186.308474 -316.135694)
			(xy 186.261203 -316.149386) (xy 186.212348 -316.155318) (xy 186.163173 -316.153337) (xy 186.114954 -316.143493)
			(xy 186.068938 -316.126041) (xy 186.026317 -316.101434) (xy 185.988196 -316.070309) (xy 185.955561 -316.033472)
			(xy 185.929258 -315.991876) (xy 185.909967 -315.9466) (xy 185.89819 -315.898816) (xy 185.89423 -315.849762)
			(xy 184.605168 -315.849762) (xy 184.604673 -315.874369) (xy 184.596778 -315.922946) (xy 184.581194 -315.969627)
			(xy 184.558323 -316.013204) (xy 184.528758 -316.052548) (xy 184.493265 -316.08664) (xy 184.452762 -316.114596)
			(xy 184.4083 -316.135694) (xy 184.361029 -316.149386) (xy 184.312174 -316.155318) (xy 184.262999 -316.153337)
			(xy 184.21478 -316.143493) (xy 184.168764 -316.126041) (xy 184.126143 -316.101434) (xy 184.088022 -316.070309)
			(xy 184.055387 -316.033472) (xy 184.029084 -315.991876) (xy 184.009793 -315.9466) (xy 183.998016 -315.898816)
			(xy 183.994056 -315.849762) (xy 182.705248 -315.849762) (xy 182.704753 -315.874369) (xy 182.696858 -315.922946)
			(xy 182.681274 -315.969627) (xy 182.658403 -316.013204) (xy 182.628838 -316.052548) (xy 182.593345 -316.08664)
			(xy 182.552842 -316.114596) (xy 182.50838 -316.135694) (xy 182.461109 -316.149386) (xy 182.412254 -316.155318)
			(xy 182.363079 -316.153337) (xy 182.31486 -316.143493) (xy 182.268844 -316.126041) (xy 182.226223 -316.101434)
			(xy 182.188102 -316.070309) (xy 182.155467 -316.033472) (xy 182.129164 -315.991876) (xy 182.109873 -315.9466)
			(xy 182.098096 -315.898816) (xy 182.094136 -315.849762) (xy 180.805328 -315.849762) (xy 180.804833 -315.874369)
			(xy 180.796938 -315.922946) (xy 180.781354 -315.969627) (xy 180.758483 -316.013204) (xy 180.728918 -316.052548)
			(xy 180.693425 -316.08664) (xy 180.652922 -316.114596) (xy 180.60846 -316.135694) (xy 180.561189 -316.149386)
			(xy 180.512334 -316.155318) (xy 180.463159 -316.153337) (xy 180.41494 -316.143493) (xy 180.368924 -316.126041)
			(xy 180.326303 -316.101434) (xy 180.288182 -316.070309) (xy 180.255547 -316.033472) (xy 180.229244 -315.991876)
			(xy 180.209953 -315.9466) (xy 180.198176 -315.898816) (xy 180.194216 -315.849762) (xy 178.905154 -315.849762)
			(xy 178.904659 -315.874369) (xy 178.896764 -315.922946) (xy 178.88118 -315.969627) (xy 178.858309 -316.013204)
			(xy 178.828744 -316.052548) (xy 178.793251 -316.08664) (xy 178.752748 -316.114596) (xy 178.708286 -316.135694)
			(xy 178.661015 -316.149386) (xy 178.61216 -316.155318) (xy 178.562985 -316.153337) (xy 178.514766 -316.143493)
			(xy 178.46875 -316.126041) (xy 178.426129 -316.101434) (xy 178.388008 -316.070309) (xy 178.355373 -316.033472)
			(xy 178.32907 -315.991876) (xy 178.309779 -315.9466) (xy 178.298002 -315.898816) (xy 178.294042 -315.849762)
			(xy 177.005234 -315.849762) (xy 177.004739 -315.874369) (xy 176.996844 -315.922946) (xy 176.98126 -315.969627)
			(xy 176.958389 -316.013204) (xy 176.928824 -316.052548) (xy 176.893331 -316.08664) (xy 176.852828 -316.114596)
			(xy 176.808366 -316.135694) (xy 176.761095 -316.149386) (xy 176.71224 -316.155318) (xy 176.663065 -316.153337)
			(xy 176.614846 -316.143493) (xy 176.56883 -316.126041) (xy 176.526209 -316.101434) (xy 176.488088 -316.070309)
			(xy 176.455453 -316.033472) (xy 176.42915 -315.991876) (xy 176.409859 -315.9466) (xy 176.398082 -315.898816)
			(xy 176.394122 -315.849762) (xy 175.105314 -315.849762) (xy 175.104819 -315.874369) (xy 175.096924 -315.922946)
			(xy 175.08134 -315.969627) (xy 175.058469 -316.013204) (xy 175.028904 -316.052548) (xy 174.993411 -316.08664)
			(xy 174.952908 -316.114596) (xy 174.908446 -316.135694) (xy 174.861175 -316.149386) (xy 174.81232 -316.155318)
			(xy 174.763145 -316.153337) (xy 174.714926 -316.143493) (xy 174.66891 -316.126041) (xy 174.626289 -316.101434)
			(xy 174.588168 -316.070309) (xy 174.555533 -316.033472) (xy 174.52923 -315.991876) (xy 174.509939 -315.9466)
			(xy 174.498162 -315.898816) (xy 174.494202 -315.849762) (xy 173.205394 -315.849762) (xy 173.204899 -315.874369)
			(xy 173.197004 -315.922946) (xy 173.18142 -315.969627) (xy 173.158549 -316.013204) (xy 173.128984 -316.052548)
			(xy 173.093491 -316.08664) (xy 173.052988 -316.114596) (xy 173.008526 -316.135694) (xy 172.961255 -316.149386)
			(xy 172.9124 -316.155318) (xy 172.863225 -316.153337) (xy 172.815006 -316.143493) (xy 172.76899 -316.126041)
			(xy 172.726369 -316.101434) (xy 172.688248 -316.070309) (xy 172.655613 -316.033472) (xy 172.62931 -315.991876)
			(xy 172.610019 -315.9466) (xy 172.598242 -315.898816) (xy 172.594282 -315.849762) (xy 171.30522 -315.849762)
			(xy 171.304725 -315.874369) (xy 171.29683 -315.922946) (xy 171.281246 -315.969627) (xy 171.258375 -316.013204)
			(xy 171.22881 -316.052548) (xy 171.193317 -316.08664) (xy 171.152814 -316.114596) (xy 171.108352 -316.135694)
			(xy 171.061081 -316.149386) (xy 171.012226 -316.155318) (xy 170.963051 -316.153337) (xy 170.914832 -316.143493)
			(xy 170.868816 -316.126041) (xy 170.826195 -316.101434) (xy 170.788074 -316.070309) (xy 170.755439 -316.033472)
			(xy 170.729136 -315.991876) (xy 170.709845 -315.9466) (xy 170.698068 -315.898816) (xy 170.694108 -315.849762)
			(xy 169.4053 -315.849762) (xy 169.404805 -315.874369) (xy 169.39691 -315.922946) (xy 169.381326 -315.969627)
			(xy 169.358455 -316.013204) (xy 169.32889 -316.052548) (xy 169.293397 -316.08664) (xy 169.252894 -316.114596)
			(xy 169.208432 -316.135694) (xy 169.161161 -316.149386) (xy 169.112306 -316.155318) (xy 169.063131 -316.153337)
			(xy 169.014912 -316.143493) (xy 168.968896 -316.126041) (xy 168.926275 -316.101434) (xy 168.888154 -316.070309)
			(xy 168.855519 -316.033472) (xy 168.829216 -315.991876) (xy 168.809925 -315.9466) (xy 168.798148 -315.898816)
			(xy 168.794188 -315.849762) (xy 167.50538 -315.849762) (xy 167.504885 -315.874369) (xy 167.49699 -315.922946)
			(xy 167.481406 -315.969627) (xy 167.458535 -316.013204) (xy 167.42897 -316.052548) (xy 167.393477 -316.08664)
			(xy 167.352974 -316.114596) (xy 167.308512 -316.135694) (xy 167.261241 -316.149386) (xy 167.212386 -316.155318)
			(xy 167.163211 -316.153337) (xy 167.114992 -316.143493) (xy 167.068976 -316.126041) (xy 167.026355 -316.101434)
			(xy 166.988234 -316.070309) (xy 166.955599 -316.033472) (xy 166.929296 -315.991876) (xy 166.910005 -315.9466)
			(xy 166.898228 -315.898816) (xy 166.894268 -315.849762) (xy 165.605206 -315.849762) (xy 165.604711 -315.874369)
			(xy 165.596816 -315.922946) (xy 165.581232 -315.969627) (xy 165.558361 -316.013204) (xy 165.528796 -316.052548)
			(xy 165.493303 -316.08664) (xy 165.4528 -316.114596) (xy 165.408338 -316.135694) (xy 165.361067 -316.149386)
			(xy 165.312212 -316.155318) (xy 165.263037 -316.153337) (xy 165.214818 -316.143493) (xy 165.168802 -316.126041)
			(xy 165.126181 -316.101434) (xy 165.08806 -316.070309) (xy 165.055425 -316.033472) (xy 165.029122 -315.991876)
			(xy 165.009831 -315.9466) (xy 164.998054 -315.898816) (xy 164.994094 -315.849762) (xy 163.705286 -315.849762)
			(xy 163.704791 -315.874369) (xy 163.696896 -315.922946) (xy 163.681312 -315.969627) (xy 163.658441 -316.013204)
			(xy 163.628876 -316.052548) (xy 163.593383 -316.08664) (xy 163.55288 -316.114596) (xy 163.508418 -316.135694)
			(xy 163.461147 -316.149386) (xy 163.412292 -316.155318) (xy 163.363117 -316.153337) (xy 163.314898 -316.143493)
			(xy 163.268882 -316.126041) (xy 163.226261 -316.101434) (xy 163.18814 -316.070309) (xy 163.155505 -316.033472)
			(xy 163.129202 -315.991876) (xy 163.109911 -315.9466) (xy 163.098134 -315.898816) (xy 163.094174 -315.849762)
			(xy 161.805366 -315.849762) (xy 161.804871 -315.874369) (xy 161.796976 -315.922946) (xy 161.781392 -315.969627)
			(xy 161.758521 -316.013204) (xy 161.728956 -316.052548) (xy 161.693463 -316.08664) (xy 161.65296 -316.114596)
			(xy 161.608498 -316.135694) (xy 161.561227 -316.149386) (xy 161.512372 -316.155318) (xy 161.463197 -316.153337)
			(xy 161.414978 -316.143493) (xy 161.368962 -316.126041) (xy 161.326341 -316.101434) (xy 161.28822 -316.070309)
			(xy 161.255585 -316.033472) (xy 161.229282 -315.991876) (xy 161.209991 -315.9466) (xy 161.198214 -315.898816)
			(xy 161.194254 -315.849762) (xy 159.905192 -315.849762) (xy 159.904697 -315.874369) (xy 159.896802 -315.922946)
			(xy 159.881218 -315.969627) (xy 159.858347 -316.013204) (xy 159.828782 -316.052548) (xy 159.793289 -316.08664)
			(xy 159.752786 -316.114596) (xy 159.708324 -316.135694) (xy 159.661053 -316.149386) (xy 159.612198 -316.155318)
			(xy 159.563023 -316.153337) (xy 159.514804 -316.143493) (xy 159.468788 -316.126041) (xy 159.426167 -316.101434)
			(xy 159.388046 -316.070309) (xy 159.355411 -316.033472) (xy 159.329108 -315.991876) (xy 159.309817 -315.9466)
			(xy 159.29804 -315.898816) (xy 159.29408 -315.849762) (xy 158.005272 -315.849762) (xy 158.004777 -315.874369)
			(xy 157.996882 -315.922946) (xy 157.981298 -315.969627) (xy 157.958427 -316.013204) (xy 157.928862 -316.052548)
			(xy 157.893369 -316.08664) (xy 157.852866 -316.114596) (xy 157.808404 -316.135694) (xy 157.761133 -316.149386)
			(xy 157.712278 -316.155318) (xy 157.663103 -316.153337) (xy 157.614884 -316.143493) (xy 157.568868 -316.126041)
			(xy 157.526247 -316.101434) (xy 157.488126 -316.070309) (xy 157.455491 -316.033472) (xy 157.429188 -315.991876)
			(xy 157.409897 -315.9466) (xy 157.39812 -315.898816) (xy 157.39416 -315.849762) (xy 156.105352 -315.849762)
			(xy 156.104857 -315.874369) (xy 156.096962 -315.922946) (xy 156.081378 -315.969627) (xy 156.058507 -316.013204)
			(xy 156.028942 -316.052548) (xy 155.993449 -316.08664) (xy 155.952946 -316.114596) (xy 155.908484 -316.135694)
			(xy 155.861213 -316.149386) (xy 155.812358 -316.155318) (xy 155.763183 -316.153337) (xy 155.714964 -316.143493)
			(xy 155.668948 -316.126041) (xy 155.626327 -316.101434) (xy 155.588206 -316.070309) (xy 155.555571 -316.033472)
			(xy 155.529268 -315.991876) (xy 155.509977 -315.9466) (xy 155.4982 -315.898816) (xy 155.49424 -315.849762)
			(xy 79.905098 -315.849762) (xy 79.904603 -315.874369) (xy 79.896708 -315.922946) (xy 79.881124 -315.969627)
			(xy 79.858253 -316.013204) (xy 79.828688 -316.052548) (xy 79.793195 -316.08664) (xy 79.752692 -316.114596)
			(xy 79.70823 -316.135694) (xy 79.660959 -316.149386) (xy 79.612104 -316.155318) (xy 79.562929 -316.153337)
			(xy 79.51471 -316.143493) (xy 79.468694 -316.126041) (xy 79.426073 -316.101434) (xy 79.387952 -316.070309)
			(xy 79.355317 -316.033472) (xy 79.329014 -315.991876) (xy 79.309723 -315.9466) (xy 79.297946 -315.898816)
			(xy 79.293986 -315.849762) (xy 78.005178 -315.849762) (xy 78.004683 -315.874369) (xy 77.996788 -315.922946)
			(xy 77.981204 -315.969627) (xy 77.958333 -316.013204) (xy 77.928768 -316.052548) (xy 77.893275 -316.08664)
			(xy 77.852772 -316.114596) (xy 77.80831 -316.135694) (xy 77.761039 -316.149386) (xy 77.712184 -316.155318)
			(xy 77.663009 -316.153337) (xy 77.61479 -316.143493) (xy 77.568774 -316.126041) (xy 77.526153 -316.101434)
			(xy 77.488032 -316.070309) (xy 77.455397 -316.033472) (xy 77.429094 -315.991876) (xy 77.409803 -315.9466)
			(xy 77.398026 -315.898816) (xy 77.394066 -315.849762) (xy 76.105258 -315.849762) (xy 76.104763 -315.874369)
			(xy 76.096868 -315.922946) (xy 76.081284 -315.969627) (xy 76.058413 -316.013204) (xy 76.028848 -316.052548)
			(xy 75.993355 -316.08664) (xy 75.952852 -316.114596) (xy 75.90839 -316.135694) (xy 75.861119 -316.149386)
			(xy 75.812264 -316.155318) (xy 75.763089 -316.153337) (xy 75.71487 -316.143493) (xy 75.668854 -316.126041)
			(xy 75.626233 -316.101434) (xy 75.588112 -316.070309) (xy 75.555477 -316.033472) (xy 75.529174 -315.991876)
			(xy 75.509883 -315.9466) (xy 75.498106 -315.898816) (xy 75.494146 -315.849762) (xy 74.205084 -315.849762)
			(xy 74.204589 -315.874369) (xy 74.196694 -315.922946) (xy 74.18111 -315.969627) (xy 74.158239 -316.013204)
			(xy 74.128674 -316.052548) (xy 74.093181 -316.08664) (xy 74.052678 -316.114596) (xy 74.008216 -316.135694)
			(xy 73.960945 -316.149386) (xy 73.91209 -316.155318) (xy 73.862915 -316.153337) (xy 73.814696 -316.143493)
			(xy 73.76868 -316.126041) (xy 73.726059 -316.101434) (xy 73.687938 -316.070309) (xy 73.655303 -316.033472)
			(xy 73.629 -315.991876) (xy 73.609709 -315.9466) (xy 73.597932 -315.898816) (xy 73.593972 -315.849762)
			(xy 72.305164 -315.849762) (xy 72.304669 -315.874369) (xy 72.296774 -315.922946) (xy 72.28119 -315.969627)
			(xy 72.258319 -316.013204) (xy 72.228754 -316.052548) (xy 72.193261 -316.08664) (xy 72.152758 -316.114596)
			(xy 72.108296 -316.135694) (xy 72.061025 -316.149386) (xy 72.01217 -316.155318) (xy 71.962995 -316.153337)
			(xy 71.914776 -316.143493) (xy 71.86876 -316.126041) (xy 71.826139 -316.101434) (xy 71.788018 -316.070309)
			(xy 71.755383 -316.033472) (xy 71.72908 -315.991876) (xy 71.709789 -315.9466) (xy 71.698012 -315.898816)
			(xy 71.694052 -315.849762) (xy 70.405244 -315.849762) (xy 70.404749 -315.874369) (xy 70.396854 -315.922946)
			(xy 70.38127 -315.969627) (xy 70.358399 -316.013204) (xy 70.328834 -316.052548) (xy 70.293341 -316.08664)
			(xy 70.252838 -316.114596) (xy 70.208376 -316.135694) (xy 70.161105 -316.149386) (xy 70.11225 -316.155318)
			(xy 70.063075 -316.153337) (xy 70.014856 -316.143493) (xy 69.96884 -316.126041) (xy 69.926219 -316.101434)
			(xy 69.888098 -316.070309) (xy 69.855463 -316.033472) (xy 69.82916 -315.991876) (xy 69.809869 -315.9466)
			(xy 69.798092 -315.898816) (xy 69.794132 -315.849762) (xy 68.50507 -315.849762) (xy 68.504575 -315.874369)
			(xy 68.49668 -315.922946) (xy 68.481096 -315.969627) (xy 68.458225 -316.013204) (xy 68.42866 -316.052548)
			(xy 68.393167 -316.08664) (xy 68.352664 -316.114596) (xy 68.308202 -316.135694) (xy 68.260931 -316.149386)
			(xy 68.212076 -316.155318) (xy 68.162901 -316.153337) (xy 68.114682 -316.143493) (xy 68.068666 -316.126041)
			(xy 68.026045 -316.101434) (xy 67.987924 -316.070309) (xy 67.955289 -316.033472) (xy 67.928986 -315.991876)
			(xy 67.909695 -315.9466) (xy 67.897918 -315.898816) (xy 67.893958 -315.849762) (xy 66.60515 -315.849762)
			(xy 66.604655 -315.874369) (xy 66.59676 -315.922946) (xy 66.581176 -315.969627) (xy 66.558305 -316.013204)
			(xy 66.52874 -316.052548) (xy 66.493247 -316.08664) (xy 66.452744 -316.114596) (xy 66.408282 -316.135694)
			(xy 66.361011 -316.149386) (xy 66.312156 -316.155318) (xy 66.262981 -316.153337) (xy 66.214762 -316.143493)
			(xy 66.168746 -316.126041) (xy 66.126125 -316.101434) (xy 66.088004 -316.070309) (xy 66.055369 -316.033472)
			(xy 66.029066 -315.991876) (xy 66.009775 -315.9466) (xy 65.997998 -315.898816) (xy 65.994038 -315.849762)
			(xy 64.70523 -315.849762) (xy 64.704735 -315.874369) (xy 64.69684 -315.922946) (xy 64.681256 -315.969627)
			(xy 64.658385 -316.013204) (xy 64.62882 -316.052548) (xy 64.593327 -316.08664) (xy 64.552824 -316.114596)
			(xy 64.508362 -316.135694) (xy 64.461091 -316.149386) (xy 64.412236 -316.155318) (xy 64.363061 -316.153337)
			(xy 64.314842 -316.143493) (xy 64.268826 -316.126041) (xy 64.226205 -316.101434) (xy 64.188084 -316.070309)
			(xy 64.155449 -316.033472) (xy 64.129146 -315.991876) (xy 64.109855 -315.9466) (xy 64.098078 -315.898816)
			(xy 64.094118 -315.849762) (xy 62.805056 -315.849762) (xy 62.804561 -315.874369) (xy 62.796666 -315.922946)
			(xy 62.781082 -315.969627) (xy 62.758211 -316.013204) (xy 62.728646 -316.052548) (xy 62.693153 -316.08664)
			(xy 62.65265 -316.114596) (xy 62.608188 -316.135694) (xy 62.560917 -316.149386) (xy 62.512062 -316.155318)
			(xy 62.462887 -316.153337) (xy 62.414668 -316.143493) (xy 62.368652 -316.126041) (xy 62.326031 -316.101434)
			(xy 62.28791 -316.070309) (xy 62.255275 -316.033472) (xy 62.228972 -315.991876) (xy 62.209681 -315.9466)
			(xy 62.197904 -315.898816) (xy 62.193944 -315.849762) (xy 60.905136 -315.849762) (xy 60.904641 -315.874369)
			(xy 60.896746 -315.922946) (xy 60.881162 -315.969627) (xy 60.858291 -316.013204) (xy 60.828726 -316.052548)
			(xy 60.793233 -316.08664) (xy 60.75273 -316.114596) (xy 60.708268 -316.135694) (xy 60.660997 -316.149386)
			(xy 60.612142 -316.155318) (xy 60.562967 -316.153337) (xy 60.514748 -316.143493) (xy 60.468732 -316.126041)
			(xy 60.426111 -316.101434) (xy 60.38799 -316.070309) (xy 60.355355 -316.033472) (xy 60.329052 -315.991876)
			(xy 60.309761 -315.9466) (xy 60.297984 -315.898816) (xy 60.294024 -315.849762) (xy 59.005216 -315.849762)
			(xy 59.004721 -315.874369) (xy 58.996826 -315.922946) (xy 58.981242 -315.969627) (xy 58.958371 -316.013204)
			(xy 58.928806 -316.052548) (xy 58.893313 -316.08664) (xy 58.85281 -316.114596) (xy 58.808348 -316.135694)
			(xy 58.761077 -316.149386) (xy 58.712222 -316.155318) (xy 58.663047 -316.153337) (xy 58.614828 -316.143493)
			(xy 58.568812 -316.126041) (xy 58.526191 -316.101434) (xy 58.48807 -316.070309) (xy 58.455435 -316.033472)
			(xy 58.429132 -315.991876) (xy 58.409841 -315.9466) (xy 58.398064 -315.898816) (xy 58.394104 -315.849762)
			(xy 57.105296 -315.849762) (xy 57.104801 -315.874369) (xy 57.096906 -315.922946) (xy 57.081322 -315.969627)
			(xy 57.058451 -316.013204) (xy 57.028886 -316.052548) (xy 56.993393 -316.08664) (xy 56.95289 -316.114596)
			(xy 56.908428 -316.135694) (xy 56.861157 -316.149386) (xy 56.812302 -316.155318) (xy 56.763127 -316.153337)
			(xy 56.714908 -316.143493) (xy 56.668892 -316.126041) (xy 56.626271 -316.101434) (xy 56.58815 -316.070309)
			(xy 56.555515 -316.033472) (xy 56.529212 -315.991876) (xy 56.509921 -315.9466) (xy 56.498144 -315.898816)
			(xy 56.494184 -315.849762) (xy 55.205122 -315.849762) (xy 55.204627 -315.874369) (xy 55.196732 -315.922946)
			(xy 55.181148 -315.969627) (xy 55.158277 -316.013204) (xy 55.128712 -316.052548) (xy 55.093219 -316.08664)
			(xy 55.052716 -316.114596) (xy 55.008254 -316.135694) (xy 54.960983 -316.149386) (xy 54.912128 -316.155318)
			(xy 54.862953 -316.153337) (xy 54.814734 -316.143493) (xy 54.768718 -316.126041) (xy 54.726097 -316.101434)
			(xy 54.687976 -316.070309) (xy 54.655341 -316.033472) (xy 54.629038 -315.991876) (xy 54.609747 -315.9466)
			(xy 54.59797 -315.898816) (xy 54.59401 -315.849762) (xy 53.305202 -315.849762) (xy 53.304707 -315.874369)
			(xy 53.296812 -315.922946) (xy 53.281228 -315.969627) (xy 53.258357 -316.013204) (xy 53.228792 -316.052548)
			(xy 53.193299 -316.08664) (xy 53.152796 -316.114596) (xy 53.108334 -316.135694) (xy 53.061063 -316.149386)
			(xy 53.012208 -316.155318) (xy 52.963033 -316.153337) (xy 52.914814 -316.143493) (xy 52.868798 -316.126041)
			(xy 52.826177 -316.101434) (xy 52.788056 -316.070309) (xy 52.755421 -316.033472) (xy 52.729118 -315.991876)
			(xy 52.709827 -315.9466) (xy 52.69805 -315.898816) (xy 52.69409 -315.849762) (xy 51.405282 -315.849762)
			(xy 51.404787 -315.874369) (xy 51.396892 -315.922946) (xy 51.381308 -315.969627) (xy 51.358437 -316.013204)
			(xy 51.328872 -316.052548) (xy 51.293379 -316.08664) (xy 51.252876 -316.114596) (xy 51.208414 -316.135694)
			(xy 51.161143 -316.149386) (xy 51.112288 -316.155318) (xy 51.063113 -316.153337) (xy 51.014894 -316.143493)
			(xy 50.968878 -316.126041) (xy 50.926257 -316.101434) (xy 50.888136 -316.070309) (xy 50.855501 -316.033472)
			(xy 50.829198 -315.991876) (xy 50.809907 -315.9466) (xy 50.79813 -315.898816) (xy 50.79417 -315.849762)
			(xy 49.505108 -315.849762) (xy 49.504613 -315.874369) (xy 49.496718 -315.922946) (xy 49.481134 -315.969627)
			(xy 49.458263 -316.013204) (xy 49.428698 -316.052548) (xy 49.393205 -316.08664) (xy 49.352702 -316.114596)
			(xy 49.30824 -316.135694) (xy 49.260969 -316.149386) (xy 49.212114 -316.155318) (xy 49.162939 -316.153337)
			(xy 49.11472 -316.143493) (xy 49.068704 -316.126041) (xy 49.026083 -316.101434) (xy 48.987962 -316.070309)
			(xy 48.955327 -316.033472) (xy 48.929024 -315.991876) (xy 48.909733 -315.9466) (xy 48.897956 -315.898816)
			(xy 48.893996 -315.849762) (xy 47.605188 -315.849762) (xy 47.604693 -315.874369) (xy 47.596798 -315.922946)
			(xy 47.581214 -315.969627) (xy 47.558343 -316.013204) (xy 47.528778 -316.052548) (xy 47.493285 -316.08664)
			(xy 47.452782 -316.114596) (xy 47.40832 -316.135694) (xy 47.361049 -316.149386) (xy 47.312194 -316.155318)
			(xy 47.263019 -316.153337) (xy 47.2148 -316.143493) (xy 47.168784 -316.126041) (xy 47.126163 -316.101434)
			(xy 47.088042 -316.070309) (xy 47.055407 -316.033472) (xy 47.029104 -315.991876) (xy 47.009813 -315.9466)
			(xy 46.998036 -315.898816) (xy 46.994076 -315.849762) (xy 45.705268 -315.849762) (xy 45.704773 -315.874369)
			(xy 45.696878 -315.922946) (xy 45.681294 -315.969627) (xy 45.658423 -316.013204) (xy 45.628858 -316.052548)
			(xy 45.593365 -316.08664) (xy 45.552862 -316.114596) (xy 45.5084 -316.135694) (xy 45.461129 -316.149386)
			(xy 45.412274 -316.155318) (xy 45.363099 -316.153337) (xy 45.31488 -316.143493) (xy 45.268864 -316.126041)
			(xy 45.226243 -316.101434) (xy 45.188122 -316.070309) (xy 45.155487 -316.033472) (xy 45.129184 -315.991876)
			(xy 45.109893 -315.9466) (xy 45.098116 -315.898816) (xy 45.094156 -315.849762) (xy 43.805094 -315.849762)
			(xy 43.804599 -315.874369) (xy 43.796704 -315.922946) (xy 43.78112 -315.969627) (xy 43.758249 -316.013204)
			(xy 43.728684 -316.052548) (xy 43.693191 -316.08664) (xy 43.652688 -316.114596) (xy 43.608226 -316.135694)
			(xy 43.560955 -316.149386) (xy 43.5121 -316.155318) (xy 43.462925 -316.153337) (xy 43.414706 -316.143493)
			(xy 43.36869 -316.126041) (xy 43.326069 -316.101434) (xy 43.287948 -316.070309) (xy 43.255313 -316.033472)
			(xy 43.22901 -315.991876) (xy 43.209719 -315.9466) (xy 43.197942 -315.898816) (xy 43.193982 -315.849762)
			(xy 41.905174 -315.849762) (xy 41.904679 -315.874369) (xy 41.896784 -315.922946) (xy 41.8812 -315.969627)
			(xy 41.858329 -316.013204) (xy 41.828764 -316.052548) (xy 41.793271 -316.08664) (xy 41.752768 -316.114596)
			(xy 41.708306 -316.135694) (xy 41.661035 -316.149386) (xy 41.61218 -316.155318) (xy 41.563005 -316.153337)
			(xy 41.514786 -316.143493) (xy 41.46877 -316.126041) (xy 41.426149 -316.101434) (xy 41.388028 -316.070309)
			(xy 41.355393 -316.033472) (xy 41.32909 -315.991876) (xy 41.309799 -315.9466) (xy 41.298022 -315.898816)
			(xy 41.294062 -315.849762) (xy 40.005254 -315.849762) (xy 40.004759 -315.874369) (xy 39.996864 -315.922946)
			(xy 39.98128 -315.969627) (xy 39.958409 -316.013204) (xy 39.928844 -316.052548) (xy 39.893351 -316.08664)
			(xy 39.852848 -316.114596) (xy 39.808386 -316.135694) (xy 39.761115 -316.149386) (xy 39.71226 -316.155318)
			(xy 39.663085 -316.153337) (xy 39.614866 -316.143493) (xy 39.56885 -316.126041) (xy 39.526229 -316.101434)
			(xy 39.488108 -316.070309) (xy 39.455473 -316.033472) (xy 39.42917 -315.991876) (xy 39.409879 -315.9466)
			(xy 39.398102 -315.898816) (xy 39.394142 -315.849762) (xy 0.509016 -315.849762) (xy 0.509016 -316.799722)
			(xy 36.544008 -316.799722) (xy 36.547968 -316.750668) (xy 36.559745 -316.702884) (xy 36.579036 -316.657608)
			(xy 36.605339 -316.616012) (xy 36.637974 -316.579175) (xy 36.676095 -316.54805) (xy 36.718716 -316.523443)
			(xy 36.764732 -316.505991) (xy 36.812951 -316.496147) (xy 36.862126 -316.494166) (xy 36.910981 -316.500098)
			(xy 36.958252 -316.51379) (xy 37.002714 -316.534888) (xy 37.043217 -316.562844) (xy 37.07871 -316.596936)
			(xy 37.108275 -316.63628) (xy 37.131146 -316.679857) (xy 37.14673 -316.726538) (xy 37.154625 -316.775115)
			(xy 37.15512 -316.799722) (xy 37.493968 -316.799722) (xy 37.497928 -316.750668) (xy 37.509705 -316.702884)
			(xy 37.528996 -316.657608) (xy 37.555299 -316.616012) (xy 37.587934 -316.579175) (xy 37.626055 -316.54805)
			(xy 37.668676 -316.523443) (xy 37.714692 -316.505991) (xy 37.762911 -316.496147) (xy 37.812086 -316.494166)
			(xy 37.860941 -316.500098) (xy 37.908212 -316.51379) (xy 37.952674 -316.534888) (xy 37.993177 -316.562844)
			(xy 38.02867 -316.596936) (xy 38.058235 -316.63628) (xy 38.081106 -316.679857) (xy 38.09669 -316.726538)
			(xy 38.104585 -316.775115) (xy 38.10508 -316.799722) (xy 39.394142 -316.799722) (xy 39.398102 -316.750668)
			(xy 39.409879 -316.702884) (xy 39.42917 -316.657608) (xy 39.455473 -316.616012) (xy 39.488108 -316.579175)
			(xy 39.526229 -316.54805) (xy 39.56885 -316.523443) (xy 39.614866 -316.505991) (xy 39.663085 -316.496147)
			(xy 39.71226 -316.494166) (xy 39.761115 -316.500098) (xy 39.808386 -316.51379) (xy 39.852848 -316.534888)
			(xy 39.893351 -316.562844) (xy 39.928844 -316.596936) (xy 39.958409 -316.63628) (xy 39.98128 -316.679857)
			(xy 39.996864 -316.726538) (xy 40.004759 -316.775115) (xy 40.005254 -316.799722) (xy 41.294062 -316.799722)
			(xy 41.298022 -316.750668) (xy 41.309799 -316.702884) (xy 41.32909 -316.657608) (xy 41.355393 -316.616012)
			(xy 41.388028 -316.579175) (xy 41.426149 -316.54805) (xy 41.46877 -316.523443) (xy 41.514786 -316.505991)
			(xy 41.563005 -316.496147) (xy 41.61218 -316.494166) (xy 41.661035 -316.500098) (xy 41.708306 -316.51379)
			(xy 41.752768 -316.534888) (xy 41.793271 -316.562844) (xy 41.828764 -316.596936) (xy 41.858329 -316.63628)
			(xy 41.8812 -316.679857) (xy 41.896784 -316.726538) (xy 41.904679 -316.775115) (xy 41.905174 -316.799722)
			(xy 43.193982 -316.799722) (xy 43.197942 -316.750668) (xy 43.209719 -316.702884) (xy 43.22901 -316.657608)
			(xy 43.255313 -316.616012) (xy 43.287948 -316.579175) (xy 43.326069 -316.54805) (xy 43.36869 -316.523443)
			(xy 43.414706 -316.505991) (xy 43.462925 -316.496147) (xy 43.5121 -316.494166) (xy 43.560955 -316.500098)
			(xy 43.608226 -316.51379) (xy 43.652688 -316.534888) (xy 43.693191 -316.562844) (xy 43.728684 -316.596936)
			(xy 43.758249 -316.63628) (xy 43.78112 -316.679857) (xy 43.796704 -316.726538) (xy 43.804599 -316.775115)
			(xy 43.805094 -316.799722) (xy 45.094156 -316.799722) (xy 45.098116 -316.750668) (xy 45.109893 -316.702884)
			(xy 45.129184 -316.657608) (xy 45.155487 -316.616012) (xy 45.188122 -316.579175) (xy 45.226243 -316.54805)
			(xy 45.268864 -316.523443) (xy 45.31488 -316.505991) (xy 45.363099 -316.496147) (xy 45.412274 -316.494166)
			(xy 45.461129 -316.500098) (xy 45.5084 -316.51379) (xy 45.552862 -316.534888) (xy 45.593365 -316.562844)
			(xy 45.628858 -316.596936) (xy 45.658423 -316.63628) (xy 45.681294 -316.679857) (xy 45.696878 -316.726538)
			(xy 45.704773 -316.775115) (xy 45.705268 -316.799722) (xy 46.994076 -316.799722) (xy 46.998036 -316.750668)
			(xy 47.009813 -316.702884) (xy 47.029104 -316.657608) (xy 47.055407 -316.616012) (xy 47.088042 -316.579175)
			(xy 47.126163 -316.54805) (xy 47.168784 -316.523443) (xy 47.2148 -316.505991) (xy 47.263019 -316.496147)
			(xy 47.312194 -316.494166) (xy 47.361049 -316.500098) (xy 47.40832 -316.51379) (xy 47.452782 -316.534888)
			(xy 47.493285 -316.562844) (xy 47.528778 -316.596936) (xy 47.558343 -316.63628) (xy 47.581214 -316.679857)
			(xy 47.596798 -316.726538) (xy 47.604693 -316.775115) (xy 47.605188 -316.799722) (xy 48.893996 -316.799722)
			(xy 48.897956 -316.750668) (xy 48.909733 -316.702884) (xy 48.929024 -316.657608) (xy 48.955327 -316.616012)
			(xy 48.987962 -316.579175) (xy 49.026083 -316.54805) (xy 49.068704 -316.523443) (xy 49.11472 -316.505991)
			(xy 49.162939 -316.496147) (xy 49.212114 -316.494166) (xy 49.260969 -316.500098) (xy 49.30824 -316.51379)
			(xy 49.352702 -316.534888) (xy 49.393205 -316.562844) (xy 49.428698 -316.596936) (xy 49.458263 -316.63628)
			(xy 49.481134 -316.679857) (xy 49.496718 -316.726538) (xy 49.504613 -316.775115) (xy 49.505108 -316.799722)
			(xy 50.79417 -316.799722) (xy 50.79813 -316.750668) (xy 50.809907 -316.702884) (xy 50.829198 -316.657608)
			(xy 50.855501 -316.616012) (xy 50.888136 -316.579175) (xy 50.926257 -316.54805) (xy 50.968878 -316.523443)
			(xy 51.014894 -316.505991) (xy 51.063113 -316.496147) (xy 51.112288 -316.494166) (xy 51.161143 -316.500098)
			(xy 51.208414 -316.51379) (xy 51.252876 -316.534888) (xy 51.293379 -316.562844) (xy 51.328872 -316.596936)
			(xy 51.358437 -316.63628) (xy 51.381308 -316.679857) (xy 51.396892 -316.726538) (xy 51.404787 -316.775115)
			(xy 51.405282 -316.799722) (xy 52.69409 -316.799722) (xy 52.69805 -316.750668) (xy 52.709827 -316.702884)
			(xy 52.729118 -316.657608) (xy 52.755421 -316.616012) (xy 52.788056 -316.579175) (xy 52.826177 -316.54805)
			(xy 52.868798 -316.523443) (xy 52.914814 -316.505991) (xy 52.963033 -316.496147) (xy 53.012208 -316.494166)
			(xy 53.061063 -316.500098) (xy 53.108334 -316.51379) (xy 53.152796 -316.534888) (xy 53.193299 -316.562844)
			(xy 53.228792 -316.596936) (xy 53.258357 -316.63628) (xy 53.281228 -316.679857) (xy 53.296812 -316.726538)
			(xy 53.304707 -316.775115) (xy 53.305202 -316.799722) (xy 54.59401 -316.799722) (xy 54.59797 -316.750668)
			(xy 54.609747 -316.702884) (xy 54.629038 -316.657608) (xy 54.655341 -316.616012) (xy 54.687976 -316.579175)
			(xy 54.726097 -316.54805) (xy 54.768718 -316.523443) (xy 54.814734 -316.505991) (xy 54.862953 -316.496147)
			(xy 54.912128 -316.494166) (xy 54.960983 -316.500098) (xy 55.008254 -316.51379) (xy 55.052716 -316.534888)
			(xy 55.093219 -316.562844) (xy 55.128712 -316.596936) (xy 55.158277 -316.63628) (xy 55.181148 -316.679857)
			(xy 55.196732 -316.726538) (xy 55.204627 -316.775115) (xy 55.205122 -316.799722) (xy 56.494184 -316.799722)
			(xy 56.498144 -316.750668) (xy 56.509921 -316.702884) (xy 56.529212 -316.657608) (xy 56.555515 -316.616012)
			(xy 56.58815 -316.579175) (xy 56.626271 -316.54805) (xy 56.668892 -316.523443) (xy 56.714908 -316.505991)
			(xy 56.763127 -316.496147) (xy 56.812302 -316.494166) (xy 56.861157 -316.500098) (xy 56.908428 -316.51379)
			(xy 56.95289 -316.534888) (xy 56.993393 -316.562844) (xy 57.028886 -316.596936) (xy 57.058451 -316.63628)
			(xy 57.081322 -316.679857) (xy 57.096906 -316.726538) (xy 57.104801 -316.775115) (xy 57.105296 -316.799722)
			(xy 58.394104 -316.799722) (xy 58.398064 -316.750668) (xy 58.409841 -316.702884) (xy 58.429132 -316.657608)
			(xy 58.455435 -316.616012) (xy 58.48807 -316.579175) (xy 58.526191 -316.54805) (xy 58.568812 -316.523443)
			(xy 58.614828 -316.505991) (xy 58.663047 -316.496147) (xy 58.712222 -316.494166) (xy 58.761077 -316.500098)
			(xy 58.808348 -316.51379) (xy 58.85281 -316.534888) (xy 58.893313 -316.562844) (xy 58.928806 -316.596936)
			(xy 58.958371 -316.63628) (xy 58.981242 -316.679857) (xy 58.996826 -316.726538) (xy 59.004721 -316.775115)
			(xy 59.005216 -316.799722) (xy 60.294024 -316.799722) (xy 60.297984 -316.750668) (xy 60.309761 -316.702884)
			(xy 60.329052 -316.657608) (xy 60.355355 -316.616012) (xy 60.38799 -316.579175) (xy 60.426111 -316.54805)
			(xy 60.468732 -316.523443) (xy 60.514748 -316.505991) (xy 60.562967 -316.496147) (xy 60.612142 -316.494166)
			(xy 60.660997 -316.500098) (xy 60.708268 -316.51379) (xy 60.75273 -316.534888) (xy 60.793233 -316.562844)
			(xy 60.828726 -316.596936) (xy 60.858291 -316.63628) (xy 60.881162 -316.679857) (xy 60.896746 -316.726538)
			(xy 60.904641 -316.775115) (xy 60.905136 -316.799722) (xy 62.193944 -316.799722) (xy 62.197904 -316.750668)
			(xy 62.209681 -316.702884) (xy 62.228972 -316.657608) (xy 62.255275 -316.616012) (xy 62.28791 -316.579175)
			(xy 62.326031 -316.54805) (xy 62.368652 -316.523443) (xy 62.414668 -316.505991) (xy 62.462887 -316.496147)
			(xy 62.512062 -316.494166) (xy 62.560917 -316.500098) (xy 62.608188 -316.51379) (xy 62.65265 -316.534888)
			(xy 62.693153 -316.562844) (xy 62.728646 -316.596936) (xy 62.758211 -316.63628) (xy 62.781082 -316.679857)
			(xy 62.796666 -316.726538) (xy 62.804561 -316.775115) (xy 62.805056 -316.799722) (xy 64.094118 -316.799722)
			(xy 64.098078 -316.750668) (xy 64.109855 -316.702884) (xy 64.129146 -316.657608) (xy 64.155449 -316.616012)
			(xy 64.188084 -316.579175) (xy 64.226205 -316.54805) (xy 64.268826 -316.523443) (xy 64.314842 -316.505991)
			(xy 64.363061 -316.496147) (xy 64.412236 -316.494166) (xy 64.461091 -316.500098) (xy 64.508362 -316.51379)
			(xy 64.552824 -316.534888) (xy 64.593327 -316.562844) (xy 64.62882 -316.596936) (xy 64.658385 -316.63628)
			(xy 64.681256 -316.679857) (xy 64.69684 -316.726538) (xy 64.704735 -316.775115) (xy 64.70523 -316.799722)
			(xy 65.994038 -316.799722) (xy 65.997998 -316.750668) (xy 66.009775 -316.702884) (xy 66.029066 -316.657608)
			(xy 66.055369 -316.616012) (xy 66.088004 -316.579175) (xy 66.126125 -316.54805) (xy 66.168746 -316.523443)
			(xy 66.214762 -316.505991) (xy 66.262981 -316.496147) (xy 66.312156 -316.494166) (xy 66.361011 -316.500098)
			(xy 66.408282 -316.51379) (xy 66.452744 -316.534888) (xy 66.493247 -316.562844) (xy 66.52874 -316.596936)
			(xy 66.558305 -316.63628) (xy 66.581176 -316.679857) (xy 66.59676 -316.726538) (xy 66.604655 -316.775115)
			(xy 66.60515 -316.799722) (xy 67.893958 -316.799722) (xy 67.897918 -316.750668) (xy 67.909695 -316.702884)
			(xy 67.928986 -316.657608) (xy 67.955289 -316.616012) (xy 67.987924 -316.579175) (xy 68.026045 -316.54805)
			(xy 68.068666 -316.523443) (xy 68.114682 -316.505991) (xy 68.162901 -316.496147) (xy 68.212076 -316.494166)
			(xy 68.260931 -316.500098) (xy 68.308202 -316.51379) (xy 68.352664 -316.534888) (xy 68.393167 -316.562844)
			(xy 68.42866 -316.596936) (xy 68.458225 -316.63628) (xy 68.481096 -316.679857) (xy 68.49668 -316.726538)
			(xy 68.504575 -316.775115) (xy 68.50507 -316.799722) (xy 69.794132 -316.799722) (xy 69.798092 -316.750668)
			(xy 69.809869 -316.702884) (xy 69.82916 -316.657608) (xy 69.855463 -316.616012) (xy 69.888098 -316.579175)
			(xy 69.926219 -316.54805) (xy 69.96884 -316.523443) (xy 70.014856 -316.505991) (xy 70.063075 -316.496147)
			(xy 70.11225 -316.494166) (xy 70.161105 -316.500098) (xy 70.208376 -316.51379) (xy 70.252838 -316.534888)
			(xy 70.293341 -316.562844) (xy 70.328834 -316.596936) (xy 70.358399 -316.63628) (xy 70.38127 -316.679857)
			(xy 70.396854 -316.726538) (xy 70.404749 -316.775115) (xy 70.405244 -316.799722) (xy 71.694052 -316.799722)
			(xy 71.698012 -316.750668) (xy 71.709789 -316.702884) (xy 71.72908 -316.657608) (xy 71.755383 -316.616012)
			(xy 71.788018 -316.579175) (xy 71.826139 -316.54805) (xy 71.86876 -316.523443) (xy 71.914776 -316.505991)
			(xy 71.962995 -316.496147) (xy 72.01217 -316.494166) (xy 72.061025 -316.500098) (xy 72.108296 -316.51379)
			(xy 72.152758 -316.534888) (xy 72.193261 -316.562844) (xy 72.228754 -316.596936) (xy 72.258319 -316.63628)
			(xy 72.28119 -316.679857) (xy 72.296774 -316.726538) (xy 72.304669 -316.775115) (xy 72.305164 -316.799722)
			(xy 73.593972 -316.799722) (xy 73.597932 -316.750668) (xy 73.609709 -316.702884) (xy 73.629 -316.657608)
			(xy 73.655303 -316.616012) (xy 73.687938 -316.579175) (xy 73.726059 -316.54805) (xy 73.76868 -316.523443)
			(xy 73.814696 -316.505991) (xy 73.862915 -316.496147) (xy 73.91209 -316.494166) (xy 73.960945 -316.500098)
			(xy 74.008216 -316.51379) (xy 74.052678 -316.534888) (xy 74.093181 -316.562844) (xy 74.128674 -316.596936)
			(xy 74.158239 -316.63628) (xy 74.18111 -316.679857) (xy 74.196694 -316.726538) (xy 74.204589 -316.775115)
			(xy 74.205084 -316.799722) (xy 75.494146 -316.799722) (xy 75.498106 -316.750668) (xy 75.509883 -316.702884)
			(xy 75.529174 -316.657608) (xy 75.555477 -316.616012) (xy 75.588112 -316.579175) (xy 75.626233 -316.54805)
			(xy 75.668854 -316.523443) (xy 75.71487 -316.505991) (xy 75.763089 -316.496147) (xy 75.812264 -316.494166)
			(xy 75.861119 -316.500098) (xy 75.90839 -316.51379) (xy 75.952852 -316.534888) (xy 75.993355 -316.562844)
			(xy 76.028848 -316.596936) (xy 76.058413 -316.63628) (xy 76.081284 -316.679857) (xy 76.096868 -316.726538)
			(xy 76.104763 -316.775115) (xy 76.105258 -316.799722) (xy 77.394066 -316.799722) (xy 77.398026 -316.750668)
			(xy 77.409803 -316.702884) (xy 77.429094 -316.657608) (xy 77.455397 -316.616012) (xy 77.488032 -316.579175)
			(xy 77.526153 -316.54805) (xy 77.568774 -316.523443) (xy 77.61479 -316.505991) (xy 77.663009 -316.496147)
			(xy 77.712184 -316.494166) (xy 77.761039 -316.500098) (xy 77.80831 -316.51379) (xy 77.852772 -316.534888)
			(xy 77.893275 -316.562844) (xy 77.928768 -316.596936) (xy 77.958333 -316.63628) (xy 77.981204 -316.679857)
			(xy 77.996788 -316.726538) (xy 78.004683 -316.775115) (xy 78.005178 -316.799722) (xy 79.293986 -316.799722)
			(xy 79.297946 -316.750668) (xy 79.309723 -316.702884) (xy 79.329014 -316.657608) (xy 79.355317 -316.616012)
			(xy 79.387952 -316.579175) (xy 79.426073 -316.54805) (xy 79.468694 -316.523443) (xy 79.51471 -316.505991)
			(xy 79.562929 -316.496147) (xy 79.612104 -316.494166) (xy 79.660959 -316.500098) (xy 79.70823 -316.51379)
			(xy 79.752692 -316.534888) (xy 79.793195 -316.562844) (xy 79.828688 -316.596936) (xy 79.858253 -316.63628)
			(xy 79.881124 -316.679857) (xy 79.896708 -316.726538) (xy 79.904603 -316.775115) (xy 79.905098 -316.799722)
			(xy 81.19416 -316.799722) (xy 81.19812 -316.750668) (xy 81.209897 -316.702884) (xy 81.229188 -316.657608)
			(xy 81.255491 -316.616012) (xy 81.288126 -316.579175) (xy 81.326247 -316.54805) (xy 81.368868 -316.523443)
			(xy 81.414884 -316.505991) (xy 81.463103 -316.496147) (xy 81.512278 -316.494166) (xy 81.561133 -316.500098)
			(xy 81.608404 -316.51379) (xy 81.652866 -316.534888) (xy 81.693369 -316.562844) (xy 81.728862 -316.596936)
			(xy 81.758427 -316.63628) (xy 81.781298 -316.679857) (xy 81.796882 -316.726538) (xy 81.804777 -316.775115)
			(xy 81.805272 -316.799722) (xy 82.14412 -316.799722) (xy 82.14808 -316.750668) (xy 82.159857 -316.702884)
			(xy 82.179148 -316.657608) (xy 82.205451 -316.616012) (xy 82.238086 -316.579175) (xy 82.276207 -316.54805)
			(xy 82.318828 -316.523443) (xy 82.364844 -316.505991) (xy 82.413063 -316.496147) (xy 82.462238 -316.494166)
			(xy 82.511093 -316.500098) (xy 82.558364 -316.51379) (xy 82.602826 -316.534888) (xy 82.643329 -316.562844)
			(xy 82.678822 -316.596936) (xy 82.708387 -316.63628) (xy 82.731258 -316.679857) (xy 82.746842 -316.726538)
			(xy 82.754737 -316.775115) (xy 82.755232 -316.799722) (xy 152.644106 -316.799722) (xy 152.648066 -316.750668)
			(xy 152.659843 -316.702884) (xy 152.679134 -316.657608) (xy 152.705437 -316.616012) (xy 152.738072 -316.579175)
			(xy 152.776193 -316.54805) (xy 152.818814 -316.523443) (xy 152.86483 -316.505991) (xy 152.913049 -316.496147)
			(xy 152.962224 -316.494166) (xy 153.011079 -316.500098) (xy 153.05835 -316.51379) (xy 153.102812 -316.534888)
			(xy 153.143315 -316.562844) (xy 153.178808 -316.596936) (xy 153.208373 -316.63628) (xy 153.231244 -316.679857)
			(xy 153.246828 -316.726538) (xy 153.254723 -316.775115) (xy 153.255218 -316.799722) (xy 153.594066 -316.799722)
			(xy 153.598026 -316.750668) (xy 153.609803 -316.702884) (xy 153.629094 -316.657608) (xy 153.655397 -316.616012)
			(xy 153.688032 -316.579175) (xy 153.726153 -316.54805) (xy 153.768774 -316.523443) (xy 153.81479 -316.505991)
			(xy 153.863009 -316.496147) (xy 153.912184 -316.494166) (xy 153.961039 -316.500098) (xy 154.00831 -316.51379)
			(xy 154.052772 -316.534888) (xy 154.093275 -316.562844) (xy 154.128768 -316.596936) (xy 154.158333 -316.63628)
			(xy 154.181204 -316.679857) (xy 154.196788 -316.726538) (xy 154.204683 -316.775115) (xy 154.205178 -316.799722)
			(xy 155.49424 -316.799722) (xy 155.4982 -316.750668) (xy 155.509977 -316.702884) (xy 155.529268 -316.657608)
			(xy 155.555571 -316.616012) (xy 155.588206 -316.579175) (xy 155.626327 -316.54805) (xy 155.668948 -316.523443)
			(xy 155.714964 -316.505991) (xy 155.763183 -316.496147) (xy 155.812358 -316.494166) (xy 155.861213 -316.500098)
			(xy 155.908484 -316.51379) (xy 155.952946 -316.534888) (xy 155.993449 -316.562844) (xy 156.028942 -316.596936)
			(xy 156.058507 -316.63628) (xy 156.081378 -316.679857) (xy 156.096962 -316.726538) (xy 156.104857 -316.775115)
			(xy 156.105352 -316.799722) (xy 157.39416 -316.799722) (xy 157.39812 -316.750668) (xy 157.409897 -316.702884)
			(xy 157.429188 -316.657608) (xy 157.455491 -316.616012) (xy 157.488126 -316.579175) (xy 157.526247 -316.54805)
			(xy 157.568868 -316.523443) (xy 157.614884 -316.505991) (xy 157.663103 -316.496147) (xy 157.712278 -316.494166)
			(xy 157.761133 -316.500098) (xy 157.808404 -316.51379) (xy 157.852866 -316.534888) (xy 157.893369 -316.562844)
			(xy 157.928862 -316.596936) (xy 157.958427 -316.63628) (xy 157.981298 -316.679857) (xy 157.996882 -316.726538)
			(xy 158.004777 -316.775115) (xy 158.005272 -316.799722) (xy 159.29408 -316.799722) (xy 159.29804 -316.750668)
			(xy 159.309817 -316.702884) (xy 159.329108 -316.657608) (xy 159.355411 -316.616012) (xy 159.388046 -316.579175)
			(xy 159.426167 -316.54805) (xy 159.468788 -316.523443) (xy 159.514804 -316.505991) (xy 159.563023 -316.496147)
			(xy 159.612198 -316.494166) (xy 159.661053 -316.500098) (xy 159.708324 -316.51379) (xy 159.752786 -316.534888)
			(xy 159.793289 -316.562844) (xy 159.828782 -316.596936) (xy 159.858347 -316.63628) (xy 159.881218 -316.679857)
			(xy 159.896802 -316.726538) (xy 159.904697 -316.775115) (xy 159.905192 -316.799722) (xy 161.194254 -316.799722)
			(xy 161.198214 -316.750668) (xy 161.209991 -316.702884) (xy 161.229282 -316.657608) (xy 161.255585 -316.616012)
			(xy 161.28822 -316.579175) (xy 161.326341 -316.54805) (xy 161.368962 -316.523443) (xy 161.414978 -316.505991)
			(xy 161.463197 -316.496147) (xy 161.512372 -316.494166) (xy 161.561227 -316.500098) (xy 161.608498 -316.51379)
			(xy 161.65296 -316.534888) (xy 161.693463 -316.562844) (xy 161.728956 -316.596936) (xy 161.758521 -316.63628)
			(xy 161.781392 -316.679857) (xy 161.796976 -316.726538) (xy 161.804871 -316.775115) (xy 161.805366 -316.799722)
			(xy 163.094174 -316.799722) (xy 163.098134 -316.750668) (xy 163.109911 -316.702884) (xy 163.129202 -316.657608)
			(xy 163.155505 -316.616012) (xy 163.18814 -316.579175) (xy 163.226261 -316.54805) (xy 163.268882 -316.523443)
			(xy 163.314898 -316.505991) (xy 163.363117 -316.496147) (xy 163.412292 -316.494166) (xy 163.461147 -316.500098)
			(xy 163.508418 -316.51379) (xy 163.55288 -316.534888) (xy 163.593383 -316.562844) (xy 163.628876 -316.596936)
			(xy 163.658441 -316.63628) (xy 163.681312 -316.679857) (xy 163.696896 -316.726538) (xy 163.704791 -316.775115)
			(xy 163.705286 -316.799722) (xy 164.994094 -316.799722) (xy 164.998054 -316.750668) (xy 165.009831 -316.702884)
			(xy 165.029122 -316.657608) (xy 165.055425 -316.616012) (xy 165.08806 -316.579175) (xy 165.126181 -316.54805)
			(xy 165.168802 -316.523443) (xy 165.214818 -316.505991) (xy 165.263037 -316.496147) (xy 165.312212 -316.494166)
			(xy 165.361067 -316.500098) (xy 165.408338 -316.51379) (xy 165.4528 -316.534888) (xy 165.493303 -316.562844)
			(xy 165.528796 -316.596936) (xy 165.558361 -316.63628) (xy 165.581232 -316.679857) (xy 165.596816 -316.726538)
			(xy 165.604711 -316.775115) (xy 165.605206 -316.799722) (xy 166.894268 -316.799722) (xy 166.898228 -316.750668)
			(xy 166.910005 -316.702884) (xy 166.929296 -316.657608) (xy 166.955599 -316.616012) (xy 166.988234 -316.579175)
			(xy 167.026355 -316.54805) (xy 167.068976 -316.523443) (xy 167.114992 -316.505991) (xy 167.163211 -316.496147)
			(xy 167.212386 -316.494166) (xy 167.261241 -316.500098) (xy 167.308512 -316.51379) (xy 167.352974 -316.534888)
			(xy 167.393477 -316.562844) (xy 167.42897 -316.596936) (xy 167.458535 -316.63628) (xy 167.481406 -316.679857)
			(xy 167.49699 -316.726538) (xy 167.504885 -316.775115) (xy 167.50538 -316.799722) (xy 168.794188 -316.799722)
			(xy 168.798148 -316.750668) (xy 168.809925 -316.702884) (xy 168.829216 -316.657608) (xy 168.855519 -316.616012)
			(xy 168.888154 -316.579175) (xy 168.926275 -316.54805) (xy 168.968896 -316.523443) (xy 169.014912 -316.505991)
			(xy 169.063131 -316.496147) (xy 169.112306 -316.494166) (xy 169.161161 -316.500098) (xy 169.208432 -316.51379)
			(xy 169.252894 -316.534888) (xy 169.293397 -316.562844) (xy 169.32889 -316.596936) (xy 169.358455 -316.63628)
			(xy 169.381326 -316.679857) (xy 169.39691 -316.726538) (xy 169.404805 -316.775115) (xy 169.4053 -316.799722)
			(xy 170.694108 -316.799722) (xy 170.698068 -316.750668) (xy 170.709845 -316.702884) (xy 170.729136 -316.657608)
			(xy 170.755439 -316.616012) (xy 170.788074 -316.579175) (xy 170.826195 -316.54805) (xy 170.868816 -316.523443)
			(xy 170.914832 -316.505991) (xy 170.963051 -316.496147) (xy 171.012226 -316.494166) (xy 171.061081 -316.500098)
			(xy 171.108352 -316.51379) (xy 171.152814 -316.534888) (xy 171.193317 -316.562844) (xy 171.22881 -316.596936)
			(xy 171.258375 -316.63628) (xy 171.281246 -316.679857) (xy 171.29683 -316.726538) (xy 171.304725 -316.775115)
			(xy 171.30522 -316.799722) (xy 172.594282 -316.799722) (xy 172.598242 -316.750668) (xy 172.610019 -316.702884)
			(xy 172.62931 -316.657608) (xy 172.655613 -316.616012) (xy 172.688248 -316.579175) (xy 172.726369 -316.54805)
			(xy 172.76899 -316.523443) (xy 172.815006 -316.505991) (xy 172.863225 -316.496147) (xy 172.9124 -316.494166)
			(xy 172.961255 -316.500098) (xy 173.008526 -316.51379) (xy 173.052988 -316.534888) (xy 173.093491 -316.562844)
			(xy 173.128984 -316.596936) (xy 173.158549 -316.63628) (xy 173.18142 -316.679857) (xy 173.197004 -316.726538)
			(xy 173.204899 -316.775115) (xy 173.205394 -316.799722) (xy 174.494202 -316.799722) (xy 174.498162 -316.750668)
			(xy 174.509939 -316.702884) (xy 174.52923 -316.657608) (xy 174.555533 -316.616012) (xy 174.588168 -316.579175)
			(xy 174.626289 -316.54805) (xy 174.66891 -316.523443) (xy 174.714926 -316.505991) (xy 174.763145 -316.496147)
			(xy 174.81232 -316.494166) (xy 174.861175 -316.500098) (xy 174.908446 -316.51379) (xy 174.952908 -316.534888)
			(xy 174.993411 -316.562844) (xy 175.028904 -316.596936) (xy 175.058469 -316.63628) (xy 175.08134 -316.679857)
			(xy 175.096924 -316.726538) (xy 175.104819 -316.775115) (xy 175.105314 -316.799722) (xy 176.394122 -316.799722)
			(xy 176.398082 -316.750668) (xy 176.409859 -316.702884) (xy 176.42915 -316.657608) (xy 176.455453 -316.616012)
			(xy 176.488088 -316.579175) (xy 176.526209 -316.54805) (xy 176.56883 -316.523443) (xy 176.614846 -316.505991)
			(xy 176.663065 -316.496147) (xy 176.71224 -316.494166) (xy 176.761095 -316.500098) (xy 176.808366 -316.51379)
			(xy 176.852828 -316.534888) (xy 176.893331 -316.562844) (xy 176.928824 -316.596936) (xy 176.958389 -316.63628)
			(xy 176.98126 -316.679857) (xy 176.996844 -316.726538) (xy 177.004739 -316.775115) (xy 177.005234 -316.799722)
			(xy 178.294042 -316.799722) (xy 178.298002 -316.750668) (xy 178.309779 -316.702884) (xy 178.32907 -316.657608)
			(xy 178.355373 -316.616012) (xy 178.388008 -316.579175) (xy 178.426129 -316.54805) (xy 178.46875 -316.523443)
			(xy 178.514766 -316.505991) (xy 178.562985 -316.496147) (xy 178.61216 -316.494166) (xy 178.661015 -316.500098)
			(xy 178.708286 -316.51379) (xy 178.752748 -316.534888) (xy 178.793251 -316.562844) (xy 178.828744 -316.596936)
			(xy 178.858309 -316.63628) (xy 178.88118 -316.679857) (xy 178.896764 -316.726538) (xy 178.904659 -316.775115)
			(xy 178.905154 -316.799722) (xy 180.194216 -316.799722) (xy 180.198176 -316.750668) (xy 180.209953 -316.702884)
			(xy 180.229244 -316.657608) (xy 180.255547 -316.616012) (xy 180.288182 -316.579175) (xy 180.326303 -316.54805)
			(xy 180.368924 -316.523443) (xy 180.41494 -316.505991) (xy 180.463159 -316.496147) (xy 180.512334 -316.494166)
			(xy 180.561189 -316.500098) (xy 180.60846 -316.51379) (xy 180.652922 -316.534888) (xy 180.693425 -316.562844)
			(xy 180.728918 -316.596936) (xy 180.758483 -316.63628) (xy 180.781354 -316.679857) (xy 180.796938 -316.726538)
			(xy 180.804833 -316.775115) (xy 180.805328 -316.799722) (xy 182.094136 -316.799722) (xy 182.098096 -316.750668)
			(xy 182.109873 -316.702884) (xy 182.129164 -316.657608) (xy 182.155467 -316.616012) (xy 182.188102 -316.579175)
			(xy 182.226223 -316.54805) (xy 182.268844 -316.523443) (xy 182.31486 -316.505991) (xy 182.363079 -316.496147)
			(xy 182.412254 -316.494166) (xy 182.461109 -316.500098) (xy 182.50838 -316.51379) (xy 182.552842 -316.534888)
			(xy 182.593345 -316.562844) (xy 182.628838 -316.596936) (xy 182.658403 -316.63628) (xy 182.681274 -316.679857)
			(xy 182.696858 -316.726538) (xy 182.704753 -316.775115) (xy 182.705248 -316.799722) (xy 183.994056 -316.799722)
			(xy 183.998016 -316.750668) (xy 184.009793 -316.702884) (xy 184.029084 -316.657608) (xy 184.055387 -316.616012)
			(xy 184.088022 -316.579175) (xy 184.126143 -316.54805) (xy 184.168764 -316.523443) (xy 184.21478 -316.505991)
			(xy 184.262999 -316.496147) (xy 184.312174 -316.494166) (xy 184.361029 -316.500098) (xy 184.4083 -316.51379)
			(xy 184.452762 -316.534888) (xy 184.493265 -316.562844) (xy 184.528758 -316.596936) (xy 184.558323 -316.63628)
			(xy 184.581194 -316.679857) (xy 184.596778 -316.726538) (xy 184.604673 -316.775115) (xy 184.605168 -316.799722)
			(xy 185.89423 -316.799722) (xy 185.89819 -316.750668) (xy 185.909967 -316.702884) (xy 185.929258 -316.657608)
			(xy 185.955561 -316.616012) (xy 185.988196 -316.579175) (xy 186.026317 -316.54805) (xy 186.068938 -316.523443)
			(xy 186.114954 -316.505991) (xy 186.163173 -316.496147) (xy 186.212348 -316.494166) (xy 186.261203 -316.500098)
			(xy 186.308474 -316.51379) (xy 186.352936 -316.534888) (xy 186.393439 -316.562844) (xy 186.428932 -316.596936)
			(xy 186.458497 -316.63628) (xy 186.481368 -316.679857) (xy 186.496952 -316.726538) (xy 186.504847 -316.775115)
			(xy 186.505342 -316.799722) (xy 187.79415 -316.799722) (xy 187.79811 -316.750668) (xy 187.809887 -316.702884)
			(xy 187.829178 -316.657608) (xy 187.855481 -316.616012) (xy 187.888116 -316.579175) (xy 187.926237 -316.54805)
			(xy 187.968858 -316.523443) (xy 188.014874 -316.505991) (xy 188.063093 -316.496147) (xy 188.112268 -316.494166)
			(xy 188.161123 -316.500098) (xy 188.208394 -316.51379) (xy 188.252856 -316.534888) (xy 188.293359 -316.562844)
			(xy 188.328852 -316.596936) (xy 188.358417 -316.63628) (xy 188.381288 -316.679857) (xy 188.396872 -316.726538)
			(xy 188.404767 -316.775115) (xy 188.405262 -316.799722) (xy 189.69407 -316.799722) (xy 189.69803 -316.750668)
			(xy 189.709807 -316.702884) (xy 189.729098 -316.657608) (xy 189.755401 -316.616012) (xy 189.788036 -316.579175)
			(xy 189.826157 -316.54805) (xy 189.868778 -316.523443) (xy 189.914794 -316.505991) (xy 189.963013 -316.496147)
			(xy 190.012188 -316.494166) (xy 190.061043 -316.500098) (xy 190.108314 -316.51379) (xy 190.152776 -316.534888)
			(xy 190.193279 -316.562844) (xy 190.228772 -316.596936) (xy 190.258337 -316.63628) (xy 190.281208 -316.679857)
			(xy 190.296792 -316.726538) (xy 190.304687 -316.775115) (xy 190.305182 -316.799722) (xy 191.594244 -316.799722)
			(xy 191.598204 -316.750668) (xy 191.609981 -316.702884) (xy 191.629272 -316.657608) (xy 191.655575 -316.616012)
			(xy 191.68821 -316.579175) (xy 191.726331 -316.54805) (xy 191.768952 -316.523443) (xy 191.814968 -316.505991)
			(xy 191.863187 -316.496147) (xy 191.912362 -316.494166) (xy 191.961217 -316.500098) (xy 192.008488 -316.51379)
			(xy 192.05295 -316.534888) (xy 192.093453 -316.562844) (xy 192.128946 -316.596936) (xy 192.158511 -316.63628)
			(xy 192.181382 -316.679857) (xy 192.196966 -316.726538) (xy 192.204861 -316.775115) (xy 192.205356 -316.799722)
			(xy 193.494164 -316.799722) (xy 193.498124 -316.750668) (xy 193.509901 -316.702884) (xy 193.529192 -316.657608)
			(xy 193.555495 -316.616012) (xy 193.58813 -316.579175) (xy 193.626251 -316.54805) (xy 193.668872 -316.523443)
			(xy 193.714888 -316.505991) (xy 193.763107 -316.496147) (xy 193.812282 -316.494166) (xy 193.861137 -316.500098)
			(xy 193.908408 -316.51379) (xy 193.95287 -316.534888) (xy 193.993373 -316.562844) (xy 194.028866 -316.596936)
			(xy 194.058431 -316.63628) (xy 194.081302 -316.679857) (xy 194.096886 -316.726538) (xy 194.104781 -316.775115)
			(xy 194.105276 -316.799722) (xy 195.394084 -316.799722) (xy 195.398044 -316.750668) (xy 195.409821 -316.702884)
			(xy 195.429112 -316.657608) (xy 195.455415 -316.616012) (xy 195.48805 -316.579175) (xy 195.526171 -316.54805)
			(xy 195.568792 -316.523443) (xy 195.614808 -316.505991) (xy 195.663027 -316.496147) (xy 195.712202 -316.494166)
			(xy 195.761057 -316.500098) (xy 195.808328 -316.51379) (xy 195.85279 -316.534888) (xy 195.893293 -316.562844)
			(xy 195.928786 -316.596936) (xy 195.958351 -316.63628) (xy 195.981222 -316.679857) (xy 195.996806 -316.726538)
			(xy 196.004701 -316.775115) (xy 196.005196 -316.799722) (xy 197.294258 -316.799722) (xy 197.298218 -316.750668)
			(xy 197.309995 -316.702884) (xy 197.329286 -316.657608) (xy 197.355589 -316.616012) (xy 197.388224 -316.579175)
			(xy 197.426345 -316.54805) (xy 197.468966 -316.523443) (xy 197.514982 -316.505991) (xy 197.563201 -316.496147)
			(xy 197.612376 -316.494166) (xy 197.661231 -316.500098) (xy 197.708502 -316.51379) (xy 197.752964 -316.534888)
			(xy 197.793467 -316.562844) (xy 197.82896 -316.596936) (xy 197.858525 -316.63628) (xy 197.881396 -316.679857)
			(xy 197.89698 -316.726538) (xy 197.904875 -316.775115) (xy 197.90537 -316.799722) (xy 198.244218 -316.799722)
			(xy 198.248178 -316.750668) (xy 198.259955 -316.702884) (xy 198.279246 -316.657608) (xy 198.305549 -316.616012)
			(xy 198.338184 -316.579175) (xy 198.376305 -316.54805) (xy 198.418926 -316.523443) (xy 198.464942 -316.505991)
			(xy 198.513161 -316.496147) (xy 198.562336 -316.494166) (xy 198.611191 -316.500098) (xy 198.658462 -316.51379)
			(xy 198.702924 -316.534888) (xy 198.743427 -316.562844) (xy 198.77892 -316.596936) (xy 198.808485 -316.63628)
			(xy 198.831356 -316.679857) (xy 198.84694 -316.726538) (xy 198.854835 -316.775115) (xy 198.85533 -316.799722)
			(xy 268.74395 -316.799722) (xy 268.74791 -316.750668) (xy 268.759687 -316.702884) (xy 268.778978 -316.657608)
			(xy 268.805281 -316.616012) (xy 268.837916 -316.579175) (xy 268.876037 -316.54805) (xy 268.918658 -316.523443)
			(xy 268.964674 -316.505991) (xy 269.012893 -316.496147) (xy 269.062068 -316.494166) (xy 269.110923 -316.500098)
			(xy 269.158194 -316.51379) (xy 269.202656 -316.534888) (xy 269.243159 -316.562844) (xy 269.278652 -316.596936)
			(xy 269.308217 -316.63628) (xy 269.331088 -316.679857) (xy 269.346672 -316.726538) (xy 269.354567 -316.775115)
			(xy 269.355062 -316.799722) (xy 269.69391 -316.799722) (xy 269.69787 -316.750668) (xy 269.709647 -316.702884)
			(xy 269.728938 -316.657608) (xy 269.755241 -316.616012) (xy 269.787876 -316.579175) (xy 269.825997 -316.54805)
			(xy 269.868618 -316.523443) (xy 269.914634 -316.505991) (xy 269.962853 -316.496147) (xy 270.012028 -316.494166)
			(xy 270.060883 -316.500098) (xy 270.108154 -316.51379) (xy 270.152616 -316.534888) (xy 270.193119 -316.562844)
			(xy 270.228612 -316.596936) (xy 270.258177 -316.63628) (xy 270.281048 -316.679857) (xy 270.296632 -316.726538)
			(xy 270.304527 -316.775115) (xy 270.305022 -316.799722) (xy 271.594084 -316.799722) (xy 271.598044 -316.750668)
			(xy 271.609821 -316.702884) (xy 271.629112 -316.657608) (xy 271.655415 -316.616012) (xy 271.68805 -316.579175)
			(xy 271.726171 -316.54805) (xy 271.768792 -316.523443) (xy 271.814808 -316.505991) (xy 271.863027 -316.496147)
			(xy 271.912202 -316.494166) (xy 271.961057 -316.500098) (xy 272.008328 -316.51379) (xy 272.05279 -316.534888)
			(xy 272.093293 -316.562844) (xy 272.128786 -316.596936) (xy 272.158351 -316.63628) (xy 272.181222 -316.679857)
			(xy 272.196806 -316.726538) (xy 272.204701 -316.775115) (xy 272.205196 -316.799722) (xy 273.494004 -316.799722)
			(xy 273.497964 -316.750668) (xy 273.509741 -316.702884) (xy 273.529032 -316.657608) (xy 273.555335 -316.616012)
			(xy 273.58797 -316.579175) (xy 273.626091 -316.54805) (xy 273.668712 -316.523443) (xy 273.714728 -316.505991)
			(xy 273.762947 -316.496147) (xy 273.812122 -316.494166) (xy 273.860977 -316.500098) (xy 273.908248 -316.51379)
			(xy 273.95271 -316.534888) (xy 273.993213 -316.562844) (xy 274.028706 -316.596936) (xy 274.058271 -316.63628)
			(xy 274.081142 -316.679857) (xy 274.096726 -316.726538) (xy 274.104621 -316.775115) (xy 274.105116 -316.799722)
			(xy 275.393924 -316.799722) (xy 275.397884 -316.750668) (xy 275.409661 -316.702884) (xy 275.428952 -316.657608)
			(xy 275.455255 -316.616012) (xy 275.48789 -316.579175) (xy 275.526011 -316.54805) (xy 275.568632 -316.523443)
			(xy 275.614648 -316.505991) (xy 275.662867 -316.496147) (xy 275.712042 -316.494166) (xy 275.760897 -316.500098)
			(xy 275.808168 -316.51379) (xy 275.85263 -316.534888) (xy 275.893133 -316.562844) (xy 275.928626 -316.596936)
			(xy 275.958191 -316.63628) (xy 275.981062 -316.679857) (xy 275.996646 -316.726538) (xy 276.004541 -316.775115)
			(xy 276.005036 -316.799722) (xy 277.294098 -316.799722) (xy 277.298058 -316.750668) (xy 277.309835 -316.702884)
			(xy 277.329126 -316.657608) (xy 277.355429 -316.616012) (xy 277.388064 -316.579175) (xy 277.426185 -316.54805)
			(xy 277.468806 -316.523443) (xy 277.514822 -316.505991) (xy 277.563041 -316.496147) (xy 277.612216 -316.494166)
			(xy 277.661071 -316.500098) (xy 277.708342 -316.51379) (xy 277.752804 -316.534888) (xy 277.793307 -316.562844)
			(xy 277.8288 -316.596936) (xy 277.858365 -316.63628) (xy 277.881236 -316.679857) (xy 277.89682 -316.726538)
			(xy 277.904715 -316.775115) (xy 277.90521 -316.799722) (xy 279.194018 -316.799722) (xy 279.197978 -316.750668)
			(xy 279.209755 -316.702884) (xy 279.229046 -316.657608) (xy 279.255349 -316.616012) (xy 279.287984 -316.579175)
			(xy 279.326105 -316.54805) (xy 279.368726 -316.523443) (xy 279.414742 -316.505991) (xy 279.462961 -316.496147)
			(xy 279.512136 -316.494166) (xy 279.560991 -316.500098) (xy 279.608262 -316.51379) (xy 279.652724 -316.534888)
			(xy 279.693227 -316.562844) (xy 279.72872 -316.596936) (xy 279.758285 -316.63628) (xy 279.781156 -316.679857)
			(xy 279.79674 -316.726538) (xy 279.804635 -316.775115) (xy 279.80513 -316.799722) (xy 281.093938 -316.799722)
			(xy 281.097898 -316.750668) (xy 281.109675 -316.702884) (xy 281.128966 -316.657608) (xy 281.155269 -316.616012)
			(xy 281.187904 -316.579175) (xy 281.226025 -316.54805) (xy 281.268646 -316.523443) (xy 281.314662 -316.505991)
			(xy 281.362881 -316.496147) (xy 281.412056 -316.494166) (xy 281.460911 -316.500098) (xy 281.508182 -316.51379)
			(xy 281.552644 -316.534888) (xy 281.593147 -316.562844) (xy 281.62864 -316.596936) (xy 281.658205 -316.63628)
			(xy 281.681076 -316.679857) (xy 281.69666 -316.726538) (xy 281.704555 -316.775115) (xy 281.70505 -316.799722)
			(xy 282.994112 -316.799722) (xy 282.998072 -316.750668) (xy 283.009849 -316.702884) (xy 283.02914 -316.657608)
			(xy 283.055443 -316.616012) (xy 283.088078 -316.579175) (xy 283.126199 -316.54805) (xy 283.16882 -316.523443)
			(xy 283.214836 -316.505991) (xy 283.263055 -316.496147) (xy 283.31223 -316.494166) (xy 283.361085 -316.500098)
			(xy 283.408356 -316.51379) (xy 283.452818 -316.534888) (xy 283.493321 -316.562844) (xy 283.528814 -316.596936)
			(xy 283.558379 -316.63628) (xy 283.58125 -316.679857) (xy 283.596834 -316.726538) (xy 283.604729 -316.775115)
			(xy 283.605224 -316.799722) (xy 284.894032 -316.799722) (xy 284.897992 -316.750668) (xy 284.909769 -316.702884)
			(xy 284.92906 -316.657608) (xy 284.955363 -316.616012) (xy 284.987998 -316.579175) (xy 285.026119 -316.54805)
			(xy 285.06874 -316.523443) (xy 285.114756 -316.505991) (xy 285.162975 -316.496147) (xy 285.21215 -316.494166)
			(xy 285.261005 -316.500098) (xy 285.308276 -316.51379) (xy 285.352738 -316.534888) (xy 285.393241 -316.562844)
			(xy 285.428734 -316.596936) (xy 285.458299 -316.63628) (xy 285.48117 -316.679857) (xy 285.496754 -316.726538)
			(xy 285.504649 -316.775115) (xy 285.505144 -316.799722) (xy 286.793952 -316.799722) (xy 286.797912 -316.750668)
			(xy 286.809689 -316.702884) (xy 286.82898 -316.657608) (xy 286.855283 -316.616012) (xy 286.887918 -316.579175)
			(xy 286.926039 -316.54805) (xy 286.96866 -316.523443) (xy 287.014676 -316.505991) (xy 287.062895 -316.496147)
			(xy 287.11207 -316.494166) (xy 287.160925 -316.500098) (xy 287.208196 -316.51379) (xy 287.252658 -316.534888)
			(xy 287.293161 -316.562844) (xy 287.328654 -316.596936) (xy 287.358219 -316.63628) (xy 287.38109 -316.679857)
			(xy 287.396674 -316.726538) (xy 287.404569 -316.775115) (xy 287.405064 -316.799722) (xy 288.694126 -316.799722)
			(xy 288.698086 -316.750668) (xy 288.709863 -316.702884) (xy 288.729154 -316.657608) (xy 288.755457 -316.616012)
			(xy 288.788092 -316.579175) (xy 288.826213 -316.54805) (xy 288.868834 -316.523443) (xy 288.91485 -316.505991)
			(xy 288.963069 -316.496147) (xy 289.012244 -316.494166) (xy 289.061099 -316.500098) (xy 289.10837 -316.51379)
			(xy 289.152832 -316.534888) (xy 289.193335 -316.562844) (xy 289.228828 -316.596936) (xy 289.258393 -316.63628)
			(xy 289.281264 -316.679857) (xy 289.296848 -316.726538) (xy 289.304743 -316.775115) (xy 289.305238 -316.799722)
			(xy 290.594046 -316.799722) (xy 290.598006 -316.750668) (xy 290.609783 -316.702884) (xy 290.629074 -316.657608)
			(xy 290.655377 -316.616012) (xy 290.688012 -316.579175) (xy 290.726133 -316.54805) (xy 290.768754 -316.523443)
			(xy 290.81477 -316.505991) (xy 290.862989 -316.496147) (xy 290.912164 -316.494166) (xy 290.961019 -316.500098)
			(xy 291.00829 -316.51379) (xy 291.052752 -316.534888) (xy 291.093255 -316.562844) (xy 291.128748 -316.596936)
			(xy 291.158313 -316.63628) (xy 291.181184 -316.679857) (xy 291.196768 -316.726538) (xy 291.204663 -316.775115)
			(xy 291.205158 -316.799722) (xy 292.493966 -316.799722) (xy 292.497926 -316.750668) (xy 292.509703 -316.702884)
			(xy 292.528994 -316.657608) (xy 292.555297 -316.616012) (xy 292.587932 -316.579175) (xy 292.626053 -316.54805)
			(xy 292.668674 -316.523443) (xy 292.71469 -316.505991) (xy 292.762909 -316.496147) (xy 292.812084 -316.494166)
			(xy 292.860939 -316.500098) (xy 292.90821 -316.51379) (xy 292.952672 -316.534888) (xy 292.993175 -316.562844)
			(xy 293.028668 -316.596936) (xy 293.058233 -316.63628) (xy 293.081104 -316.679857) (xy 293.096688 -316.726538)
			(xy 293.104583 -316.775115) (xy 293.105078 -316.799722) (xy 294.393886 -316.799722) (xy 294.397846 -316.750668)
			(xy 294.409623 -316.702884) (xy 294.428914 -316.657608) (xy 294.455217 -316.616012) (xy 294.487852 -316.579175)
			(xy 294.525973 -316.54805) (xy 294.568594 -316.523443) (xy 294.61461 -316.505991) (xy 294.662829 -316.496147)
			(xy 294.712004 -316.494166) (xy 294.760859 -316.500098) (xy 294.80813 -316.51379) (xy 294.852592 -316.534888)
			(xy 294.893095 -316.562844) (xy 294.928588 -316.596936) (xy 294.958153 -316.63628) (xy 294.981024 -316.679857)
			(xy 294.996608 -316.726538) (xy 295.004503 -316.775115) (xy 295.004998 -316.799722) (xy 296.29406 -316.799722)
			(xy 296.29802 -316.750668) (xy 296.309797 -316.702884) (xy 296.329088 -316.657608) (xy 296.355391 -316.616012)
			(xy 296.388026 -316.579175) (xy 296.426147 -316.54805) (xy 296.468768 -316.523443) (xy 296.514784 -316.505991)
			(xy 296.563003 -316.496147) (xy 296.612178 -316.494166) (xy 296.661033 -316.500098) (xy 296.708304 -316.51379)
			(xy 296.752766 -316.534888) (xy 296.793269 -316.562844) (xy 296.828762 -316.596936) (xy 296.858327 -316.63628)
			(xy 296.881198 -316.679857) (xy 296.896782 -316.726538) (xy 296.904677 -316.775115) (xy 296.905172 -316.799722)
			(xy 298.19398 -316.799722) (xy 298.19794 -316.750668) (xy 298.209717 -316.702884) (xy 298.229008 -316.657608)
			(xy 298.255311 -316.616012) (xy 298.287946 -316.579175) (xy 298.326067 -316.54805) (xy 298.368688 -316.523443)
			(xy 298.414704 -316.505991) (xy 298.462923 -316.496147) (xy 298.512098 -316.494166) (xy 298.560953 -316.500098)
			(xy 298.608224 -316.51379) (xy 298.652686 -316.534888) (xy 298.693189 -316.562844) (xy 298.728682 -316.596936)
			(xy 298.758247 -316.63628) (xy 298.781118 -316.679857) (xy 298.796702 -316.726538) (xy 298.804597 -316.775115)
			(xy 298.805092 -316.799722) (xy 300.0939 -316.799722) (xy 300.09786 -316.750668) (xy 300.109637 -316.702884)
			(xy 300.128928 -316.657608) (xy 300.155231 -316.616012) (xy 300.187866 -316.579175) (xy 300.225987 -316.54805)
			(xy 300.268608 -316.523443) (xy 300.314624 -316.505991) (xy 300.362843 -316.496147) (xy 300.412018 -316.494166)
			(xy 300.460873 -316.500098) (xy 300.508144 -316.51379) (xy 300.552606 -316.534888) (xy 300.593109 -316.562844)
			(xy 300.628602 -316.596936) (xy 300.658167 -316.63628) (xy 300.681038 -316.679857) (xy 300.696622 -316.726538)
			(xy 300.704517 -316.775115) (xy 300.705012 -316.799722) (xy 301.994074 -316.799722) (xy 301.998034 -316.750668)
			(xy 302.009811 -316.702884) (xy 302.029102 -316.657608) (xy 302.055405 -316.616012) (xy 302.08804 -316.579175)
			(xy 302.126161 -316.54805) (xy 302.168782 -316.523443) (xy 302.214798 -316.505991) (xy 302.263017 -316.496147)
			(xy 302.312192 -316.494166) (xy 302.361047 -316.500098) (xy 302.408318 -316.51379) (xy 302.45278 -316.534888)
			(xy 302.493283 -316.562844) (xy 302.528776 -316.596936) (xy 302.558341 -316.63628) (xy 302.581212 -316.679857)
			(xy 302.596796 -316.726538) (xy 302.604691 -316.775115) (xy 302.605186 -316.799722) (xy 303.893994 -316.799722)
			(xy 303.897954 -316.750668) (xy 303.909731 -316.702884) (xy 303.929022 -316.657608) (xy 303.955325 -316.616012)
			(xy 303.98796 -316.579175) (xy 304.026081 -316.54805) (xy 304.068702 -316.523443) (xy 304.114718 -316.505991)
			(xy 304.162937 -316.496147) (xy 304.212112 -316.494166) (xy 304.260967 -316.500098) (xy 304.308238 -316.51379)
			(xy 304.3527 -316.534888) (xy 304.393203 -316.562844) (xy 304.428696 -316.596936) (xy 304.458261 -316.63628)
			(xy 304.481132 -316.679857) (xy 304.496716 -316.726538) (xy 304.504611 -316.775115) (xy 304.505106 -316.799722)
			(xy 305.793914 -316.799722) (xy 305.797874 -316.750668) (xy 305.809651 -316.702884) (xy 305.828942 -316.657608)
			(xy 305.855245 -316.616012) (xy 305.88788 -316.579175) (xy 305.926001 -316.54805) (xy 305.968622 -316.523443)
			(xy 306.014638 -316.505991) (xy 306.062857 -316.496147) (xy 306.112032 -316.494166) (xy 306.160887 -316.500098)
			(xy 306.208158 -316.51379) (xy 306.25262 -316.534888) (xy 306.293123 -316.562844) (xy 306.328616 -316.596936)
			(xy 306.358181 -316.63628) (xy 306.381052 -316.679857) (xy 306.396636 -316.726538) (xy 306.404531 -316.775115)
			(xy 306.405026 -316.799722) (xy 307.694088 -316.799722) (xy 307.698048 -316.750668) (xy 307.709825 -316.702884)
			(xy 307.729116 -316.657608) (xy 307.755419 -316.616012) (xy 307.788054 -316.579175) (xy 307.826175 -316.54805)
			(xy 307.868796 -316.523443) (xy 307.914812 -316.505991) (xy 307.963031 -316.496147) (xy 308.012206 -316.494166)
			(xy 308.061061 -316.500098) (xy 308.108332 -316.51379) (xy 308.152794 -316.534888) (xy 308.193297 -316.562844)
			(xy 308.22879 -316.596936) (xy 308.258355 -316.63628) (xy 308.281226 -316.679857) (xy 308.29681 -316.726538)
			(xy 308.304705 -316.775115) (xy 308.3052 -316.799722) (xy 309.594008 -316.799722) (xy 309.597968 -316.750668)
			(xy 309.609745 -316.702884) (xy 309.629036 -316.657608) (xy 309.655339 -316.616012) (xy 309.687974 -316.579175)
			(xy 309.726095 -316.54805) (xy 309.768716 -316.523443) (xy 309.814732 -316.505991) (xy 309.862951 -316.496147)
			(xy 309.912126 -316.494166) (xy 309.960981 -316.500098) (xy 310.008252 -316.51379) (xy 310.052714 -316.534888)
			(xy 310.093217 -316.562844) (xy 310.12871 -316.596936) (xy 310.158275 -316.63628) (xy 310.181146 -316.679857)
			(xy 310.19673 -316.726538) (xy 310.204625 -316.775115) (xy 310.20512 -316.799722) (xy 311.493928 -316.799722)
			(xy 311.497888 -316.750668) (xy 311.509665 -316.702884) (xy 311.528956 -316.657608) (xy 311.555259 -316.616012)
			(xy 311.587894 -316.579175) (xy 311.626015 -316.54805) (xy 311.668636 -316.523443) (xy 311.714652 -316.505991)
			(xy 311.762871 -316.496147) (xy 311.812046 -316.494166) (xy 311.860901 -316.500098) (xy 311.908172 -316.51379)
			(xy 311.952634 -316.534888) (xy 311.993137 -316.562844) (xy 312.02863 -316.596936) (xy 312.058195 -316.63628)
			(xy 312.081066 -316.679857) (xy 312.09665 -316.726538) (xy 312.104545 -316.775115) (xy 312.10504 -316.799722)
			(xy 313.394102 -316.799722) (xy 313.398062 -316.750668) (xy 313.409839 -316.702884) (xy 313.42913 -316.657608)
			(xy 313.455433 -316.616012) (xy 313.488068 -316.579175) (xy 313.526189 -316.54805) (xy 313.56881 -316.523443)
			(xy 313.614826 -316.505991) (xy 313.663045 -316.496147) (xy 313.71222 -316.494166) (xy 313.761075 -316.500098)
			(xy 313.808346 -316.51379) (xy 313.852808 -316.534888) (xy 313.893311 -316.562844) (xy 313.928804 -316.596936)
			(xy 313.958369 -316.63628) (xy 313.98124 -316.679857) (xy 313.996824 -316.726538) (xy 314.004719 -316.775115)
			(xy 314.005214 -316.799722) (xy 314.344062 -316.799722) (xy 314.348022 -316.750668) (xy 314.359799 -316.702884)
			(xy 314.37909 -316.657608) (xy 314.405393 -316.616012) (xy 314.438028 -316.579175) (xy 314.476149 -316.54805)
			(xy 314.51877 -316.523443) (xy 314.564786 -316.505991) (xy 314.613005 -316.496147) (xy 314.66218 -316.494166)
			(xy 314.711035 -316.500098) (xy 314.758306 -316.51379) (xy 314.802768 -316.534888) (xy 314.843271 -316.562844)
			(xy 314.878764 -316.596936) (xy 314.908329 -316.63628) (xy 314.9312 -316.679857) (xy 314.946784 -316.726538)
			(xy 314.954679 -316.775115) (xy 314.955174 -316.799722) (xy 384.844048 -316.799722) (xy 384.848008 -316.750668)
			(xy 384.859785 -316.702884) (xy 384.879076 -316.657608) (xy 384.905379 -316.616012) (xy 384.938014 -316.579175)
			(xy 384.976135 -316.54805) (xy 385.018756 -316.523443) (xy 385.064772 -316.505991) (xy 385.112991 -316.496147)
			(xy 385.162166 -316.494166) (xy 385.211021 -316.500098) (xy 385.258292 -316.51379) (xy 385.302754 -316.534888)
			(xy 385.343257 -316.562844) (xy 385.37875 -316.596936) (xy 385.408315 -316.63628) (xy 385.431186 -316.679857)
			(xy 385.44677 -316.726538) (xy 385.454665 -316.775115) (xy 385.45516 -316.799722) (xy 385.794008 -316.799722)
			(xy 385.797968 -316.750668) (xy 385.809745 -316.702884) (xy 385.829036 -316.657608) (xy 385.855339 -316.616012)
			(xy 385.887974 -316.579175) (xy 385.926095 -316.54805) (xy 385.968716 -316.523443) (xy 386.014732 -316.505991)
			(xy 386.062951 -316.496147) (xy 386.112126 -316.494166) (xy 386.160981 -316.500098) (xy 386.208252 -316.51379)
			(xy 386.252714 -316.534888) (xy 386.293217 -316.562844) (xy 386.32871 -316.596936) (xy 386.358275 -316.63628)
			(xy 386.381146 -316.679857) (xy 386.39673 -316.726538) (xy 386.404625 -316.775115) (xy 386.40512 -316.799722)
			(xy 387.694182 -316.799722) (xy 387.698142 -316.750668) (xy 387.709919 -316.702884) (xy 387.72921 -316.657608)
			(xy 387.755513 -316.616012) (xy 387.788148 -316.579175) (xy 387.826269 -316.54805) (xy 387.86889 -316.523443)
			(xy 387.914906 -316.505991) (xy 387.963125 -316.496147) (xy 388.0123 -316.494166) (xy 388.061155 -316.500098)
			(xy 388.108426 -316.51379) (xy 388.152888 -316.534888) (xy 388.193391 -316.562844) (xy 388.228884 -316.596936)
			(xy 388.258449 -316.63628) (xy 388.28132 -316.679857) (xy 388.296904 -316.726538) (xy 388.304799 -316.775115)
			(xy 388.305294 -316.799722) (xy 389.594102 -316.799722) (xy 389.598062 -316.750668) (xy 389.609839 -316.702884)
			(xy 389.62913 -316.657608) (xy 389.655433 -316.616012) (xy 389.688068 -316.579175) (xy 389.726189 -316.54805)
			(xy 389.76881 -316.523443) (xy 389.814826 -316.505991) (xy 389.863045 -316.496147) (xy 389.91222 -316.494166)
			(xy 389.961075 -316.500098) (xy 390.008346 -316.51379) (xy 390.052808 -316.534888) (xy 390.093311 -316.562844)
			(xy 390.128804 -316.596936) (xy 390.158369 -316.63628) (xy 390.18124 -316.679857) (xy 390.196824 -316.726538)
			(xy 390.204719 -316.775115) (xy 390.205214 -316.799722) (xy 391.494022 -316.799722) (xy 391.497982 -316.750668)
			(xy 391.509759 -316.702884) (xy 391.52905 -316.657608) (xy 391.555353 -316.616012) (xy 391.587988 -316.579175)
			(xy 391.626109 -316.54805) (xy 391.66873 -316.523443) (xy 391.714746 -316.505991) (xy 391.762965 -316.496147)
			(xy 391.81214 -316.494166) (xy 391.860995 -316.500098) (xy 391.908266 -316.51379) (xy 391.952728 -316.534888)
			(xy 391.993231 -316.562844) (xy 392.028724 -316.596936) (xy 392.058289 -316.63628) (xy 392.08116 -316.679857)
			(xy 392.096744 -316.726538) (xy 392.104639 -316.775115) (xy 392.105134 -316.799722) (xy 393.394196 -316.799722)
			(xy 393.398156 -316.750668) (xy 393.409933 -316.702884) (xy 393.429224 -316.657608) (xy 393.455527 -316.616012)
			(xy 393.488162 -316.579175) (xy 393.526283 -316.54805) (xy 393.568904 -316.523443) (xy 393.61492 -316.505991)
			(xy 393.663139 -316.496147) (xy 393.712314 -316.494166) (xy 393.761169 -316.500098) (xy 393.80844 -316.51379)
			(xy 393.852902 -316.534888) (xy 393.893405 -316.562844) (xy 393.928898 -316.596936) (xy 393.958463 -316.63628)
			(xy 393.981334 -316.679857) (xy 393.996918 -316.726538) (xy 394.004813 -316.775115) (xy 394.005308 -316.799722)
			(xy 395.294116 -316.799722) (xy 395.298076 -316.750668) (xy 395.309853 -316.702884) (xy 395.329144 -316.657608)
			(xy 395.355447 -316.616012) (xy 395.388082 -316.579175) (xy 395.426203 -316.54805) (xy 395.468824 -316.523443)
			(xy 395.51484 -316.505991) (xy 395.563059 -316.496147) (xy 395.612234 -316.494166) (xy 395.661089 -316.500098)
			(xy 395.70836 -316.51379) (xy 395.752822 -316.534888) (xy 395.793325 -316.562844) (xy 395.828818 -316.596936)
			(xy 395.858383 -316.63628) (xy 395.881254 -316.679857) (xy 395.896838 -316.726538) (xy 395.904733 -316.775115)
			(xy 395.905228 -316.799722) (xy 397.194036 -316.799722) (xy 397.197996 -316.750668) (xy 397.209773 -316.702884)
			(xy 397.229064 -316.657608) (xy 397.255367 -316.616012) (xy 397.288002 -316.579175) (xy 397.326123 -316.54805)
			(xy 397.368744 -316.523443) (xy 397.41476 -316.505991) (xy 397.462979 -316.496147) (xy 397.512154 -316.494166)
			(xy 397.561009 -316.500098) (xy 397.60828 -316.51379) (xy 397.652742 -316.534888) (xy 397.693245 -316.562844)
			(xy 397.728738 -316.596936) (xy 397.758303 -316.63628) (xy 397.781174 -316.679857) (xy 397.796758 -316.726538)
			(xy 397.804653 -316.775115) (xy 397.805148 -316.799722) (xy 399.09421 -316.799722) (xy 399.09817 -316.750668)
			(xy 399.109947 -316.702884) (xy 399.129238 -316.657608) (xy 399.155541 -316.616012) (xy 399.188176 -316.579175)
			(xy 399.226297 -316.54805) (xy 399.268918 -316.523443) (xy 399.314934 -316.505991) (xy 399.363153 -316.496147)
			(xy 399.412328 -316.494166) (xy 399.461183 -316.500098) (xy 399.508454 -316.51379) (xy 399.552916 -316.534888)
			(xy 399.593419 -316.562844) (xy 399.628912 -316.596936) (xy 399.658477 -316.63628) (xy 399.681348 -316.679857)
			(xy 399.696932 -316.726538) (xy 399.704827 -316.775115) (xy 399.705322 -316.799722) (xy 400.99413 -316.799722)
			(xy 400.99809 -316.750668) (xy 401.009867 -316.702884) (xy 401.029158 -316.657608) (xy 401.055461 -316.616012)
			(xy 401.088096 -316.579175) (xy 401.126217 -316.54805) (xy 401.168838 -316.523443) (xy 401.214854 -316.505991)
			(xy 401.263073 -316.496147) (xy 401.312248 -316.494166) (xy 401.361103 -316.500098) (xy 401.408374 -316.51379)
			(xy 401.452836 -316.534888) (xy 401.493339 -316.562844) (xy 401.528832 -316.596936) (xy 401.558397 -316.63628)
			(xy 401.581268 -316.679857) (xy 401.596852 -316.726538) (xy 401.604747 -316.775115) (xy 401.605242 -316.799722)
			(xy 402.89405 -316.799722) (xy 402.89801 -316.750668) (xy 402.909787 -316.702884) (xy 402.929078 -316.657608)
			(xy 402.955381 -316.616012) (xy 402.988016 -316.579175) (xy 403.026137 -316.54805) (xy 403.068758 -316.523443)
			(xy 403.114774 -316.505991) (xy 403.162993 -316.496147) (xy 403.212168 -316.494166) (xy 403.261023 -316.500098)
			(xy 403.308294 -316.51379) (xy 403.352756 -316.534888) (xy 403.393259 -316.562844) (xy 403.428752 -316.596936)
			(xy 403.458317 -316.63628) (xy 403.481188 -316.679857) (xy 403.496772 -316.726538) (xy 403.504667 -316.775115)
			(xy 403.505162 -316.799722) (xy 404.794224 -316.799722) (xy 404.798184 -316.750668) (xy 404.809961 -316.702884)
			(xy 404.829252 -316.657608) (xy 404.855555 -316.616012) (xy 404.88819 -316.579175) (xy 404.926311 -316.54805)
			(xy 404.968932 -316.523443) (xy 405.014948 -316.505991) (xy 405.063167 -316.496147) (xy 405.112342 -316.494166)
			(xy 405.161197 -316.500098) (xy 405.208468 -316.51379) (xy 405.25293 -316.534888) (xy 405.293433 -316.562844)
			(xy 405.328926 -316.596936) (xy 405.358491 -316.63628) (xy 405.381362 -316.679857) (xy 405.396946 -316.726538)
			(xy 405.404841 -316.775115) (xy 405.405336 -316.799722) (xy 406.694144 -316.799722) (xy 406.698104 -316.750668)
			(xy 406.709881 -316.702884) (xy 406.729172 -316.657608) (xy 406.755475 -316.616012) (xy 406.78811 -316.579175)
			(xy 406.826231 -316.54805) (xy 406.868852 -316.523443) (xy 406.914868 -316.505991) (xy 406.963087 -316.496147)
			(xy 407.012262 -316.494166) (xy 407.061117 -316.500098) (xy 407.108388 -316.51379) (xy 407.15285 -316.534888)
			(xy 407.193353 -316.562844) (xy 407.228846 -316.596936) (xy 407.258411 -316.63628) (xy 407.281282 -316.679857)
			(xy 407.296866 -316.726538) (xy 407.304761 -316.775115) (xy 407.305256 -316.799722) (xy 408.594064 -316.799722)
			(xy 408.598024 -316.750668) (xy 408.609801 -316.702884) (xy 408.629092 -316.657608) (xy 408.655395 -316.616012)
			(xy 408.68803 -316.579175) (xy 408.726151 -316.54805) (xy 408.768772 -316.523443) (xy 408.814788 -316.505991)
			(xy 408.863007 -316.496147) (xy 408.912182 -316.494166) (xy 408.961037 -316.500098) (xy 409.008308 -316.51379)
			(xy 409.05277 -316.534888) (xy 409.093273 -316.562844) (xy 409.128766 -316.596936) (xy 409.158331 -316.63628)
			(xy 409.181202 -316.679857) (xy 409.196786 -316.726538) (xy 409.204681 -316.775115) (xy 409.205176 -316.799722)
			(xy 410.493984 -316.799722) (xy 410.497944 -316.750668) (xy 410.509721 -316.702884) (xy 410.529012 -316.657608)
			(xy 410.555315 -316.616012) (xy 410.58795 -316.579175) (xy 410.626071 -316.54805) (xy 410.668692 -316.523443)
			(xy 410.714708 -316.505991) (xy 410.762927 -316.496147) (xy 410.812102 -316.494166) (xy 410.860957 -316.500098)
			(xy 410.908228 -316.51379) (xy 410.95269 -316.534888) (xy 410.993193 -316.562844) (xy 411.028686 -316.596936)
			(xy 411.058251 -316.63628) (xy 411.081122 -316.679857) (xy 411.096706 -316.726538) (xy 411.104601 -316.775115)
			(xy 411.105096 -316.799722) (xy 412.394158 -316.799722) (xy 412.398118 -316.750668) (xy 412.409895 -316.702884)
			(xy 412.429186 -316.657608) (xy 412.455489 -316.616012) (xy 412.488124 -316.579175) (xy 412.526245 -316.54805)
			(xy 412.568866 -316.523443) (xy 412.614882 -316.505991) (xy 412.663101 -316.496147) (xy 412.712276 -316.494166)
			(xy 412.761131 -316.500098) (xy 412.808402 -316.51379) (xy 412.852864 -316.534888) (xy 412.893367 -316.562844)
			(xy 412.92886 -316.596936) (xy 412.958425 -316.63628) (xy 412.981296 -316.679857) (xy 412.99688 -316.726538)
			(xy 413.004775 -316.775115) (xy 413.00527 -316.799722) (xy 414.294078 -316.799722) (xy 414.298038 -316.750668)
			(xy 414.309815 -316.702884) (xy 414.329106 -316.657608) (xy 414.355409 -316.616012) (xy 414.388044 -316.579175)
			(xy 414.426165 -316.54805) (xy 414.468786 -316.523443) (xy 414.514802 -316.505991) (xy 414.563021 -316.496147)
			(xy 414.612196 -316.494166) (xy 414.661051 -316.500098) (xy 414.708322 -316.51379) (xy 414.752784 -316.534888)
			(xy 414.793287 -316.562844) (xy 414.82878 -316.596936) (xy 414.858345 -316.63628) (xy 414.881216 -316.679857)
			(xy 414.8968 -316.726538) (xy 414.904695 -316.775115) (xy 414.90519 -316.799722) (xy 416.193998 -316.799722)
			(xy 416.197958 -316.750668) (xy 416.209735 -316.702884) (xy 416.229026 -316.657608) (xy 416.255329 -316.616012)
			(xy 416.287964 -316.579175) (xy 416.326085 -316.54805) (xy 416.368706 -316.523443) (xy 416.414722 -316.505991)
			(xy 416.462941 -316.496147) (xy 416.512116 -316.494166) (xy 416.560971 -316.500098) (xy 416.608242 -316.51379)
			(xy 416.652704 -316.534888) (xy 416.693207 -316.562844) (xy 416.7287 -316.596936) (xy 416.758265 -316.63628)
			(xy 416.781136 -316.679857) (xy 416.79672 -316.726538) (xy 416.804615 -316.775115) (xy 416.80511 -316.799722)
			(xy 418.094172 -316.799722) (xy 418.098132 -316.750668) (xy 418.109909 -316.702884) (xy 418.1292 -316.657608)
			(xy 418.155503 -316.616012) (xy 418.188138 -316.579175) (xy 418.226259 -316.54805) (xy 418.26888 -316.523443)
			(xy 418.314896 -316.505991) (xy 418.363115 -316.496147) (xy 418.41229 -316.494166) (xy 418.461145 -316.500098)
			(xy 418.508416 -316.51379) (xy 418.552878 -316.534888) (xy 418.593381 -316.562844) (xy 418.628874 -316.596936)
			(xy 418.658439 -316.63628) (xy 418.68131 -316.679857) (xy 418.696894 -316.726538) (xy 418.704789 -316.775115)
			(xy 418.705284 -316.799722) (xy 419.994092 -316.799722) (xy 419.998052 -316.750668) (xy 420.009829 -316.702884)
			(xy 420.02912 -316.657608) (xy 420.055423 -316.616012) (xy 420.088058 -316.579175) (xy 420.126179 -316.54805)
			(xy 420.1688 -316.523443) (xy 420.214816 -316.505991) (xy 420.263035 -316.496147) (xy 420.31221 -316.494166)
			(xy 420.361065 -316.500098) (xy 420.408336 -316.51379) (xy 420.452798 -316.534888) (xy 420.493301 -316.562844)
			(xy 420.528794 -316.596936) (xy 420.558359 -316.63628) (xy 420.58123 -316.679857) (xy 420.596814 -316.726538)
			(xy 420.604709 -316.775115) (xy 420.605204 -316.799722) (xy 421.894012 -316.799722) (xy 421.897972 -316.750668)
			(xy 421.909749 -316.702884) (xy 421.92904 -316.657608) (xy 421.955343 -316.616012) (xy 421.987978 -316.579175)
			(xy 422.026099 -316.54805) (xy 422.06872 -316.523443) (xy 422.114736 -316.505991) (xy 422.162955 -316.496147)
			(xy 422.21213 -316.494166) (xy 422.260985 -316.500098) (xy 422.308256 -316.51379) (xy 422.352718 -316.534888)
			(xy 422.393221 -316.562844) (xy 422.428714 -316.596936) (xy 422.458279 -316.63628) (xy 422.48115 -316.679857)
			(xy 422.496734 -316.726538) (xy 422.504629 -316.775115) (xy 422.505124 -316.799722) (xy 423.794186 -316.799722)
			(xy 423.798146 -316.750668) (xy 423.809923 -316.702884) (xy 423.829214 -316.657608) (xy 423.855517 -316.616012)
			(xy 423.888152 -316.579175) (xy 423.926273 -316.54805) (xy 423.968894 -316.523443) (xy 424.01491 -316.505991)
			(xy 424.063129 -316.496147) (xy 424.112304 -316.494166) (xy 424.161159 -316.500098) (xy 424.20843 -316.51379)
			(xy 424.252892 -316.534888) (xy 424.293395 -316.562844) (xy 424.328888 -316.596936) (xy 424.358453 -316.63628)
			(xy 424.381324 -316.679857) (xy 424.396908 -316.726538) (xy 424.404803 -316.775115) (xy 424.405298 -316.799722)
			(xy 425.694106 -316.799722) (xy 425.698066 -316.750668) (xy 425.709843 -316.702884) (xy 425.729134 -316.657608)
			(xy 425.755437 -316.616012) (xy 425.788072 -316.579175) (xy 425.826193 -316.54805) (xy 425.868814 -316.523443)
			(xy 425.91483 -316.505991) (xy 425.963049 -316.496147) (xy 426.012224 -316.494166) (xy 426.061079 -316.500098)
			(xy 426.10835 -316.51379) (xy 426.152812 -316.534888) (xy 426.193315 -316.562844) (xy 426.228808 -316.596936)
			(xy 426.258373 -316.63628) (xy 426.281244 -316.679857) (xy 426.296828 -316.726538) (xy 426.304723 -316.775115)
			(xy 426.305218 -316.799722) (xy 427.594026 -316.799722) (xy 427.597986 -316.750668) (xy 427.609763 -316.702884)
			(xy 427.629054 -316.657608) (xy 427.655357 -316.616012) (xy 427.687992 -316.579175) (xy 427.726113 -316.54805)
			(xy 427.768734 -316.523443) (xy 427.81475 -316.505991) (xy 427.862969 -316.496147) (xy 427.912144 -316.494166)
			(xy 427.960999 -316.500098) (xy 428.00827 -316.51379) (xy 428.052732 -316.534888) (xy 428.093235 -316.562844)
			(xy 428.128728 -316.596936) (xy 428.158293 -316.63628) (xy 428.181164 -316.679857) (xy 428.196748 -316.726538)
			(xy 428.204643 -316.775115) (xy 428.205138 -316.799722) (xy 429.4942 -316.799722) (xy 429.49816 -316.750668)
			(xy 429.509937 -316.702884) (xy 429.529228 -316.657608) (xy 429.555531 -316.616012) (xy 429.588166 -316.579175)
			(xy 429.626287 -316.54805) (xy 429.668908 -316.523443) (xy 429.714924 -316.505991) (xy 429.763143 -316.496147)
			(xy 429.812318 -316.494166) (xy 429.861173 -316.500098) (xy 429.908444 -316.51379) (xy 429.952906 -316.534888)
			(xy 429.993409 -316.562844) (xy 430.028902 -316.596936) (xy 430.058467 -316.63628) (xy 430.081338 -316.679857)
			(xy 430.096922 -316.726538) (xy 430.104817 -316.775115) (xy 430.105312 -316.799722) (xy 430.44416 -316.799722)
			(xy 430.44812 -316.750668) (xy 430.459897 -316.702884) (xy 430.479188 -316.657608) (xy 430.505491 -316.616012)
			(xy 430.538126 -316.579175) (xy 430.576247 -316.54805) (xy 430.618868 -316.523443) (xy 430.664884 -316.505991)
			(xy 430.713103 -316.496147) (xy 430.762278 -316.494166) (xy 430.811133 -316.500098) (xy 430.858404 -316.51379)
			(xy 430.902866 -316.534888) (xy 430.943369 -316.562844) (xy 430.978862 -316.596936) (xy 431.008427 -316.63628)
			(xy 431.031298 -316.679857) (xy 431.046882 -316.726538) (xy 431.054777 -316.775115) (xy 431.055272 -316.799722)
			(xy 431.054777 -316.824329) (xy 431.046882 -316.872906) (xy 431.031298 -316.919587) (xy 431.008427 -316.963164)
			(xy 430.978862 -317.002508) (xy 430.943369 -317.0366) (xy 430.902866 -317.064556) (xy 430.858404 -317.085654)
			(xy 430.811133 -317.099346) (xy 430.762278 -317.105278) (xy 430.713103 -317.103297) (xy 430.664884 -317.093453)
			(xy 430.618868 -317.076001) (xy 430.576247 -317.051394) (xy 430.538126 -317.020269) (xy 430.505491 -316.983432)
			(xy 430.479188 -316.941836) (xy 430.459897 -316.89656) (xy 430.44812 -316.848776) (xy 430.44416 -316.799722)
			(xy 430.105312 -316.799722) (xy 430.104817 -316.824329) (xy 430.096922 -316.872906) (xy 430.081338 -316.919587)
			(xy 430.058467 -316.963164) (xy 430.028902 -317.002508) (xy 429.993409 -317.0366) (xy 429.952906 -317.064556)
			(xy 429.908444 -317.085654) (xy 429.861173 -317.099346) (xy 429.812318 -317.105278) (xy 429.763143 -317.103297)
			(xy 429.714924 -317.093453) (xy 429.668908 -317.076001) (xy 429.626287 -317.051394) (xy 429.588166 -317.020269)
			(xy 429.555531 -316.983432) (xy 429.529228 -316.941836) (xy 429.509937 -316.89656) (xy 429.49816 -316.848776)
			(xy 429.4942 -316.799722) (xy 428.205138 -316.799722) (xy 428.204643 -316.824329) (xy 428.196748 -316.872906)
			(xy 428.181164 -316.919587) (xy 428.158293 -316.963164) (xy 428.128728 -317.002508) (xy 428.093235 -317.0366)
			(xy 428.052732 -317.064556) (xy 428.00827 -317.085654) (xy 427.960999 -317.099346) (xy 427.912144 -317.105278)
			(xy 427.862969 -317.103297) (xy 427.81475 -317.093453) (xy 427.768734 -317.076001) (xy 427.726113 -317.051394)
			(xy 427.687992 -317.020269) (xy 427.655357 -316.983432) (xy 427.629054 -316.941836) (xy 427.609763 -316.89656)
			(xy 427.597986 -316.848776) (xy 427.594026 -316.799722) (xy 426.305218 -316.799722) (xy 426.304723 -316.824329)
			(xy 426.296828 -316.872906) (xy 426.281244 -316.919587) (xy 426.258373 -316.963164) (xy 426.228808 -317.002508)
			(xy 426.193315 -317.0366) (xy 426.152812 -317.064556) (xy 426.10835 -317.085654) (xy 426.061079 -317.099346)
			(xy 426.012224 -317.105278) (xy 425.963049 -317.103297) (xy 425.91483 -317.093453) (xy 425.868814 -317.076001)
			(xy 425.826193 -317.051394) (xy 425.788072 -317.020269) (xy 425.755437 -316.983432) (xy 425.729134 -316.941836)
			(xy 425.709843 -316.89656) (xy 425.698066 -316.848776) (xy 425.694106 -316.799722) (xy 424.405298 -316.799722)
			(xy 424.404803 -316.824329) (xy 424.396908 -316.872906) (xy 424.381324 -316.919587) (xy 424.358453 -316.963164)
			(xy 424.328888 -317.002508) (xy 424.293395 -317.0366) (xy 424.252892 -317.064556) (xy 424.20843 -317.085654)
			(xy 424.161159 -317.099346) (xy 424.112304 -317.105278) (xy 424.063129 -317.103297) (xy 424.01491 -317.093453)
			(xy 423.968894 -317.076001) (xy 423.926273 -317.051394) (xy 423.888152 -317.020269) (xy 423.855517 -316.983432)
			(xy 423.829214 -316.941836) (xy 423.809923 -316.89656) (xy 423.798146 -316.848776) (xy 423.794186 -316.799722)
			(xy 422.505124 -316.799722) (xy 422.504629 -316.824329) (xy 422.496734 -316.872906) (xy 422.48115 -316.919587)
			(xy 422.458279 -316.963164) (xy 422.428714 -317.002508) (xy 422.393221 -317.0366) (xy 422.352718 -317.064556)
			(xy 422.308256 -317.085654) (xy 422.260985 -317.099346) (xy 422.21213 -317.105278) (xy 422.162955 -317.103297)
			(xy 422.114736 -317.093453) (xy 422.06872 -317.076001) (xy 422.026099 -317.051394) (xy 421.987978 -317.020269)
			(xy 421.955343 -316.983432) (xy 421.92904 -316.941836) (xy 421.909749 -316.89656) (xy 421.897972 -316.848776)
			(xy 421.894012 -316.799722) (xy 420.605204 -316.799722) (xy 420.604709 -316.824329) (xy 420.596814 -316.872906)
			(xy 420.58123 -316.919587) (xy 420.558359 -316.963164) (xy 420.528794 -317.002508) (xy 420.493301 -317.0366)
			(xy 420.452798 -317.064556) (xy 420.408336 -317.085654) (xy 420.361065 -317.099346) (xy 420.31221 -317.105278)
			(xy 420.263035 -317.103297) (xy 420.214816 -317.093453) (xy 420.1688 -317.076001) (xy 420.126179 -317.051394)
			(xy 420.088058 -317.020269) (xy 420.055423 -316.983432) (xy 420.02912 -316.941836) (xy 420.009829 -316.89656)
			(xy 419.998052 -316.848776) (xy 419.994092 -316.799722) (xy 418.705284 -316.799722) (xy 418.704789 -316.824329)
			(xy 418.696894 -316.872906) (xy 418.68131 -316.919587) (xy 418.658439 -316.963164) (xy 418.628874 -317.002508)
			(xy 418.593381 -317.0366) (xy 418.552878 -317.064556) (xy 418.508416 -317.085654) (xy 418.461145 -317.099346)
			(xy 418.41229 -317.105278) (xy 418.363115 -317.103297) (xy 418.314896 -317.093453) (xy 418.26888 -317.076001)
			(xy 418.226259 -317.051394) (xy 418.188138 -317.020269) (xy 418.155503 -316.983432) (xy 418.1292 -316.941836)
			(xy 418.109909 -316.89656) (xy 418.098132 -316.848776) (xy 418.094172 -316.799722) (xy 416.80511 -316.799722)
			(xy 416.804615 -316.824329) (xy 416.79672 -316.872906) (xy 416.781136 -316.919587) (xy 416.758265 -316.963164)
			(xy 416.7287 -317.002508) (xy 416.693207 -317.0366) (xy 416.652704 -317.064556) (xy 416.608242 -317.085654)
			(xy 416.560971 -317.099346) (xy 416.512116 -317.105278) (xy 416.462941 -317.103297) (xy 416.414722 -317.093453)
			(xy 416.368706 -317.076001) (xy 416.326085 -317.051394) (xy 416.287964 -317.020269) (xy 416.255329 -316.983432)
			(xy 416.229026 -316.941836) (xy 416.209735 -316.89656) (xy 416.197958 -316.848776) (xy 416.193998 -316.799722)
			(xy 414.90519 -316.799722) (xy 414.904695 -316.824329) (xy 414.8968 -316.872906) (xy 414.881216 -316.919587)
			(xy 414.858345 -316.963164) (xy 414.82878 -317.002508) (xy 414.793287 -317.0366) (xy 414.752784 -317.064556)
			(xy 414.708322 -317.085654) (xy 414.661051 -317.099346) (xy 414.612196 -317.105278) (xy 414.563021 -317.103297)
			(xy 414.514802 -317.093453) (xy 414.468786 -317.076001) (xy 414.426165 -317.051394) (xy 414.388044 -317.020269)
			(xy 414.355409 -316.983432) (xy 414.329106 -316.941836) (xy 414.309815 -316.89656) (xy 414.298038 -316.848776)
			(xy 414.294078 -316.799722) (xy 413.00527 -316.799722) (xy 413.004775 -316.824329) (xy 412.99688 -316.872906)
			(xy 412.981296 -316.919587) (xy 412.958425 -316.963164) (xy 412.92886 -317.002508) (xy 412.893367 -317.0366)
			(xy 412.852864 -317.064556) (xy 412.808402 -317.085654) (xy 412.761131 -317.099346) (xy 412.712276 -317.105278)
			(xy 412.663101 -317.103297) (xy 412.614882 -317.093453) (xy 412.568866 -317.076001) (xy 412.526245 -317.051394)
			(xy 412.488124 -317.020269) (xy 412.455489 -316.983432) (xy 412.429186 -316.941836) (xy 412.409895 -316.89656)
			(xy 412.398118 -316.848776) (xy 412.394158 -316.799722) (xy 411.105096 -316.799722) (xy 411.104601 -316.824329)
			(xy 411.096706 -316.872906) (xy 411.081122 -316.919587) (xy 411.058251 -316.963164) (xy 411.028686 -317.002508)
			(xy 410.993193 -317.0366) (xy 410.95269 -317.064556) (xy 410.908228 -317.085654) (xy 410.860957 -317.099346)
			(xy 410.812102 -317.105278) (xy 410.762927 -317.103297) (xy 410.714708 -317.093453) (xy 410.668692 -317.076001)
			(xy 410.626071 -317.051394) (xy 410.58795 -317.020269) (xy 410.555315 -316.983432) (xy 410.529012 -316.941836)
			(xy 410.509721 -316.89656) (xy 410.497944 -316.848776) (xy 410.493984 -316.799722) (xy 409.205176 -316.799722)
			(xy 409.204681 -316.824329) (xy 409.196786 -316.872906) (xy 409.181202 -316.919587) (xy 409.158331 -316.963164)
			(xy 409.128766 -317.002508) (xy 409.093273 -317.0366) (xy 409.05277 -317.064556) (xy 409.008308 -317.085654)
			(xy 408.961037 -317.099346) (xy 408.912182 -317.105278) (xy 408.863007 -317.103297) (xy 408.814788 -317.093453)
			(xy 408.768772 -317.076001) (xy 408.726151 -317.051394) (xy 408.68803 -317.020269) (xy 408.655395 -316.983432)
			(xy 408.629092 -316.941836) (xy 408.609801 -316.89656) (xy 408.598024 -316.848776) (xy 408.594064 -316.799722)
			(xy 407.305256 -316.799722) (xy 407.304761 -316.824329) (xy 407.296866 -316.872906) (xy 407.281282 -316.919587)
			(xy 407.258411 -316.963164) (xy 407.228846 -317.002508) (xy 407.193353 -317.0366) (xy 407.15285 -317.064556)
			(xy 407.108388 -317.085654) (xy 407.061117 -317.099346) (xy 407.012262 -317.105278) (xy 406.963087 -317.103297)
			(xy 406.914868 -317.093453) (xy 406.868852 -317.076001) (xy 406.826231 -317.051394) (xy 406.78811 -317.020269)
			(xy 406.755475 -316.983432) (xy 406.729172 -316.941836) (xy 406.709881 -316.89656) (xy 406.698104 -316.848776)
			(xy 406.694144 -316.799722) (xy 405.405336 -316.799722) (xy 405.404841 -316.824329) (xy 405.396946 -316.872906)
			(xy 405.381362 -316.919587) (xy 405.358491 -316.963164) (xy 405.328926 -317.002508) (xy 405.293433 -317.0366)
			(xy 405.25293 -317.064556) (xy 405.208468 -317.085654) (xy 405.161197 -317.099346) (xy 405.112342 -317.105278)
			(xy 405.063167 -317.103297) (xy 405.014948 -317.093453) (xy 404.968932 -317.076001) (xy 404.926311 -317.051394)
			(xy 404.88819 -317.020269) (xy 404.855555 -316.983432) (xy 404.829252 -316.941836) (xy 404.809961 -316.89656)
			(xy 404.798184 -316.848776) (xy 404.794224 -316.799722) (xy 403.505162 -316.799722) (xy 403.504667 -316.824329)
			(xy 403.496772 -316.872906) (xy 403.481188 -316.919587) (xy 403.458317 -316.963164) (xy 403.428752 -317.002508)
			(xy 403.393259 -317.0366) (xy 403.352756 -317.064556) (xy 403.308294 -317.085654) (xy 403.261023 -317.099346)
			(xy 403.212168 -317.105278) (xy 403.162993 -317.103297) (xy 403.114774 -317.093453) (xy 403.068758 -317.076001)
			(xy 403.026137 -317.051394) (xy 402.988016 -317.020269) (xy 402.955381 -316.983432) (xy 402.929078 -316.941836)
			(xy 402.909787 -316.89656) (xy 402.89801 -316.848776) (xy 402.89405 -316.799722) (xy 401.605242 -316.799722)
			(xy 401.604747 -316.824329) (xy 401.596852 -316.872906) (xy 401.581268 -316.919587) (xy 401.558397 -316.963164)
			(xy 401.528832 -317.002508) (xy 401.493339 -317.0366) (xy 401.452836 -317.064556) (xy 401.408374 -317.085654)
			(xy 401.361103 -317.099346) (xy 401.312248 -317.105278) (xy 401.263073 -317.103297) (xy 401.214854 -317.093453)
			(xy 401.168838 -317.076001) (xy 401.126217 -317.051394) (xy 401.088096 -317.020269) (xy 401.055461 -316.983432)
			(xy 401.029158 -316.941836) (xy 401.009867 -316.89656) (xy 400.99809 -316.848776) (xy 400.99413 -316.799722)
			(xy 399.705322 -316.799722) (xy 399.704827 -316.824329) (xy 399.696932 -316.872906) (xy 399.681348 -316.919587)
			(xy 399.658477 -316.963164) (xy 399.628912 -317.002508) (xy 399.593419 -317.0366) (xy 399.552916 -317.064556)
			(xy 399.508454 -317.085654) (xy 399.461183 -317.099346) (xy 399.412328 -317.105278) (xy 399.363153 -317.103297)
			(xy 399.314934 -317.093453) (xy 399.268918 -317.076001) (xy 399.226297 -317.051394) (xy 399.188176 -317.020269)
			(xy 399.155541 -316.983432) (xy 399.129238 -316.941836) (xy 399.109947 -316.89656) (xy 399.09817 -316.848776)
			(xy 399.09421 -316.799722) (xy 397.805148 -316.799722) (xy 397.804653 -316.824329) (xy 397.796758 -316.872906)
			(xy 397.781174 -316.919587) (xy 397.758303 -316.963164) (xy 397.728738 -317.002508) (xy 397.693245 -317.0366)
			(xy 397.652742 -317.064556) (xy 397.60828 -317.085654) (xy 397.561009 -317.099346) (xy 397.512154 -317.105278)
			(xy 397.462979 -317.103297) (xy 397.41476 -317.093453) (xy 397.368744 -317.076001) (xy 397.326123 -317.051394)
			(xy 397.288002 -317.020269) (xy 397.255367 -316.983432) (xy 397.229064 -316.941836) (xy 397.209773 -316.89656)
			(xy 397.197996 -316.848776) (xy 397.194036 -316.799722) (xy 395.905228 -316.799722) (xy 395.904733 -316.824329)
			(xy 395.896838 -316.872906) (xy 395.881254 -316.919587) (xy 395.858383 -316.963164) (xy 395.828818 -317.002508)
			(xy 395.793325 -317.0366) (xy 395.752822 -317.064556) (xy 395.70836 -317.085654) (xy 395.661089 -317.099346)
			(xy 395.612234 -317.105278) (xy 395.563059 -317.103297) (xy 395.51484 -317.093453) (xy 395.468824 -317.076001)
			(xy 395.426203 -317.051394) (xy 395.388082 -317.020269) (xy 395.355447 -316.983432) (xy 395.329144 -316.941836)
			(xy 395.309853 -316.89656) (xy 395.298076 -316.848776) (xy 395.294116 -316.799722) (xy 394.005308 -316.799722)
			(xy 394.004813 -316.824329) (xy 393.996918 -316.872906) (xy 393.981334 -316.919587) (xy 393.958463 -316.963164)
			(xy 393.928898 -317.002508) (xy 393.893405 -317.0366) (xy 393.852902 -317.064556) (xy 393.80844 -317.085654)
			(xy 393.761169 -317.099346) (xy 393.712314 -317.105278) (xy 393.663139 -317.103297) (xy 393.61492 -317.093453)
			(xy 393.568904 -317.076001) (xy 393.526283 -317.051394) (xy 393.488162 -317.020269) (xy 393.455527 -316.983432)
			(xy 393.429224 -316.941836) (xy 393.409933 -316.89656) (xy 393.398156 -316.848776) (xy 393.394196 -316.799722)
			(xy 392.105134 -316.799722) (xy 392.104639 -316.824329) (xy 392.096744 -316.872906) (xy 392.08116 -316.919587)
			(xy 392.058289 -316.963164) (xy 392.028724 -317.002508) (xy 391.993231 -317.0366) (xy 391.952728 -317.064556)
			(xy 391.908266 -317.085654) (xy 391.860995 -317.099346) (xy 391.81214 -317.105278) (xy 391.762965 -317.103297)
			(xy 391.714746 -317.093453) (xy 391.66873 -317.076001) (xy 391.626109 -317.051394) (xy 391.587988 -317.020269)
			(xy 391.555353 -316.983432) (xy 391.52905 -316.941836) (xy 391.509759 -316.89656) (xy 391.497982 -316.848776)
			(xy 391.494022 -316.799722) (xy 390.205214 -316.799722) (xy 390.204719 -316.824329) (xy 390.196824 -316.872906)
			(xy 390.18124 -316.919587) (xy 390.158369 -316.963164) (xy 390.128804 -317.002508) (xy 390.093311 -317.0366)
			(xy 390.052808 -317.064556) (xy 390.008346 -317.085654) (xy 389.961075 -317.099346) (xy 389.91222 -317.105278)
			(xy 389.863045 -317.103297) (xy 389.814826 -317.093453) (xy 389.76881 -317.076001) (xy 389.726189 -317.051394)
			(xy 389.688068 -317.020269) (xy 389.655433 -316.983432) (xy 389.62913 -316.941836) (xy 389.609839 -316.89656)
			(xy 389.598062 -316.848776) (xy 389.594102 -316.799722) (xy 388.305294 -316.799722) (xy 388.304799 -316.824329)
			(xy 388.296904 -316.872906) (xy 388.28132 -316.919587) (xy 388.258449 -316.963164) (xy 388.228884 -317.002508)
			(xy 388.193391 -317.0366) (xy 388.152888 -317.064556) (xy 388.108426 -317.085654) (xy 388.061155 -317.099346)
			(xy 388.0123 -317.105278) (xy 387.963125 -317.103297) (xy 387.914906 -317.093453) (xy 387.86889 -317.076001)
			(xy 387.826269 -317.051394) (xy 387.788148 -317.020269) (xy 387.755513 -316.983432) (xy 387.72921 -316.941836)
			(xy 387.709919 -316.89656) (xy 387.698142 -316.848776) (xy 387.694182 -316.799722) (xy 386.40512 -316.799722)
			(xy 386.404625 -316.824329) (xy 386.39673 -316.872906) (xy 386.381146 -316.919587) (xy 386.358275 -316.963164)
			(xy 386.32871 -317.002508) (xy 386.293217 -317.0366) (xy 386.252714 -317.064556) (xy 386.208252 -317.085654)
			(xy 386.160981 -317.099346) (xy 386.112126 -317.105278) (xy 386.062951 -317.103297) (xy 386.014732 -317.093453)
			(xy 385.968716 -317.076001) (xy 385.926095 -317.051394) (xy 385.887974 -317.020269) (xy 385.855339 -316.983432)
			(xy 385.829036 -316.941836) (xy 385.809745 -316.89656) (xy 385.797968 -316.848776) (xy 385.794008 -316.799722)
			(xy 385.45516 -316.799722) (xy 385.454665 -316.824329) (xy 385.44677 -316.872906) (xy 385.431186 -316.919587)
			(xy 385.408315 -316.963164) (xy 385.37875 -317.002508) (xy 385.343257 -317.0366) (xy 385.302754 -317.064556)
			(xy 385.258292 -317.085654) (xy 385.211021 -317.099346) (xy 385.162166 -317.105278) (xy 385.112991 -317.103297)
			(xy 385.064772 -317.093453) (xy 385.018756 -317.076001) (xy 384.976135 -317.051394) (xy 384.938014 -317.020269)
			(xy 384.905379 -316.983432) (xy 384.879076 -316.941836) (xy 384.859785 -316.89656) (xy 384.848008 -316.848776)
			(xy 384.844048 -316.799722) (xy 314.955174 -316.799722) (xy 314.954679 -316.824329) (xy 314.946784 -316.872906)
			(xy 314.9312 -316.919587) (xy 314.908329 -316.963164) (xy 314.878764 -317.002508) (xy 314.843271 -317.0366)
			(xy 314.802768 -317.064556) (xy 314.758306 -317.085654) (xy 314.711035 -317.099346) (xy 314.66218 -317.105278)
			(xy 314.613005 -317.103297) (xy 314.564786 -317.093453) (xy 314.51877 -317.076001) (xy 314.476149 -317.051394)
			(xy 314.438028 -317.020269) (xy 314.405393 -316.983432) (xy 314.37909 -316.941836) (xy 314.359799 -316.89656)
			(xy 314.348022 -316.848776) (xy 314.344062 -316.799722) (xy 314.005214 -316.799722) (xy 314.004719 -316.824329)
			(xy 313.996824 -316.872906) (xy 313.98124 -316.919587) (xy 313.958369 -316.963164) (xy 313.928804 -317.002508)
			(xy 313.893311 -317.0366) (xy 313.852808 -317.064556) (xy 313.808346 -317.085654) (xy 313.761075 -317.099346)
			(xy 313.71222 -317.105278) (xy 313.663045 -317.103297) (xy 313.614826 -317.093453) (xy 313.56881 -317.076001)
			(xy 313.526189 -317.051394) (xy 313.488068 -317.020269) (xy 313.455433 -316.983432) (xy 313.42913 -316.941836)
			(xy 313.409839 -316.89656) (xy 313.398062 -316.848776) (xy 313.394102 -316.799722) (xy 312.10504 -316.799722)
			(xy 312.104545 -316.824329) (xy 312.09665 -316.872906) (xy 312.081066 -316.919587) (xy 312.058195 -316.963164)
			(xy 312.02863 -317.002508) (xy 311.993137 -317.0366) (xy 311.952634 -317.064556) (xy 311.908172 -317.085654)
			(xy 311.860901 -317.099346) (xy 311.812046 -317.105278) (xy 311.762871 -317.103297) (xy 311.714652 -317.093453)
			(xy 311.668636 -317.076001) (xy 311.626015 -317.051394) (xy 311.587894 -317.020269) (xy 311.555259 -316.983432)
			(xy 311.528956 -316.941836) (xy 311.509665 -316.89656) (xy 311.497888 -316.848776) (xy 311.493928 -316.799722)
			(xy 310.20512 -316.799722) (xy 310.204625 -316.824329) (xy 310.19673 -316.872906) (xy 310.181146 -316.919587)
			(xy 310.158275 -316.963164) (xy 310.12871 -317.002508) (xy 310.093217 -317.0366) (xy 310.052714 -317.064556)
			(xy 310.008252 -317.085654) (xy 309.960981 -317.099346) (xy 309.912126 -317.105278) (xy 309.862951 -317.103297)
			(xy 309.814732 -317.093453) (xy 309.768716 -317.076001) (xy 309.726095 -317.051394) (xy 309.687974 -317.020269)
			(xy 309.655339 -316.983432) (xy 309.629036 -316.941836) (xy 309.609745 -316.89656) (xy 309.597968 -316.848776)
			(xy 309.594008 -316.799722) (xy 308.3052 -316.799722) (xy 308.304705 -316.824329) (xy 308.29681 -316.872906)
			(xy 308.281226 -316.919587) (xy 308.258355 -316.963164) (xy 308.22879 -317.002508) (xy 308.193297 -317.0366)
			(xy 308.152794 -317.064556) (xy 308.108332 -317.085654) (xy 308.061061 -317.099346) (xy 308.012206 -317.105278)
			(xy 307.963031 -317.103297) (xy 307.914812 -317.093453) (xy 307.868796 -317.076001) (xy 307.826175 -317.051394)
			(xy 307.788054 -317.020269) (xy 307.755419 -316.983432) (xy 307.729116 -316.941836) (xy 307.709825 -316.89656)
			(xy 307.698048 -316.848776) (xy 307.694088 -316.799722) (xy 306.405026 -316.799722) (xy 306.404531 -316.824329)
			(xy 306.396636 -316.872906) (xy 306.381052 -316.919587) (xy 306.358181 -316.963164) (xy 306.328616 -317.002508)
			(xy 306.293123 -317.0366) (xy 306.25262 -317.064556) (xy 306.208158 -317.085654) (xy 306.160887 -317.099346)
			(xy 306.112032 -317.105278) (xy 306.062857 -317.103297) (xy 306.014638 -317.093453) (xy 305.968622 -317.076001)
			(xy 305.926001 -317.051394) (xy 305.88788 -317.020269) (xy 305.855245 -316.983432) (xy 305.828942 -316.941836)
			(xy 305.809651 -316.89656) (xy 305.797874 -316.848776) (xy 305.793914 -316.799722) (xy 304.505106 -316.799722)
			(xy 304.504611 -316.824329) (xy 304.496716 -316.872906) (xy 304.481132 -316.919587) (xy 304.458261 -316.963164)
			(xy 304.428696 -317.002508) (xy 304.393203 -317.0366) (xy 304.3527 -317.064556) (xy 304.308238 -317.085654)
			(xy 304.260967 -317.099346) (xy 304.212112 -317.105278) (xy 304.162937 -317.103297) (xy 304.114718 -317.093453)
			(xy 304.068702 -317.076001) (xy 304.026081 -317.051394) (xy 303.98796 -317.020269) (xy 303.955325 -316.983432)
			(xy 303.929022 -316.941836) (xy 303.909731 -316.89656) (xy 303.897954 -316.848776) (xy 303.893994 -316.799722)
			(xy 302.605186 -316.799722) (xy 302.604691 -316.824329) (xy 302.596796 -316.872906) (xy 302.581212 -316.919587)
			(xy 302.558341 -316.963164) (xy 302.528776 -317.002508) (xy 302.493283 -317.0366) (xy 302.45278 -317.064556)
			(xy 302.408318 -317.085654) (xy 302.361047 -317.099346) (xy 302.312192 -317.105278) (xy 302.263017 -317.103297)
			(xy 302.214798 -317.093453) (xy 302.168782 -317.076001) (xy 302.126161 -317.051394) (xy 302.08804 -317.020269)
			(xy 302.055405 -316.983432) (xy 302.029102 -316.941836) (xy 302.009811 -316.89656) (xy 301.998034 -316.848776)
			(xy 301.994074 -316.799722) (xy 300.705012 -316.799722) (xy 300.704517 -316.824329) (xy 300.696622 -316.872906)
			(xy 300.681038 -316.919587) (xy 300.658167 -316.963164) (xy 300.628602 -317.002508) (xy 300.593109 -317.0366)
			(xy 300.552606 -317.064556) (xy 300.508144 -317.085654) (xy 300.460873 -317.099346) (xy 300.412018 -317.105278)
			(xy 300.362843 -317.103297) (xy 300.314624 -317.093453) (xy 300.268608 -317.076001) (xy 300.225987 -317.051394)
			(xy 300.187866 -317.020269) (xy 300.155231 -316.983432) (xy 300.128928 -316.941836) (xy 300.109637 -316.89656)
			(xy 300.09786 -316.848776) (xy 300.0939 -316.799722) (xy 298.805092 -316.799722) (xy 298.804597 -316.824329)
			(xy 298.796702 -316.872906) (xy 298.781118 -316.919587) (xy 298.758247 -316.963164) (xy 298.728682 -317.002508)
			(xy 298.693189 -317.0366) (xy 298.652686 -317.064556) (xy 298.608224 -317.085654) (xy 298.560953 -317.099346)
			(xy 298.512098 -317.105278) (xy 298.462923 -317.103297) (xy 298.414704 -317.093453) (xy 298.368688 -317.076001)
			(xy 298.326067 -317.051394) (xy 298.287946 -317.020269) (xy 298.255311 -316.983432) (xy 298.229008 -316.941836)
			(xy 298.209717 -316.89656) (xy 298.19794 -316.848776) (xy 298.19398 -316.799722) (xy 296.905172 -316.799722)
			(xy 296.904677 -316.824329) (xy 296.896782 -316.872906) (xy 296.881198 -316.919587) (xy 296.858327 -316.963164)
			(xy 296.828762 -317.002508) (xy 296.793269 -317.0366) (xy 296.752766 -317.064556) (xy 296.708304 -317.085654)
			(xy 296.661033 -317.099346) (xy 296.612178 -317.105278) (xy 296.563003 -317.103297) (xy 296.514784 -317.093453)
			(xy 296.468768 -317.076001) (xy 296.426147 -317.051394) (xy 296.388026 -317.020269) (xy 296.355391 -316.983432)
			(xy 296.329088 -316.941836) (xy 296.309797 -316.89656) (xy 296.29802 -316.848776) (xy 296.29406 -316.799722)
			(xy 295.004998 -316.799722) (xy 295.004503 -316.824329) (xy 294.996608 -316.872906) (xy 294.981024 -316.919587)
			(xy 294.958153 -316.963164) (xy 294.928588 -317.002508) (xy 294.893095 -317.0366) (xy 294.852592 -317.064556)
			(xy 294.80813 -317.085654) (xy 294.760859 -317.099346) (xy 294.712004 -317.105278) (xy 294.662829 -317.103297)
			(xy 294.61461 -317.093453) (xy 294.568594 -317.076001) (xy 294.525973 -317.051394) (xy 294.487852 -317.020269)
			(xy 294.455217 -316.983432) (xy 294.428914 -316.941836) (xy 294.409623 -316.89656) (xy 294.397846 -316.848776)
			(xy 294.393886 -316.799722) (xy 293.105078 -316.799722) (xy 293.104583 -316.824329) (xy 293.096688 -316.872906)
			(xy 293.081104 -316.919587) (xy 293.058233 -316.963164) (xy 293.028668 -317.002508) (xy 292.993175 -317.0366)
			(xy 292.952672 -317.064556) (xy 292.90821 -317.085654) (xy 292.860939 -317.099346) (xy 292.812084 -317.105278)
			(xy 292.762909 -317.103297) (xy 292.71469 -317.093453) (xy 292.668674 -317.076001) (xy 292.626053 -317.051394)
			(xy 292.587932 -317.020269) (xy 292.555297 -316.983432) (xy 292.528994 -316.941836) (xy 292.509703 -316.89656)
			(xy 292.497926 -316.848776) (xy 292.493966 -316.799722) (xy 291.205158 -316.799722) (xy 291.204663 -316.824329)
			(xy 291.196768 -316.872906) (xy 291.181184 -316.919587) (xy 291.158313 -316.963164) (xy 291.128748 -317.002508)
			(xy 291.093255 -317.0366) (xy 291.052752 -317.064556) (xy 291.00829 -317.085654) (xy 290.961019 -317.099346)
			(xy 290.912164 -317.105278) (xy 290.862989 -317.103297) (xy 290.81477 -317.093453) (xy 290.768754 -317.076001)
			(xy 290.726133 -317.051394) (xy 290.688012 -317.020269) (xy 290.655377 -316.983432) (xy 290.629074 -316.941836)
			(xy 290.609783 -316.89656) (xy 290.598006 -316.848776) (xy 290.594046 -316.799722) (xy 289.305238 -316.799722)
			(xy 289.304743 -316.824329) (xy 289.296848 -316.872906) (xy 289.281264 -316.919587) (xy 289.258393 -316.963164)
			(xy 289.228828 -317.002508) (xy 289.193335 -317.0366) (xy 289.152832 -317.064556) (xy 289.10837 -317.085654)
			(xy 289.061099 -317.099346) (xy 289.012244 -317.105278) (xy 288.963069 -317.103297) (xy 288.91485 -317.093453)
			(xy 288.868834 -317.076001) (xy 288.826213 -317.051394) (xy 288.788092 -317.020269) (xy 288.755457 -316.983432)
			(xy 288.729154 -316.941836) (xy 288.709863 -316.89656) (xy 288.698086 -316.848776) (xy 288.694126 -316.799722)
			(xy 287.405064 -316.799722) (xy 287.404569 -316.824329) (xy 287.396674 -316.872906) (xy 287.38109 -316.919587)
			(xy 287.358219 -316.963164) (xy 287.328654 -317.002508) (xy 287.293161 -317.0366) (xy 287.252658 -317.064556)
			(xy 287.208196 -317.085654) (xy 287.160925 -317.099346) (xy 287.11207 -317.105278) (xy 287.062895 -317.103297)
			(xy 287.014676 -317.093453) (xy 286.96866 -317.076001) (xy 286.926039 -317.051394) (xy 286.887918 -317.020269)
			(xy 286.855283 -316.983432) (xy 286.82898 -316.941836) (xy 286.809689 -316.89656) (xy 286.797912 -316.848776)
			(xy 286.793952 -316.799722) (xy 285.505144 -316.799722) (xy 285.504649 -316.824329) (xy 285.496754 -316.872906)
			(xy 285.48117 -316.919587) (xy 285.458299 -316.963164) (xy 285.428734 -317.002508) (xy 285.393241 -317.0366)
			(xy 285.352738 -317.064556) (xy 285.308276 -317.085654) (xy 285.261005 -317.099346) (xy 285.21215 -317.105278)
			(xy 285.162975 -317.103297) (xy 285.114756 -317.093453) (xy 285.06874 -317.076001) (xy 285.026119 -317.051394)
			(xy 284.987998 -317.020269) (xy 284.955363 -316.983432) (xy 284.92906 -316.941836) (xy 284.909769 -316.89656)
			(xy 284.897992 -316.848776) (xy 284.894032 -316.799722) (xy 283.605224 -316.799722) (xy 283.604729 -316.824329)
			(xy 283.596834 -316.872906) (xy 283.58125 -316.919587) (xy 283.558379 -316.963164) (xy 283.528814 -317.002508)
			(xy 283.493321 -317.0366) (xy 283.452818 -317.064556) (xy 283.408356 -317.085654) (xy 283.361085 -317.099346)
			(xy 283.31223 -317.105278) (xy 283.263055 -317.103297) (xy 283.214836 -317.093453) (xy 283.16882 -317.076001)
			(xy 283.126199 -317.051394) (xy 283.088078 -317.020269) (xy 283.055443 -316.983432) (xy 283.02914 -316.941836)
			(xy 283.009849 -316.89656) (xy 282.998072 -316.848776) (xy 282.994112 -316.799722) (xy 281.70505 -316.799722)
			(xy 281.704555 -316.824329) (xy 281.69666 -316.872906) (xy 281.681076 -316.919587) (xy 281.658205 -316.963164)
			(xy 281.62864 -317.002508) (xy 281.593147 -317.0366) (xy 281.552644 -317.064556) (xy 281.508182 -317.085654)
			(xy 281.460911 -317.099346) (xy 281.412056 -317.105278) (xy 281.362881 -317.103297) (xy 281.314662 -317.093453)
			(xy 281.268646 -317.076001) (xy 281.226025 -317.051394) (xy 281.187904 -317.020269) (xy 281.155269 -316.983432)
			(xy 281.128966 -316.941836) (xy 281.109675 -316.89656) (xy 281.097898 -316.848776) (xy 281.093938 -316.799722)
			(xy 279.80513 -316.799722) (xy 279.804635 -316.824329) (xy 279.79674 -316.872906) (xy 279.781156 -316.919587)
			(xy 279.758285 -316.963164) (xy 279.72872 -317.002508) (xy 279.693227 -317.0366) (xy 279.652724 -317.064556)
			(xy 279.608262 -317.085654) (xy 279.560991 -317.099346) (xy 279.512136 -317.105278) (xy 279.462961 -317.103297)
			(xy 279.414742 -317.093453) (xy 279.368726 -317.076001) (xy 279.326105 -317.051394) (xy 279.287984 -317.020269)
			(xy 279.255349 -316.983432) (xy 279.229046 -316.941836) (xy 279.209755 -316.89656) (xy 279.197978 -316.848776)
			(xy 279.194018 -316.799722) (xy 277.90521 -316.799722) (xy 277.904715 -316.824329) (xy 277.89682 -316.872906)
			(xy 277.881236 -316.919587) (xy 277.858365 -316.963164) (xy 277.8288 -317.002508) (xy 277.793307 -317.0366)
			(xy 277.752804 -317.064556) (xy 277.708342 -317.085654) (xy 277.661071 -317.099346) (xy 277.612216 -317.105278)
			(xy 277.563041 -317.103297) (xy 277.514822 -317.093453) (xy 277.468806 -317.076001) (xy 277.426185 -317.051394)
			(xy 277.388064 -317.020269) (xy 277.355429 -316.983432) (xy 277.329126 -316.941836) (xy 277.309835 -316.89656)
			(xy 277.298058 -316.848776) (xy 277.294098 -316.799722) (xy 276.005036 -316.799722) (xy 276.004541 -316.824329)
			(xy 275.996646 -316.872906) (xy 275.981062 -316.919587) (xy 275.958191 -316.963164) (xy 275.928626 -317.002508)
			(xy 275.893133 -317.0366) (xy 275.85263 -317.064556) (xy 275.808168 -317.085654) (xy 275.760897 -317.099346)
			(xy 275.712042 -317.105278) (xy 275.662867 -317.103297) (xy 275.614648 -317.093453) (xy 275.568632 -317.076001)
			(xy 275.526011 -317.051394) (xy 275.48789 -317.020269) (xy 275.455255 -316.983432) (xy 275.428952 -316.941836)
			(xy 275.409661 -316.89656) (xy 275.397884 -316.848776) (xy 275.393924 -316.799722) (xy 274.105116 -316.799722)
			(xy 274.104621 -316.824329) (xy 274.096726 -316.872906) (xy 274.081142 -316.919587) (xy 274.058271 -316.963164)
			(xy 274.028706 -317.002508) (xy 273.993213 -317.0366) (xy 273.95271 -317.064556) (xy 273.908248 -317.085654)
			(xy 273.860977 -317.099346) (xy 273.812122 -317.105278) (xy 273.762947 -317.103297) (xy 273.714728 -317.093453)
			(xy 273.668712 -317.076001) (xy 273.626091 -317.051394) (xy 273.58797 -317.020269) (xy 273.555335 -316.983432)
			(xy 273.529032 -316.941836) (xy 273.509741 -316.89656) (xy 273.497964 -316.848776) (xy 273.494004 -316.799722)
			(xy 272.205196 -316.799722) (xy 272.204701 -316.824329) (xy 272.196806 -316.872906) (xy 272.181222 -316.919587)
			(xy 272.158351 -316.963164) (xy 272.128786 -317.002508) (xy 272.093293 -317.0366) (xy 272.05279 -317.064556)
			(xy 272.008328 -317.085654) (xy 271.961057 -317.099346) (xy 271.912202 -317.105278) (xy 271.863027 -317.103297)
			(xy 271.814808 -317.093453) (xy 271.768792 -317.076001) (xy 271.726171 -317.051394) (xy 271.68805 -317.020269)
			(xy 271.655415 -316.983432) (xy 271.629112 -316.941836) (xy 271.609821 -316.89656) (xy 271.598044 -316.848776)
			(xy 271.594084 -316.799722) (xy 270.305022 -316.799722) (xy 270.304527 -316.824329) (xy 270.296632 -316.872906)
			(xy 270.281048 -316.919587) (xy 270.258177 -316.963164) (xy 270.228612 -317.002508) (xy 270.193119 -317.0366)
			(xy 270.152616 -317.064556) (xy 270.108154 -317.085654) (xy 270.060883 -317.099346) (xy 270.012028 -317.105278)
			(xy 269.962853 -317.103297) (xy 269.914634 -317.093453) (xy 269.868618 -317.076001) (xy 269.825997 -317.051394)
			(xy 269.787876 -317.020269) (xy 269.755241 -316.983432) (xy 269.728938 -316.941836) (xy 269.709647 -316.89656)
			(xy 269.69787 -316.848776) (xy 269.69391 -316.799722) (xy 269.355062 -316.799722) (xy 269.354567 -316.824329)
			(xy 269.346672 -316.872906) (xy 269.331088 -316.919587) (xy 269.308217 -316.963164) (xy 269.278652 -317.002508)
			(xy 269.243159 -317.0366) (xy 269.202656 -317.064556) (xy 269.158194 -317.085654) (xy 269.110923 -317.099346)
			(xy 269.062068 -317.105278) (xy 269.012893 -317.103297) (xy 268.964674 -317.093453) (xy 268.918658 -317.076001)
			(xy 268.876037 -317.051394) (xy 268.837916 -317.020269) (xy 268.805281 -316.983432) (xy 268.778978 -316.941836)
			(xy 268.759687 -316.89656) (xy 268.74791 -316.848776) (xy 268.74395 -316.799722) (xy 198.85533 -316.799722)
			(xy 198.854835 -316.824329) (xy 198.84694 -316.872906) (xy 198.831356 -316.919587) (xy 198.808485 -316.963164)
			(xy 198.77892 -317.002508) (xy 198.743427 -317.0366) (xy 198.702924 -317.064556) (xy 198.658462 -317.085654)
			(xy 198.611191 -317.099346) (xy 198.562336 -317.105278) (xy 198.513161 -317.103297) (xy 198.464942 -317.093453)
			(xy 198.418926 -317.076001) (xy 198.376305 -317.051394) (xy 198.338184 -317.020269) (xy 198.305549 -316.983432)
			(xy 198.279246 -316.941836) (xy 198.259955 -316.89656) (xy 198.248178 -316.848776) (xy 198.244218 -316.799722)
			(xy 197.90537 -316.799722) (xy 197.904875 -316.824329) (xy 197.89698 -316.872906) (xy 197.881396 -316.919587)
			(xy 197.858525 -316.963164) (xy 197.82896 -317.002508) (xy 197.793467 -317.0366) (xy 197.752964 -317.064556)
			(xy 197.708502 -317.085654) (xy 197.661231 -317.099346) (xy 197.612376 -317.105278) (xy 197.563201 -317.103297)
			(xy 197.514982 -317.093453) (xy 197.468966 -317.076001) (xy 197.426345 -317.051394) (xy 197.388224 -317.020269)
			(xy 197.355589 -316.983432) (xy 197.329286 -316.941836) (xy 197.309995 -316.89656) (xy 197.298218 -316.848776)
			(xy 197.294258 -316.799722) (xy 196.005196 -316.799722) (xy 196.004701 -316.824329) (xy 195.996806 -316.872906)
			(xy 195.981222 -316.919587) (xy 195.958351 -316.963164) (xy 195.928786 -317.002508) (xy 195.893293 -317.0366)
			(xy 195.85279 -317.064556) (xy 195.808328 -317.085654) (xy 195.761057 -317.099346) (xy 195.712202 -317.105278)
			(xy 195.663027 -317.103297) (xy 195.614808 -317.093453) (xy 195.568792 -317.076001) (xy 195.526171 -317.051394)
			(xy 195.48805 -317.020269) (xy 195.455415 -316.983432) (xy 195.429112 -316.941836) (xy 195.409821 -316.89656)
			(xy 195.398044 -316.848776) (xy 195.394084 -316.799722) (xy 194.105276 -316.799722) (xy 194.104781 -316.824329)
			(xy 194.096886 -316.872906) (xy 194.081302 -316.919587) (xy 194.058431 -316.963164) (xy 194.028866 -317.002508)
			(xy 193.993373 -317.0366) (xy 193.95287 -317.064556) (xy 193.908408 -317.085654) (xy 193.861137 -317.099346)
			(xy 193.812282 -317.105278) (xy 193.763107 -317.103297) (xy 193.714888 -317.093453) (xy 193.668872 -317.076001)
			(xy 193.626251 -317.051394) (xy 193.58813 -317.020269) (xy 193.555495 -316.983432) (xy 193.529192 -316.941836)
			(xy 193.509901 -316.89656) (xy 193.498124 -316.848776) (xy 193.494164 -316.799722) (xy 192.205356 -316.799722)
			(xy 192.204861 -316.824329) (xy 192.196966 -316.872906) (xy 192.181382 -316.919587) (xy 192.158511 -316.963164)
			(xy 192.128946 -317.002508) (xy 192.093453 -317.0366) (xy 192.05295 -317.064556) (xy 192.008488 -317.085654)
			(xy 191.961217 -317.099346) (xy 191.912362 -317.105278) (xy 191.863187 -317.103297) (xy 191.814968 -317.093453)
			(xy 191.768952 -317.076001) (xy 191.726331 -317.051394) (xy 191.68821 -317.020269) (xy 191.655575 -316.983432)
			(xy 191.629272 -316.941836) (xy 191.609981 -316.89656) (xy 191.598204 -316.848776) (xy 191.594244 -316.799722)
			(xy 190.305182 -316.799722) (xy 190.304687 -316.824329) (xy 190.296792 -316.872906) (xy 190.281208 -316.919587)
			(xy 190.258337 -316.963164) (xy 190.228772 -317.002508) (xy 190.193279 -317.0366) (xy 190.152776 -317.064556)
			(xy 190.108314 -317.085654) (xy 190.061043 -317.099346) (xy 190.012188 -317.105278) (xy 189.963013 -317.103297)
			(xy 189.914794 -317.093453) (xy 189.868778 -317.076001) (xy 189.826157 -317.051394) (xy 189.788036 -317.020269)
			(xy 189.755401 -316.983432) (xy 189.729098 -316.941836) (xy 189.709807 -316.89656) (xy 189.69803 -316.848776)
			(xy 189.69407 -316.799722) (xy 188.405262 -316.799722) (xy 188.404767 -316.824329) (xy 188.396872 -316.872906)
			(xy 188.381288 -316.919587) (xy 188.358417 -316.963164) (xy 188.328852 -317.002508) (xy 188.293359 -317.0366)
			(xy 188.252856 -317.064556) (xy 188.208394 -317.085654) (xy 188.161123 -317.099346) (xy 188.112268 -317.105278)
			(xy 188.063093 -317.103297) (xy 188.014874 -317.093453) (xy 187.968858 -317.076001) (xy 187.926237 -317.051394)
			(xy 187.888116 -317.020269) (xy 187.855481 -316.983432) (xy 187.829178 -316.941836) (xy 187.809887 -316.89656)
			(xy 187.79811 -316.848776) (xy 187.79415 -316.799722) (xy 186.505342 -316.799722) (xy 186.504847 -316.824329)
			(xy 186.496952 -316.872906) (xy 186.481368 -316.919587) (xy 186.458497 -316.963164) (xy 186.428932 -317.002508)
			(xy 186.393439 -317.0366) (xy 186.352936 -317.064556) (xy 186.308474 -317.085654) (xy 186.261203 -317.099346)
			(xy 186.212348 -317.105278) (xy 186.163173 -317.103297) (xy 186.114954 -317.093453) (xy 186.068938 -317.076001)
			(xy 186.026317 -317.051394) (xy 185.988196 -317.020269) (xy 185.955561 -316.983432) (xy 185.929258 -316.941836)
			(xy 185.909967 -316.89656) (xy 185.89819 -316.848776) (xy 185.89423 -316.799722) (xy 184.605168 -316.799722)
			(xy 184.604673 -316.824329) (xy 184.596778 -316.872906) (xy 184.581194 -316.919587) (xy 184.558323 -316.963164)
			(xy 184.528758 -317.002508) (xy 184.493265 -317.0366) (xy 184.452762 -317.064556) (xy 184.4083 -317.085654)
			(xy 184.361029 -317.099346) (xy 184.312174 -317.105278) (xy 184.262999 -317.103297) (xy 184.21478 -317.093453)
			(xy 184.168764 -317.076001) (xy 184.126143 -317.051394) (xy 184.088022 -317.020269) (xy 184.055387 -316.983432)
			(xy 184.029084 -316.941836) (xy 184.009793 -316.89656) (xy 183.998016 -316.848776) (xy 183.994056 -316.799722)
			(xy 182.705248 -316.799722) (xy 182.704753 -316.824329) (xy 182.696858 -316.872906) (xy 182.681274 -316.919587)
			(xy 182.658403 -316.963164) (xy 182.628838 -317.002508) (xy 182.593345 -317.0366) (xy 182.552842 -317.064556)
			(xy 182.50838 -317.085654) (xy 182.461109 -317.099346) (xy 182.412254 -317.105278) (xy 182.363079 -317.103297)
			(xy 182.31486 -317.093453) (xy 182.268844 -317.076001) (xy 182.226223 -317.051394) (xy 182.188102 -317.020269)
			(xy 182.155467 -316.983432) (xy 182.129164 -316.941836) (xy 182.109873 -316.89656) (xy 182.098096 -316.848776)
			(xy 182.094136 -316.799722) (xy 180.805328 -316.799722) (xy 180.804833 -316.824329) (xy 180.796938 -316.872906)
			(xy 180.781354 -316.919587) (xy 180.758483 -316.963164) (xy 180.728918 -317.002508) (xy 180.693425 -317.0366)
			(xy 180.652922 -317.064556) (xy 180.60846 -317.085654) (xy 180.561189 -317.099346) (xy 180.512334 -317.105278)
			(xy 180.463159 -317.103297) (xy 180.41494 -317.093453) (xy 180.368924 -317.076001) (xy 180.326303 -317.051394)
			(xy 180.288182 -317.020269) (xy 180.255547 -316.983432) (xy 180.229244 -316.941836) (xy 180.209953 -316.89656)
			(xy 180.198176 -316.848776) (xy 180.194216 -316.799722) (xy 178.905154 -316.799722) (xy 178.904659 -316.824329)
			(xy 178.896764 -316.872906) (xy 178.88118 -316.919587) (xy 178.858309 -316.963164) (xy 178.828744 -317.002508)
			(xy 178.793251 -317.0366) (xy 178.752748 -317.064556) (xy 178.708286 -317.085654) (xy 178.661015 -317.099346)
			(xy 178.61216 -317.105278) (xy 178.562985 -317.103297) (xy 178.514766 -317.093453) (xy 178.46875 -317.076001)
			(xy 178.426129 -317.051394) (xy 178.388008 -317.020269) (xy 178.355373 -316.983432) (xy 178.32907 -316.941836)
			(xy 178.309779 -316.89656) (xy 178.298002 -316.848776) (xy 178.294042 -316.799722) (xy 177.005234 -316.799722)
			(xy 177.004739 -316.824329) (xy 176.996844 -316.872906) (xy 176.98126 -316.919587) (xy 176.958389 -316.963164)
			(xy 176.928824 -317.002508) (xy 176.893331 -317.0366) (xy 176.852828 -317.064556) (xy 176.808366 -317.085654)
			(xy 176.761095 -317.099346) (xy 176.71224 -317.105278) (xy 176.663065 -317.103297) (xy 176.614846 -317.093453)
			(xy 176.56883 -317.076001) (xy 176.526209 -317.051394) (xy 176.488088 -317.020269) (xy 176.455453 -316.983432)
			(xy 176.42915 -316.941836) (xy 176.409859 -316.89656) (xy 176.398082 -316.848776) (xy 176.394122 -316.799722)
			(xy 175.105314 -316.799722) (xy 175.104819 -316.824329) (xy 175.096924 -316.872906) (xy 175.08134 -316.919587)
			(xy 175.058469 -316.963164) (xy 175.028904 -317.002508) (xy 174.993411 -317.0366) (xy 174.952908 -317.064556)
			(xy 174.908446 -317.085654) (xy 174.861175 -317.099346) (xy 174.81232 -317.105278) (xy 174.763145 -317.103297)
			(xy 174.714926 -317.093453) (xy 174.66891 -317.076001) (xy 174.626289 -317.051394) (xy 174.588168 -317.020269)
			(xy 174.555533 -316.983432) (xy 174.52923 -316.941836) (xy 174.509939 -316.89656) (xy 174.498162 -316.848776)
			(xy 174.494202 -316.799722) (xy 173.205394 -316.799722) (xy 173.204899 -316.824329) (xy 173.197004 -316.872906)
			(xy 173.18142 -316.919587) (xy 173.158549 -316.963164) (xy 173.128984 -317.002508) (xy 173.093491 -317.0366)
			(xy 173.052988 -317.064556) (xy 173.008526 -317.085654) (xy 172.961255 -317.099346) (xy 172.9124 -317.105278)
			(xy 172.863225 -317.103297) (xy 172.815006 -317.093453) (xy 172.76899 -317.076001) (xy 172.726369 -317.051394)
			(xy 172.688248 -317.020269) (xy 172.655613 -316.983432) (xy 172.62931 -316.941836) (xy 172.610019 -316.89656)
			(xy 172.598242 -316.848776) (xy 172.594282 -316.799722) (xy 171.30522 -316.799722) (xy 171.304725 -316.824329)
			(xy 171.29683 -316.872906) (xy 171.281246 -316.919587) (xy 171.258375 -316.963164) (xy 171.22881 -317.002508)
			(xy 171.193317 -317.0366) (xy 171.152814 -317.064556) (xy 171.108352 -317.085654) (xy 171.061081 -317.099346)
			(xy 171.012226 -317.105278) (xy 170.963051 -317.103297) (xy 170.914832 -317.093453) (xy 170.868816 -317.076001)
			(xy 170.826195 -317.051394) (xy 170.788074 -317.020269) (xy 170.755439 -316.983432) (xy 170.729136 -316.941836)
			(xy 170.709845 -316.89656) (xy 170.698068 -316.848776) (xy 170.694108 -316.799722) (xy 169.4053 -316.799722)
			(xy 169.404805 -316.824329) (xy 169.39691 -316.872906) (xy 169.381326 -316.919587) (xy 169.358455 -316.963164)
			(xy 169.32889 -317.002508) (xy 169.293397 -317.0366) (xy 169.252894 -317.064556) (xy 169.208432 -317.085654)
			(xy 169.161161 -317.099346) (xy 169.112306 -317.105278) (xy 169.063131 -317.103297) (xy 169.014912 -317.093453)
			(xy 168.968896 -317.076001) (xy 168.926275 -317.051394) (xy 168.888154 -317.020269) (xy 168.855519 -316.983432)
			(xy 168.829216 -316.941836) (xy 168.809925 -316.89656) (xy 168.798148 -316.848776) (xy 168.794188 -316.799722)
			(xy 167.50538 -316.799722) (xy 167.504885 -316.824329) (xy 167.49699 -316.872906) (xy 167.481406 -316.919587)
			(xy 167.458535 -316.963164) (xy 167.42897 -317.002508) (xy 167.393477 -317.0366) (xy 167.352974 -317.064556)
			(xy 167.308512 -317.085654) (xy 167.261241 -317.099346) (xy 167.212386 -317.105278) (xy 167.163211 -317.103297)
			(xy 167.114992 -317.093453) (xy 167.068976 -317.076001) (xy 167.026355 -317.051394) (xy 166.988234 -317.020269)
			(xy 166.955599 -316.983432) (xy 166.929296 -316.941836) (xy 166.910005 -316.89656) (xy 166.898228 -316.848776)
			(xy 166.894268 -316.799722) (xy 165.605206 -316.799722) (xy 165.604711 -316.824329) (xy 165.596816 -316.872906)
			(xy 165.581232 -316.919587) (xy 165.558361 -316.963164) (xy 165.528796 -317.002508) (xy 165.493303 -317.0366)
			(xy 165.4528 -317.064556) (xy 165.408338 -317.085654) (xy 165.361067 -317.099346) (xy 165.312212 -317.105278)
			(xy 165.263037 -317.103297) (xy 165.214818 -317.093453) (xy 165.168802 -317.076001) (xy 165.126181 -317.051394)
			(xy 165.08806 -317.020269) (xy 165.055425 -316.983432) (xy 165.029122 -316.941836) (xy 165.009831 -316.89656)
			(xy 164.998054 -316.848776) (xy 164.994094 -316.799722) (xy 163.705286 -316.799722) (xy 163.704791 -316.824329)
			(xy 163.696896 -316.872906) (xy 163.681312 -316.919587) (xy 163.658441 -316.963164) (xy 163.628876 -317.002508)
			(xy 163.593383 -317.0366) (xy 163.55288 -317.064556) (xy 163.508418 -317.085654) (xy 163.461147 -317.099346)
			(xy 163.412292 -317.105278) (xy 163.363117 -317.103297) (xy 163.314898 -317.093453) (xy 163.268882 -317.076001)
			(xy 163.226261 -317.051394) (xy 163.18814 -317.020269) (xy 163.155505 -316.983432) (xy 163.129202 -316.941836)
			(xy 163.109911 -316.89656) (xy 163.098134 -316.848776) (xy 163.094174 -316.799722) (xy 161.805366 -316.799722)
			(xy 161.804871 -316.824329) (xy 161.796976 -316.872906) (xy 161.781392 -316.919587) (xy 161.758521 -316.963164)
			(xy 161.728956 -317.002508) (xy 161.693463 -317.0366) (xy 161.65296 -317.064556) (xy 161.608498 -317.085654)
			(xy 161.561227 -317.099346) (xy 161.512372 -317.105278) (xy 161.463197 -317.103297) (xy 161.414978 -317.093453)
			(xy 161.368962 -317.076001) (xy 161.326341 -317.051394) (xy 161.28822 -317.020269) (xy 161.255585 -316.983432)
			(xy 161.229282 -316.941836) (xy 161.209991 -316.89656) (xy 161.198214 -316.848776) (xy 161.194254 -316.799722)
			(xy 159.905192 -316.799722) (xy 159.904697 -316.824329) (xy 159.896802 -316.872906) (xy 159.881218 -316.919587)
			(xy 159.858347 -316.963164) (xy 159.828782 -317.002508) (xy 159.793289 -317.0366) (xy 159.752786 -317.064556)
			(xy 159.708324 -317.085654) (xy 159.661053 -317.099346) (xy 159.612198 -317.105278) (xy 159.563023 -317.103297)
			(xy 159.514804 -317.093453) (xy 159.468788 -317.076001) (xy 159.426167 -317.051394) (xy 159.388046 -317.020269)
			(xy 159.355411 -316.983432) (xy 159.329108 -316.941836) (xy 159.309817 -316.89656) (xy 159.29804 -316.848776)
			(xy 159.29408 -316.799722) (xy 158.005272 -316.799722) (xy 158.004777 -316.824329) (xy 157.996882 -316.872906)
			(xy 157.981298 -316.919587) (xy 157.958427 -316.963164) (xy 157.928862 -317.002508) (xy 157.893369 -317.0366)
			(xy 157.852866 -317.064556) (xy 157.808404 -317.085654) (xy 157.761133 -317.099346) (xy 157.712278 -317.105278)
			(xy 157.663103 -317.103297) (xy 157.614884 -317.093453) (xy 157.568868 -317.076001) (xy 157.526247 -317.051394)
			(xy 157.488126 -317.020269) (xy 157.455491 -316.983432) (xy 157.429188 -316.941836) (xy 157.409897 -316.89656)
			(xy 157.39812 -316.848776) (xy 157.39416 -316.799722) (xy 156.105352 -316.799722) (xy 156.104857 -316.824329)
			(xy 156.096962 -316.872906) (xy 156.081378 -316.919587) (xy 156.058507 -316.963164) (xy 156.028942 -317.002508)
			(xy 155.993449 -317.0366) (xy 155.952946 -317.064556) (xy 155.908484 -317.085654) (xy 155.861213 -317.099346)
			(xy 155.812358 -317.105278) (xy 155.763183 -317.103297) (xy 155.714964 -317.093453) (xy 155.668948 -317.076001)
			(xy 155.626327 -317.051394) (xy 155.588206 -317.020269) (xy 155.555571 -316.983432) (xy 155.529268 -316.941836)
			(xy 155.509977 -316.89656) (xy 155.4982 -316.848776) (xy 155.49424 -316.799722) (xy 154.205178 -316.799722)
			(xy 154.204683 -316.824329) (xy 154.196788 -316.872906) (xy 154.181204 -316.919587) (xy 154.158333 -316.963164)
			(xy 154.128768 -317.002508) (xy 154.093275 -317.0366) (xy 154.052772 -317.064556) (xy 154.00831 -317.085654)
			(xy 153.961039 -317.099346) (xy 153.912184 -317.105278) (xy 153.863009 -317.103297) (xy 153.81479 -317.093453)
			(xy 153.768774 -317.076001) (xy 153.726153 -317.051394) (xy 153.688032 -317.020269) (xy 153.655397 -316.983432)
			(xy 153.629094 -316.941836) (xy 153.609803 -316.89656) (xy 153.598026 -316.848776) (xy 153.594066 -316.799722)
			(xy 153.255218 -316.799722) (xy 153.254723 -316.824329) (xy 153.246828 -316.872906) (xy 153.231244 -316.919587)
			(xy 153.208373 -316.963164) (xy 153.178808 -317.002508) (xy 153.143315 -317.0366) (xy 153.102812 -317.064556)
			(xy 153.05835 -317.085654) (xy 153.011079 -317.099346) (xy 152.962224 -317.105278) (xy 152.913049 -317.103297)
			(xy 152.86483 -317.093453) (xy 152.818814 -317.076001) (xy 152.776193 -317.051394) (xy 152.738072 -317.020269)
			(xy 152.705437 -316.983432) (xy 152.679134 -316.941836) (xy 152.659843 -316.89656) (xy 152.648066 -316.848776)
			(xy 152.644106 -316.799722) (xy 82.755232 -316.799722) (xy 82.754737 -316.824329) (xy 82.746842 -316.872906)
			(xy 82.731258 -316.919587) (xy 82.708387 -316.963164) (xy 82.678822 -317.002508) (xy 82.643329 -317.0366)
			(xy 82.602826 -317.064556) (xy 82.558364 -317.085654) (xy 82.511093 -317.099346) (xy 82.462238 -317.105278)
			(xy 82.413063 -317.103297) (xy 82.364844 -317.093453) (xy 82.318828 -317.076001) (xy 82.276207 -317.051394)
			(xy 82.238086 -317.020269) (xy 82.205451 -316.983432) (xy 82.179148 -316.941836) (xy 82.159857 -316.89656)
			(xy 82.14808 -316.848776) (xy 82.14412 -316.799722) (xy 81.805272 -316.799722) (xy 81.804777 -316.824329)
			(xy 81.796882 -316.872906) (xy 81.781298 -316.919587) (xy 81.758427 -316.963164) (xy 81.728862 -317.002508)
			(xy 81.693369 -317.0366) (xy 81.652866 -317.064556) (xy 81.608404 -317.085654) (xy 81.561133 -317.099346)
			(xy 81.512278 -317.105278) (xy 81.463103 -317.103297) (xy 81.414884 -317.093453) (xy 81.368868 -317.076001)
			(xy 81.326247 -317.051394) (xy 81.288126 -317.020269) (xy 81.255491 -316.983432) (xy 81.229188 -316.941836)
			(xy 81.209897 -316.89656) (xy 81.19812 -316.848776) (xy 81.19416 -316.799722) (xy 79.905098 -316.799722)
			(xy 79.904603 -316.824329) (xy 79.896708 -316.872906) (xy 79.881124 -316.919587) (xy 79.858253 -316.963164)
			(xy 79.828688 -317.002508) (xy 79.793195 -317.0366) (xy 79.752692 -317.064556) (xy 79.70823 -317.085654)
			(xy 79.660959 -317.099346) (xy 79.612104 -317.105278) (xy 79.562929 -317.103297) (xy 79.51471 -317.093453)
			(xy 79.468694 -317.076001) (xy 79.426073 -317.051394) (xy 79.387952 -317.020269) (xy 79.355317 -316.983432)
			(xy 79.329014 -316.941836) (xy 79.309723 -316.89656) (xy 79.297946 -316.848776) (xy 79.293986 -316.799722)
			(xy 78.005178 -316.799722) (xy 78.004683 -316.824329) (xy 77.996788 -316.872906) (xy 77.981204 -316.919587)
			(xy 77.958333 -316.963164) (xy 77.928768 -317.002508) (xy 77.893275 -317.0366) (xy 77.852772 -317.064556)
			(xy 77.80831 -317.085654) (xy 77.761039 -317.099346) (xy 77.712184 -317.105278) (xy 77.663009 -317.103297)
			(xy 77.61479 -317.093453) (xy 77.568774 -317.076001) (xy 77.526153 -317.051394) (xy 77.488032 -317.020269)
			(xy 77.455397 -316.983432) (xy 77.429094 -316.941836) (xy 77.409803 -316.89656) (xy 77.398026 -316.848776)
			(xy 77.394066 -316.799722) (xy 76.105258 -316.799722) (xy 76.104763 -316.824329) (xy 76.096868 -316.872906)
			(xy 76.081284 -316.919587) (xy 76.058413 -316.963164) (xy 76.028848 -317.002508) (xy 75.993355 -317.0366)
			(xy 75.952852 -317.064556) (xy 75.90839 -317.085654) (xy 75.861119 -317.099346) (xy 75.812264 -317.105278)
			(xy 75.763089 -317.103297) (xy 75.71487 -317.093453) (xy 75.668854 -317.076001) (xy 75.626233 -317.051394)
			(xy 75.588112 -317.020269) (xy 75.555477 -316.983432) (xy 75.529174 -316.941836) (xy 75.509883 -316.89656)
			(xy 75.498106 -316.848776) (xy 75.494146 -316.799722) (xy 74.205084 -316.799722) (xy 74.204589 -316.824329)
			(xy 74.196694 -316.872906) (xy 74.18111 -316.919587) (xy 74.158239 -316.963164) (xy 74.128674 -317.002508)
			(xy 74.093181 -317.0366) (xy 74.052678 -317.064556) (xy 74.008216 -317.085654) (xy 73.960945 -317.099346)
			(xy 73.91209 -317.105278) (xy 73.862915 -317.103297) (xy 73.814696 -317.093453) (xy 73.76868 -317.076001)
			(xy 73.726059 -317.051394) (xy 73.687938 -317.020269) (xy 73.655303 -316.983432) (xy 73.629 -316.941836)
			(xy 73.609709 -316.89656) (xy 73.597932 -316.848776) (xy 73.593972 -316.799722) (xy 72.305164 -316.799722)
			(xy 72.304669 -316.824329) (xy 72.296774 -316.872906) (xy 72.28119 -316.919587) (xy 72.258319 -316.963164)
			(xy 72.228754 -317.002508) (xy 72.193261 -317.0366) (xy 72.152758 -317.064556) (xy 72.108296 -317.085654)
			(xy 72.061025 -317.099346) (xy 72.01217 -317.105278) (xy 71.962995 -317.103297) (xy 71.914776 -317.093453)
			(xy 71.86876 -317.076001) (xy 71.826139 -317.051394) (xy 71.788018 -317.020269) (xy 71.755383 -316.983432)
			(xy 71.72908 -316.941836) (xy 71.709789 -316.89656) (xy 71.698012 -316.848776) (xy 71.694052 -316.799722)
			(xy 70.405244 -316.799722) (xy 70.404749 -316.824329) (xy 70.396854 -316.872906) (xy 70.38127 -316.919587)
			(xy 70.358399 -316.963164) (xy 70.328834 -317.002508) (xy 70.293341 -317.0366) (xy 70.252838 -317.064556)
			(xy 70.208376 -317.085654) (xy 70.161105 -317.099346) (xy 70.11225 -317.105278) (xy 70.063075 -317.103297)
			(xy 70.014856 -317.093453) (xy 69.96884 -317.076001) (xy 69.926219 -317.051394) (xy 69.888098 -317.020269)
			(xy 69.855463 -316.983432) (xy 69.82916 -316.941836) (xy 69.809869 -316.89656) (xy 69.798092 -316.848776)
			(xy 69.794132 -316.799722) (xy 68.50507 -316.799722) (xy 68.504575 -316.824329) (xy 68.49668 -316.872906)
			(xy 68.481096 -316.919587) (xy 68.458225 -316.963164) (xy 68.42866 -317.002508) (xy 68.393167 -317.0366)
			(xy 68.352664 -317.064556) (xy 68.308202 -317.085654) (xy 68.260931 -317.099346) (xy 68.212076 -317.105278)
			(xy 68.162901 -317.103297) (xy 68.114682 -317.093453) (xy 68.068666 -317.076001) (xy 68.026045 -317.051394)
			(xy 67.987924 -317.020269) (xy 67.955289 -316.983432) (xy 67.928986 -316.941836) (xy 67.909695 -316.89656)
			(xy 67.897918 -316.848776) (xy 67.893958 -316.799722) (xy 66.60515 -316.799722) (xy 66.604655 -316.824329)
			(xy 66.59676 -316.872906) (xy 66.581176 -316.919587) (xy 66.558305 -316.963164) (xy 66.52874 -317.002508)
			(xy 66.493247 -317.0366) (xy 66.452744 -317.064556) (xy 66.408282 -317.085654) (xy 66.361011 -317.099346)
			(xy 66.312156 -317.105278) (xy 66.262981 -317.103297) (xy 66.214762 -317.093453) (xy 66.168746 -317.076001)
			(xy 66.126125 -317.051394) (xy 66.088004 -317.020269) (xy 66.055369 -316.983432) (xy 66.029066 -316.941836)
			(xy 66.009775 -316.89656) (xy 65.997998 -316.848776) (xy 65.994038 -316.799722) (xy 64.70523 -316.799722)
			(xy 64.704735 -316.824329) (xy 64.69684 -316.872906) (xy 64.681256 -316.919587) (xy 64.658385 -316.963164)
			(xy 64.62882 -317.002508) (xy 64.593327 -317.0366) (xy 64.552824 -317.064556) (xy 64.508362 -317.085654)
			(xy 64.461091 -317.099346) (xy 64.412236 -317.105278) (xy 64.363061 -317.103297) (xy 64.314842 -317.093453)
			(xy 64.268826 -317.076001) (xy 64.226205 -317.051394) (xy 64.188084 -317.020269) (xy 64.155449 -316.983432)
			(xy 64.129146 -316.941836) (xy 64.109855 -316.89656) (xy 64.098078 -316.848776) (xy 64.094118 -316.799722)
			(xy 62.805056 -316.799722) (xy 62.804561 -316.824329) (xy 62.796666 -316.872906) (xy 62.781082 -316.919587)
			(xy 62.758211 -316.963164) (xy 62.728646 -317.002508) (xy 62.693153 -317.0366) (xy 62.65265 -317.064556)
			(xy 62.608188 -317.085654) (xy 62.560917 -317.099346) (xy 62.512062 -317.105278) (xy 62.462887 -317.103297)
			(xy 62.414668 -317.093453) (xy 62.368652 -317.076001) (xy 62.326031 -317.051394) (xy 62.28791 -317.020269)
			(xy 62.255275 -316.983432) (xy 62.228972 -316.941836) (xy 62.209681 -316.89656) (xy 62.197904 -316.848776)
			(xy 62.193944 -316.799722) (xy 60.905136 -316.799722) (xy 60.904641 -316.824329) (xy 60.896746 -316.872906)
			(xy 60.881162 -316.919587) (xy 60.858291 -316.963164) (xy 60.828726 -317.002508) (xy 60.793233 -317.0366)
			(xy 60.75273 -317.064556) (xy 60.708268 -317.085654) (xy 60.660997 -317.099346) (xy 60.612142 -317.105278)
			(xy 60.562967 -317.103297) (xy 60.514748 -317.093453) (xy 60.468732 -317.076001) (xy 60.426111 -317.051394)
			(xy 60.38799 -317.020269) (xy 60.355355 -316.983432) (xy 60.329052 -316.941836) (xy 60.309761 -316.89656)
			(xy 60.297984 -316.848776) (xy 60.294024 -316.799722) (xy 59.005216 -316.799722) (xy 59.004721 -316.824329)
			(xy 58.996826 -316.872906) (xy 58.981242 -316.919587) (xy 58.958371 -316.963164) (xy 58.928806 -317.002508)
			(xy 58.893313 -317.0366) (xy 58.85281 -317.064556) (xy 58.808348 -317.085654) (xy 58.761077 -317.099346)
			(xy 58.712222 -317.105278) (xy 58.663047 -317.103297) (xy 58.614828 -317.093453) (xy 58.568812 -317.076001)
			(xy 58.526191 -317.051394) (xy 58.48807 -317.020269) (xy 58.455435 -316.983432) (xy 58.429132 -316.941836)
			(xy 58.409841 -316.89656) (xy 58.398064 -316.848776) (xy 58.394104 -316.799722) (xy 57.105296 -316.799722)
			(xy 57.104801 -316.824329) (xy 57.096906 -316.872906) (xy 57.081322 -316.919587) (xy 57.058451 -316.963164)
			(xy 57.028886 -317.002508) (xy 56.993393 -317.0366) (xy 56.95289 -317.064556) (xy 56.908428 -317.085654)
			(xy 56.861157 -317.099346) (xy 56.812302 -317.105278) (xy 56.763127 -317.103297) (xy 56.714908 -317.093453)
			(xy 56.668892 -317.076001) (xy 56.626271 -317.051394) (xy 56.58815 -317.020269) (xy 56.555515 -316.983432)
			(xy 56.529212 -316.941836) (xy 56.509921 -316.89656) (xy 56.498144 -316.848776) (xy 56.494184 -316.799722)
			(xy 55.205122 -316.799722) (xy 55.204627 -316.824329) (xy 55.196732 -316.872906) (xy 55.181148 -316.919587)
			(xy 55.158277 -316.963164) (xy 55.128712 -317.002508) (xy 55.093219 -317.0366) (xy 55.052716 -317.064556)
			(xy 55.008254 -317.085654) (xy 54.960983 -317.099346) (xy 54.912128 -317.105278) (xy 54.862953 -317.103297)
			(xy 54.814734 -317.093453) (xy 54.768718 -317.076001) (xy 54.726097 -317.051394) (xy 54.687976 -317.020269)
			(xy 54.655341 -316.983432) (xy 54.629038 -316.941836) (xy 54.609747 -316.89656) (xy 54.59797 -316.848776)
			(xy 54.59401 -316.799722) (xy 53.305202 -316.799722) (xy 53.304707 -316.824329) (xy 53.296812 -316.872906)
			(xy 53.281228 -316.919587) (xy 53.258357 -316.963164) (xy 53.228792 -317.002508) (xy 53.193299 -317.0366)
			(xy 53.152796 -317.064556) (xy 53.108334 -317.085654) (xy 53.061063 -317.099346) (xy 53.012208 -317.105278)
			(xy 52.963033 -317.103297) (xy 52.914814 -317.093453) (xy 52.868798 -317.076001) (xy 52.826177 -317.051394)
			(xy 52.788056 -317.020269) (xy 52.755421 -316.983432) (xy 52.729118 -316.941836) (xy 52.709827 -316.89656)
			(xy 52.69805 -316.848776) (xy 52.69409 -316.799722) (xy 51.405282 -316.799722) (xy 51.404787 -316.824329)
			(xy 51.396892 -316.872906) (xy 51.381308 -316.919587) (xy 51.358437 -316.963164) (xy 51.328872 -317.002508)
			(xy 51.293379 -317.0366) (xy 51.252876 -317.064556) (xy 51.208414 -317.085654) (xy 51.161143 -317.099346)
			(xy 51.112288 -317.105278) (xy 51.063113 -317.103297) (xy 51.014894 -317.093453) (xy 50.968878 -317.076001)
			(xy 50.926257 -317.051394) (xy 50.888136 -317.020269) (xy 50.855501 -316.983432) (xy 50.829198 -316.941836)
			(xy 50.809907 -316.89656) (xy 50.79813 -316.848776) (xy 50.79417 -316.799722) (xy 49.505108 -316.799722)
			(xy 49.504613 -316.824329) (xy 49.496718 -316.872906) (xy 49.481134 -316.919587) (xy 49.458263 -316.963164)
			(xy 49.428698 -317.002508) (xy 49.393205 -317.0366) (xy 49.352702 -317.064556) (xy 49.30824 -317.085654)
			(xy 49.260969 -317.099346) (xy 49.212114 -317.105278) (xy 49.162939 -317.103297) (xy 49.11472 -317.093453)
			(xy 49.068704 -317.076001) (xy 49.026083 -317.051394) (xy 48.987962 -317.020269) (xy 48.955327 -316.983432)
			(xy 48.929024 -316.941836) (xy 48.909733 -316.89656) (xy 48.897956 -316.848776) (xy 48.893996 -316.799722)
			(xy 47.605188 -316.799722) (xy 47.604693 -316.824329) (xy 47.596798 -316.872906) (xy 47.581214 -316.919587)
			(xy 47.558343 -316.963164) (xy 47.528778 -317.002508) (xy 47.493285 -317.0366) (xy 47.452782 -317.064556)
			(xy 47.40832 -317.085654) (xy 47.361049 -317.099346) (xy 47.312194 -317.105278) (xy 47.263019 -317.103297)
			(xy 47.2148 -317.093453) (xy 47.168784 -317.076001) (xy 47.126163 -317.051394) (xy 47.088042 -317.020269)
			(xy 47.055407 -316.983432) (xy 47.029104 -316.941836) (xy 47.009813 -316.89656) (xy 46.998036 -316.848776)
			(xy 46.994076 -316.799722) (xy 45.705268 -316.799722) (xy 45.704773 -316.824329) (xy 45.696878 -316.872906)
			(xy 45.681294 -316.919587) (xy 45.658423 -316.963164) (xy 45.628858 -317.002508) (xy 45.593365 -317.0366)
			(xy 45.552862 -317.064556) (xy 45.5084 -317.085654) (xy 45.461129 -317.099346) (xy 45.412274 -317.105278)
			(xy 45.363099 -317.103297) (xy 45.31488 -317.093453) (xy 45.268864 -317.076001) (xy 45.226243 -317.051394)
			(xy 45.188122 -317.020269) (xy 45.155487 -316.983432) (xy 45.129184 -316.941836) (xy 45.109893 -316.89656)
			(xy 45.098116 -316.848776) (xy 45.094156 -316.799722) (xy 43.805094 -316.799722) (xy 43.804599 -316.824329)
			(xy 43.796704 -316.872906) (xy 43.78112 -316.919587) (xy 43.758249 -316.963164) (xy 43.728684 -317.002508)
			(xy 43.693191 -317.0366) (xy 43.652688 -317.064556) (xy 43.608226 -317.085654) (xy 43.560955 -317.099346)
			(xy 43.5121 -317.105278) (xy 43.462925 -317.103297) (xy 43.414706 -317.093453) (xy 43.36869 -317.076001)
			(xy 43.326069 -317.051394) (xy 43.287948 -317.020269) (xy 43.255313 -316.983432) (xy 43.22901 -316.941836)
			(xy 43.209719 -316.89656) (xy 43.197942 -316.848776) (xy 43.193982 -316.799722) (xy 41.905174 -316.799722)
			(xy 41.904679 -316.824329) (xy 41.896784 -316.872906) (xy 41.8812 -316.919587) (xy 41.858329 -316.963164)
			(xy 41.828764 -317.002508) (xy 41.793271 -317.0366) (xy 41.752768 -317.064556) (xy 41.708306 -317.085654)
			(xy 41.661035 -317.099346) (xy 41.61218 -317.105278) (xy 41.563005 -317.103297) (xy 41.514786 -317.093453)
			(xy 41.46877 -317.076001) (xy 41.426149 -317.051394) (xy 41.388028 -317.020269) (xy 41.355393 -316.983432)
			(xy 41.32909 -316.941836) (xy 41.309799 -316.89656) (xy 41.298022 -316.848776) (xy 41.294062 -316.799722)
			(xy 40.005254 -316.799722) (xy 40.004759 -316.824329) (xy 39.996864 -316.872906) (xy 39.98128 -316.919587)
			(xy 39.958409 -316.963164) (xy 39.928844 -317.002508) (xy 39.893351 -317.0366) (xy 39.852848 -317.064556)
			(xy 39.808386 -317.085654) (xy 39.761115 -317.099346) (xy 39.71226 -317.105278) (xy 39.663085 -317.103297)
			(xy 39.614866 -317.093453) (xy 39.56885 -317.076001) (xy 39.526229 -317.051394) (xy 39.488108 -317.020269)
			(xy 39.455473 -316.983432) (xy 39.42917 -316.941836) (xy 39.409879 -316.89656) (xy 39.398102 -316.848776)
			(xy 39.394142 -316.799722) (xy 38.10508 -316.799722) (xy 38.104585 -316.824329) (xy 38.09669 -316.872906)
			(xy 38.081106 -316.919587) (xy 38.058235 -316.963164) (xy 38.02867 -317.002508) (xy 37.993177 -317.0366)
			(xy 37.952674 -317.064556) (xy 37.908212 -317.085654) (xy 37.860941 -317.099346) (xy 37.812086 -317.105278)
			(xy 37.762911 -317.103297) (xy 37.714692 -317.093453) (xy 37.668676 -317.076001) (xy 37.626055 -317.051394)
			(xy 37.587934 -317.020269) (xy 37.555299 -316.983432) (xy 37.528996 -316.941836) (xy 37.509705 -316.89656)
			(xy 37.497928 -316.848776) (xy 37.493968 -316.799722) (xy 37.15512 -316.799722) (xy 37.154625 -316.824329)
			(xy 37.14673 -316.872906) (xy 37.131146 -316.919587) (xy 37.108275 -316.963164) (xy 37.07871 -317.002508)
			(xy 37.043217 -317.0366) (xy 37.002714 -317.064556) (xy 36.958252 -317.085654) (xy 36.910981 -317.099346)
			(xy 36.862126 -317.105278) (xy 36.812951 -317.103297) (xy 36.764732 -317.093453) (xy 36.718716 -317.076001)
			(xy 36.676095 -317.051394) (xy 36.637974 -317.020269) (xy 36.605339 -316.983432) (xy 36.579036 -316.941836)
			(xy 36.559745 -316.89656) (xy 36.547968 -316.848776) (xy 36.544008 -316.799722) (xy 0.509016 -316.799722)
			(xy 0.509016 -317.749936) (xy 38.444182 -317.749936) (xy 38.448142 -317.700882) (xy 38.459919 -317.653098)
			(xy 38.47921 -317.607822) (xy 38.505513 -317.566226) (xy 38.538148 -317.529389) (xy 38.576269 -317.498264)
			(xy 38.61889 -317.473657) (xy 38.664906 -317.456205) (xy 38.713125 -317.446361) (xy 38.7623 -317.44438)
			(xy 38.811155 -317.450312) (xy 38.858426 -317.464004) (xy 38.902888 -317.485102) (xy 38.943391 -317.513058)
			(xy 38.978884 -317.54715) (xy 39.008449 -317.586494) (xy 39.03132 -317.630071) (xy 39.046904 -317.676752)
			(xy 39.054799 -317.725329) (xy 39.055294 -317.749936) (xy 40.344102 -317.749936) (xy 40.348062 -317.700882)
			(xy 40.359839 -317.653098) (xy 40.37913 -317.607822) (xy 40.405433 -317.566226) (xy 40.438068 -317.529389)
			(xy 40.476189 -317.498264) (xy 40.51881 -317.473657) (xy 40.564826 -317.456205) (xy 40.613045 -317.446361)
			(xy 40.66222 -317.44438) (xy 40.711075 -317.450312) (xy 40.758346 -317.464004) (xy 40.802808 -317.485102)
			(xy 40.843311 -317.513058) (xy 40.878804 -317.54715) (xy 40.908369 -317.586494) (xy 40.93124 -317.630071)
			(xy 40.946824 -317.676752) (xy 40.954719 -317.725329) (xy 40.955214 -317.749936) (xy 42.244022 -317.749936)
			(xy 42.247982 -317.700882) (xy 42.259759 -317.653098) (xy 42.27905 -317.607822) (xy 42.305353 -317.566226)
			(xy 42.337988 -317.529389) (xy 42.376109 -317.498264) (xy 42.41873 -317.473657) (xy 42.464746 -317.456205)
			(xy 42.512965 -317.446361) (xy 42.56214 -317.44438) (xy 42.610995 -317.450312) (xy 42.658266 -317.464004)
			(xy 42.702728 -317.485102) (xy 42.743231 -317.513058) (xy 42.778724 -317.54715) (xy 42.808289 -317.586494)
			(xy 42.83116 -317.630071) (xy 42.846744 -317.676752) (xy 42.854639 -317.725329) (xy 42.855134 -317.749936)
			(xy 44.143942 -317.749936) (xy 44.147902 -317.700882) (xy 44.159679 -317.653098) (xy 44.17897 -317.607822)
			(xy 44.205273 -317.566226) (xy 44.237908 -317.529389) (xy 44.276029 -317.498264) (xy 44.31865 -317.473657)
			(xy 44.364666 -317.456205) (xy 44.412885 -317.446361) (xy 44.46206 -317.44438) (xy 44.510915 -317.450312)
			(xy 44.558186 -317.464004) (xy 44.602648 -317.485102) (xy 44.643151 -317.513058) (xy 44.678644 -317.54715)
			(xy 44.708209 -317.586494) (xy 44.73108 -317.630071) (xy 44.746664 -317.676752) (xy 44.754559 -317.725329)
			(xy 44.755054 -317.749936) (xy 46.044116 -317.749936) (xy 46.048076 -317.700882) (xy 46.059853 -317.653098)
			(xy 46.079144 -317.607822) (xy 46.105447 -317.566226) (xy 46.138082 -317.529389) (xy 46.176203 -317.498264)
			(xy 46.218824 -317.473657) (xy 46.26484 -317.456205) (xy 46.313059 -317.446361) (xy 46.362234 -317.44438)
			(xy 46.411089 -317.450312) (xy 46.45836 -317.464004) (xy 46.502822 -317.485102) (xy 46.543325 -317.513058)
			(xy 46.578818 -317.54715) (xy 46.608383 -317.586494) (xy 46.631254 -317.630071) (xy 46.646838 -317.676752)
			(xy 46.654733 -317.725329) (xy 46.655228 -317.749936) (xy 47.944036 -317.749936) (xy 47.947996 -317.700882)
			(xy 47.959773 -317.653098) (xy 47.979064 -317.607822) (xy 48.005367 -317.566226) (xy 48.038002 -317.529389)
			(xy 48.076123 -317.498264) (xy 48.118744 -317.473657) (xy 48.16476 -317.456205) (xy 48.212979 -317.446361)
			(xy 48.262154 -317.44438) (xy 48.311009 -317.450312) (xy 48.35828 -317.464004) (xy 48.402742 -317.485102)
			(xy 48.443245 -317.513058) (xy 48.478738 -317.54715) (xy 48.508303 -317.586494) (xy 48.531174 -317.630071)
			(xy 48.546758 -317.676752) (xy 48.554653 -317.725329) (xy 48.555148 -317.749936) (xy 49.843956 -317.749936)
			(xy 49.847916 -317.700882) (xy 49.859693 -317.653098) (xy 49.878984 -317.607822) (xy 49.905287 -317.566226)
			(xy 49.937922 -317.529389) (xy 49.976043 -317.498264) (xy 50.018664 -317.473657) (xy 50.06468 -317.456205)
			(xy 50.112899 -317.446361) (xy 50.162074 -317.44438) (xy 50.210929 -317.450312) (xy 50.2582 -317.464004)
			(xy 50.302662 -317.485102) (xy 50.343165 -317.513058) (xy 50.378658 -317.54715) (xy 50.408223 -317.586494)
			(xy 50.431094 -317.630071) (xy 50.446678 -317.676752) (xy 50.454573 -317.725329) (xy 50.455068 -317.749936)
			(xy 51.74413 -317.749936) (xy 51.74809 -317.700882) (xy 51.759867 -317.653098) (xy 51.779158 -317.607822)
			(xy 51.805461 -317.566226) (xy 51.838096 -317.529389) (xy 51.876217 -317.498264) (xy 51.918838 -317.473657)
			(xy 51.964854 -317.456205) (xy 52.013073 -317.446361) (xy 52.062248 -317.44438) (xy 52.111103 -317.450312)
			(xy 52.158374 -317.464004) (xy 52.202836 -317.485102) (xy 52.243339 -317.513058) (xy 52.278832 -317.54715)
			(xy 52.308397 -317.586494) (xy 52.331268 -317.630071) (xy 52.346852 -317.676752) (xy 52.354747 -317.725329)
			(xy 52.355242 -317.749936) (xy 53.64405 -317.749936) (xy 53.64801 -317.700882) (xy 53.659787 -317.653098)
			(xy 53.679078 -317.607822) (xy 53.705381 -317.566226) (xy 53.738016 -317.529389) (xy 53.776137 -317.498264)
			(xy 53.818758 -317.473657) (xy 53.864774 -317.456205) (xy 53.912993 -317.446361) (xy 53.962168 -317.44438)
			(xy 54.011023 -317.450312) (xy 54.058294 -317.464004) (xy 54.102756 -317.485102) (xy 54.143259 -317.513058)
			(xy 54.178752 -317.54715) (xy 54.208317 -317.586494) (xy 54.231188 -317.630071) (xy 54.246772 -317.676752)
			(xy 54.254667 -317.725329) (xy 54.255162 -317.749936) (xy 55.54397 -317.749936) (xy 55.54793 -317.700882)
			(xy 55.559707 -317.653098) (xy 55.578998 -317.607822) (xy 55.605301 -317.566226) (xy 55.637936 -317.529389)
			(xy 55.676057 -317.498264) (xy 55.718678 -317.473657) (xy 55.764694 -317.456205) (xy 55.812913 -317.446361)
			(xy 55.862088 -317.44438) (xy 55.910943 -317.450312) (xy 55.958214 -317.464004) (xy 56.002676 -317.485102)
			(xy 56.043179 -317.513058) (xy 56.078672 -317.54715) (xy 56.108237 -317.586494) (xy 56.131108 -317.630071)
			(xy 56.146692 -317.676752) (xy 56.154587 -317.725329) (xy 56.155082 -317.749936) (xy 57.444144 -317.749936)
			(xy 57.448104 -317.700882) (xy 57.459881 -317.653098) (xy 57.479172 -317.607822) (xy 57.505475 -317.566226)
			(xy 57.53811 -317.529389) (xy 57.576231 -317.498264) (xy 57.618852 -317.473657) (xy 57.664868 -317.456205)
			(xy 57.713087 -317.446361) (xy 57.762262 -317.44438) (xy 57.811117 -317.450312) (xy 57.858388 -317.464004)
			(xy 57.90285 -317.485102) (xy 57.943353 -317.513058) (xy 57.978846 -317.54715) (xy 58.008411 -317.586494)
			(xy 58.031282 -317.630071) (xy 58.046866 -317.676752) (xy 58.054761 -317.725329) (xy 58.055256 -317.749936)
			(xy 59.344064 -317.749936) (xy 59.348024 -317.700882) (xy 59.359801 -317.653098) (xy 59.379092 -317.607822)
			(xy 59.405395 -317.566226) (xy 59.43803 -317.529389) (xy 59.476151 -317.498264) (xy 59.518772 -317.473657)
			(xy 59.564788 -317.456205) (xy 59.613007 -317.446361) (xy 59.662182 -317.44438) (xy 59.711037 -317.450312)
			(xy 59.758308 -317.464004) (xy 59.80277 -317.485102) (xy 59.843273 -317.513058) (xy 59.878766 -317.54715)
			(xy 59.908331 -317.586494) (xy 59.931202 -317.630071) (xy 59.946786 -317.676752) (xy 59.954681 -317.725329)
			(xy 59.955176 -317.749936) (xy 61.243984 -317.749936) (xy 61.247944 -317.700882) (xy 61.259721 -317.653098)
			(xy 61.279012 -317.607822) (xy 61.305315 -317.566226) (xy 61.33795 -317.529389) (xy 61.376071 -317.498264)
			(xy 61.418692 -317.473657) (xy 61.464708 -317.456205) (xy 61.512927 -317.446361) (xy 61.562102 -317.44438)
			(xy 61.610957 -317.450312) (xy 61.658228 -317.464004) (xy 61.70269 -317.485102) (xy 61.743193 -317.513058)
			(xy 61.778686 -317.54715) (xy 61.808251 -317.586494) (xy 61.831122 -317.630071) (xy 61.846706 -317.676752)
			(xy 61.854601 -317.725329) (xy 61.855096 -317.749936) (xy 63.144158 -317.749936) (xy 63.148118 -317.700882)
			(xy 63.159895 -317.653098) (xy 63.179186 -317.607822) (xy 63.205489 -317.566226) (xy 63.238124 -317.529389)
			(xy 63.276245 -317.498264) (xy 63.318866 -317.473657) (xy 63.364882 -317.456205) (xy 63.413101 -317.446361)
			(xy 63.462276 -317.44438) (xy 63.511131 -317.450312) (xy 63.558402 -317.464004) (xy 63.602864 -317.485102)
			(xy 63.643367 -317.513058) (xy 63.67886 -317.54715) (xy 63.708425 -317.586494) (xy 63.731296 -317.630071)
			(xy 63.74688 -317.676752) (xy 63.754775 -317.725329) (xy 63.75527 -317.749936) (xy 65.044078 -317.749936)
			(xy 65.048038 -317.700882) (xy 65.059815 -317.653098) (xy 65.079106 -317.607822) (xy 65.105409 -317.566226)
			(xy 65.138044 -317.529389) (xy 65.176165 -317.498264) (xy 65.218786 -317.473657) (xy 65.264802 -317.456205)
			(xy 65.313021 -317.446361) (xy 65.362196 -317.44438) (xy 65.411051 -317.450312) (xy 65.458322 -317.464004)
			(xy 65.502784 -317.485102) (xy 65.543287 -317.513058) (xy 65.57878 -317.54715) (xy 65.608345 -317.586494)
			(xy 65.631216 -317.630071) (xy 65.6468 -317.676752) (xy 65.654695 -317.725329) (xy 65.65519 -317.749936)
			(xy 66.943998 -317.749936) (xy 66.947958 -317.700882) (xy 66.959735 -317.653098) (xy 66.979026 -317.607822)
			(xy 67.005329 -317.566226) (xy 67.037964 -317.529389) (xy 67.076085 -317.498264) (xy 67.118706 -317.473657)
			(xy 67.164722 -317.456205) (xy 67.212941 -317.446361) (xy 67.262116 -317.44438) (xy 67.310971 -317.450312)
			(xy 67.358242 -317.464004) (xy 67.402704 -317.485102) (xy 67.443207 -317.513058) (xy 67.4787 -317.54715)
			(xy 67.508265 -317.586494) (xy 67.531136 -317.630071) (xy 67.54672 -317.676752) (xy 67.554615 -317.725329)
			(xy 67.55511 -317.749936) (xy 68.844172 -317.749936) (xy 68.848132 -317.700882) (xy 68.859909 -317.653098)
			(xy 68.8792 -317.607822) (xy 68.905503 -317.566226) (xy 68.938138 -317.529389) (xy 68.976259 -317.498264)
			(xy 69.01888 -317.473657) (xy 69.064896 -317.456205) (xy 69.113115 -317.446361) (xy 69.16229 -317.44438)
			(xy 69.211145 -317.450312) (xy 69.258416 -317.464004) (xy 69.302878 -317.485102) (xy 69.343381 -317.513058)
			(xy 69.378874 -317.54715) (xy 69.408439 -317.586494) (xy 69.43131 -317.630071) (xy 69.446894 -317.676752)
			(xy 69.454789 -317.725329) (xy 69.455284 -317.749936) (xy 70.744092 -317.749936) (xy 70.748052 -317.700882)
			(xy 70.759829 -317.653098) (xy 70.77912 -317.607822) (xy 70.805423 -317.566226) (xy 70.838058 -317.529389)
			(xy 70.876179 -317.498264) (xy 70.9188 -317.473657) (xy 70.964816 -317.456205) (xy 71.013035 -317.446361)
			(xy 71.06221 -317.44438) (xy 71.111065 -317.450312) (xy 71.158336 -317.464004) (xy 71.202798 -317.485102)
			(xy 71.243301 -317.513058) (xy 71.278794 -317.54715) (xy 71.308359 -317.586494) (xy 71.33123 -317.630071)
			(xy 71.346814 -317.676752) (xy 71.354709 -317.725329) (xy 71.355204 -317.749936) (xy 72.644012 -317.749936)
			(xy 72.647972 -317.700882) (xy 72.659749 -317.653098) (xy 72.67904 -317.607822) (xy 72.705343 -317.566226)
			(xy 72.737978 -317.529389) (xy 72.776099 -317.498264) (xy 72.81872 -317.473657) (xy 72.864736 -317.456205)
			(xy 72.912955 -317.446361) (xy 72.96213 -317.44438) (xy 73.010985 -317.450312) (xy 73.058256 -317.464004)
			(xy 73.102718 -317.485102) (xy 73.143221 -317.513058) (xy 73.178714 -317.54715) (xy 73.208279 -317.586494)
			(xy 73.23115 -317.630071) (xy 73.246734 -317.676752) (xy 73.254629 -317.725329) (xy 73.255124 -317.749936)
			(xy 74.544186 -317.749936) (xy 74.548146 -317.700882) (xy 74.559923 -317.653098) (xy 74.579214 -317.607822)
			(xy 74.605517 -317.566226) (xy 74.638152 -317.529389) (xy 74.676273 -317.498264) (xy 74.718894 -317.473657)
			(xy 74.76491 -317.456205) (xy 74.813129 -317.446361) (xy 74.862304 -317.44438) (xy 74.911159 -317.450312)
			(xy 74.95843 -317.464004) (xy 75.002892 -317.485102) (xy 75.043395 -317.513058) (xy 75.078888 -317.54715)
			(xy 75.108453 -317.586494) (xy 75.131324 -317.630071) (xy 75.146908 -317.676752) (xy 75.154803 -317.725329)
			(xy 75.155298 -317.749936) (xy 76.444106 -317.749936) (xy 76.448066 -317.700882) (xy 76.459843 -317.653098)
			(xy 76.479134 -317.607822) (xy 76.505437 -317.566226) (xy 76.538072 -317.529389) (xy 76.576193 -317.498264)
			(xy 76.618814 -317.473657) (xy 76.66483 -317.456205) (xy 76.713049 -317.446361) (xy 76.762224 -317.44438)
			(xy 76.811079 -317.450312) (xy 76.85835 -317.464004) (xy 76.902812 -317.485102) (xy 76.943315 -317.513058)
			(xy 76.978808 -317.54715) (xy 77.008373 -317.586494) (xy 77.031244 -317.630071) (xy 77.046828 -317.676752)
			(xy 77.054723 -317.725329) (xy 77.055218 -317.749936) (xy 78.344026 -317.749936) (xy 78.347986 -317.700882)
			(xy 78.359763 -317.653098) (xy 78.379054 -317.607822) (xy 78.405357 -317.566226) (xy 78.437992 -317.529389)
			(xy 78.476113 -317.498264) (xy 78.518734 -317.473657) (xy 78.56475 -317.456205) (xy 78.612969 -317.446361)
			(xy 78.662144 -317.44438) (xy 78.710999 -317.450312) (xy 78.75827 -317.464004) (xy 78.802732 -317.485102)
			(xy 78.843235 -317.513058) (xy 78.878728 -317.54715) (xy 78.908293 -317.586494) (xy 78.931164 -317.630071)
			(xy 78.946748 -317.676752) (xy 78.954643 -317.725329) (xy 78.955138 -317.749936) (xy 80.243946 -317.749936)
			(xy 80.247906 -317.700882) (xy 80.259683 -317.653098) (xy 80.278974 -317.607822) (xy 80.305277 -317.566226)
			(xy 80.337912 -317.529389) (xy 80.376033 -317.498264) (xy 80.418654 -317.473657) (xy 80.46467 -317.456205)
			(xy 80.512889 -317.446361) (xy 80.562064 -317.44438) (xy 80.610919 -317.450312) (xy 80.65819 -317.464004)
			(xy 80.702652 -317.485102) (xy 80.743155 -317.513058) (xy 80.778648 -317.54715) (xy 80.808213 -317.586494)
			(xy 80.831084 -317.630071) (xy 80.846668 -317.676752) (xy 80.854563 -317.725329) (xy 80.855058 -317.749936)
			(xy 154.54428 -317.749936) (xy 154.54824 -317.700882) (xy 154.560017 -317.653098) (xy 154.579308 -317.607822)
			(xy 154.605611 -317.566226) (xy 154.638246 -317.529389) (xy 154.676367 -317.498264) (xy 154.718988 -317.473657)
			(xy 154.765004 -317.456205) (xy 154.813223 -317.446361) (xy 154.862398 -317.44438) (xy 154.911253 -317.450312)
			(xy 154.958524 -317.464004) (xy 155.002986 -317.485102) (xy 155.043489 -317.513058) (xy 155.078982 -317.54715)
			(xy 155.108547 -317.586494) (xy 155.131418 -317.630071) (xy 155.147002 -317.676752) (xy 155.154897 -317.725329)
			(xy 155.155392 -317.749936) (xy 156.4442 -317.749936) (xy 156.44816 -317.700882) (xy 156.459937 -317.653098)
			(xy 156.479228 -317.607822) (xy 156.505531 -317.566226) (xy 156.538166 -317.529389) (xy 156.576287 -317.498264)
			(xy 156.618908 -317.473657) (xy 156.664924 -317.456205) (xy 156.713143 -317.446361) (xy 156.762318 -317.44438)
			(xy 156.811173 -317.450312) (xy 156.858444 -317.464004) (xy 156.902906 -317.485102) (xy 156.943409 -317.513058)
			(xy 156.978902 -317.54715) (xy 157.008467 -317.586494) (xy 157.031338 -317.630071) (xy 157.046922 -317.676752)
			(xy 157.054817 -317.725329) (xy 157.055312 -317.749936) (xy 158.34412 -317.749936) (xy 158.34808 -317.700882)
			(xy 158.359857 -317.653098) (xy 158.379148 -317.607822) (xy 158.405451 -317.566226) (xy 158.438086 -317.529389)
			(xy 158.476207 -317.498264) (xy 158.518828 -317.473657) (xy 158.564844 -317.456205) (xy 158.613063 -317.446361)
			(xy 158.662238 -317.44438) (xy 158.711093 -317.450312) (xy 158.758364 -317.464004) (xy 158.802826 -317.485102)
			(xy 158.843329 -317.513058) (xy 158.878822 -317.54715) (xy 158.908387 -317.586494) (xy 158.931258 -317.630071)
			(xy 158.946842 -317.676752) (xy 158.954737 -317.725329) (xy 158.955232 -317.749936) (xy 160.24404 -317.749936)
			(xy 160.248 -317.700882) (xy 160.259777 -317.653098) (xy 160.279068 -317.607822) (xy 160.305371 -317.566226)
			(xy 160.338006 -317.529389) (xy 160.376127 -317.498264) (xy 160.418748 -317.473657) (xy 160.464764 -317.456205)
			(xy 160.512983 -317.446361) (xy 160.562158 -317.44438) (xy 160.611013 -317.450312) (xy 160.658284 -317.464004)
			(xy 160.702746 -317.485102) (xy 160.743249 -317.513058) (xy 160.778742 -317.54715) (xy 160.808307 -317.586494)
			(xy 160.831178 -317.630071) (xy 160.846762 -317.676752) (xy 160.854657 -317.725329) (xy 160.855152 -317.749936)
			(xy 162.144214 -317.749936) (xy 162.148174 -317.700882) (xy 162.159951 -317.653098) (xy 162.179242 -317.607822)
			(xy 162.205545 -317.566226) (xy 162.23818 -317.529389) (xy 162.276301 -317.498264) (xy 162.318922 -317.473657)
			(xy 162.364938 -317.456205) (xy 162.413157 -317.446361) (xy 162.462332 -317.44438) (xy 162.511187 -317.450312)
			(xy 162.558458 -317.464004) (xy 162.60292 -317.485102) (xy 162.643423 -317.513058) (xy 162.678916 -317.54715)
			(xy 162.708481 -317.586494) (xy 162.731352 -317.630071) (xy 162.746936 -317.676752) (xy 162.754831 -317.725329)
			(xy 162.755326 -317.749936) (xy 164.044134 -317.749936) (xy 164.048094 -317.700882) (xy 164.059871 -317.653098)
			(xy 164.079162 -317.607822) (xy 164.105465 -317.566226) (xy 164.1381 -317.529389) (xy 164.176221 -317.498264)
			(xy 164.218842 -317.473657) (xy 164.264858 -317.456205) (xy 164.313077 -317.446361) (xy 164.362252 -317.44438)
			(xy 164.411107 -317.450312) (xy 164.458378 -317.464004) (xy 164.50284 -317.485102) (xy 164.543343 -317.513058)
			(xy 164.578836 -317.54715) (xy 164.608401 -317.586494) (xy 164.631272 -317.630071) (xy 164.646856 -317.676752)
			(xy 164.654751 -317.725329) (xy 164.655246 -317.749936) (xy 165.944054 -317.749936) (xy 165.948014 -317.700882)
			(xy 165.959791 -317.653098) (xy 165.979082 -317.607822) (xy 166.005385 -317.566226) (xy 166.03802 -317.529389)
			(xy 166.076141 -317.498264) (xy 166.118762 -317.473657) (xy 166.164778 -317.456205) (xy 166.212997 -317.446361)
			(xy 166.262172 -317.44438) (xy 166.311027 -317.450312) (xy 166.358298 -317.464004) (xy 166.40276 -317.485102)
			(xy 166.443263 -317.513058) (xy 166.478756 -317.54715) (xy 166.508321 -317.586494) (xy 166.531192 -317.630071)
			(xy 166.546776 -317.676752) (xy 166.554671 -317.725329) (xy 166.555166 -317.749936) (xy 167.844228 -317.749936)
			(xy 167.848188 -317.700882) (xy 167.859965 -317.653098) (xy 167.879256 -317.607822) (xy 167.905559 -317.566226)
			(xy 167.938194 -317.529389) (xy 167.976315 -317.498264) (xy 168.018936 -317.473657) (xy 168.064952 -317.456205)
			(xy 168.113171 -317.446361) (xy 168.162346 -317.44438) (xy 168.211201 -317.450312) (xy 168.258472 -317.464004)
			(xy 168.302934 -317.485102) (xy 168.343437 -317.513058) (xy 168.37893 -317.54715) (xy 168.408495 -317.586494)
			(xy 168.431366 -317.630071) (xy 168.44695 -317.676752) (xy 168.454845 -317.725329) (xy 168.45534 -317.749936)
			(xy 169.744148 -317.749936) (xy 169.748108 -317.700882) (xy 169.759885 -317.653098) (xy 169.779176 -317.607822)
			(xy 169.805479 -317.566226) (xy 169.838114 -317.529389) (xy 169.876235 -317.498264) (xy 169.918856 -317.473657)
			(xy 169.964872 -317.456205) (xy 170.013091 -317.446361) (xy 170.062266 -317.44438) (xy 170.111121 -317.450312)
			(xy 170.158392 -317.464004) (xy 170.202854 -317.485102) (xy 170.243357 -317.513058) (xy 170.27885 -317.54715)
			(xy 170.308415 -317.586494) (xy 170.331286 -317.630071) (xy 170.34687 -317.676752) (xy 170.354765 -317.725329)
			(xy 170.35526 -317.749936) (xy 171.644068 -317.749936) (xy 171.648028 -317.700882) (xy 171.659805 -317.653098)
			(xy 171.679096 -317.607822) (xy 171.705399 -317.566226) (xy 171.738034 -317.529389) (xy 171.776155 -317.498264)
			(xy 171.818776 -317.473657) (xy 171.864792 -317.456205) (xy 171.913011 -317.446361) (xy 171.962186 -317.44438)
			(xy 172.011041 -317.450312) (xy 172.058312 -317.464004) (xy 172.102774 -317.485102) (xy 172.143277 -317.513058)
			(xy 172.17877 -317.54715) (xy 172.208335 -317.586494) (xy 172.231206 -317.630071) (xy 172.24679 -317.676752)
			(xy 172.254685 -317.725329) (xy 172.25518 -317.749936) (xy 173.544242 -317.749936) (xy 173.548202 -317.700882)
			(xy 173.559979 -317.653098) (xy 173.57927 -317.607822) (xy 173.605573 -317.566226) (xy 173.638208 -317.529389)
			(xy 173.676329 -317.498264) (xy 173.71895 -317.473657) (xy 173.764966 -317.456205) (xy 173.813185 -317.446361)
			(xy 173.86236 -317.44438) (xy 173.911215 -317.450312) (xy 173.958486 -317.464004) (xy 174.002948 -317.485102)
			(xy 174.043451 -317.513058) (xy 174.078944 -317.54715) (xy 174.108509 -317.586494) (xy 174.13138 -317.630071)
			(xy 174.146964 -317.676752) (xy 174.154859 -317.725329) (xy 174.155354 -317.749936) (xy 175.444162 -317.749936)
			(xy 175.448122 -317.700882) (xy 175.459899 -317.653098) (xy 175.47919 -317.607822) (xy 175.505493 -317.566226)
			(xy 175.538128 -317.529389) (xy 175.576249 -317.498264) (xy 175.61887 -317.473657) (xy 175.664886 -317.456205)
			(xy 175.713105 -317.446361) (xy 175.76228 -317.44438) (xy 175.811135 -317.450312) (xy 175.858406 -317.464004)
			(xy 175.902868 -317.485102) (xy 175.943371 -317.513058) (xy 175.978864 -317.54715) (xy 176.008429 -317.586494)
			(xy 176.0313 -317.630071) (xy 176.046884 -317.676752) (xy 176.054779 -317.725329) (xy 176.055274 -317.749936)
			(xy 177.344082 -317.749936) (xy 177.348042 -317.700882) (xy 177.359819 -317.653098) (xy 177.37911 -317.607822)
			(xy 177.405413 -317.566226) (xy 177.438048 -317.529389) (xy 177.476169 -317.498264) (xy 177.51879 -317.473657)
			(xy 177.564806 -317.456205) (xy 177.613025 -317.446361) (xy 177.6622 -317.44438) (xy 177.711055 -317.450312)
			(xy 177.758326 -317.464004) (xy 177.802788 -317.485102) (xy 177.843291 -317.513058) (xy 177.878784 -317.54715)
			(xy 177.908349 -317.586494) (xy 177.93122 -317.630071) (xy 177.946804 -317.676752) (xy 177.954699 -317.725329)
			(xy 177.955194 -317.749936) (xy 179.244256 -317.749936) (xy 179.248216 -317.700882) (xy 179.259993 -317.653098)
			(xy 179.279284 -317.607822) (xy 179.305587 -317.566226) (xy 179.338222 -317.529389) (xy 179.376343 -317.498264)
			(xy 179.418964 -317.473657) (xy 179.46498 -317.456205) (xy 179.513199 -317.446361) (xy 179.562374 -317.44438)
			(xy 179.611229 -317.450312) (xy 179.6585 -317.464004) (xy 179.702962 -317.485102) (xy 179.743465 -317.513058)
			(xy 179.778958 -317.54715) (xy 179.808523 -317.586494) (xy 179.831394 -317.630071) (xy 179.846978 -317.676752)
			(xy 179.854873 -317.725329) (xy 179.855368 -317.749936) (xy 181.144176 -317.749936) (xy 181.148136 -317.700882)
			(xy 181.159913 -317.653098) (xy 181.179204 -317.607822) (xy 181.205507 -317.566226) (xy 181.238142 -317.529389)
			(xy 181.276263 -317.498264) (xy 181.318884 -317.473657) (xy 181.3649 -317.456205) (xy 181.413119 -317.446361)
			(xy 181.462294 -317.44438) (xy 181.511149 -317.450312) (xy 181.55842 -317.464004) (xy 181.602882 -317.485102)
			(xy 181.643385 -317.513058) (xy 181.678878 -317.54715) (xy 181.708443 -317.586494) (xy 181.731314 -317.630071)
			(xy 181.746898 -317.676752) (xy 181.754793 -317.725329) (xy 181.755288 -317.749936) (xy 183.044096 -317.749936)
			(xy 183.048056 -317.700882) (xy 183.059833 -317.653098) (xy 183.079124 -317.607822) (xy 183.105427 -317.566226)
			(xy 183.138062 -317.529389) (xy 183.176183 -317.498264) (xy 183.218804 -317.473657) (xy 183.26482 -317.456205)
			(xy 183.313039 -317.446361) (xy 183.362214 -317.44438) (xy 183.411069 -317.450312) (xy 183.45834 -317.464004)
			(xy 183.502802 -317.485102) (xy 183.543305 -317.513058) (xy 183.578798 -317.54715) (xy 183.608363 -317.586494)
			(xy 183.631234 -317.630071) (xy 183.646818 -317.676752) (xy 183.654713 -317.725329) (xy 183.655208 -317.749936)
			(xy 184.94427 -317.749936) (xy 184.94823 -317.700882) (xy 184.960007 -317.653098) (xy 184.979298 -317.607822)
			(xy 185.005601 -317.566226) (xy 185.038236 -317.529389) (xy 185.076357 -317.498264) (xy 185.118978 -317.473657)
			(xy 185.164994 -317.456205) (xy 185.213213 -317.446361) (xy 185.262388 -317.44438) (xy 185.311243 -317.450312)
			(xy 185.358514 -317.464004) (xy 185.402976 -317.485102) (xy 185.443479 -317.513058) (xy 185.478972 -317.54715)
			(xy 185.508537 -317.586494) (xy 185.531408 -317.630071) (xy 185.546992 -317.676752) (xy 185.554887 -317.725329)
			(xy 185.555382 -317.749936) (xy 186.84419 -317.749936) (xy 186.84815 -317.700882) (xy 186.859927 -317.653098)
			(xy 186.879218 -317.607822) (xy 186.905521 -317.566226) (xy 186.938156 -317.529389) (xy 186.976277 -317.498264)
			(xy 187.018898 -317.473657) (xy 187.064914 -317.456205) (xy 187.113133 -317.446361) (xy 187.162308 -317.44438)
			(xy 187.211163 -317.450312) (xy 187.258434 -317.464004) (xy 187.302896 -317.485102) (xy 187.343399 -317.513058)
			(xy 187.378892 -317.54715) (xy 187.408457 -317.586494) (xy 187.431328 -317.630071) (xy 187.446912 -317.676752)
			(xy 187.454807 -317.725329) (xy 187.455302 -317.749936) (xy 188.74411 -317.749936) (xy 188.74807 -317.700882)
			(xy 188.759847 -317.653098) (xy 188.779138 -317.607822) (xy 188.805441 -317.566226) (xy 188.838076 -317.529389)
			(xy 188.876197 -317.498264) (xy 188.918818 -317.473657) (xy 188.964834 -317.456205) (xy 189.013053 -317.446361)
			(xy 189.062228 -317.44438) (xy 189.111083 -317.450312) (xy 189.158354 -317.464004) (xy 189.202816 -317.485102)
			(xy 189.243319 -317.513058) (xy 189.278812 -317.54715) (xy 189.308377 -317.586494) (xy 189.331248 -317.630071)
			(xy 189.346832 -317.676752) (xy 189.354727 -317.725329) (xy 189.355222 -317.749936) (xy 190.644284 -317.749936)
			(xy 190.648244 -317.700882) (xy 190.660021 -317.653098) (xy 190.679312 -317.607822) (xy 190.705615 -317.566226)
			(xy 190.73825 -317.529389) (xy 190.776371 -317.498264) (xy 190.818992 -317.473657) (xy 190.865008 -317.456205)
			(xy 190.913227 -317.446361) (xy 190.962402 -317.44438) (xy 191.011257 -317.450312) (xy 191.058528 -317.464004)
			(xy 191.10299 -317.485102) (xy 191.143493 -317.513058) (xy 191.178986 -317.54715) (xy 191.208551 -317.586494)
			(xy 191.231422 -317.630071) (xy 191.247006 -317.676752) (xy 191.254901 -317.725329) (xy 191.255396 -317.749936)
			(xy 192.544204 -317.749936) (xy 192.548164 -317.700882) (xy 192.559941 -317.653098) (xy 192.579232 -317.607822)
			(xy 192.605535 -317.566226) (xy 192.63817 -317.529389) (xy 192.676291 -317.498264) (xy 192.718912 -317.473657)
			(xy 192.764928 -317.456205) (xy 192.813147 -317.446361) (xy 192.862322 -317.44438) (xy 192.911177 -317.450312)
			(xy 192.958448 -317.464004) (xy 193.00291 -317.485102) (xy 193.043413 -317.513058) (xy 193.078906 -317.54715)
			(xy 193.108471 -317.586494) (xy 193.131342 -317.630071) (xy 193.146926 -317.676752) (xy 193.154821 -317.725329)
			(xy 193.155316 -317.749936) (xy 194.444124 -317.749936) (xy 194.448084 -317.700882) (xy 194.459861 -317.653098)
			(xy 194.479152 -317.607822) (xy 194.505455 -317.566226) (xy 194.53809 -317.529389) (xy 194.576211 -317.498264)
			(xy 194.618832 -317.473657) (xy 194.664848 -317.456205) (xy 194.713067 -317.446361) (xy 194.762242 -317.44438)
			(xy 194.811097 -317.450312) (xy 194.858368 -317.464004) (xy 194.90283 -317.485102) (xy 194.943333 -317.513058)
			(xy 194.978826 -317.54715) (xy 195.008391 -317.586494) (xy 195.031262 -317.630071) (xy 195.046846 -317.676752)
			(xy 195.054741 -317.725329) (xy 195.055236 -317.749936) (xy 196.344044 -317.749936) (xy 196.348004 -317.700882)
			(xy 196.359781 -317.653098) (xy 196.379072 -317.607822) (xy 196.405375 -317.566226) (xy 196.43801 -317.529389)
			(xy 196.476131 -317.498264) (xy 196.518752 -317.473657) (xy 196.564768 -317.456205) (xy 196.612987 -317.446361)
			(xy 196.662162 -317.44438) (xy 196.711017 -317.450312) (xy 196.758288 -317.464004) (xy 196.80275 -317.485102)
			(xy 196.843253 -317.513058) (xy 196.878746 -317.54715) (xy 196.908311 -317.586494) (xy 196.931182 -317.630071)
			(xy 196.946766 -317.676752) (xy 196.954661 -317.725329) (xy 196.955156 -317.749936) (xy 270.644124 -317.749936)
			(xy 270.648084 -317.700882) (xy 270.659861 -317.653098) (xy 270.679152 -317.607822) (xy 270.705455 -317.566226)
			(xy 270.73809 -317.529389) (xy 270.776211 -317.498264) (xy 270.818832 -317.473657) (xy 270.864848 -317.456205)
			(xy 270.913067 -317.446361) (xy 270.962242 -317.44438) (xy 271.011097 -317.450312) (xy 271.058368 -317.464004)
			(xy 271.10283 -317.485102) (xy 271.143333 -317.513058) (xy 271.178826 -317.54715) (xy 271.208391 -317.586494)
			(xy 271.231262 -317.630071) (xy 271.246846 -317.676752) (xy 271.254741 -317.725329) (xy 271.255236 -317.749936)
			(xy 272.544044 -317.749936) (xy 272.548004 -317.700882) (xy 272.559781 -317.653098) (xy 272.579072 -317.607822)
			(xy 272.605375 -317.566226) (xy 272.63801 -317.529389) (xy 272.676131 -317.498264) (xy 272.718752 -317.473657)
			(xy 272.764768 -317.456205) (xy 272.812987 -317.446361) (xy 272.862162 -317.44438) (xy 272.911017 -317.450312)
			(xy 272.958288 -317.464004) (xy 273.00275 -317.485102) (xy 273.043253 -317.513058) (xy 273.078746 -317.54715)
			(xy 273.108311 -317.586494) (xy 273.131182 -317.630071) (xy 273.146766 -317.676752) (xy 273.154661 -317.725329)
			(xy 273.155156 -317.749936) (xy 274.443964 -317.749936) (xy 274.447924 -317.700882) (xy 274.459701 -317.653098)
			(xy 274.478992 -317.607822) (xy 274.505295 -317.566226) (xy 274.53793 -317.529389) (xy 274.576051 -317.498264)
			(xy 274.618672 -317.473657) (xy 274.664688 -317.456205) (xy 274.712907 -317.446361) (xy 274.762082 -317.44438)
			(xy 274.810937 -317.450312) (xy 274.858208 -317.464004) (xy 274.90267 -317.485102) (xy 274.943173 -317.513058)
			(xy 274.978666 -317.54715) (xy 275.008231 -317.586494) (xy 275.031102 -317.630071) (xy 275.046686 -317.676752)
			(xy 275.054581 -317.725329) (xy 275.055076 -317.749936) (xy 276.343884 -317.749936) (xy 276.347844 -317.700882)
			(xy 276.359621 -317.653098) (xy 276.378912 -317.607822) (xy 276.405215 -317.566226) (xy 276.43785 -317.529389)
			(xy 276.475971 -317.498264) (xy 276.518592 -317.473657) (xy 276.564608 -317.456205) (xy 276.612827 -317.446361)
			(xy 276.662002 -317.44438) (xy 276.710857 -317.450312) (xy 276.758128 -317.464004) (xy 276.80259 -317.485102)
			(xy 276.843093 -317.513058) (xy 276.878586 -317.54715) (xy 276.908151 -317.586494) (xy 276.931022 -317.630071)
			(xy 276.946606 -317.676752) (xy 276.954501 -317.725329) (xy 276.954996 -317.749936) (xy 278.244058 -317.749936)
			(xy 278.248018 -317.700882) (xy 278.259795 -317.653098) (xy 278.279086 -317.607822) (xy 278.305389 -317.566226)
			(xy 278.338024 -317.529389) (xy 278.376145 -317.498264) (xy 278.418766 -317.473657) (xy 278.464782 -317.456205)
			(xy 278.513001 -317.446361) (xy 278.562176 -317.44438) (xy 278.611031 -317.450312) (xy 278.658302 -317.464004)
			(xy 278.702764 -317.485102) (xy 278.743267 -317.513058) (xy 278.77876 -317.54715) (xy 278.808325 -317.586494)
			(xy 278.831196 -317.630071) (xy 278.84678 -317.676752) (xy 278.854675 -317.725329) (xy 278.85517 -317.749936)
			(xy 280.143978 -317.749936) (xy 280.147938 -317.700882) (xy 280.159715 -317.653098) (xy 280.179006 -317.607822)
			(xy 280.205309 -317.566226) (xy 280.237944 -317.529389) (xy 280.276065 -317.498264) (xy 280.318686 -317.473657)
			(xy 280.364702 -317.456205) (xy 280.412921 -317.446361) (xy 280.462096 -317.44438) (xy 280.510951 -317.450312)
			(xy 280.558222 -317.464004) (xy 280.602684 -317.485102) (xy 280.643187 -317.513058) (xy 280.67868 -317.54715)
			(xy 280.708245 -317.586494) (xy 280.731116 -317.630071) (xy 280.7467 -317.676752) (xy 280.754595 -317.725329)
			(xy 280.75509 -317.749936) (xy 282.043898 -317.749936) (xy 282.047858 -317.700882) (xy 282.059635 -317.653098)
			(xy 282.078926 -317.607822) (xy 282.105229 -317.566226) (xy 282.137864 -317.529389) (xy 282.175985 -317.498264)
			(xy 282.218606 -317.473657) (xy 282.264622 -317.456205) (xy 282.312841 -317.446361) (xy 282.362016 -317.44438)
			(xy 282.410871 -317.450312) (xy 282.458142 -317.464004) (xy 282.502604 -317.485102) (xy 282.543107 -317.513058)
			(xy 282.5786 -317.54715) (xy 282.608165 -317.586494) (xy 282.631036 -317.630071) (xy 282.64662 -317.676752)
			(xy 282.654515 -317.725329) (xy 282.65501 -317.749936) (xy 283.944072 -317.749936) (xy 283.948032 -317.700882)
			(xy 283.959809 -317.653098) (xy 283.9791 -317.607822) (xy 284.005403 -317.566226) (xy 284.038038 -317.529389)
			(xy 284.076159 -317.498264) (xy 284.11878 -317.473657) (xy 284.164796 -317.456205) (xy 284.213015 -317.446361)
			(xy 284.26219 -317.44438) (xy 284.311045 -317.450312) (xy 284.358316 -317.464004) (xy 284.402778 -317.485102)
			(xy 284.443281 -317.513058) (xy 284.478774 -317.54715) (xy 284.508339 -317.586494) (xy 284.53121 -317.630071)
			(xy 284.546794 -317.676752) (xy 284.554689 -317.725329) (xy 284.555184 -317.749936) (xy 285.843992 -317.749936)
			(xy 285.847952 -317.700882) (xy 285.859729 -317.653098) (xy 285.87902 -317.607822) (xy 285.905323 -317.566226)
			(xy 285.937958 -317.529389) (xy 285.976079 -317.498264) (xy 286.0187 -317.473657) (xy 286.064716 -317.456205)
			(xy 286.112935 -317.446361) (xy 286.16211 -317.44438) (xy 286.210965 -317.450312) (xy 286.258236 -317.464004)
			(xy 286.302698 -317.485102) (xy 286.343201 -317.513058) (xy 286.378694 -317.54715) (xy 286.408259 -317.586494)
			(xy 286.43113 -317.630071) (xy 286.446714 -317.676752) (xy 286.454609 -317.725329) (xy 286.455104 -317.749936)
			(xy 287.743912 -317.749936) (xy 287.747872 -317.700882) (xy 287.759649 -317.653098) (xy 287.77894 -317.607822)
			(xy 287.805243 -317.566226) (xy 287.837878 -317.529389) (xy 287.875999 -317.498264) (xy 287.91862 -317.473657)
			(xy 287.964636 -317.456205) (xy 288.012855 -317.446361) (xy 288.06203 -317.44438) (xy 288.110885 -317.450312)
			(xy 288.158156 -317.464004) (xy 288.202618 -317.485102) (xy 288.243121 -317.513058) (xy 288.278614 -317.54715)
			(xy 288.308179 -317.586494) (xy 288.33105 -317.630071) (xy 288.346634 -317.676752) (xy 288.354529 -317.725329)
			(xy 288.355024 -317.749936) (xy 289.644086 -317.749936) (xy 289.648046 -317.700882) (xy 289.659823 -317.653098)
			(xy 289.679114 -317.607822) (xy 289.705417 -317.566226) (xy 289.738052 -317.529389) (xy 289.776173 -317.498264)
			(xy 289.818794 -317.473657) (xy 289.86481 -317.456205) (xy 289.913029 -317.446361) (xy 289.962204 -317.44438)
			(xy 290.011059 -317.450312) (xy 290.05833 -317.464004) (xy 290.102792 -317.485102) (xy 290.143295 -317.513058)
			(xy 290.178788 -317.54715) (xy 290.208353 -317.586494) (xy 290.231224 -317.630071) (xy 290.246808 -317.676752)
			(xy 290.254703 -317.725329) (xy 290.255198 -317.749936) (xy 291.544006 -317.749936) (xy 291.547966 -317.700882)
			(xy 291.559743 -317.653098) (xy 291.579034 -317.607822) (xy 291.605337 -317.566226) (xy 291.637972 -317.529389)
			(xy 291.676093 -317.498264) (xy 291.718714 -317.473657) (xy 291.76473 -317.456205) (xy 291.812949 -317.446361)
			(xy 291.862124 -317.44438) (xy 291.910979 -317.450312) (xy 291.95825 -317.464004) (xy 292.002712 -317.485102)
			(xy 292.043215 -317.513058) (xy 292.078708 -317.54715) (xy 292.108273 -317.586494) (xy 292.131144 -317.630071)
			(xy 292.146728 -317.676752) (xy 292.154623 -317.725329) (xy 292.155118 -317.749936) (xy 293.443926 -317.749936)
			(xy 293.447886 -317.700882) (xy 293.459663 -317.653098) (xy 293.478954 -317.607822) (xy 293.505257 -317.566226)
			(xy 293.537892 -317.529389) (xy 293.576013 -317.498264) (xy 293.618634 -317.473657) (xy 293.66465 -317.456205)
			(xy 293.712869 -317.446361) (xy 293.762044 -317.44438) (xy 293.810899 -317.450312) (xy 293.85817 -317.464004)
			(xy 293.902632 -317.485102) (xy 293.943135 -317.513058) (xy 293.978628 -317.54715) (xy 294.008193 -317.586494)
			(xy 294.031064 -317.630071) (xy 294.046648 -317.676752) (xy 294.054543 -317.725329) (xy 294.055038 -317.749936)
			(xy 295.3441 -317.749936) (xy 295.34806 -317.700882) (xy 295.359837 -317.653098) (xy 295.379128 -317.607822)
			(xy 295.405431 -317.566226) (xy 295.438066 -317.529389) (xy 295.476187 -317.498264) (xy 295.518808 -317.473657)
			(xy 295.564824 -317.456205) (xy 295.613043 -317.446361) (xy 295.662218 -317.44438) (xy 295.711073 -317.450312)
			(xy 295.758344 -317.464004) (xy 295.802806 -317.485102) (xy 295.843309 -317.513058) (xy 295.878802 -317.54715)
			(xy 295.908367 -317.586494) (xy 295.931238 -317.630071) (xy 295.946822 -317.676752) (xy 295.954717 -317.725329)
			(xy 295.955212 -317.749936) (xy 297.24402 -317.749936) (xy 297.24798 -317.700882) (xy 297.259757 -317.653098)
			(xy 297.279048 -317.607822) (xy 297.305351 -317.566226) (xy 297.337986 -317.529389) (xy 297.376107 -317.498264)
			(xy 297.418728 -317.473657) (xy 297.464744 -317.456205) (xy 297.512963 -317.446361) (xy 297.562138 -317.44438)
			(xy 297.610993 -317.450312) (xy 297.658264 -317.464004) (xy 297.702726 -317.485102) (xy 297.743229 -317.513058)
			(xy 297.778722 -317.54715) (xy 297.808287 -317.586494) (xy 297.831158 -317.630071) (xy 297.846742 -317.676752)
			(xy 297.854637 -317.725329) (xy 297.855132 -317.749936) (xy 299.14394 -317.749936) (xy 299.1479 -317.700882)
			(xy 299.159677 -317.653098) (xy 299.178968 -317.607822) (xy 299.205271 -317.566226) (xy 299.237906 -317.529389)
			(xy 299.276027 -317.498264) (xy 299.318648 -317.473657) (xy 299.364664 -317.456205) (xy 299.412883 -317.446361)
			(xy 299.462058 -317.44438) (xy 299.510913 -317.450312) (xy 299.558184 -317.464004) (xy 299.602646 -317.485102)
			(xy 299.643149 -317.513058) (xy 299.678642 -317.54715) (xy 299.708207 -317.586494) (xy 299.731078 -317.630071)
			(xy 299.746662 -317.676752) (xy 299.754557 -317.725329) (xy 299.755052 -317.749936) (xy 301.044114 -317.749936)
			(xy 301.048074 -317.700882) (xy 301.059851 -317.653098) (xy 301.079142 -317.607822) (xy 301.105445 -317.566226)
			(xy 301.13808 -317.529389) (xy 301.176201 -317.498264) (xy 301.218822 -317.473657) (xy 301.264838 -317.456205)
			(xy 301.313057 -317.446361) (xy 301.362232 -317.44438) (xy 301.411087 -317.450312) (xy 301.458358 -317.464004)
			(xy 301.50282 -317.485102) (xy 301.543323 -317.513058) (xy 301.578816 -317.54715) (xy 301.608381 -317.586494)
			(xy 301.631252 -317.630071) (xy 301.646836 -317.676752) (xy 301.654731 -317.725329) (xy 301.655226 -317.749936)
			(xy 302.944034 -317.749936) (xy 302.947994 -317.700882) (xy 302.959771 -317.653098) (xy 302.979062 -317.607822)
			(xy 303.005365 -317.566226) (xy 303.038 -317.529389) (xy 303.076121 -317.498264) (xy 303.118742 -317.473657)
			(xy 303.164758 -317.456205) (xy 303.212977 -317.446361) (xy 303.262152 -317.44438) (xy 303.311007 -317.450312)
			(xy 303.358278 -317.464004) (xy 303.40274 -317.485102) (xy 303.443243 -317.513058) (xy 303.478736 -317.54715)
			(xy 303.508301 -317.586494) (xy 303.531172 -317.630071) (xy 303.546756 -317.676752) (xy 303.554651 -317.725329)
			(xy 303.555146 -317.749936) (xy 304.843954 -317.749936) (xy 304.847914 -317.700882) (xy 304.859691 -317.653098)
			(xy 304.878982 -317.607822) (xy 304.905285 -317.566226) (xy 304.93792 -317.529389) (xy 304.976041 -317.498264)
			(xy 305.018662 -317.473657) (xy 305.064678 -317.456205) (xy 305.112897 -317.446361) (xy 305.162072 -317.44438)
			(xy 305.210927 -317.450312) (xy 305.258198 -317.464004) (xy 305.30266 -317.485102) (xy 305.343163 -317.513058)
			(xy 305.378656 -317.54715) (xy 305.408221 -317.586494) (xy 305.431092 -317.630071) (xy 305.446676 -317.676752)
			(xy 305.454571 -317.725329) (xy 305.455066 -317.749936) (xy 306.744128 -317.749936) (xy 306.748088 -317.700882)
			(xy 306.759865 -317.653098) (xy 306.779156 -317.607822) (xy 306.805459 -317.566226) (xy 306.838094 -317.529389)
			(xy 306.876215 -317.498264) (xy 306.918836 -317.473657) (xy 306.964852 -317.456205) (xy 307.013071 -317.446361)
			(xy 307.062246 -317.44438) (xy 307.111101 -317.450312) (xy 307.158372 -317.464004) (xy 307.202834 -317.485102)
			(xy 307.243337 -317.513058) (xy 307.27883 -317.54715) (xy 307.308395 -317.586494) (xy 307.331266 -317.630071)
			(xy 307.34685 -317.676752) (xy 307.354745 -317.725329) (xy 307.35524 -317.749936) (xy 308.644048 -317.749936)
			(xy 308.648008 -317.700882) (xy 308.659785 -317.653098) (xy 308.679076 -317.607822) (xy 308.705379 -317.566226)
			(xy 308.738014 -317.529389) (xy 308.776135 -317.498264) (xy 308.818756 -317.473657) (xy 308.864772 -317.456205)
			(xy 308.912991 -317.446361) (xy 308.962166 -317.44438) (xy 309.011021 -317.450312) (xy 309.058292 -317.464004)
			(xy 309.102754 -317.485102) (xy 309.143257 -317.513058) (xy 309.17875 -317.54715) (xy 309.208315 -317.586494)
			(xy 309.231186 -317.630071) (xy 309.24677 -317.676752) (xy 309.254665 -317.725329) (xy 309.25516 -317.749936)
			(xy 310.543968 -317.749936) (xy 310.547928 -317.700882) (xy 310.559705 -317.653098) (xy 310.578996 -317.607822)
			(xy 310.605299 -317.566226) (xy 310.637934 -317.529389) (xy 310.676055 -317.498264) (xy 310.718676 -317.473657)
			(xy 310.764692 -317.456205) (xy 310.812911 -317.446361) (xy 310.862086 -317.44438) (xy 310.910941 -317.450312)
			(xy 310.958212 -317.464004) (xy 311.002674 -317.485102) (xy 311.043177 -317.513058) (xy 311.07867 -317.54715)
			(xy 311.108235 -317.586494) (xy 311.131106 -317.630071) (xy 311.14669 -317.676752) (xy 311.154585 -317.725329)
			(xy 311.15508 -317.749936) (xy 312.443888 -317.749936) (xy 312.447848 -317.700882) (xy 312.459625 -317.653098)
			(xy 312.478916 -317.607822) (xy 312.505219 -317.566226) (xy 312.537854 -317.529389) (xy 312.575975 -317.498264)
			(xy 312.618596 -317.473657) (xy 312.664612 -317.456205) (xy 312.712831 -317.446361) (xy 312.762006 -317.44438)
			(xy 312.810861 -317.450312) (xy 312.858132 -317.464004) (xy 312.902594 -317.485102) (xy 312.943097 -317.513058)
			(xy 312.97859 -317.54715) (xy 313.008155 -317.586494) (xy 313.031026 -317.630071) (xy 313.04661 -317.676752)
			(xy 313.054505 -317.725329) (xy 313.055 -317.749936) (xy 386.744222 -317.749936) (xy 386.748182 -317.700882)
			(xy 386.759959 -317.653098) (xy 386.77925 -317.607822) (xy 386.805553 -317.566226) (xy 386.838188 -317.529389)
			(xy 386.876309 -317.498264) (xy 386.91893 -317.473657) (xy 386.964946 -317.456205) (xy 387.013165 -317.446361)
			(xy 387.06234 -317.44438) (xy 387.111195 -317.450312) (xy 387.158466 -317.464004) (xy 387.202928 -317.485102)
			(xy 387.243431 -317.513058) (xy 387.278924 -317.54715) (xy 387.308489 -317.586494) (xy 387.33136 -317.630071)
			(xy 387.346944 -317.676752) (xy 387.354839 -317.725329) (xy 387.355334 -317.749936) (xy 388.644142 -317.749936)
			(xy 388.648102 -317.700882) (xy 388.659879 -317.653098) (xy 388.67917 -317.607822) (xy 388.705473 -317.566226)
			(xy 388.738108 -317.529389) (xy 388.776229 -317.498264) (xy 388.81885 -317.473657) (xy 388.864866 -317.456205)
			(xy 388.913085 -317.446361) (xy 388.96226 -317.44438) (xy 389.011115 -317.450312) (xy 389.058386 -317.464004)
			(xy 389.102848 -317.485102) (xy 389.143351 -317.513058) (xy 389.178844 -317.54715) (xy 389.208409 -317.586494)
			(xy 389.23128 -317.630071) (xy 389.246864 -317.676752) (xy 389.254759 -317.725329) (xy 389.255254 -317.749936)
			(xy 390.544062 -317.749936) (xy 390.548022 -317.700882) (xy 390.559799 -317.653098) (xy 390.57909 -317.607822)
			(xy 390.605393 -317.566226) (xy 390.638028 -317.529389) (xy 390.676149 -317.498264) (xy 390.71877 -317.473657)
			(xy 390.764786 -317.456205) (xy 390.813005 -317.446361) (xy 390.86218 -317.44438) (xy 390.911035 -317.450312)
			(xy 390.958306 -317.464004) (xy 391.002768 -317.485102) (xy 391.043271 -317.513058) (xy 391.078764 -317.54715)
			(xy 391.108329 -317.586494) (xy 391.1312 -317.630071) (xy 391.146784 -317.676752) (xy 391.154679 -317.725329)
			(xy 391.155174 -317.749936) (xy 392.443982 -317.749936) (xy 392.447942 -317.700882) (xy 392.459719 -317.653098)
			(xy 392.47901 -317.607822) (xy 392.505313 -317.566226) (xy 392.537948 -317.529389) (xy 392.576069 -317.498264)
			(xy 392.61869 -317.473657) (xy 392.664706 -317.456205) (xy 392.712925 -317.446361) (xy 392.7621 -317.44438)
			(xy 392.810955 -317.450312) (xy 392.858226 -317.464004) (xy 392.902688 -317.485102) (xy 392.943191 -317.513058)
			(xy 392.978684 -317.54715) (xy 393.008249 -317.586494) (xy 393.03112 -317.630071) (xy 393.046704 -317.676752)
			(xy 393.054599 -317.725329) (xy 393.055094 -317.749936) (xy 394.344156 -317.749936) (xy 394.348116 -317.700882)
			(xy 394.359893 -317.653098) (xy 394.379184 -317.607822) (xy 394.405487 -317.566226) (xy 394.438122 -317.529389)
			(xy 394.476243 -317.498264) (xy 394.518864 -317.473657) (xy 394.56488 -317.456205) (xy 394.613099 -317.446361)
			(xy 394.662274 -317.44438) (xy 394.711129 -317.450312) (xy 394.7584 -317.464004) (xy 394.802862 -317.485102)
			(xy 394.843365 -317.513058) (xy 394.878858 -317.54715) (xy 394.908423 -317.586494) (xy 394.931294 -317.630071)
			(xy 394.946878 -317.676752) (xy 394.954773 -317.725329) (xy 394.955268 -317.749936) (xy 396.244076 -317.749936)
			(xy 396.248036 -317.700882) (xy 396.259813 -317.653098) (xy 396.279104 -317.607822) (xy 396.305407 -317.566226)
			(xy 396.338042 -317.529389) (xy 396.376163 -317.498264) (xy 396.418784 -317.473657) (xy 396.4648 -317.456205)
			(xy 396.513019 -317.446361) (xy 396.562194 -317.44438) (xy 396.611049 -317.450312) (xy 396.65832 -317.464004)
			(xy 396.702782 -317.485102) (xy 396.743285 -317.513058) (xy 396.778778 -317.54715) (xy 396.808343 -317.586494)
			(xy 396.831214 -317.630071) (xy 396.846798 -317.676752) (xy 396.854693 -317.725329) (xy 396.855188 -317.749936)
			(xy 398.143996 -317.749936) (xy 398.147956 -317.700882) (xy 398.159733 -317.653098) (xy 398.179024 -317.607822)
			(xy 398.205327 -317.566226) (xy 398.237962 -317.529389) (xy 398.276083 -317.498264) (xy 398.318704 -317.473657)
			(xy 398.36472 -317.456205) (xy 398.412939 -317.446361) (xy 398.462114 -317.44438) (xy 398.510969 -317.450312)
			(xy 398.55824 -317.464004) (xy 398.602702 -317.485102) (xy 398.643205 -317.513058) (xy 398.678698 -317.54715)
			(xy 398.708263 -317.586494) (xy 398.731134 -317.630071) (xy 398.746718 -317.676752) (xy 398.754613 -317.725329)
			(xy 398.755108 -317.749936) (xy 400.04417 -317.749936) (xy 400.04813 -317.700882) (xy 400.059907 -317.653098)
			(xy 400.079198 -317.607822) (xy 400.105501 -317.566226) (xy 400.138136 -317.529389) (xy 400.176257 -317.498264)
			(xy 400.218878 -317.473657) (xy 400.264894 -317.456205) (xy 400.313113 -317.446361) (xy 400.362288 -317.44438)
			(xy 400.411143 -317.450312) (xy 400.458414 -317.464004) (xy 400.502876 -317.485102) (xy 400.543379 -317.513058)
			(xy 400.578872 -317.54715) (xy 400.608437 -317.586494) (xy 400.631308 -317.630071) (xy 400.646892 -317.676752)
			(xy 400.654787 -317.725329) (xy 400.655282 -317.749936) (xy 401.94409 -317.749936) (xy 401.94805 -317.700882)
			(xy 401.959827 -317.653098) (xy 401.979118 -317.607822) (xy 402.005421 -317.566226) (xy 402.038056 -317.529389)
			(xy 402.076177 -317.498264) (xy 402.118798 -317.473657) (xy 402.164814 -317.456205) (xy 402.213033 -317.446361)
			(xy 402.262208 -317.44438) (xy 402.311063 -317.450312) (xy 402.358334 -317.464004) (xy 402.402796 -317.485102)
			(xy 402.443299 -317.513058) (xy 402.478792 -317.54715) (xy 402.508357 -317.586494) (xy 402.531228 -317.630071)
			(xy 402.546812 -317.676752) (xy 402.554707 -317.725329) (xy 402.555202 -317.749936) (xy 403.84401 -317.749936)
			(xy 403.84797 -317.700882) (xy 403.859747 -317.653098) (xy 403.879038 -317.607822) (xy 403.905341 -317.566226)
			(xy 403.937976 -317.529389) (xy 403.976097 -317.498264) (xy 404.018718 -317.473657) (xy 404.064734 -317.456205)
			(xy 404.112953 -317.446361) (xy 404.162128 -317.44438) (xy 404.210983 -317.450312) (xy 404.258254 -317.464004)
			(xy 404.302716 -317.485102) (xy 404.343219 -317.513058) (xy 404.378712 -317.54715) (xy 404.408277 -317.586494)
			(xy 404.431148 -317.630071) (xy 404.446732 -317.676752) (xy 404.454627 -317.725329) (xy 404.455122 -317.749936)
			(xy 405.744184 -317.749936) (xy 405.748144 -317.700882) (xy 405.759921 -317.653098) (xy 405.779212 -317.607822)
			(xy 405.805515 -317.566226) (xy 405.83815 -317.529389) (xy 405.876271 -317.498264) (xy 405.918892 -317.473657)
			(xy 405.964908 -317.456205) (xy 406.013127 -317.446361) (xy 406.062302 -317.44438) (xy 406.111157 -317.450312)
			(xy 406.158428 -317.464004) (xy 406.20289 -317.485102) (xy 406.243393 -317.513058) (xy 406.278886 -317.54715)
			(xy 406.308451 -317.586494) (xy 406.331322 -317.630071) (xy 406.346906 -317.676752) (xy 406.354801 -317.725329)
			(xy 406.355296 -317.749936) (xy 407.644104 -317.749936) (xy 407.648064 -317.700882) (xy 407.659841 -317.653098)
			(xy 407.679132 -317.607822) (xy 407.705435 -317.566226) (xy 407.73807 -317.529389) (xy 407.776191 -317.498264)
			(xy 407.818812 -317.473657) (xy 407.864828 -317.456205) (xy 407.913047 -317.446361) (xy 407.962222 -317.44438)
			(xy 408.011077 -317.450312) (xy 408.058348 -317.464004) (xy 408.10281 -317.485102) (xy 408.143313 -317.513058)
			(xy 408.178806 -317.54715) (xy 408.208371 -317.586494) (xy 408.231242 -317.630071) (xy 408.246826 -317.676752)
			(xy 408.254721 -317.725329) (xy 408.255216 -317.749936) (xy 409.544024 -317.749936) (xy 409.547984 -317.700882)
			(xy 409.559761 -317.653098) (xy 409.579052 -317.607822) (xy 409.605355 -317.566226) (xy 409.63799 -317.529389)
			(xy 409.676111 -317.498264) (xy 409.718732 -317.473657) (xy 409.764748 -317.456205) (xy 409.812967 -317.446361)
			(xy 409.862142 -317.44438) (xy 409.910997 -317.450312) (xy 409.958268 -317.464004) (xy 410.00273 -317.485102)
			(xy 410.043233 -317.513058) (xy 410.078726 -317.54715) (xy 410.108291 -317.586494) (xy 410.131162 -317.630071)
			(xy 410.146746 -317.676752) (xy 410.154641 -317.725329) (xy 410.155136 -317.749936) (xy 411.444198 -317.749936)
			(xy 411.448158 -317.700882) (xy 411.459935 -317.653098) (xy 411.479226 -317.607822) (xy 411.505529 -317.566226)
			(xy 411.538164 -317.529389) (xy 411.576285 -317.498264) (xy 411.618906 -317.473657) (xy 411.664922 -317.456205)
			(xy 411.713141 -317.446361) (xy 411.762316 -317.44438) (xy 411.811171 -317.450312) (xy 411.858442 -317.464004)
			(xy 411.902904 -317.485102) (xy 411.943407 -317.513058) (xy 411.9789 -317.54715) (xy 412.008465 -317.586494)
			(xy 412.031336 -317.630071) (xy 412.04692 -317.676752) (xy 412.054815 -317.725329) (xy 412.05531 -317.749936)
			(xy 413.344118 -317.749936) (xy 413.348078 -317.700882) (xy 413.359855 -317.653098) (xy 413.379146 -317.607822)
			(xy 413.405449 -317.566226) (xy 413.438084 -317.529389) (xy 413.476205 -317.498264) (xy 413.518826 -317.473657)
			(xy 413.564842 -317.456205) (xy 413.613061 -317.446361) (xy 413.662236 -317.44438) (xy 413.711091 -317.450312)
			(xy 413.758362 -317.464004) (xy 413.802824 -317.485102) (xy 413.843327 -317.513058) (xy 413.87882 -317.54715)
			(xy 413.908385 -317.586494) (xy 413.931256 -317.630071) (xy 413.94684 -317.676752) (xy 413.954735 -317.725329)
			(xy 413.95523 -317.749936) (xy 415.244038 -317.749936) (xy 415.247998 -317.700882) (xy 415.259775 -317.653098)
			(xy 415.279066 -317.607822) (xy 415.305369 -317.566226) (xy 415.338004 -317.529389) (xy 415.376125 -317.498264)
			(xy 415.418746 -317.473657) (xy 415.464762 -317.456205) (xy 415.512981 -317.446361) (xy 415.562156 -317.44438)
			(xy 415.611011 -317.450312) (xy 415.658282 -317.464004) (xy 415.702744 -317.485102) (xy 415.743247 -317.513058)
			(xy 415.77874 -317.54715) (xy 415.808305 -317.586494) (xy 415.831176 -317.630071) (xy 415.84676 -317.676752)
			(xy 415.854655 -317.725329) (xy 415.85515 -317.749936) (xy 417.144212 -317.749936) (xy 417.148172 -317.700882)
			(xy 417.159949 -317.653098) (xy 417.17924 -317.607822) (xy 417.205543 -317.566226) (xy 417.238178 -317.529389)
			(xy 417.276299 -317.498264) (xy 417.31892 -317.473657) (xy 417.364936 -317.456205) (xy 417.413155 -317.446361)
			(xy 417.46233 -317.44438) (xy 417.511185 -317.450312) (xy 417.558456 -317.464004) (xy 417.602918 -317.485102)
			(xy 417.643421 -317.513058) (xy 417.678914 -317.54715) (xy 417.708479 -317.586494) (xy 417.73135 -317.630071)
			(xy 417.746934 -317.676752) (xy 417.754829 -317.725329) (xy 417.755324 -317.749936) (xy 419.044132 -317.749936)
			(xy 419.048092 -317.700882) (xy 419.059869 -317.653098) (xy 419.07916 -317.607822) (xy 419.105463 -317.566226)
			(xy 419.138098 -317.529389) (xy 419.176219 -317.498264) (xy 419.21884 -317.473657) (xy 419.264856 -317.456205)
			(xy 419.313075 -317.446361) (xy 419.36225 -317.44438) (xy 419.411105 -317.450312) (xy 419.458376 -317.464004)
			(xy 419.502838 -317.485102) (xy 419.543341 -317.513058) (xy 419.578834 -317.54715) (xy 419.608399 -317.586494)
			(xy 419.63127 -317.630071) (xy 419.646854 -317.676752) (xy 419.654749 -317.725329) (xy 419.655244 -317.749936)
			(xy 420.944052 -317.749936) (xy 420.948012 -317.700882) (xy 420.959789 -317.653098) (xy 420.97908 -317.607822)
			(xy 421.005383 -317.566226) (xy 421.038018 -317.529389) (xy 421.076139 -317.498264) (xy 421.11876 -317.473657)
			(xy 421.164776 -317.456205) (xy 421.212995 -317.446361) (xy 421.26217 -317.44438) (xy 421.311025 -317.450312)
			(xy 421.358296 -317.464004) (xy 421.402758 -317.485102) (xy 421.443261 -317.513058) (xy 421.478754 -317.54715)
			(xy 421.508319 -317.586494) (xy 421.53119 -317.630071) (xy 421.546774 -317.676752) (xy 421.554669 -317.725329)
			(xy 421.555164 -317.749936) (xy 422.844226 -317.749936) (xy 422.848186 -317.700882) (xy 422.859963 -317.653098)
			(xy 422.879254 -317.607822) (xy 422.905557 -317.566226) (xy 422.938192 -317.529389) (xy 422.976313 -317.498264)
			(xy 423.018934 -317.473657) (xy 423.06495 -317.456205) (xy 423.113169 -317.446361) (xy 423.162344 -317.44438)
			(xy 423.211199 -317.450312) (xy 423.25847 -317.464004) (xy 423.302932 -317.485102) (xy 423.343435 -317.513058)
			(xy 423.378928 -317.54715) (xy 423.408493 -317.586494) (xy 423.431364 -317.630071) (xy 423.446948 -317.676752)
			(xy 423.454843 -317.725329) (xy 423.455338 -317.749936) (xy 424.744146 -317.749936) (xy 424.748106 -317.700882)
			(xy 424.759883 -317.653098) (xy 424.779174 -317.607822) (xy 424.805477 -317.566226) (xy 424.838112 -317.529389)
			(xy 424.876233 -317.498264) (xy 424.918854 -317.473657) (xy 424.96487 -317.456205) (xy 425.013089 -317.446361)
			(xy 425.062264 -317.44438) (xy 425.111119 -317.450312) (xy 425.15839 -317.464004) (xy 425.202852 -317.485102)
			(xy 425.243355 -317.513058) (xy 425.278848 -317.54715) (xy 425.308413 -317.586494) (xy 425.331284 -317.630071)
			(xy 425.346868 -317.676752) (xy 425.354763 -317.725329) (xy 425.355258 -317.749936) (xy 426.644066 -317.749936)
			(xy 426.648026 -317.700882) (xy 426.659803 -317.653098) (xy 426.679094 -317.607822) (xy 426.705397 -317.566226)
			(xy 426.738032 -317.529389) (xy 426.776153 -317.498264) (xy 426.818774 -317.473657) (xy 426.86479 -317.456205)
			(xy 426.913009 -317.446361) (xy 426.962184 -317.44438) (xy 427.011039 -317.450312) (xy 427.05831 -317.464004)
			(xy 427.102772 -317.485102) (xy 427.143275 -317.513058) (xy 427.178768 -317.54715) (xy 427.208333 -317.586494)
			(xy 427.231204 -317.630071) (xy 427.246788 -317.676752) (xy 427.254683 -317.725329) (xy 427.255178 -317.749936)
			(xy 428.543986 -317.749936) (xy 428.547946 -317.700882) (xy 428.559723 -317.653098) (xy 428.579014 -317.607822)
			(xy 428.605317 -317.566226) (xy 428.637952 -317.529389) (xy 428.676073 -317.498264) (xy 428.718694 -317.473657)
			(xy 428.76471 -317.456205) (xy 428.812929 -317.446361) (xy 428.862104 -317.44438) (xy 428.910959 -317.450312)
			(xy 428.95823 -317.464004) (xy 429.002692 -317.485102) (xy 429.043195 -317.513058) (xy 429.078688 -317.54715)
			(xy 429.108253 -317.586494) (xy 429.131124 -317.630071) (xy 429.146708 -317.676752) (xy 429.154603 -317.725329)
			(xy 429.155098 -317.749936) (xy 429.154603 -317.774543) (xy 429.146708 -317.82312) (xy 429.131124 -317.869801)
			(xy 429.108253 -317.913378) (xy 429.078688 -317.952722) (xy 429.043195 -317.986814) (xy 429.002692 -318.01477)
			(xy 428.95823 -318.035868) (xy 428.910959 -318.04956) (xy 428.862104 -318.055492) (xy 428.812929 -318.053511)
			(xy 428.76471 -318.043667) (xy 428.718694 -318.026215) (xy 428.676073 -318.001608) (xy 428.637952 -317.970483)
			(xy 428.605317 -317.933646) (xy 428.579014 -317.89205) (xy 428.559723 -317.846774) (xy 428.547946 -317.79899)
			(xy 428.543986 -317.749936) (xy 427.255178 -317.749936) (xy 427.254683 -317.774543) (xy 427.246788 -317.82312)
			(xy 427.231204 -317.869801) (xy 427.208333 -317.913378) (xy 427.178768 -317.952722) (xy 427.143275 -317.986814)
			(xy 427.102772 -318.01477) (xy 427.05831 -318.035868) (xy 427.011039 -318.04956) (xy 426.962184 -318.055492)
			(xy 426.913009 -318.053511) (xy 426.86479 -318.043667) (xy 426.818774 -318.026215) (xy 426.776153 -318.001608)
			(xy 426.738032 -317.970483) (xy 426.705397 -317.933646) (xy 426.679094 -317.89205) (xy 426.659803 -317.846774)
			(xy 426.648026 -317.79899) (xy 426.644066 -317.749936) (xy 425.355258 -317.749936) (xy 425.354763 -317.774543)
			(xy 425.346868 -317.82312) (xy 425.331284 -317.869801) (xy 425.308413 -317.913378) (xy 425.278848 -317.952722)
			(xy 425.243355 -317.986814) (xy 425.202852 -318.01477) (xy 425.15839 -318.035868) (xy 425.111119 -318.04956)
			(xy 425.062264 -318.055492) (xy 425.013089 -318.053511) (xy 424.96487 -318.043667) (xy 424.918854 -318.026215)
			(xy 424.876233 -318.001608) (xy 424.838112 -317.970483) (xy 424.805477 -317.933646) (xy 424.779174 -317.89205)
			(xy 424.759883 -317.846774) (xy 424.748106 -317.79899) (xy 424.744146 -317.749936) (xy 423.455338 -317.749936)
			(xy 423.454843 -317.774543) (xy 423.446948 -317.82312) (xy 423.431364 -317.869801) (xy 423.408493 -317.913378)
			(xy 423.378928 -317.952722) (xy 423.343435 -317.986814) (xy 423.302932 -318.01477) (xy 423.25847 -318.035868)
			(xy 423.211199 -318.04956) (xy 423.162344 -318.055492) (xy 423.113169 -318.053511) (xy 423.06495 -318.043667)
			(xy 423.018934 -318.026215) (xy 422.976313 -318.001608) (xy 422.938192 -317.970483) (xy 422.905557 -317.933646)
			(xy 422.879254 -317.89205) (xy 422.859963 -317.846774) (xy 422.848186 -317.79899) (xy 422.844226 -317.749936)
			(xy 421.555164 -317.749936) (xy 421.554669 -317.774543) (xy 421.546774 -317.82312) (xy 421.53119 -317.869801)
			(xy 421.508319 -317.913378) (xy 421.478754 -317.952722) (xy 421.443261 -317.986814) (xy 421.402758 -318.01477)
			(xy 421.358296 -318.035868) (xy 421.311025 -318.04956) (xy 421.26217 -318.055492) (xy 421.212995 -318.053511)
			(xy 421.164776 -318.043667) (xy 421.11876 -318.026215) (xy 421.076139 -318.001608) (xy 421.038018 -317.970483)
			(xy 421.005383 -317.933646) (xy 420.97908 -317.89205) (xy 420.959789 -317.846774) (xy 420.948012 -317.79899)
			(xy 420.944052 -317.749936) (xy 419.655244 -317.749936) (xy 419.654749 -317.774543) (xy 419.646854 -317.82312)
			(xy 419.63127 -317.869801) (xy 419.608399 -317.913378) (xy 419.578834 -317.952722) (xy 419.543341 -317.986814)
			(xy 419.502838 -318.01477) (xy 419.458376 -318.035868) (xy 419.411105 -318.04956) (xy 419.36225 -318.055492)
			(xy 419.313075 -318.053511) (xy 419.264856 -318.043667) (xy 419.21884 -318.026215) (xy 419.176219 -318.001608)
			(xy 419.138098 -317.970483) (xy 419.105463 -317.933646) (xy 419.07916 -317.89205) (xy 419.059869 -317.846774)
			(xy 419.048092 -317.79899) (xy 419.044132 -317.749936) (xy 417.755324 -317.749936) (xy 417.754829 -317.774543)
			(xy 417.746934 -317.82312) (xy 417.73135 -317.869801) (xy 417.708479 -317.913378) (xy 417.678914 -317.952722)
			(xy 417.643421 -317.986814) (xy 417.602918 -318.01477) (xy 417.558456 -318.035868) (xy 417.511185 -318.04956)
			(xy 417.46233 -318.055492) (xy 417.413155 -318.053511) (xy 417.364936 -318.043667) (xy 417.31892 -318.026215)
			(xy 417.276299 -318.001608) (xy 417.238178 -317.970483) (xy 417.205543 -317.933646) (xy 417.17924 -317.89205)
			(xy 417.159949 -317.846774) (xy 417.148172 -317.79899) (xy 417.144212 -317.749936) (xy 415.85515 -317.749936)
			(xy 415.854655 -317.774543) (xy 415.84676 -317.82312) (xy 415.831176 -317.869801) (xy 415.808305 -317.913378)
			(xy 415.77874 -317.952722) (xy 415.743247 -317.986814) (xy 415.702744 -318.01477) (xy 415.658282 -318.035868)
			(xy 415.611011 -318.04956) (xy 415.562156 -318.055492) (xy 415.512981 -318.053511) (xy 415.464762 -318.043667)
			(xy 415.418746 -318.026215) (xy 415.376125 -318.001608) (xy 415.338004 -317.970483) (xy 415.305369 -317.933646)
			(xy 415.279066 -317.89205) (xy 415.259775 -317.846774) (xy 415.247998 -317.79899) (xy 415.244038 -317.749936)
			(xy 413.95523 -317.749936) (xy 413.954735 -317.774543) (xy 413.94684 -317.82312) (xy 413.931256 -317.869801)
			(xy 413.908385 -317.913378) (xy 413.87882 -317.952722) (xy 413.843327 -317.986814) (xy 413.802824 -318.01477)
			(xy 413.758362 -318.035868) (xy 413.711091 -318.04956) (xy 413.662236 -318.055492) (xy 413.613061 -318.053511)
			(xy 413.564842 -318.043667) (xy 413.518826 -318.026215) (xy 413.476205 -318.001608) (xy 413.438084 -317.970483)
			(xy 413.405449 -317.933646) (xy 413.379146 -317.89205) (xy 413.359855 -317.846774) (xy 413.348078 -317.79899)
			(xy 413.344118 -317.749936) (xy 412.05531 -317.749936) (xy 412.054815 -317.774543) (xy 412.04692 -317.82312)
			(xy 412.031336 -317.869801) (xy 412.008465 -317.913378) (xy 411.9789 -317.952722) (xy 411.943407 -317.986814)
			(xy 411.902904 -318.01477) (xy 411.858442 -318.035868) (xy 411.811171 -318.04956) (xy 411.762316 -318.055492)
			(xy 411.713141 -318.053511) (xy 411.664922 -318.043667) (xy 411.618906 -318.026215) (xy 411.576285 -318.001608)
			(xy 411.538164 -317.970483) (xy 411.505529 -317.933646) (xy 411.479226 -317.89205) (xy 411.459935 -317.846774)
			(xy 411.448158 -317.79899) (xy 411.444198 -317.749936) (xy 410.155136 -317.749936) (xy 410.154641 -317.774543)
			(xy 410.146746 -317.82312) (xy 410.131162 -317.869801) (xy 410.108291 -317.913378) (xy 410.078726 -317.952722)
			(xy 410.043233 -317.986814) (xy 410.00273 -318.01477) (xy 409.958268 -318.035868) (xy 409.910997 -318.04956)
			(xy 409.862142 -318.055492) (xy 409.812967 -318.053511) (xy 409.764748 -318.043667) (xy 409.718732 -318.026215)
			(xy 409.676111 -318.001608) (xy 409.63799 -317.970483) (xy 409.605355 -317.933646) (xy 409.579052 -317.89205)
			(xy 409.559761 -317.846774) (xy 409.547984 -317.79899) (xy 409.544024 -317.749936) (xy 408.255216 -317.749936)
			(xy 408.254721 -317.774543) (xy 408.246826 -317.82312) (xy 408.231242 -317.869801) (xy 408.208371 -317.913378)
			(xy 408.178806 -317.952722) (xy 408.143313 -317.986814) (xy 408.10281 -318.01477) (xy 408.058348 -318.035868)
			(xy 408.011077 -318.04956) (xy 407.962222 -318.055492) (xy 407.913047 -318.053511) (xy 407.864828 -318.043667)
			(xy 407.818812 -318.026215) (xy 407.776191 -318.001608) (xy 407.73807 -317.970483) (xy 407.705435 -317.933646)
			(xy 407.679132 -317.89205) (xy 407.659841 -317.846774) (xy 407.648064 -317.79899) (xy 407.644104 -317.749936)
			(xy 406.355296 -317.749936) (xy 406.354801 -317.774543) (xy 406.346906 -317.82312) (xy 406.331322 -317.869801)
			(xy 406.308451 -317.913378) (xy 406.278886 -317.952722) (xy 406.243393 -317.986814) (xy 406.20289 -318.01477)
			(xy 406.158428 -318.035868) (xy 406.111157 -318.04956) (xy 406.062302 -318.055492) (xy 406.013127 -318.053511)
			(xy 405.964908 -318.043667) (xy 405.918892 -318.026215) (xy 405.876271 -318.001608) (xy 405.83815 -317.970483)
			(xy 405.805515 -317.933646) (xy 405.779212 -317.89205) (xy 405.759921 -317.846774) (xy 405.748144 -317.79899)
			(xy 405.744184 -317.749936) (xy 404.455122 -317.749936) (xy 404.454627 -317.774543) (xy 404.446732 -317.82312)
			(xy 404.431148 -317.869801) (xy 404.408277 -317.913378) (xy 404.378712 -317.952722) (xy 404.343219 -317.986814)
			(xy 404.302716 -318.01477) (xy 404.258254 -318.035868) (xy 404.210983 -318.04956) (xy 404.162128 -318.055492)
			(xy 404.112953 -318.053511) (xy 404.064734 -318.043667) (xy 404.018718 -318.026215) (xy 403.976097 -318.001608)
			(xy 403.937976 -317.970483) (xy 403.905341 -317.933646) (xy 403.879038 -317.89205) (xy 403.859747 -317.846774)
			(xy 403.84797 -317.79899) (xy 403.84401 -317.749936) (xy 402.555202 -317.749936) (xy 402.554707 -317.774543)
			(xy 402.546812 -317.82312) (xy 402.531228 -317.869801) (xy 402.508357 -317.913378) (xy 402.478792 -317.952722)
			(xy 402.443299 -317.986814) (xy 402.402796 -318.01477) (xy 402.358334 -318.035868) (xy 402.311063 -318.04956)
			(xy 402.262208 -318.055492) (xy 402.213033 -318.053511) (xy 402.164814 -318.043667) (xy 402.118798 -318.026215)
			(xy 402.076177 -318.001608) (xy 402.038056 -317.970483) (xy 402.005421 -317.933646) (xy 401.979118 -317.89205)
			(xy 401.959827 -317.846774) (xy 401.94805 -317.79899) (xy 401.94409 -317.749936) (xy 400.655282 -317.749936)
			(xy 400.654787 -317.774543) (xy 400.646892 -317.82312) (xy 400.631308 -317.869801) (xy 400.608437 -317.913378)
			(xy 400.578872 -317.952722) (xy 400.543379 -317.986814) (xy 400.502876 -318.01477) (xy 400.458414 -318.035868)
			(xy 400.411143 -318.04956) (xy 400.362288 -318.055492) (xy 400.313113 -318.053511) (xy 400.264894 -318.043667)
			(xy 400.218878 -318.026215) (xy 400.176257 -318.001608) (xy 400.138136 -317.970483) (xy 400.105501 -317.933646)
			(xy 400.079198 -317.89205) (xy 400.059907 -317.846774) (xy 400.04813 -317.79899) (xy 400.04417 -317.749936)
			(xy 398.755108 -317.749936) (xy 398.754613 -317.774543) (xy 398.746718 -317.82312) (xy 398.731134 -317.869801)
			(xy 398.708263 -317.913378) (xy 398.678698 -317.952722) (xy 398.643205 -317.986814) (xy 398.602702 -318.01477)
			(xy 398.55824 -318.035868) (xy 398.510969 -318.04956) (xy 398.462114 -318.055492) (xy 398.412939 -318.053511)
			(xy 398.36472 -318.043667) (xy 398.318704 -318.026215) (xy 398.276083 -318.001608) (xy 398.237962 -317.970483)
			(xy 398.205327 -317.933646) (xy 398.179024 -317.89205) (xy 398.159733 -317.846774) (xy 398.147956 -317.79899)
			(xy 398.143996 -317.749936) (xy 396.855188 -317.749936) (xy 396.854693 -317.774543) (xy 396.846798 -317.82312)
			(xy 396.831214 -317.869801) (xy 396.808343 -317.913378) (xy 396.778778 -317.952722) (xy 396.743285 -317.986814)
			(xy 396.702782 -318.01477) (xy 396.65832 -318.035868) (xy 396.611049 -318.04956) (xy 396.562194 -318.055492)
			(xy 396.513019 -318.053511) (xy 396.4648 -318.043667) (xy 396.418784 -318.026215) (xy 396.376163 -318.001608)
			(xy 396.338042 -317.970483) (xy 396.305407 -317.933646) (xy 396.279104 -317.89205) (xy 396.259813 -317.846774)
			(xy 396.248036 -317.79899) (xy 396.244076 -317.749936) (xy 394.955268 -317.749936) (xy 394.954773 -317.774543)
			(xy 394.946878 -317.82312) (xy 394.931294 -317.869801) (xy 394.908423 -317.913378) (xy 394.878858 -317.952722)
			(xy 394.843365 -317.986814) (xy 394.802862 -318.01477) (xy 394.7584 -318.035868) (xy 394.711129 -318.04956)
			(xy 394.662274 -318.055492) (xy 394.613099 -318.053511) (xy 394.56488 -318.043667) (xy 394.518864 -318.026215)
			(xy 394.476243 -318.001608) (xy 394.438122 -317.970483) (xy 394.405487 -317.933646) (xy 394.379184 -317.89205)
			(xy 394.359893 -317.846774) (xy 394.348116 -317.79899) (xy 394.344156 -317.749936) (xy 393.055094 -317.749936)
			(xy 393.054599 -317.774543) (xy 393.046704 -317.82312) (xy 393.03112 -317.869801) (xy 393.008249 -317.913378)
			(xy 392.978684 -317.952722) (xy 392.943191 -317.986814) (xy 392.902688 -318.01477) (xy 392.858226 -318.035868)
			(xy 392.810955 -318.04956) (xy 392.7621 -318.055492) (xy 392.712925 -318.053511) (xy 392.664706 -318.043667)
			(xy 392.61869 -318.026215) (xy 392.576069 -318.001608) (xy 392.537948 -317.970483) (xy 392.505313 -317.933646)
			(xy 392.47901 -317.89205) (xy 392.459719 -317.846774) (xy 392.447942 -317.79899) (xy 392.443982 -317.749936)
			(xy 391.155174 -317.749936) (xy 391.154679 -317.774543) (xy 391.146784 -317.82312) (xy 391.1312 -317.869801)
			(xy 391.108329 -317.913378) (xy 391.078764 -317.952722) (xy 391.043271 -317.986814) (xy 391.002768 -318.01477)
			(xy 390.958306 -318.035868) (xy 390.911035 -318.04956) (xy 390.86218 -318.055492) (xy 390.813005 -318.053511)
			(xy 390.764786 -318.043667) (xy 390.71877 -318.026215) (xy 390.676149 -318.001608) (xy 390.638028 -317.970483)
			(xy 390.605393 -317.933646) (xy 390.57909 -317.89205) (xy 390.559799 -317.846774) (xy 390.548022 -317.79899)
			(xy 390.544062 -317.749936) (xy 389.255254 -317.749936) (xy 389.254759 -317.774543) (xy 389.246864 -317.82312)
			(xy 389.23128 -317.869801) (xy 389.208409 -317.913378) (xy 389.178844 -317.952722) (xy 389.143351 -317.986814)
			(xy 389.102848 -318.01477) (xy 389.058386 -318.035868) (xy 389.011115 -318.04956) (xy 388.96226 -318.055492)
			(xy 388.913085 -318.053511) (xy 388.864866 -318.043667) (xy 388.81885 -318.026215) (xy 388.776229 -318.001608)
			(xy 388.738108 -317.970483) (xy 388.705473 -317.933646) (xy 388.67917 -317.89205) (xy 388.659879 -317.846774)
			(xy 388.648102 -317.79899) (xy 388.644142 -317.749936) (xy 387.355334 -317.749936) (xy 387.354839 -317.774543)
			(xy 387.346944 -317.82312) (xy 387.33136 -317.869801) (xy 387.308489 -317.913378) (xy 387.278924 -317.952722)
			(xy 387.243431 -317.986814) (xy 387.202928 -318.01477) (xy 387.158466 -318.035868) (xy 387.111195 -318.04956)
			(xy 387.06234 -318.055492) (xy 387.013165 -318.053511) (xy 386.964946 -318.043667) (xy 386.91893 -318.026215)
			(xy 386.876309 -318.001608) (xy 386.838188 -317.970483) (xy 386.805553 -317.933646) (xy 386.77925 -317.89205)
			(xy 386.759959 -317.846774) (xy 386.748182 -317.79899) (xy 386.744222 -317.749936) (xy 313.055 -317.749936)
			(xy 313.054505 -317.774543) (xy 313.04661 -317.82312) (xy 313.031026 -317.869801) (xy 313.008155 -317.913378)
			(xy 312.97859 -317.952722) (xy 312.943097 -317.986814) (xy 312.902594 -318.01477) (xy 312.858132 -318.035868)
			(xy 312.810861 -318.04956) (xy 312.762006 -318.055492) (xy 312.712831 -318.053511) (xy 312.664612 -318.043667)
			(xy 312.618596 -318.026215) (xy 312.575975 -318.001608) (xy 312.537854 -317.970483) (xy 312.505219 -317.933646)
			(xy 312.478916 -317.89205) (xy 312.459625 -317.846774) (xy 312.447848 -317.79899) (xy 312.443888 -317.749936)
			(xy 311.15508 -317.749936) (xy 311.154585 -317.774543) (xy 311.14669 -317.82312) (xy 311.131106 -317.869801)
			(xy 311.108235 -317.913378) (xy 311.07867 -317.952722) (xy 311.043177 -317.986814) (xy 311.002674 -318.01477)
			(xy 310.958212 -318.035868) (xy 310.910941 -318.04956) (xy 310.862086 -318.055492) (xy 310.812911 -318.053511)
			(xy 310.764692 -318.043667) (xy 310.718676 -318.026215) (xy 310.676055 -318.001608) (xy 310.637934 -317.970483)
			(xy 310.605299 -317.933646) (xy 310.578996 -317.89205) (xy 310.559705 -317.846774) (xy 310.547928 -317.79899)
			(xy 310.543968 -317.749936) (xy 309.25516 -317.749936) (xy 309.254665 -317.774543) (xy 309.24677 -317.82312)
			(xy 309.231186 -317.869801) (xy 309.208315 -317.913378) (xy 309.17875 -317.952722) (xy 309.143257 -317.986814)
			(xy 309.102754 -318.01477) (xy 309.058292 -318.035868) (xy 309.011021 -318.04956) (xy 308.962166 -318.055492)
			(xy 308.912991 -318.053511) (xy 308.864772 -318.043667) (xy 308.818756 -318.026215) (xy 308.776135 -318.001608)
			(xy 308.738014 -317.970483) (xy 308.705379 -317.933646) (xy 308.679076 -317.89205) (xy 308.659785 -317.846774)
			(xy 308.648008 -317.79899) (xy 308.644048 -317.749936) (xy 307.35524 -317.749936) (xy 307.354745 -317.774543)
			(xy 307.34685 -317.82312) (xy 307.331266 -317.869801) (xy 307.308395 -317.913378) (xy 307.27883 -317.952722)
			(xy 307.243337 -317.986814) (xy 307.202834 -318.01477) (xy 307.158372 -318.035868) (xy 307.111101 -318.04956)
			(xy 307.062246 -318.055492) (xy 307.013071 -318.053511) (xy 306.964852 -318.043667) (xy 306.918836 -318.026215)
			(xy 306.876215 -318.001608) (xy 306.838094 -317.970483) (xy 306.805459 -317.933646) (xy 306.779156 -317.89205)
			(xy 306.759865 -317.846774) (xy 306.748088 -317.79899) (xy 306.744128 -317.749936) (xy 305.455066 -317.749936)
			(xy 305.454571 -317.774543) (xy 305.446676 -317.82312) (xy 305.431092 -317.869801) (xy 305.408221 -317.913378)
			(xy 305.378656 -317.952722) (xy 305.343163 -317.986814) (xy 305.30266 -318.01477) (xy 305.258198 -318.035868)
			(xy 305.210927 -318.04956) (xy 305.162072 -318.055492) (xy 305.112897 -318.053511) (xy 305.064678 -318.043667)
			(xy 305.018662 -318.026215) (xy 304.976041 -318.001608) (xy 304.93792 -317.970483) (xy 304.905285 -317.933646)
			(xy 304.878982 -317.89205) (xy 304.859691 -317.846774) (xy 304.847914 -317.79899) (xy 304.843954 -317.749936)
			(xy 303.555146 -317.749936) (xy 303.554651 -317.774543) (xy 303.546756 -317.82312) (xy 303.531172 -317.869801)
			(xy 303.508301 -317.913378) (xy 303.478736 -317.952722) (xy 303.443243 -317.986814) (xy 303.40274 -318.01477)
			(xy 303.358278 -318.035868) (xy 303.311007 -318.04956) (xy 303.262152 -318.055492) (xy 303.212977 -318.053511)
			(xy 303.164758 -318.043667) (xy 303.118742 -318.026215) (xy 303.076121 -318.001608) (xy 303.038 -317.970483)
			(xy 303.005365 -317.933646) (xy 302.979062 -317.89205) (xy 302.959771 -317.846774) (xy 302.947994 -317.79899)
			(xy 302.944034 -317.749936) (xy 301.655226 -317.749936) (xy 301.654731 -317.774543) (xy 301.646836 -317.82312)
			(xy 301.631252 -317.869801) (xy 301.608381 -317.913378) (xy 301.578816 -317.952722) (xy 301.543323 -317.986814)
			(xy 301.50282 -318.01477) (xy 301.458358 -318.035868) (xy 301.411087 -318.04956) (xy 301.362232 -318.055492)
			(xy 301.313057 -318.053511) (xy 301.264838 -318.043667) (xy 301.218822 -318.026215) (xy 301.176201 -318.001608)
			(xy 301.13808 -317.970483) (xy 301.105445 -317.933646) (xy 301.079142 -317.89205) (xy 301.059851 -317.846774)
			(xy 301.048074 -317.79899) (xy 301.044114 -317.749936) (xy 299.755052 -317.749936) (xy 299.754557 -317.774543)
			(xy 299.746662 -317.82312) (xy 299.731078 -317.869801) (xy 299.708207 -317.913378) (xy 299.678642 -317.952722)
			(xy 299.643149 -317.986814) (xy 299.602646 -318.01477) (xy 299.558184 -318.035868) (xy 299.510913 -318.04956)
			(xy 299.462058 -318.055492) (xy 299.412883 -318.053511) (xy 299.364664 -318.043667) (xy 299.318648 -318.026215)
			(xy 299.276027 -318.001608) (xy 299.237906 -317.970483) (xy 299.205271 -317.933646) (xy 299.178968 -317.89205)
			(xy 299.159677 -317.846774) (xy 299.1479 -317.79899) (xy 299.14394 -317.749936) (xy 297.855132 -317.749936)
			(xy 297.854637 -317.774543) (xy 297.846742 -317.82312) (xy 297.831158 -317.869801) (xy 297.808287 -317.913378)
			(xy 297.778722 -317.952722) (xy 297.743229 -317.986814) (xy 297.702726 -318.01477) (xy 297.658264 -318.035868)
			(xy 297.610993 -318.04956) (xy 297.562138 -318.055492) (xy 297.512963 -318.053511) (xy 297.464744 -318.043667)
			(xy 297.418728 -318.026215) (xy 297.376107 -318.001608) (xy 297.337986 -317.970483) (xy 297.305351 -317.933646)
			(xy 297.279048 -317.89205) (xy 297.259757 -317.846774) (xy 297.24798 -317.79899) (xy 297.24402 -317.749936)
			(xy 295.955212 -317.749936) (xy 295.954717 -317.774543) (xy 295.946822 -317.82312) (xy 295.931238 -317.869801)
			(xy 295.908367 -317.913378) (xy 295.878802 -317.952722) (xy 295.843309 -317.986814) (xy 295.802806 -318.01477)
			(xy 295.758344 -318.035868) (xy 295.711073 -318.04956) (xy 295.662218 -318.055492) (xy 295.613043 -318.053511)
			(xy 295.564824 -318.043667) (xy 295.518808 -318.026215) (xy 295.476187 -318.001608) (xy 295.438066 -317.970483)
			(xy 295.405431 -317.933646) (xy 295.379128 -317.89205) (xy 295.359837 -317.846774) (xy 295.34806 -317.79899)
			(xy 295.3441 -317.749936) (xy 294.055038 -317.749936) (xy 294.054543 -317.774543) (xy 294.046648 -317.82312)
			(xy 294.031064 -317.869801) (xy 294.008193 -317.913378) (xy 293.978628 -317.952722) (xy 293.943135 -317.986814)
			(xy 293.902632 -318.01477) (xy 293.85817 -318.035868) (xy 293.810899 -318.04956) (xy 293.762044 -318.055492)
			(xy 293.712869 -318.053511) (xy 293.66465 -318.043667) (xy 293.618634 -318.026215) (xy 293.576013 -318.001608)
			(xy 293.537892 -317.970483) (xy 293.505257 -317.933646) (xy 293.478954 -317.89205) (xy 293.459663 -317.846774)
			(xy 293.447886 -317.79899) (xy 293.443926 -317.749936) (xy 292.155118 -317.749936) (xy 292.154623 -317.774543)
			(xy 292.146728 -317.82312) (xy 292.131144 -317.869801) (xy 292.108273 -317.913378) (xy 292.078708 -317.952722)
			(xy 292.043215 -317.986814) (xy 292.002712 -318.01477) (xy 291.95825 -318.035868) (xy 291.910979 -318.04956)
			(xy 291.862124 -318.055492) (xy 291.812949 -318.053511) (xy 291.76473 -318.043667) (xy 291.718714 -318.026215)
			(xy 291.676093 -318.001608) (xy 291.637972 -317.970483) (xy 291.605337 -317.933646) (xy 291.579034 -317.89205)
			(xy 291.559743 -317.846774) (xy 291.547966 -317.79899) (xy 291.544006 -317.749936) (xy 290.255198 -317.749936)
			(xy 290.254703 -317.774543) (xy 290.246808 -317.82312) (xy 290.231224 -317.869801) (xy 290.208353 -317.913378)
			(xy 290.178788 -317.952722) (xy 290.143295 -317.986814) (xy 290.102792 -318.01477) (xy 290.05833 -318.035868)
			(xy 290.011059 -318.04956) (xy 289.962204 -318.055492) (xy 289.913029 -318.053511) (xy 289.86481 -318.043667)
			(xy 289.818794 -318.026215) (xy 289.776173 -318.001608) (xy 289.738052 -317.970483) (xy 289.705417 -317.933646)
			(xy 289.679114 -317.89205) (xy 289.659823 -317.846774) (xy 289.648046 -317.79899) (xy 289.644086 -317.749936)
			(xy 288.355024 -317.749936) (xy 288.354529 -317.774543) (xy 288.346634 -317.82312) (xy 288.33105 -317.869801)
			(xy 288.308179 -317.913378) (xy 288.278614 -317.952722) (xy 288.243121 -317.986814) (xy 288.202618 -318.01477)
			(xy 288.158156 -318.035868) (xy 288.110885 -318.04956) (xy 288.06203 -318.055492) (xy 288.012855 -318.053511)
			(xy 287.964636 -318.043667) (xy 287.91862 -318.026215) (xy 287.875999 -318.001608) (xy 287.837878 -317.970483)
			(xy 287.805243 -317.933646) (xy 287.77894 -317.89205) (xy 287.759649 -317.846774) (xy 287.747872 -317.79899)
			(xy 287.743912 -317.749936) (xy 286.455104 -317.749936) (xy 286.454609 -317.774543) (xy 286.446714 -317.82312)
			(xy 286.43113 -317.869801) (xy 286.408259 -317.913378) (xy 286.378694 -317.952722) (xy 286.343201 -317.986814)
			(xy 286.302698 -318.01477) (xy 286.258236 -318.035868) (xy 286.210965 -318.04956) (xy 286.16211 -318.055492)
			(xy 286.112935 -318.053511) (xy 286.064716 -318.043667) (xy 286.0187 -318.026215) (xy 285.976079 -318.001608)
			(xy 285.937958 -317.970483) (xy 285.905323 -317.933646) (xy 285.87902 -317.89205) (xy 285.859729 -317.846774)
			(xy 285.847952 -317.79899) (xy 285.843992 -317.749936) (xy 284.555184 -317.749936) (xy 284.554689 -317.774543)
			(xy 284.546794 -317.82312) (xy 284.53121 -317.869801) (xy 284.508339 -317.913378) (xy 284.478774 -317.952722)
			(xy 284.443281 -317.986814) (xy 284.402778 -318.01477) (xy 284.358316 -318.035868) (xy 284.311045 -318.04956)
			(xy 284.26219 -318.055492) (xy 284.213015 -318.053511) (xy 284.164796 -318.043667) (xy 284.11878 -318.026215)
			(xy 284.076159 -318.001608) (xy 284.038038 -317.970483) (xy 284.005403 -317.933646) (xy 283.9791 -317.89205)
			(xy 283.959809 -317.846774) (xy 283.948032 -317.79899) (xy 283.944072 -317.749936) (xy 282.65501 -317.749936)
			(xy 282.654515 -317.774543) (xy 282.64662 -317.82312) (xy 282.631036 -317.869801) (xy 282.608165 -317.913378)
			(xy 282.5786 -317.952722) (xy 282.543107 -317.986814) (xy 282.502604 -318.01477) (xy 282.458142 -318.035868)
			(xy 282.410871 -318.04956) (xy 282.362016 -318.055492) (xy 282.312841 -318.053511) (xy 282.264622 -318.043667)
			(xy 282.218606 -318.026215) (xy 282.175985 -318.001608) (xy 282.137864 -317.970483) (xy 282.105229 -317.933646)
			(xy 282.078926 -317.89205) (xy 282.059635 -317.846774) (xy 282.047858 -317.79899) (xy 282.043898 -317.749936)
			(xy 280.75509 -317.749936) (xy 280.754595 -317.774543) (xy 280.7467 -317.82312) (xy 280.731116 -317.869801)
			(xy 280.708245 -317.913378) (xy 280.67868 -317.952722) (xy 280.643187 -317.986814) (xy 280.602684 -318.01477)
			(xy 280.558222 -318.035868) (xy 280.510951 -318.04956) (xy 280.462096 -318.055492) (xy 280.412921 -318.053511)
			(xy 280.364702 -318.043667) (xy 280.318686 -318.026215) (xy 280.276065 -318.001608) (xy 280.237944 -317.970483)
			(xy 280.205309 -317.933646) (xy 280.179006 -317.89205) (xy 280.159715 -317.846774) (xy 280.147938 -317.79899)
			(xy 280.143978 -317.749936) (xy 278.85517 -317.749936) (xy 278.854675 -317.774543) (xy 278.84678 -317.82312)
			(xy 278.831196 -317.869801) (xy 278.808325 -317.913378) (xy 278.77876 -317.952722) (xy 278.743267 -317.986814)
			(xy 278.702764 -318.01477) (xy 278.658302 -318.035868) (xy 278.611031 -318.04956) (xy 278.562176 -318.055492)
			(xy 278.513001 -318.053511) (xy 278.464782 -318.043667) (xy 278.418766 -318.026215) (xy 278.376145 -318.001608)
			(xy 278.338024 -317.970483) (xy 278.305389 -317.933646) (xy 278.279086 -317.89205) (xy 278.259795 -317.846774)
			(xy 278.248018 -317.79899) (xy 278.244058 -317.749936) (xy 276.954996 -317.749936) (xy 276.954501 -317.774543)
			(xy 276.946606 -317.82312) (xy 276.931022 -317.869801) (xy 276.908151 -317.913378) (xy 276.878586 -317.952722)
			(xy 276.843093 -317.986814) (xy 276.80259 -318.01477) (xy 276.758128 -318.035868) (xy 276.710857 -318.04956)
			(xy 276.662002 -318.055492) (xy 276.612827 -318.053511) (xy 276.564608 -318.043667) (xy 276.518592 -318.026215)
			(xy 276.475971 -318.001608) (xy 276.43785 -317.970483) (xy 276.405215 -317.933646) (xy 276.378912 -317.89205)
			(xy 276.359621 -317.846774) (xy 276.347844 -317.79899) (xy 276.343884 -317.749936) (xy 275.055076 -317.749936)
			(xy 275.054581 -317.774543) (xy 275.046686 -317.82312) (xy 275.031102 -317.869801) (xy 275.008231 -317.913378)
			(xy 274.978666 -317.952722) (xy 274.943173 -317.986814) (xy 274.90267 -318.01477) (xy 274.858208 -318.035868)
			(xy 274.810937 -318.04956) (xy 274.762082 -318.055492) (xy 274.712907 -318.053511) (xy 274.664688 -318.043667)
			(xy 274.618672 -318.026215) (xy 274.576051 -318.001608) (xy 274.53793 -317.970483) (xy 274.505295 -317.933646)
			(xy 274.478992 -317.89205) (xy 274.459701 -317.846774) (xy 274.447924 -317.79899) (xy 274.443964 -317.749936)
			(xy 273.155156 -317.749936) (xy 273.154661 -317.774543) (xy 273.146766 -317.82312) (xy 273.131182 -317.869801)
			(xy 273.108311 -317.913378) (xy 273.078746 -317.952722) (xy 273.043253 -317.986814) (xy 273.00275 -318.01477)
			(xy 272.958288 -318.035868) (xy 272.911017 -318.04956) (xy 272.862162 -318.055492) (xy 272.812987 -318.053511)
			(xy 272.764768 -318.043667) (xy 272.718752 -318.026215) (xy 272.676131 -318.001608) (xy 272.63801 -317.970483)
			(xy 272.605375 -317.933646) (xy 272.579072 -317.89205) (xy 272.559781 -317.846774) (xy 272.548004 -317.79899)
			(xy 272.544044 -317.749936) (xy 271.255236 -317.749936) (xy 271.254741 -317.774543) (xy 271.246846 -317.82312)
			(xy 271.231262 -317.869801) (xy 271.208391 -317.913378) (xy 271.178826 -317.952722) (xy 271.143333 -317.986814)
			(xy 271.10283 -318.01477) (xy 271.058368 -318.035868) (xy 271.011097 -318.04956) (xy 270.962242 -318.055492)
			(xy 270.913067 -318.053511) (xy 270.864848 -318.043667) (xy 270.818832 -318.026215) (xy 270.776211 -318.001608)
			(xy 270.73809 -317.970483) (xy 270.705455 -317.933646) (xy 270.679152 -317.89205) (xy 270.659861 -317.846774)
			(xy 270.648084 -317.79899) (xy 270.644124 -317.749936) (xy 196.955156 -317.749936) (xy 196.954661 -317.774543)
			(xy 196.946766 -317.82312) (xy 196.931182 -317.869801) (xy 196.908311 -317.913378) (xy 196.878746 -317.952722)
			(xy 196.843253 -317.986814) (xy 196.80275 -318.01477) (xy 196.758288 -318.035868) (xy 196.711017 -318.04956)
			(xy 196.662162 -318.055492) (xy 196.612987 -318.053511) (xy 196.564768 -318.043667) (xy 196.518752 -318.026215)
			(xy 196.476131 -318.001608) (xy 196.43801 -317.970483) (xy 196.405375 -317.933646) (xy 196.379072 -317.89205)
			(xy 196.359781 -317.846774) (xy 196.348004 -317.79899) (xy 196.344044 -317.749936) (xy 195.055236 -317.749936)
			(xy 195.054741 -317.774543) (xy 195.046846 -317.82312) (xy 195.031262 -317.869801) (xy 195.008391 -317.913378)
			(xy 194.978826 -317.952722) (xy 194.943333 -317.986814) (xy 194.90283 -318.01477) (xy 194.858368 -318.035868)
			(xy 194.811097 -318.04956) (xy 194.762242 -318.055492) (xy 194.713067 -318.053511) (xy 194.664848 -318.043667)
			(xy 194.618832 -318.026215) (xy 194.576211 -318.001608) (xy 194.53809 -317.970483) (xy 194.505455 -317.933646)
			(xy 194.479152 -317.89205) (xy 194.459861 -317.846774) (xy 194.448084 -317.79899) (xy 194.444124 -317.749936)
			(xy 193.155316 -317.749936) (xy 193.154821 -317.774543) (xy 193.146926 -317.82312) (xy 193.131342 -317.869801)
			(xy 193.108471 -317.913378) (xy 193.078906 -317.952722) (xy 193.043413 -317.986814) (xy 193.00291 -318.01477)
			(xy 192.958448 -318.035868) (xy 192.911177 -318.04956) (xy 192.862322 -318.055492) (xy 192.813147 -318.053511)
			(xy 192.764928 -318.043667) (xy 192.718912 -318.026215) (xy 192.676291 -318.001608) (xy 192.63817 -317.970483)
			(xy 192.605535 -317.933646) (xy 192.579232 -317.89205) (xy 192.559941 -317.846774) (xy 192.548164 -317.79899)
			(xy 192.544204 -317.749936) (xy 191.255396 -317.749936) (xy 191.254901 -317.774543) (xy 191.247006 -317.82312)
			(xy 191.231422 -317.869801) (xy 191.208551 -317.913378) (xy 191.178986 -317.952722) (xy 191.143493 -317.986814)
			(xy 191.10299 -318.01477) (xy 191.058528 -318.035868) (xy 191.011257 -318.04956) (xy 190.962402 -318.055492)
			(xy 190.913227 -318.053511) (xy 190.865008 -318.043667) (xy 190.818992 -318.026215) (xy 190.776371 -318.001608)
			(xy 190.73825 -317.970483) (xy 190.705615 -317.933646) (xy 190.679312 -317.89205) (xy 190.660021 -317.846774)
			(xy 190.648244 -317.79899) (xy 190.644284 -317.749936) (xy 189.355222 -317.749936) (xy 189.354727 -317.774543)
			(xy 189.346832 -317.82312) (xy 189.331248 -317.869801) (xy 189.308377 -317.913378) (xy 189.278812 -317.952722)
			(xy 189.243319 -317.986814) (xy 189.202816 -318.01477) (xy 189.158354 -318.035868) (xy 189.111083 -318.04956)
			(xy 189.062228 -318.055492) (xy 189.013053 -318.053511) (xy 188.964834 -318.043667) (xy 188.918818 -318.026215)
			(xy 188.876197 -318.001608) (xy 188.838076 -317.970483) (xy 188.805441 -317.933646) (xy 188.779138 -317.89205)
			(xy 188.759847 -317.846774) (xy 188.74807 -317.79899) (xy 188.74411 -317.749936) (xy 187.455302 -317.749936)
			(xy 187.454807 -317.774543) (xy 187.446912 -317.82312) (xy 187.431328 -317.869801) (xy 187.408457 -317.913378)
			(xy 187.378892 -317.952722) (xy 187.343399 -317.986814) (xy 187.302896 -318.01477) (xy 187.258434 -318.035868)
			(xy 187.211163 -318.04956) (xy 187.162308 -318.055492) (xy 187.113133 -318.053511) (xy 187.064914 -318.043667)
			(xy 187.018898 -318.026215) (xy 186.976277 -318.001608) (xy 186.938156 -317.970483) (xy 186.905521 -317.933646)
			(xy 186.879218 -317.89205) (xy 186.859927 -317.846774) (xy 186.84815 -317.79899) (xy 186.84419 -317.749936)
			(xy 185.555382 -317.749936) (xy 185.554887 -317.774543) (xy 185.546992 -317.82312) (xy 185.531408 -317.869801)
			(xy 185.508537 -317.913378) (xy 185.478972 -317.952722) (xy 185.443479 -317.986814) (xy 185.402976 -318.01477)
			(xy 185.358514 -318.035868) (xy 185.311243 -318.04956) (xy 185.262388 -318.055492) (xy 185.213213 -318.053511)
			(xy 185.164994 -318.043667) (xy 185.118978 -318.026215) (xy 185.076357 -318.001608) (xy 185.038236 -317.970483)
			(xy 185.005601 -317.933646) (xy 184.979298 -317.89205) (xy 184.960007 -317.846774) (xy 184.94823 -317.79899)
			(xy 184.94427 -317.749936) (xy 183.655208 -317.749936) (xy 183.654713 -317.774543) (xy 183.646818 -317.82312)
			(xy 183.631234 -317.869801) (xy 183.608363 -317.913378) (xy 183.578798 -317.952722) (xy 183.543305 -317.986814)
			(xy 183.502802 -318.01477) (xy 183.45834 -318.035868) (xy 183.411069 -318.04956) (xy 183.362214 -318.055492)
			(xy 183.313039 -318.053511) (xy 183.26482 -318.043667) (xy 183.218804 -318.026215) (xy 183.176183 -318.001608)
			(xy 183.138062 -317.970483) (xy 183.105427 -317.933646) (xy 183.079124 -317.89205) (xy 183.059833 -317.846774)
			(xy 183.048056 -317.79899) (xy 183.044096 -317.749936) (xy 181.755288 -317.749936) (xy 181.754793 -317.774543)
			(xy 181.746898 -317.82312) (xy 181.731314 -317.869801) (xy 181.708443 -317.913378) (xy 181.678878 -317.952722)
			(xy 181.643385 -317.986814) (xy 181.602882 -318.01477) (xy 181.55842 -318.035868) (xy 181.511149 -318.04956)
			(xy 181.462294 -318.055492) (xy 181.413119 -318.053511) (xy 181.3649 -318.043667) (xy 181.318884 -318.026215)
			(xy 181.276263 -318.001608) (xy 181.238142 -317.970483) (xy 181.205507 -317.933646) (xy 181.179204 -317.89205)
			(xy 181.159913 -317.846774) (xy 181.148136 -317.79899) (xy 181.144176 -317.749936) (xy 179.855368 -317.749936)
			(xy 179.854873 -317.774543) (xy 179.846978 -317.82312) (xy 179.831394 -317.869801) (xy 179.808523 -317.913378)
			(xy 179.778958 -317.952722) (xy 179.743465 -317.986814) (xy 179.702962 -318.01477) (xy 179.6585 -318.035868)
			(xy 179.611229 -318.04956) (xy 179.562374 -318.055492) (xy 179.513199 -318.053511) (xy 179.46498 -318.043667)
			(xy 179.418964 -318.026215) (xy 179.376343 -318.001608) (xy 179.338222 -317.970483) (xy 179.305587 -317.933646)
			(xy 179.279284 -317.89205) (xy 179.259993 -317.846774) (xy 179.248216 -317.79899) (xy 179.244256 -317.749936)
			(xy 177.955194 -317.749936) (xy 177.954699 -317.774543) (xy 177.946804 -317.82312) (xy 177.93122 -317.869801)
			(xy 177.908349 -317.913378) (xy 177.878784 -317.952722) (xy 177.843291 -317.986814) (xy 177.802788 -318.01477)
			(xy 177.758326 -318.035868) (xy 177.711055 -318.04956) (xy 177.6622 -318.055492) (xy 177.613025 -318.053511)
			(xy 177.564806 -318.043667) (xy 177.51879 -318.026215) (xy 177.476169 -318.001608) (xy 177.438048 -317.970483)
			(xy 177.405413 -317.933646) (xy 177.37911 -317.89205) (xy 177.359819 -317.846774) (xy 177.348042 -317.79899)
			(xy 177.344082 -317.749936) (xy 176.055274 -317.749936) (xy 176.054779 -317.774543) (xy 176.046884 -317.82312)
			(xy 176.0313 -317.869801) (xy 176.008429 -317.913378) (xy 175.978864 -317.952722) (xy 175.943371 -317.986814)
			(xy 175.902868 -318.01477) (xy 175.858406 -318.035868) (xy 175.811135 -318.04956) (xy 175.76228 -318.055492)
			(xy 175.713105 -318.053511) (xy 175.664886 -318.043667) (xy 175.61887 -318.026215) (xy 175.576249 -318.001608)
			(xy 175.538128 -317.970483) (xy 175.505493 -317.933646) (xy 175.47919 -317.89205) (xy 175.459899 -317.846774)
			(xy 175.448122 -317.79899) (xy 175.444162 -317.749936) (xy 174.155354 -317.749936) (xy 174.154859 -317.774543)
			(xy 174.146964 -317.82312) (xy 174.13138 -317.869801) (xy 174.108509 -317.913378) (xy 174.078944 -317.952722)
			(xy 174.043451 -317.986814) (xy 174.002948 -318.01477) (xy 173.958486 -318.035868) (xy 173.911215 -318.04956)
			(xy 173.86236 -318.055492) (xy 173.813185 -318.053511) (xy 173.764966 -318.043667) (xy 173.71895 -318.026215)
			(xy 173.676329 -318.001608) (xy 173.638208 -317.970483) (xy 173.605573 -317.933646) (xy 173.57927 -317.89205)
			(xy 173.559979 -317.846774) (xy 173.548202 -317.79899) (xy 173.544242 -317.749936) (xy 172.25518 -317.749936)
			(xy 172.254685 -317.774543) (xy 172.24679 -317.82312) (xy 172.231206 -317.869801) (xy 172.208335 -317.913378)
			(xy 172.17877 -317.952722) (xy 172.143277 -317.986814) (xy 172.102774 -318.01477) (xy 172.058312 -318.035868)
			(xy 172.011041 -318.04956) (xy 171.962186 -318.055492) (xy 171.913011 -318.053511) (xy 171.864792 -318.043667)
			(xy 171.818776 -318.026215) (xy 171.776155 -318.001608) (xy 171.738034 -317.970483) (xy 171.705399 -317.933646)
			(xy 171.679096 -317.89205) (xy 171.659805 -317.846774) (xy 171.648028 -317.79899) (xy 171.644068 -317.749936)
			(xy 170.35526 -317.749936) (xy 170.354765 -317.774543) (xy 170.34687 -317.82312) (xy 170.331286 -317.869801)
			(xy 170.308415 -317.913378) (xy 170.27885 -317.952722) (xy 170.243357 -317.986814) (xy 170.202854 -318.01477)
			(xy 170.158392 -318.035868) (xy 170.111121 -318.04956) (xy 170.062266 -318.055492) (xy 170.013091 -318.053511)
			(xy 169.964872 -318.043667) (xy 169.918856 -318.026215) (xy 169.876235 -318.001608) (xy 169.838114 -317.970483)
			(xy 169.805479 -317.933646) (xy 169.779176 -317.89205) (xy 169.759885 -317.846774) (xy 169.748108 -317.79899)
			(xy 169.744148 -317.749936) (xy 168.45534 -317.749936) (xy 168.454845 -317.774543) (xy 168.44695 -317.82312)
			(xy 168.431366 -317.869801) (xy 168.408495 -317.913378) (xy 168.37893 -317.952722) (xy 168.343437 -317.986814)
			(xy 168.302934 -318.01477) (xy 168.258472 -318.035868) (xy 168.211201 -318.04956) (xy 168.162346 -318.055492)
			(xy 168.113171 -318.053511) (xy 168.064952 -318.043667) (xy 168.018936 -318.026215) (xy 167.976315 -318.001608)
			(xy 167.938194 -317.970483) (xy 167.905559 -317.933646) (xy 167.879256 -317.89205) (xy 167.859965 -317.846774)
			(xy 167.848188 -317.79899) (xy 167.844228 -317.749936) (xy 166.555166 -317.749936) (xy 166.554671 -317.774543)
			(xy 166.546776 -317.82312) (xy 166.531192 -317.869801) (xy 166.508321 -317.913378) (xy 166.478756 -317.952722)
			(xy 166.443263 -317.986814) (xy 166.40276 -318.01477) (xy 166.358298 -318.035868) (xy 166.311027 -318.04956)
			(xy 166.262172 -318.055492) (xy 166.212997 -318.053511) (xy 166.164778 -318.043667) (xy 166.118762 -318.026215)
			(xy 166.076141 -318.001608) (xy 166.03802 -317.970483) (xy 166.005385 -317.933646) (xy 165.979082 -317.89205)
			(xy 165.959791 -317.846774) (xy 165.948014 -317.79899) (xy 165.944054 -317.749936) (xy 164.655246 -317.749936)
			(xy 164.654751 -317.774543) (xy 164.646856 -317.82312) (xy 164.631272 -317.869801) (xy 164.608401 -317.913378)
			(xy 164.578836 -317.952722) (xy 164.543343 -317.986814) (xy 164.50284 -318.01477) (xy 164.458378 -318.035868)
			(xy 164.411107 -318.04956) (xy 164.362252 -318.055492) (xy 164.313077 -318.053511) (xy 164.264858 -318.043667)
			(xy 164.218842 -318.026215) (xy 164.176221 -318.001608) (xy 164.1381 -317.970483) (xy 164.105465 -317.933646)
			(xy 164.079162 -317.89205) (xy 164.059871 -317.846774) (xy 164.048094 -317.79899) (xy 164.044134 -317.749936)
			(xy 162.755326 -317.749936) (xy 162.754831 -317.774543) (xy 162.746936 -317.82312) (xy 162.731352 -317.869801)
			(xy 162.708481 -317.913378) (xy 162.678916 -317.952722) (xy 162.643423 -317.986814) (xy 162.60292 -318.01477)
			(xy 162.558458 -318.035868) (xy 162.511187 -318.04956) (xy 162.462332 -318.055492) (xy 162.413157 -318.053511)
			(xy 162.364938 -318.043667) (xy 162.318922 -318.026215) (xy 162.276301 -318.001608) (xy 162.23818 -317.970483)
			(xy 162.205545 -317.933646) (xy 162.179242 -317.89205) (xy 162.159951 -317.846774) (xy 162.148174 -317.79899)
			(xy 162.144214 -317.749936) (xy 160.855152 -317.749936) (xy 160.854657 -317.774543) (xy 160.846762 -317.82312)
			(xy 160.831178 -317.869801) (xy 160.808307 -317.913378) (xy 160.778742 -317.952722) (xy 160.743249 -317.986814)
			(xy 160.702746 -318.01477) (xy 160.658284 -318.035868) (xy 160.611013 -318.04956) (xy 160.562158 -318.055492)
			(xy 160.512983 -318.053511) (xy 160.464764 -318.043667) (xy 160.418748 -318.026215) (xy 160.376127 -318.001608)
			(xy 160.338006 -317.970483) (xy 160.305371 -317.933646) (xy 160.279068 -317.89205) (xy 160.259777 -317.846774)
			(xy 160.248 -317.79899) (xy 160.24404 -317.749936) (xy 158.955232 -317.749936) (xy 158.954737 -317.774543)
			(xy 158.946842 -317.82312) (xy 158.931258 -317.869801) (xy 158.908387 -317.913378) (xy 158.878822 -317.952722)
			(xy 158.843329 -317.986814) (xy 158.802826 -318.01477) (xy 158.758364 -318.035868) (xy 158.711093 -318.04956)
			(xy 158.662238 -318.055492) (xy 158.613063 -318.053511) (xy 158.564844 -318.043667) (xy 158.518828 -318.026215)
			(xy 158.476207 -318.001608) (xy 158.438086 -317.970483) (xy 158.405451 -317.933646) (xy 158.379148 -317.89205)
			(xy 158.359857 -317.846774) (xy 158.34808 -317.79899) (xy 158.34412 -317.749936) (xy 157.055312 -317.749936)
			(xy 157.054817 -317.774543) (xy 157.046922 -317.82312) (xy 157.031338 -317.869801) (xy 157.008467 -317.913378)
			(xy 156.978902 -317.952722) (xy 156.943409 -317.986814) (xy 156.902906 -318.01477) (xy 156.858444 -318.035868)
			(xy 156.811173 -318.04956) (xy 156.762318 -318.055492) (xy 156.713143 -318.053511) (xy 156.664924 -318.043667)
			(xy 156.618908 -318.026215) (xy 156.576287 -318.001608) (xy 156.538166 -317.970483) (xy 156.505531 -317.933646)
			(xy 156.479228 -317.89205) (xy 156.459937 -317.846774) (xy 156.44816 -317.79899) (xy 156.4442 -317.749936)
			(xy 155.155392 -317.749936) (xy 155.154897 -317.774543) (xy 155.147002 -317.82312) (xy 155.131418 -317.869801)
			(xy 155.108547 -317.913378) (xy 155.078982 -317.952722) (xy 155.043489 -317.986814) (xy 155.002986 -318.01477)
			(xy 154.958524 -318.035868) (xy 154.911253 -318.04956) (xy 154.862398 -318.055492) (xy 154.813223 -318.053511)
			(xy 154.765004 -318.043667) (xy 154.718988 -318.026215) (xy 154.676367 -318.001608) (xy 154.638246 -317.970483)
			(xy 154.605611 -317.933646) (xy 154.579308 -317.89205) (xy 154.560017 -317.846774) (xy 154.54824 -317.79899)
			(xy 154.54428 -317.749936) (xy 80.855058 -317.749936) (xy 80.854563 -317.774543) (xy 80.846668 -317.82312)
			(xy 80.831084 -317.869801) (xy 80.808213 -317.913378) (xy 80.778648 -317.952722) (xy 80.743155 -317.986814)
			(xy 80.702652 -318.01477) (xy 80.65819 -318.035868) (xy 80.610919 -318.04956) (xy 80.562064 -318.055492)
			(xy 80.512889 -318.053511) (xy 80.46467 -318.043667) (xy 80.418654 -318.026215) (xy 80.376033 -318.001608)
			(xy 80.337912 -317.970483) (xy 80.305277 -317.933646) (xy 80.278974 -317.89205) (xy 80.259683 -317.846774)
			(xy 80.247906 -317.79899) (xy 80.243946 -317.749936) (xy 78.955138 -317.749936) (xy 78.954643 -317.774543)
			(xy 78.946748 -317.82312) (xy 78.931164 -317.869801) (xy 78.908293 -317.913378) (xy 78.878728 -317.952722)
			(xy 78.843235 -317.986814) (xy 78.802732 -318.01477) (xy 78.75827 -318.035868) (xy 78.710999 -318.04956)
			(xy 78.662144 -318.055492) (xy 78.612969 -318.053511) (xy 78.56475 -318.043667) (xy 78.518734 -318.026215)
			(xy 78.476113 -318.001608) (xy 78.437992 -317.970483) (xy 78.405357 -317.933646) (xy 78.379054 -317.89205)
			(xy 78.359763 -317.846774) (xy 78.347986 -317.79899) (xy 78.344026 -317.749936) (xy 77.055218 -317.749936)
			(xy 77.054723 -317.774543) (xy 77.046828 -317.82312) (xy 77.031244 -317.869801) (xy 77.008373 -317.913378)
			(xy 76.978808 -317.952722) (xy 76.943315 -317.986814) (xy 76.902812 -318.01477) (xy 76.85835 -318.035868)
			(xy 76.811079 -318.04956) (xy 76.762224 -318.055492) (xy 76.713049 -318.053511) (xy 76.66483 -318.043667)
			(xy 76.618814 -318.026215) (xy 76.576193 -318.001608) (xy 76.538072 -317.970483) (xy 76.505437 -317.933646)
			(xy 76.479134 -317.89205) (xy 76.459843 -317.846774) (xy 76.448066 -317.79899) (xy 76.444106 -317.749936)
			(xy 75.155298 -317.749936) (xy 75.154803 -317.774543) (xy 75.146908 -317.82312) (xy 75.131324 -317.869801)
			(xy 75.108453 -317.913378) (xy 75.078888 -317.952722) (xy 75.043395 -317.986814) (xy 75.002892 -318.01477)
			(xy 74.95843 -318.035868) (xy 74.911159 -318.04956) (xy 74.862304 -318.055492) (xy 74.813129 -318.053511)
			(xy 74.76491 -318.043667) (xy 74.718894 -318.026215) (xy 74.676273 -318.001608) (xy 74.638152 -317.970483)
			(xy 74.605517 -317.933646) (xy 74.579214 -317.89205) (xy 74.559923 -317.846774) (xy 74.548146 -317.79899)
			(xy 74.544186 -317.749936) (xy 73.255124 -317.749936) (xy 73.254629 -317.774543) (xy 73.246734 -317.82312)
			(xy 73.23115 -317.869801) (xy 73.208279 -317.913378) (xy 73.178714 -317.952722) (xy 73.143221 -317.986814)
			(xy 73.102718 -318.01477) (xy 73.058256 -318.035868) (xy 73.010985 -318.04956) (xy 72.96213 -318.055492)
			(xy 72.912955 -318.053511) (xy 72.864736 -318.043667) (xy 72.81872 -318.026215) (xy 72.776099 -318.001608)
			(xy 72.737978 -317.970483) (xy 72.705343 -317.933646) (xy 72.67904 -317.89205) (xy 72.659749 -317.846774)
			(xy 72.647972 -317.79899) (xy 72.644012 -317.749936) (xy 71.355204 -317.749936) (xy 71.354709 -317.774543)
			(xy 71.346814 -317.82312) (xy 71.33123 -317.869801) (xy 71.308359 -317.913378) (xy 71.278794 -317.952722)
			(xy 71.243301 -317.986814) (xy 71.202798 -318.01477) (xy 71.158336 -318.035868) (xy 71.111065 -318.04956)
			(xy 71.06221 -318.055492) (xy 71.013035 -318.053511) (xy 70.964816 -318.043667) (xy 70.9188 -318.026215)
			(xy 70.876179 -318.001608) (xy 70.838058 -317.970483) (xy 70.805423 -317.933646) (xy 70.77912 -317.89205)
			(xy 70.759829 -317.846774) (xy 70.748052 -317.79899) (xy 70.744092 -317.749936) (xy 69.455284 -317.749936)
			(xy 69.454789 -317.774543) (xy 69.446894 -317.82312) (xy 69.43131 -317.869801) (xy 69.408439 -317.913378)
			(xy 69.378874 -317.952722) (xy 69.343381 -317.986814) (xy 69.302878 -318.01477) (xy 69.258416 -318.035868)
			(xy 69.211145 -318.04956) (xy 69.16229 -318.055492) (xy 69.113115 -318.053511) (xy 69.064896 -318.043667)
			(xy 69.01888 -318.026215) (xy 68.976259 -318.001608) (xy 68.938138 -317.970483) (xy 68.905503 -317.933646)
			(xy 68.8792 -317.89205) (xy 68.859909 -317.846774) (xy 68.848132 -317.79899) (xy 68.844172 -317.749936)
			(xy 67.55511 -317.749936) (xy 67.554615 -317.774543) (xy 67.54672 -317.82312) (xy 67.531136 -317.869801)
			(xy 67.508265 -317.913378) (xy 67.4787 -317.952722) (xy 67.443207 -317.986814) (xy 67.402704 -318.01477)
			(xy 67.358242 -318.035868) (xy 67.310971 -318.04956) (xy 67.262116 -318.055492) (xy 67.212941 -318.053511)
			(xy 67.164722 -318.043667) (xy 67.118706 -318.026215) (xy 67.076085 -318.001608) (xy 67.037964 -317.970483)
			(xy 67.005329 -317.933646) (xy 66.979026 -317.89205) (xy 66.959735 -317.846774) (xy 66.947958 -317.79899)
			(xy 66.943998 -317.749936) (xy 65.65519 -317.749936) (xy 65.654695 -317.774543) (xy 65.6468 -317.82312)
			(xy 65.631216 -317.869801) (xy 65.608345 -317.913378) (xy 65.57878 -317.952722) (xy 65.543287 -317.986814)
			(xy 65.502784 -318.01477) (xy 65.458322 -318.035868) (xy 65.411051 -318.04956) (xy 65.362196 -318.055492)
			(xy 65.313021 -318.053511) (xy 65.264802 -318.043667) (xy 65.218786 -318.026215) (xy 65.176165 -318.001608)
			(xy 65.138044 -317.970483) (xy 65.105409 -317.933646) (xy 65.079106 -317.89205) (xy 65.059815 -317.846774)
			(xy 65.048038 -317.79899) (xy 65.044078 -317.749936) (xy 63.75527 -317.749936) (xy 63.754775 -317.774543)
			(xy 63.74688 -317.82312) (xy 63.731296 -317.869801) (xy 63.708425 -317.913378) (xy 63.67886 -317.952722)
			(xy 63.643367 -317.986814) (xy 63.602864 -318.01477) (xy 63.558402 -318.035868) (xy 63.511131 -318.04956)
			(xy 63.462276 -318.055492) (xy 63.413101 -318.053511) (xy 63.364882 -318.043667) (xy 63.318866 -318.026215)
			(xy 63.276245 -318.001608) (xy 63.238124 -317.970483) (xy 63.205489 -317.933646) (xy 63.179186 -317.89205)
			(xy 63.159895 -317.846774) (xy 63.148118 -317.79899) (xy 63.144158 -317.749936) (xy 61.855096 -317.749936)
			(xy 61.854601 -317.774543) (xy 61.846706 -317.82312) (xy 61.831122 -317.869801) (xy 61.808251 -317.913378)
			(xy 61.778686 -317.952722) (xy 61.743193 -317.986814) (xy 61.70269 -318.01477) (xy 61.658228 -318.035868)
			(xy 61.610957 -318.04956) (xy 61.562102 -318.055492) (xy 61.512927 -318.053511) (xy 61.464708 -318.043667)
			(xy 61.418692 -318.026215) (xy 61.376071 -318.001608) (xy 61.33795 -317.970483) (xy 61.305315 -317.933646)
			(xy 61.279012 -317.89205) (xy 61.259721 -317.846774) (xy 61.247944 -317.79899) (xy 61.243984 -317.749936)
			(xy 59.955176 -317.749936) (xy 59.954681 -317.774543) (xy 59.946786 -317.82312) (xy 59.931202 -317.869801)
			(xy 59.908331 -317.913378) (xy 59.878766 -317.952722) (xy 59.843273 -317.986814) (xy 59.80277 -318.01477)
			(xy 59.758308 -318.035868) (xy 59.711037 -318.04956) (xy 59.662182 -318.055492) (xy 59.613007 -318.053511)
			(xy 59.564788 -318.043667) (xy 59.518772 -318.026215) (xy 59.476151 -318.001608) (xy 59.43803 -317.970483)
			(xy 59.405395 -317.933646) (xy 59.379092 -317.89205) (xy 59.359801 -317.846774) (xy 59.348024 -317.79899)
			(xy 59.344064 -317.749936) (xy 58.055256 -317.749936) (xy 58.054761 -317.774543) (xy 58.046866 -317.82312)
			(xy 58.031282 -317.869801) (xy 58.008411 -317.913378) (xy 57.978846 -317.952722) (xy 57.943353 -317.986814)
			(xy 57.90285 -318.01477) (xy 57.858388 -318.035868) (xy 57.811117 -318.04956) (xy 57.762262 -318.055492)
			(xy 57.713087 -318.053511) (xy 57.664868 -318.043667) (xy 57.618852 -318.026215) (xy 57.576231 -318.001608)
			(xy 57.53811 -317.970483) (xy 57.505475 -317.933646) (xy 57.479172 -317.89205) (xy 57.459881 -317.846774)
			(xy 57.448104 -317.79899) (xy 57.444144 -317.749936) (xy 56.155082 -317.749936) (xy 56.154587 -317.774543)
			(xy 56.146692 -317.82312) (xy 56.131108 -317.869801) (xy 56.108237 -317.913378) (xy 56.078672 -317.952722)
			(xy 56.043179 -317.986814) (xy 56.002676 -318.01477) (xy 55.958214 -318.035868) (xy 55.910943 -318.04956)
			(xy 55.862088 -318.055492) (xy 55.812913 -318.053511) (xy 55.764694 -318.043667) (xy 55.718678 -318.026215)
			(xy 55.676057 -318.001608) (xy 55.637936 -317.970483) (xy 55.605301 -317.933646) (xy 55.578998 -317.89205)
			(xy 55.559707 -317.846774) (xy 55.54793 -317.79899) (xy 55.54397 -317.749936) (xy 54.255162 -317.749936)
			(xy 54.254667 -317.774543) (xy 54.246772 -317.82312) (xy 54.231188 -317.869801) (xy 54.208317 -317.913378)
			(xy 54.178752 -317.952722) (xy 54.143259 -317.986814) (xy 54.102756 -318.01477) (xy 54.058294 -318.035868)
			(xy 54.011023 -318.04956) (xy 53.962168 -318.055492) (xy 53.912993 -318.053511) (xy 53.864774 -318.043667)
			(xy 53.818758 -318.026215) (xy 53.776137 -318.001608) (xy 53.738016 -317.970483) (xy 53.705381 -317.933646)
			(xy 53.679078 -317.89205) (xy 53.659787 -317.846774) (xy 53.64801 -317.79899) (xy 53.64405 -317.749936)
			(xy 52.355242 -317.749936) (xy 52.354747 -317.774543) (xy 52.346852 -317.82312) (xy 52.331268 -317.869801)
			(xy 52.308397 -317.913378) (xy 52.278832 -317.952722) (xy 52.243339 -317.986814) (xy 52.202836 -318.01477)
			(xy 52.158374 -318.035868) (xy 52.111103 -318.04956) (xy 52.062248 -318.055492) (xy 52.013073 -318.053511)
			(xy 51.964854 -318.043667) (xy 51.918838 -318.026215) (xy 51.876217 -318.001608) (xy 51.838096 -317.970483)
			(xy 51.805461 -317.933646) (xy 51.779158 -317.89205) (xy 51.759867 -317.846774) (xy 51.74809 -317.79899)
			(xy 51.74413 -317.749936) (xy 50.455068 -317.749936) (xy 50.454573 -317.774543) (xy 50.446678 -317.82312)
			(xy 50.431094 -317.869801) (xy 50.408223 -317.913378) (xy 50.378658 -317.952722) (xy 50.343165 -317.986814)
			(xy 50.302662 -318.01477) (xy 50.2582 -318.035868) (xy 50.210929 -318.04956) (xy 50.162074 -318.055492)
			(xy 50.112899 -318.053511) (xy 50.06468 -318.043667) (xy 50.018664 -318.026215) (xy 49.976043 -318.001608)
			(xy 49.937922 -317.970483) (xy 49.905287 -317.933646) (xy 49.878984 -317.89205) (xy 49.859693 -317.846774)
			(xy 49.847916 -317.79899) (xy 49.843956 -317.749936) (xy 48.555148 -317.749936) (xy 48.554653 -317.774543)
			(xy 48.546758 -317.82312) (xy 48.531174 -317.869801) (xy 48.508303 -317.913378) (xy 48.478738 -317.952722)
			(xy 48.443245 -317.986814) (xy 48.402742 -318.01477) (xy 48.35828 -318.035868) (xy 48.311009 -318.04956)
			(xy 48.262154 -318.055492) (xy 48.212979 -318.053511) (xy 48.16476 -318.043667) (xy 48.118744 -318.026215)
			(xy 48.076123 -318.001608) (xy 48.038002 -317.970483) (xy 48.005367 -317.933646) (xy 47.979064 -317.89205)
			(xy 47.959773 -317.846774) (xy 47.947996 -317.79899) (xy 47.944036 -317.749936) (xy 46.655228 -317.749936)
			(xy 46.654733 -317.774543) (xy 46.646838 -317.82312) (xy 46.631254 -317.869801) (xy 46.608383 -317.913378)
			(xy 46.578818 -317.952722) (xy 46.543325 -317.986814) (xy 46.502822 -318.01477) (xy 46.45836 -318.035868)
			(xy 46.411089 -318.04956) (xy 46.362234 -318.055492) (xy 46.313059 -318.053511) (xy 46.26484 -318.043667)
			(xy 46.218824 -318.026215) (xy 46.176203 -318.001608) (xy 46.138082 -317.970483) (xy 46.105447 -317.933646)
			(xy 46.079144 -317.89205) (xy 46.059853 -317.846774) (xy 46.048076 -317.79899) (xy 46.044116 -317.749936)
			(xy 44.755054 -317.749936) (xy 44.754559 -317.774543) (xy 44.746664 -317.82312) (xy 44.73108 -317.869801)
			(xy 44.708209 -317.913378) (xy 44.678644 -317.952722) (xy 44.643151 -317.986814) (xy 44.602648 -318.01477)
			(xy 44.558186 -318.035868) (xy 44.510915 -318.04956) (xy 44.46206 -318.055492) (xy 44.412885 -318.053511)
			(xy 44.364666 -318.043667) (xy 44.31865 -318.026215) (xy 44.276029 -318.001608) (xy 44.237908 -317.970483)
			(xy 44.205273 -317.933646) (xy 44.17897 -317.89205) (xy 44.159679 -317.846774) (xy 44.147902 -317.79899)
			(xy 44.143942 -317.749936) (xy 42.855134 -317.749936) (xy 42.854639 -317.774543) (xy 42.846744 -317.82312)
			(xy 42.83116 -317.869801) (xy 42.808289 -317.913378) (xy 42.778724 -317.952722) (xy 42.743231 -317.986814)
			(xy 42.702728 -318.01477) (xy 42.658266 -318.035868) (xy 42.610995 -318.04956) (xy 42.56214 -318.055492)
			(xy 42.512965 -318.053511) (xy 42.464746 -318.043667) (xy 42.41873 -318.026215) (xy 42.376109 -318.001608)
			(xy 42.337988 -317.970483) (xy 42.305353 -317.933646) (xy 42.27905 -317.89205) (xy 42.259759 -317.846774)
			(xy 42.247982 -317.79899) (xy 42.244022 -317.749936) (xy 40.955214 -317.749936) (xy 40.954719 -317.774543)
			(xy 40.946824 -317.82312) (xy 40.93124 -317.869801) (xy 40.908369 -317.913378) (xy 40.878804 -317.952722)
			(xy 40.843311 -317.986814) (xy 40.802808 -318.01477) (xy 40.758346 -318.035868) (xy 40.711075 -318.04956)
			(xy 40.66222 -318.055492) (xy 40.613045 -318.053511) (xy 40.564826 -318.043667) (xy 40.51881 -318.026215)
			(xy 40.476189 -318.001608) (xy 40.438068 -317.970483) (xy 40.405433 -317.933646) (xy 40.37913 -317.89205)
			(xy 40.359839 -317.846774) (xy 40.348062 -317.79899) (xy 40.344102 -317.749936) (xy 39.055294 -317.749936)
			(xy 39.054799 -317.774543) (xy 39.046904 -317.82312) (xy 39.03132 -317.869801) (xy 39.008449 -317.913378)
			(xy 38.978884 -317.952722) (xy 38.943391 -317.986814) (xy 38.902888 -318.01477) (xy 38.858426 -318.035868)
			(xy 38.811155 -318.04956) (xy 38.7623 -318.055492) (xy 38.713125 -318.053511) (xy 38.664906 -318.043667)
			(xy 38.61889 -318.026215) (xy 38.576269 -318.001608) (xy 38.538148 -317.970483) (xy 38.505513 -317.933646)
			(xy 38.47921 -317.89205) (xy 38.459919 -317.846774) (xy 38.448142 -317.79899) (xy 38.444182 -317.749936)
			(xy 0.509016 -317.749936) (xy 0.509016 -320.900044) (xy 26.882353 -320.900044) (xy 26.886342 -320.751504)
			(xy 26.898299 -320.603391) (xy 26.918189 -320.456134) (xy 26.945954 -320.310158) (xy 26.981515 -320.165881)
			(xy 27.024769 -320.023722) (xy 27.075591 -319.884089) (xy 27.133835 -319.747386) (xy 27.199333 -319.614006)
			(xy 27.271896 -319.484334) (xy 27.351314 -319.358744) (xy 27.437359 -319.237597) (xy 27.529783 -319.121244)
			(xy 27.628319 -319.01002) (xy 27.732683 -318.904245) (xy 27.842575 -318.804225) (xy 27.957676 -318.710247)
			(xy 28.077656 -318.622583) (xy 28.202169 -318.541486) (xy 28.330855 -318.467189) (xy 28.463344 -318.399907)
			(xy 28.599253 -318.339833) (xy 28.738191 -318.287141) (xy 28.879757 -318.241982) (xy 29.023543 -318.204487)
			(xy 29.169134 -318.174765) (xy 29.31611 -318.1529) (xy 29.464049 -318.138956) (xy 29.612522 -318.132972)
			(xy 29.761103 -318.134967) (xy 29.909362 -318.144935) (xy 30.056873 -318.162846) (xy 30.203209 -318.188649)
			(xy 30.34795 -318.222269) (xy 30.490677 -318.263611) (xy 30.63098 -318.312554) (xy 30.768453 -318.368957)
			(xy 30.9027 -318.432658) (xy 31.033335 -318.503474) (xy 31.15998 -318.581199) (xy 31.28227 -318.66561)
			(xy 31.326643 -318.699896) (xy 38.444182 -318.699896) (xy 38.448142 -318.650842) (xy 38.459919 -318.603058)
			(xy 38.47921 -318.557782) (xy 38.505513 -318.516186) (xy 38.538148 -318.479349) (xy 38.576269 -318.448224)
			(xy 38.61889 -318.423617) (xy 38.664906 -318.406165) (xy 38.713125 -318.396321) (xy 38.7623 -318.39434)
			(xy 38.811155 -318.400272) (xy 38.858426 -318.413964) (xy 38.902888 -318.435062) (xy 38.943391 -318.463018)
			(xy 38.978884 -318.49711) (xy 39.008449 -318.536454) (xy 39.03132 -318.580031) (xy 39.046904 -318.626712)
			(xy 39.054799 -318.675289) (xy 39.055294 -318.699896) (xy 40.344102 -318.699896) (xy 40.348062 -318.650842)
			(xy 40.359839 -318.603058) (xy 40.37913 -318.557782) (xy 40.405433 -318.516186) (xy 40.438068 -318.479349)
			(xy 40.476189 -318.448224) (xy 40.51881 -318.423617) (xy 40.564826 -318.406165) (xy 40.613045 -318.396321)
			(xy 40.66222 -318.39434) (xy 40.711075 -318.400272) (xy 40.758346 -318.413964) (xy 40.802808 -318.435062)
			(xy 40.843311 -318.463018) (xy 40.878804 -318.49711) (xy 40.908369 -318.536454) (xy 40.93124 -318.580031)
			(xy 40.946824 -318.626712) (xy 40.954719 -318.675289) (xy 40.955214 -318.699896) (xy 42.244022 -318.699896)
			(xy 42.247982 -318.650842) (xy 42.259759 -318.603058) (xy 42.27905 -318.557782) (xy 42.305353 -318.516186)
			(xy 42.337988 -318.479349) (xy 42.376109 -318.448224) (xy 42.41873 -318.423617) (xy 42.464746 -318.406165)
			(xy 42.512965 -318.396321) (xy 42.56214 -318.39434) (xy 42.610995 -318.400272) (xy 42.658266 -318.413964)
			(xy 42.702728 -318.435062) (xy 42.743231 -318.463018) (xy 42.778724 -318.49711) (xy 42.808289 -318.536454)
			(xy 42.83116 -318.580031) (xy 42.846744 -318.626712) (xy 42.854639 -318.675289) (xy 42.855134 -318.699896)
			(xy 44.143942 -318.699896) (xy 44.147902 -318.650842) (xy 44.159679 -318.603058) (xy 44.17897 -318.557782)
			(xy 44.205273 -318.516186) (xy 44.237908 -318.479349) (xy 44.276029 -318.448224) (xy 44.31865 -318.423617)
			(xy 44.364666 -318.406165) (xy 44.412885 -318.396321) (xy 44.46206 -318.39434) (xy 44.510915 -318.400272)
			(xy 44.558186 -318.413964) (xy 44.602648 -318.435062) (xy 44.643151 -318.463018) (xy 44.678644 -318.49711)
			(xy 44.708209 -318.536454) (xy 44.73108 -318.580031) (xy 44.746664 -318.626712) (xy 44.754559 -318.675289)
			(xy 44.755054 -318.699896) (xy 46.044116 -318.699896) (xy 46.048076 -318.650842) (xy 46.059853 -318.603058)
			(xy 46.079144 -318.557782) (xy 46.105447 -318.516186) (xy 46.138082 -318.479349) (xy 46.176203 -318.448224)
			(xy 46.218824 -318.423617) (xy 46.26484 -318.406165) (xy 46.313059 -318.396321) (xy 46.362234 -318.39434)
			(xy 46.411089 -318.400272) (xy 46.45836 -318.413964) (xy 46.502822 -318.435062) (xy 46.543325 -318.463018)
			(xy 46.578818 -318.49711) (xy 46.608383 -318.536454) (xy 46.631254 -318.580031) (xy 46.646838 -318.626712)
			(xy 46.654733 -318.675289) (xy 46.655228 -318.699896) (xy 47.944036 -318.699896) (xy 47.947996 -318.650842)
			(xy 47.959773 -318.603058) (xy 47.979064 -318.557782) (xy 48.005367 -318.516186) (xy 48.038002 -318.479349)
			(xy 48.076123 -318.448224) (xy 48.118744 -318.423617) (xy 48.16476 -318.406165) (xy 48.212979 -318.396321)
			(xy 48.262154 -318.39434) (xy 48.311009 -318.400272) (xy 48.35828 -318.413964) (xy 48.402742 -318.435062)
			(xy 48.443245 -318.463018) (xy 48.478738 -318.49711) (xy 48.508303 -318.536454) (xy 48.531174 -318.580031)
			(xy 48.546758 -318.626712) (xy 48.554653 -318.675289) (xy 48.555148 -318.699896) (xy 49.843956 -318.699896)
			(xy 49.847916 -318.650842) (xy 49.859693 -318.603058) (xy 49.878984 -318.557782) (xy 49.905287 -318.516186)
			(xy 49.937922 -318.479349) (xy 49.976043 -318.448224) (xy 50.018664 -318.423617) (xy 50.06468 -318.406165)
			(xy 50.112899 -318.396321) (xy 50.162074 -318.39434) (xy 50.210929 -318.400272) (xy 50.2582 -318.413964)
			(xy 50.302662 -318.435062) (xy 50.343165 -318.463018) (xy 50.378658 -318.49711) (xy 50.408223 -318.536454)
			(xy 50.431094 -318.580031) (xy 50.446678 -318.626712) (xy 50.454573 -318.675289) (xy 50.455068 -318.699896)
			(xy 51.74413 -318.699896) (xy 51.74809 -318.650842) (xy 51.759867 -318.603058) (xy 51.779158 -318.557782)
			(xy 51.805461 -318.516186) (xy 51.838096 -318.479349) (xy 51.876217 -318.448224) (xy 51.918838 -318.423617)
			(xy 51.964854 -318.406165) (xy 52.013073 -318.396321) (xy 52.062248 -318.39434) (xy 52.111103 -318.400272)
			(xy 52.158374 -318.413964) (xy 52.202836 -318.435062) (xy 52.243339 -318.463018) (xy 52.278832 -318.49711)
			(xy 52.308397 -318.536454) (xy 52.331268 -318.580031) (xy 52.346852 -318.626712) (xy 52.354747 -318.675289)
			(xy 52.355242 -318.699896) (xy 53.64405 -318.699896) (xy 53.64801 -318.650842) (xy 53.659787 -318.603058)
			(xy 53.679078 -318.557782) (xy 53.705381 -318.516186) (xy 53.738016 -318.479349) (xy 53.776137 -318.448224)
			(xy 53.818758 -318.423617) (xy 53.864774 -318.406165) (xy 53.912993 -318.396321) (xy 53.962168 -318.39434)
			(xy 54.011023 -318.400272) (xy 54.058294 -318.413964) (xy 54.102756 -318.435062) (xy 54.143259 -318.463018)
			(xy 54.178752 -318.49711) (xy 54.208317 -318.536454) (xy 54.231188 -318.580031) (xy 54.246772 -318.626712)
			(xy 54.254667 -318.675289) (xy 54.255162 -318.699896) (xy 55.54397 -318.699896) (xy 55.54793 -318.650842)
			(xy 55.559707 -318.603058) (xy 55.578998 -318.557782) (xy 55.605301 -318.516186) (xy 55.637936 -318.479349)
			(xy 55.676057 -318.448224) (xy 55.718678 -318.423617) (xy 55.764694 -318.406165) (xy 55.812913 -318.396321)
			(xy 55.862088 -318.39434) (xy 55.910943 -318.400272) (xy 55.958214 -318.413964) (xy 56.002676 -318.435062)
			(xy 56.043179 -318.463018) (xy 56.078672 -318.49711) (xy 56.108237 -318.536454) (xy 56.131108 -318.580031)
			(xy 56.146692 -318.626712) (xy 56.154587 -318.675289) (xy 56.155082 -318.699896) (xy 57.444144 -318.699896)
			(xy 57.448104 -318.650842) (xy 57.459881 -318.603058) (xy 57.479172 -318.557782) (xy 57.505475 -318.516186)
			(xy 57.53811 -318.479349) (xy 57.576231 -318.448224) (xy 57.618852 -318.423617) (xy 57.664868 -318.406165)
			(xy 57.713087 -318.396321) (xy 57.762262 -318.39434) (xy 57.811117 -318.400272) (xy 57.858388 -318.413964)
			(xy 57.90285 -318.435062) (xy 57.943353 -318.463018) (xy 57.978846 -318.49711) (xy 58.008411 -318.536454)
			(xy 58.031282 -318.580031) (xy 58.046866 -318.626712) (xy 58.054761 -318.675289) (xy 58.055256 -318.699896)
			(xy 59.344064 -318.699896) (xy 59.348024 -318.650842) (xy 59.359801 -318.603058) (xy 59.379092 -318.557782)
			(xy 59.405395 -318.516186) (xy 59.43803 -318.479349) (xy 59.476151 -318.448224) (xy 59.518772 -318.423617)
			(xy 59.564788 -318.406165) (xy 59.613007 -318.396321) (xy 59.662182 -318.39434) (xy 59.711037 -318.400272)
			(xy 59.758308 -318.413964) (xy 59.80277 -318.435062) (xy 59.843273 -318.463018) (xy 59.878766 -318.49711)
			(xy 59.908331 -318.536454) (xy 59.931202 -318.580031) (xy 59.946786 -318.626712) (xy 59.954681 -318.675289)
			(xy 59.955176 -318.699896) (xy 61.243984 -318.699896) (xy 61.247944 -318.650842) (xy 61.259721 -318.603058)
			(xy 61.279012 -318.557782) (xy 61.305315 -318.516186) (xy 61.33795 -318.479349) (xy 61.376071 -318.448224)
			(xy 61.418692 -318.423617) (xy 61.464708 -318.406165) (xy 61.512927 -318.396321) (xy 61.562102 -318.39434)
			(xy 61.610957 -318.400272) (xy 61.658228 -318.413964) (xy 61.70269 -318.435062) (xy 61.743193 -318.463018)
			(xy 61.778686 -318.49711) (xy 61.808251 -318.536454) (xy 61.831122 -318.580031) (xy 61.846706 -318.626712)
			(xy 61.854601 -318.675289) (xy 61.855096 -318.699896) (xy 63.144158 -318.699896) (xy 63.148118 -318.650842)
			(xy 63.159895 -318.603058) (xy 63.179186 -318.557782) (xy 63.205489 -318.516186) (xy 63.238124 -318.479349)
			(xy 63.276245 -318.448224) (xy 63.318866 -318.423617) (xy 63.364882 -318.406165) (xy 63.413101 -318.396321)
			(xy 63.462276 -318.39434) (xy 63.511131 -318.400272) (xy 63.558402 -318.413964) (xy 63.602864 -318.435062)
			(xy 63.643367 -318.463018) (xy 63.67886 -318.49711) (xy 63.708425 -318.536454) (xy 63.731296 -318.580031)
			(xy 63.74688 -318.626712) (xy 63.754775 -318.675289) (xy 63.75527 -318.699896) (xy 65.044078 -318.699896)
			(xy 65.048038 -318.650842) (xy 65.059815 -318.603058) (xy 65.079106 -318.557782) (xy 65.105409 -318.516186)
			(xy 65.138044 -318.479349) (xy 65.176165 -318.448224) (xy 65.218786 -318.423617) (xy 65.264802 -318.406165)
			(xy 65.313021 -318.396321) (xy 65.362196 -318.39434) (xy 65.411051 -318.400272) (xy 65.458322 -318.413964)
			(xy 65.502784 -318.435062) (xy 65.543287 -318.463018) (xy 65.57878 -318.49711) (xy 65.608345 -318.536454)
			(xy 65.631216 -318.580031) (xy 65.6468 -318.626712) (xy 65.654695 -318.675289) (xy 65.65519 -318.699896)
			(xy 66.943998 -318.699896) (xy 66.947958 -318.650842) (xy 66.959735 -318.603058) (xy 66.979026 -318.557782)
			(xy 67.005329 -318.516186) (xy 67.037964 -318.479349) (xy 67.076085 -318.448224) (xy 67.118706 -318.423617)
			(xy 67.164722 -318.406165) (xy 67.212941 -318.396321) (xy 67.262116 -318.39434) (xy 67.310971 -318.400272)
			(xy 67.358242 -318.413964) (xy 67.402704 -318.435062) (xy 67.443207 -318.463018) (xy 67.4787 -318.49711)
			(xy 67.508265 -318.536454) (xy 67.531136 -318.580031) (xy 67.54672 -318.626712) (xy 67.554615 -318.675289)
			(xy 67.55511 -318.699896) (xy 68.844172 -318.699896) (xy 68.848132 -318.650842) (xy 68.859909 -318.603058)
			(xy 68.8792 -318.557782) (xy 68.905503 -318.516186) (xy 68.938138 -318.479349) (xy 68.976259 -318.448224)
			(xy 69.01888 -318.423617) (xy 69.064896 -318.406165) (xy 69.113115 -318.396321) (xy 69.16229 -318.39434)
			(xy 69.211145 -318.400272) (xy 69.258416 -318.413964) (xy 69.302878 -318.435062) (xy 69.343381 -318.463018)
			(xy 69.378874 -318.49711) (xy 69.408439 -318.536454) (xy 69.43131 -318.580031) (xy 69.446894 -318.626712)
			(xy 69.454789 -318.675289) (xy 69.455284 -318.699896) (xy 70.744092 -318.699896) (xy 70.748052 -318.650842)
			(xy 70.759829 -318.603058) (xy 70.77912 -318.557782) (xy 70.805423 -318.516186) (xy 70.838058 -318.479349)
			(xy 70.876179 -318.448224) (xy 70.9188 -318.423617) (xy 70.964816 -318.406165) (xy 71.013035 -318.396321)
			(xy 71.06221 -318.39434) (xy 71.111065 -318.400272) (xy 71.158336 -318.413964) (xy 71.202798 -318.435062)
			(xy 71.243301 -318.463018) (xy 71.278794 -318.49711) (xy 71.308359 -318.536454) (xy 71.33123 -318.580031)
			(xy 71.346814 -318.626712) (xy 71.354709 -318.675289) (xy 71.355204 -318.699896) (xy 72.644012 -318.699896)
			(xy 72.647972 -318.650842) (xy 72.659749 -318.603058) (xy 72.67904 -318.557782) (xy 72.705343 -318.516186)
			(xy 72.737978 -318.479349) (xy 72.776099 -318.448224) (xy 72.81872 -318.423617) (xy 72.864736 -318.406165)
			(xy 72.912955 -318.396321) (xy 72.96213 -318.39434) (xy 73.010985 -318.400272) (xy 73.058256 -318.413964)
			(xy 73.102718 -318.435062) (xy 73.143221 -318.463018) (xy 73.178714 -318.49711) (xy 73.208279 -318.536454)
			(xy 73.23115 -318.580031) (xy 73.246734 -318.626712) (xy 73.254629 -318.675289) (xy 73.255124 -318.699896)
			(xy 74.544186 -318.699896) (xy 74.548146 -318.650842) (xy 74.559923 -318.603058) (xy 74.579214 -318.557782)
			(xy 74.605517 -318.516186) (xy 74.638152 -318.479349) (xy 74.676273 -318.448224) (xy 74.718894 -318.423617)
			(xy 74.76491 -318.406165) (xy 74.813129 -318.396321) (xy 74.862304 -318.39434) (xy 74.911159 -318.400272)
			(xy 74.95843 -318.413964) (xy 75.002892 -318.435062) (xy 75.043395 -318.463018) (xy 75.078888 -318.49711)
			(xy 75.108453 -318.536454) (xy 75.131324 -318.580031) (xy 75.146908 -318.626712) (xy 75.154803 -318.675289)
			(xy 75.155298 -318.699896) (xy 76.444106 -318.699896) (xy 76.448066 -318.650842) (xy 76.459843 -318.603058)
			(xy 76.479134 -318.557782) (xy 76.505437 -318.516186) (xy 76.538072 -318.479349) (xy 76.576193 -318.448224)
			(xy 76.618814 -318.423617) (xy 76.66483 -318.406165) (xy 76.713049 -318.396321) (xy 76.762224 -318.39434)
			(xy 76.811079 -318.400272) (xy 76.85835 -318.413964) (xy 76.902812 -318.435062) (xy 76.943315 -318.463018)
			(xy 76.978808 -318.49711) (xy 77.008373 -318.536454) (xy 77.031244 -318.580031) (xy 77.046828 -318.626712)
			(xy 77.054723 -318.675289) (xy 77.055218 -318.699896) (xy 78.344026 -318.699896) (xy 78.347986 -318.650842)
			(xy 78.359763 -318.603058) (xy 78.379054 -318.557782) (xy 78.405357 -318.516186) (xy 78.437992 -318.479349)
			(xy 78.476113 -318.448224) (xy 78.518734 -318.423617) (xy 78.56475 -318.406165) (xy 78.612969 -318.396321)
			(xy 78.662144 -318.39434) (xy 78.710999 -318.400272) (xy 78.75827 -318.413964) (xy 78.802732 -318.435062)
			(xy 78.843235 -318.463018) (xy 78.878728 -318.49711) (xy 78.908293 -318.536454) (xy 78.931164 -318.580031)
			(xy 78.946748 -318.626712) (xy 78.954643 -318.675289) (xy 78.955138 -318.699896) (xy 80.243946 -318.699896)
			(xy 80.247906 -318.650842) (xy 80.259683 -318.603058) (xy 80.278974 -318.557782) (xy 80.305277 -318.516186)
			(xy 80.337912 -318.479349) (xy 80.376033 -318.448224) (xy 80.418654 -318.423617) (xy 80.46467 -318.406165)
			(xy 80.512889 -318.396321) (xy 80.562064 -318.39434) (xy 80.610919 -318.400272) (xy 80.65819 -318.413964)
			(xy 80.702652 -318.435062) (xy 80.743155 -318.463018) (xy 80.778648 -318.49711) (xy 80.808213 -318.536454)
			(xy 80.831084 -318.580031) (xy 80.846668 -318.626712) (xy 80.854563 -318.675289) (xy 80.855058 -318.699896)
			(xy 80.854563 -318.724503) (xy 80.846668 -318.77308) (xy 80.831084 -318.819761) (xy 80.808213 -318.863338)
			(xy 80.778648 -318.902682) (xy 80.743155 -318.936774) (xy 80.702652 -318.96473) (xy 80.65819 -318.985828)
			(xy 80.610919 -318.99952) (xy 80.562064 -319.005452) (xy 80.512889 -319.003471) (xy 80.46467 -318.993627)
			(xy 80.418654 -318.976175) (xy 80.376033 -318.951568) (xy 80.337912 -318.920443) (xy 80.305277 -318.883606)
			(xy 80.278974 -318.84201) (xy 80.259683 -318.796734) (xy 80.247906 -318.74895) (xy 80.243946 -318.699896)
			(xy 78.955138 -318.699896) (xy 78.954643 -318.724503) (xy 78.946748 -318.77308) (xy 78.931164 -318.819761)
			(xy 78.908293 -318.863338) (xy 78.878728 -318.902682) (xy 78.843235 -318.936774) (xy 78.802732 -318.96473)
			(xy 78.75827 -318.985828) (xy 78.710999 -318.99952) (xy 78.662144 -319.005452) (xy 78.612969 -319.003471)
			(xy 78.56475 -318.993627) (xy 78.518734 -318.976175) (xy 78.476113 -318.951568) (xy 78.437992 -318.920443)
			(xy 78.405357 -318.883606) (xy 78.379054 -318.84201) (xy 78.359763 -318.796734) (xy 78.347986 -318.74895)
			(xy 78.344026 -318.699896) (xy 77.055218 -318.699896) (xy 77.054723 -318.724503) (xy 77.046828 -318.77308)
			(xy 77.031244 -318.819761) (xy 77.008373 -318.863338) (xy 76.978808 -318.902682) (xy 76.943315 -318.936774)
			(xy 76.902812 -318.96473) (xy 76.85835 -318.985828) (xy 76.811079 -318.99952) (xy 76.762224 -319.005452)
			(xy 76.713049 -319.003471) (xy 76.66483 -318.993627) (xy 76.618814 -318.976175) (xy 76.576193 -318.951568)
			(xy 76.538072 -318.920443) (xy 76.505437 -318.883606) (xy 76.479134 -318.84201) (xy 76.459843 -318.796734)
			(xy 76.448066 -318.74895) (xy 76.444106 -318.699896) (xy 75.155298 -318.699896) (xy 75.154803 -318.724503)
			(xy 75.146908 -318.77308) (xy 75.131324 -318.819761) (xy 75.108453 -318.863338) (xy 75.078888 -318.902682)
			(xy 75.043395 -318.936774) (xy 75.002892 -318.96473) (xy 74.95843 -318.985828) (xy 74.911159 -318.99952)
			(xy 74.862304 -319.005452) (xy 74.813129 -319.003471) (xy 74.76491 -318.993627) (xy 74.718894 -318.976175)
			(xy 74.676273 -318.951568) (xy 74.638152 -318.920443) (xy 74.605517 -318.883606) (xy 74.579214 -318.84201)
			(xy 74.559923 -318.796734) (xy 74.548146 -318.74895) (xy 74.544186 -318.699896) (xy 73.255124 -318.699896)
			(xy 73.254629 -318.724503) (xy 73.246734 -318.77308) (xy 73.23115 -318.819761) (xy 73.208279 -318.863338)
			(xy 73.178714 -318.902682) (xy 73.143221 -318.936774) (xy 73.102718 -318.96473) (xy 73.058256 -318.985828)
			(xy 73.010985 -318.99952) (xy 72.96213 -319.005452) (xy 72.912955 -319.003471) (xy 72.864736 -318.993627)
			(xy 72.81872 -318.976175) (xy 72.776099 -318.951568) (xy 72.737978 -318.920443) (xy 72.705343 -318.883606)
			(xy 72.67904 -318.84201) (xy 72.659749 -318.796734) (xy 72.647972 -318.74895) (xy 72.644012 -318.699896)
			(xy 71.355204 -318.699896) (xy 71.354709 -318.724503) (xy 71.346814 -318.77308) (xy 71.33123 -318.819761)
			(xy 71.308359 -318.863338) (xy 71.278794 -318.902682) (xy 71.243301 -318.936774) (xy 71.202798 -318.96473)
			(xy 71.158336 -318.985828) (xy 71.111065 -318.99952) (xy 71.06221 -319.005452) (xy 71.013035 -319.003471)
			(xy 70.964816 -318.993627) (xy 70.9188 -318.976175) (xy 70.876179 -318.951568) (xy 70.838058 -318.920443)
			(xy 70.805423 -318.883606) (xy 70.77912 -318.84201) (xy 70.759829 -318.796734) (xy 70.748052 -318.74895)
			(xy 70.744092 -318.699896) (xy 69.455284 -318.699896) (xy 69.454789 -318.724503) (xy 69.446894 -318.77308)
			(xy 69.43131 -318.819761) (xy 69.408439 -318.863338) (xy 69.378874 -318.902682) (xy 69.343381 -318.936774)
			(xy 69.302878 -318.96473) (xy 69.258416 -318.985828) (xy 69.211145 -318.99952) (xy 69.16229 -319.005452)
			(xy 69.113115 -319.003471) (xy 69.064896 -318.993627) (xy 69.01888 -318.976175) (xy 68.976259 -318.951568)
			(xy 68.938138 -318.920443) (xy 68.905503 -318.883606) (xy 68.8792 -318.84201) (xy 68.859909 -318.796734)
			(xy 68.848132 -318.74895) (xy 68.844172 -318.699896) (xy 67.55511 -318.699896) (xy 67.554615 -318.724503)
			(xy 67.54672 -318.77308) (xy 67.531136 -318.819761) (xy 67.508265 -318.863338) (xy 67.4787 -318.902682)
			(xy 67.443207 -318.936774) (xy 67.402704 -318.96473) (xy 67.358242 -318.985828) (xy 67.310971 -318.99952)
			(xy 67.262116 -319.005452) (xy 67.212941 -319.003471) (xy 67.164722 -318.993627) (xy 67.118706 -318.976175)
			(xy 67.076085 -318.951568) (xy 67.037964 -318.920443) (xy 67.005329 -318.883606) (xy 66.979026 -318.84201)
			(xy 66.959735 -318.796734) (xy 66.947958 -318.74895) (xy 66.943998 -318.699896) (xy 65.65519 -318.699896)
			(xy 65.654695 -318.724503) (xy 65.6468 -318.77308) (xy 65.631216 -318.819761) (xy 65.608345 -318.863338)
			(xy 65.57878 -318.902682) (xy 65.543287 -318.936774) (xy 65.502784 -318.96473) (xy 65.458322 -318.985828)
			(xy 65.411051 -318.99952) (xy 65.362196 -319.005452) (xy 65.313021 -319.003471) (xy 65.264802 -318.993627)
			(xy 65.218786 -318.976175) (xy 65.176165 -318.951568) (xy 65.138044 -318.920443) (xy 65.105409 -318.883606)
			(xy 65.079106 -318.84201) (xy 65.059815 -318.796734) (xy 65.048038 -318.74895) (xy 65.044078 -318.699896)
			(xy 63.75527 -318.699896) (xy 63.754775 -318.724503) (xy 63.74688 -318.77308) (xy 63.731296 -318.819761)
			(xy 63.708425 -318.863338) (xy 63.67886 -318.902682) (xy 63.643367 -318.936774) (xy 63.602864 -318.96473)
			(xy 63.558402 -318.985828) (xy 63.511131 -318.99952) (xy 63.462276 -319.005452) (xy 63.413101 -319.003471)
			(xy 63.364882 -318.993627) (xy 63.318866 -318.976175) (xy 63.276245 -318.951568) (xy 63.238124 -318.920443)
			(xy 63.205489 -318.883606) (xy 63.179186 -318.84201) (xy 63.159895 -318.796734) (xy 63.148118 -318.74895)
			(xy 63.144158 -318.699896) (xy 61.855096 -318.699896) (xy 61.854601 -318.724503) (xy 61.846706 -318.77308)
			(xy 61.831122 -318.819761) (xy 61.808251 -318.863338) (xy 61.778686 -318.902682) (xy 61.743193 -318.936774)
			(xy 61.70269 -318.96473) (xy 61.658228 -318.985828) (xy 61.610957 -318.99952) (xy 61.562102 -319.005452)
			(xy 61.512927 -319.003471) (xy 61.464708 -318.993627) (xy 61.418692 -318.976175) (xy 61.376071 -318.951568)
			(xy 61.33795 -318.920443) (xy 61.305315 -318.883606) (xy 61.279012 -318.84201) (xy 61.259721 -318.796734)
			(xy 61.247944 -318.74895) (xy 61.243984 -318.699896) (xy 59.955176 -318.699896) (xy 59.954681 -318.724503)
			(xy 59.946786 -318.77308) (xy 59.931202 -318.819761) (xy 59.908331 -318.863338) (xy 59.878766 -318.902682)
			(xy 59.843273 -318.936774) (xy 59.80277 -318.96473) (xy 59.758308 -318.985828) (xy 59.711037 -318.99952)
			(xy 59.662182 -319.005452) (xy 59.613007 -319.003471) (xy 59.564788 -318.993627) (xy 59.518772 -318.976175)
			(xy 59.476151 -318.951568) (xy 59.43803 -318.920443) (xy 59.405395 -318.883606) (xy 59.379092 -318.84201)
			(xy 59.359801 -318.796734) (xy 59.348024 -318.74895) (xy 59.344064 -318.699896) (xy 58.055256 -318.699896)
			(xy 58.054761 -318.724503) (xy 58.046866 -318.77308) (xy 58.031282 -318.819761) (xy 58.008411 -318.863338)
			(xy 57.978846 -318.902682) (xy 57.943353 -318.936774) (xy 57.90285 -318.96473) (xy 57.858388 -318.985828)
			(xy 57.811117 -318.99952) (xy 57.762262 -319.005452) (xy 57.713087 -319.003471) (xy 57.664868 -318.993627)
			(xy 57.618852 -318.976175) (xy 57.576231 -318.951568) (xy 57.53811 -318.920443) (xy 57.505475 -318.883606)
			(xy 57.479172 -318.84201) (xy 57.459881 -318.796734) (xy 57.448104 -318.74895) (xy 57.444144 -318.699896)
			(xy 56.155082 -318.699896) (xy 56.154587 -318.724503) (xy 56.146692 -318.77308) (xy 56.131108 -318.819761)
			(xy 56.108237 -318.863338) (xy 56.078672 -318.902682) (xy 56.043179 -318.936774) (xy 56.002676 -318.96473)
			(xy 55.958214 -318.985828) (xy 55.910943 -318.99952) (xy 55.862088 -319.005452) (xy 55.812913 -319.003471)
			(xy 55.764694 -318.993627) (xy 55.718678 -318.976175) (xy 55.676057 -318.951568) (xy 55.637936 -318.920443)
			(xy 55.605301 -318.883606) (xy 55.578998 -318.84201) (xy 55.559707 -318.796734) (xy 55.54793 -318.74895)
			(xy 55.54397 -318.699896) (xy 54.255162 -318.699896) (xy 54.254667 -318.724503) (xy 54.246772 -318.77308)
			(xy 54.231188 -318.819761) (xy 54.208317 -318.863338) (xy 54.178752 -318.902682) (xy 54.143259 -318.936774)
			(xy 54.102756 -318.96473) (xy 54.058294 -318.985828) (xy 54.011023 -318.99952) (xy 53.962168 -319.005452)
			(xy 53.912993 -319.003471) (xy 53.864774 -318.993627) (xy 53.818758 -318.976175) (xy 53.776137 -318.951568)
			(xy 53.738016 -318.920443) (xy 53.705381 -318.883606) (xy 53.679078 -318.84201) (xy 53.659787 -318.796734)
			(xy 53.64801 -318.74895) (xy 53.64405 -318.699896) (xy 52.355242 -318.699896) (xy 52.354747 -318.724503)
			(xy 52.346852 -318.77308) (xy 52.331268 -318.819761) (xy 52.308397 -318.863338) (xy 52.278832 -318.902682)
			(xy 52.243339 -318.936774) (xy 52.202836 -318.96473) (xy 52.158374 -318.985828) (xy 52.111103 -318.99952)
			(xy 52.062248 -319.005452) (xy 52.013073 -319.003471) (xy 51.964854 -318.993627) (xy 51.918838 -318.976175)
			(xy 51.876217 -318.951568) (xy 51.838096 -318.920443) (xy 51.805461 -318.883606) (xy 51.779158 -318.84201)
			(xy 51.759867 -318.796734) (xy 51.74809 -318.74895) (xy 51.74413 -318.699896) (xy 50.455068 -318.699896)
			(xy 50.454573 -318.724503) (xy 50.446678 -318.77308) (xy 50.431094 -318.819761) (xy 50.408223 -318.863338)
			(xy 50.378658 -318.902682) (xy 50.343165 -318.936774) (xy 50.302662 -318.96473) (xy 50.2582 -318.985828)
			(xy 50.210929 -318.99952) (xy 50.162074 -319.005452) (xy 50.112899 -319.003471) (xy 50.06468 -318.993627)
			(xy 50.018664 -318.976175) (xy 49.976043 -318.951568) (xy 49.937922 -318.920443) (xy 49.905287 -318.883606)
			(xy 49.878984 -318.84201) (xy 49.859693 -318.796734) (xy 49.847916 -318.74895) (xy 49.843956 -318.699896)
			(xy 48.555148 -318.699896) (xy 48.554653 -318.724503) (xy 48.546758 -318.77308) (xy 48.531174 -318.819761)
			(xy 48.508303 -318.863338) (xy 48.478738 -318.902682) (xy 48.443245 -318.936774) (xy 48.402742 -318.96473)
			(xy 48.35828 -318.985828) (xy 48.311009 -318.99952) (xy 48.262154 -319.005452) (xy 48.212979 -319.003471)
			(xy 48.16476 -318.993627) (xy 48.118744 -318.976175) (xy 48.076123 -318.951568) (xy 48.038002 -318.920443)
			(xy 48.005367 -318.883606) (xy 47.979064 -318.84201) (xy 47.959773 -318.796734) (xy 47.947996 -318.74895)
			(xy 47.944036 -318.699896) (xy 46.655228 -318.699896) (xy 46.654733 -318.724503) (xy 46.646838 -318.77308)
			(xy 46.631254 -318.819761) (xy 46.608383 -318.863338) (xy 46.578818 -318.902682) (xy 46.543325 -318.936774)
			(xy 46.502822 -318.96473) (xy 46.45836 -318.985828) (xy 46.411089 -318.99952) (xy 46.362234 -319.005452)
			(xy 46.313059 -319.003471) (xy 46.26484 -318.993627) (xy 46.218824 -318.976175) (xy 46.176203 -318.951568)
			(xy 46.138082 -318.920443) (xy 46.105447 -318.883606) (xy 46.079144 -318.84201) (xy 46.059853 -318.796734)
			(xy 46.048076 -318.74895) (xy 46.044116 -318.699896) (xy 44.755054 -318.699896) (xy 44.754559 -318.724503)
			(xy 44.746664 -318.77308) (xy 44.73108 -318.819761) (xy 44.708209 -318.863338) (xy 44.678644 -318.902682)
			(xy 44.643151 -318.936774) (xy 44.602648 -318.96473) (xy 44.558186 -318.985828) (xy 44.510915 -318.99952)
			(xy 44.46206 -319.005452) (xy 44.412885 -319.003471) (xy 44.364666 -318.993627) (xy 44.31865 -318.976175)
			(xy 44.276029 -318.951568) (xy 44.237908 -318.920443) (xy 44.205273 -318.883606) (xy 44.17897 -318.84201)
			(xy 44.159679 -318.796734) (xy 44.147902 -318.74895) (xy 44.143942 -318.699896) (xy 42.855134 -318.699896)
			(xy 42.854639 -318.724503) (xy 42.846744 -318.77308) (xy 42.83116 -318.819761) (xy 42.808289 -318.863338)
			(xy 42.778724 -318.902682) (xy 42.743231 -318.936774) (xy 42.702728 -318.96473) (xy 42.658266 -318.985828)
			(xy 42.610995 -318.99952) (xy 42.56214 -319.005452) (xy 42.512965 -319.003471) (xy 42.464746 -318.993627)
			(xy 42.41873 -318.976175) (xy 42.376109 -318.951568) (xy 42.337988 -318.920443) (xy 42.305353 -318.883606)
			(xy 42.27905 -318.84201) (xy 42.259759 -318.796734) (xy 42.247982 -318.74895) (xy 42.244022 -318.699896)
			(xy 40.955214 -318.699896) (xy 40.954719 -318.724503) (xy 40.946824 -318.77308) (xy 40.93124 -318.819761)
			(xy 40.908369 -318.863338) (xy 40.878804 -318.902682) (xy 40.843311 -318.936774) (xy 40.802808 -318.96473)
			(xy 40.758346 -318.985828) (xy 40.711075 -318.99952) (xy 40.66222 -319.005452) (xy 40.613045 -319.003471)
			(xy 40.564826 -318.993627) (xy 40.51881 -318.976175) (xy 40.476189 -318.951568) (xy 40.438068 -318.920443)
			(xy 40.405433 -318.883606) (xy 40.37913 -318.84201) (xy 40.359839 -318.796734) (xy 40.348062 -318.74895)
			(xy 40.344102 -318.699896) (xy 39.055294 -318.699896) (xy 39.054799 -318.724503) (xy 39.046904 -318.77308)
			(xy 39.03132 -318.819761) (xy 39.008449 -318.863338) (xy 38.978884 -318.902682) (xy 38.943391 -318.936774)
			(xy 38.902888 -318.96473) (xy 38.858426 -318.985828) (xy 38.811155 -318.99952) (xy 38.7623 -319.005452)
			(xy 38.713125 -319.003471) (xy 38.664906 -318.993627) (xy 38.61889 -318.976175) (xy 38.576269 -318.951568)
			(xy 38.538148 -318.920443) (xy 38.505513 -318.883606) (xy 38.47921 -318.84201) (xy 38.459919 -318.796734)
			(xy 38.448142 -318.74895) (xy 38.444182 -318.699896) (xy 31.326643 -318.699896) (xy 31.399853 -318.756463)
			(xy 31.51239 -318.853497) (xy 31.619557 -318.956432) (xy 31.721044 -319.064971) (xy 31.816558 -319.1788)
			(xy 31.905825 -319.297593) (xy 31.988586 -319.421005) (xy 32.064604 -319.548683) (xy 32.133659 -319.680256)
			(xy 32.195552 -319.815347) (xy 32.250105 -319.953564) (xy 32.29716 -320.094511) (xy 32.336582 -320.237781)
			(xy 32.368256 -320.38296) (xy 32.392092 -320.529629) (xy 32.408021 -320.677367) (xy 32.415997 -320.825747)
			(xy 32.416496 -320.900044) (xy 86.882487 -320.900044) (xy 86.886476 -320.751504) (xy 86.898433 -320.603391)
			(xy 86.918323 -320.456134) (xy 86.946088 -320.310158) (xy 86.981649 -320.165881) (xy 87.024903 -320.023722)
			(xy 87.075725 -319.884089) (xy 87.133969 -319.747386) (xy 87.199467 -319.614006) (xy 87.27203 -319.484334)
			(xy 87.351448 -319.358744) (xy 87.437493 -319.237597) (xy 87.529917 -319.121244) (xy 87.628453 -319.01002)
			(xy 87.732817 -318.904245) (xy 87.842709 -318.804225) (xy 87.95781 -318.710247) (xy 88.07779 -318.622583)
			(xy 88.202303 -318.541486) (xy 88.330989 -318.467189) (xy 88.463478 -318.399907) (xy 88.599387 -318.339833)
			(xy 88.738325 -318.287141) (xy 88.879891 -318.241982) (xy 89.023677 -318.204487) (xy 89.169268 -318.174765)
			(xy 89.316244 -318.1529) (xy 89.464183 -318.138956) (xy 89.612656 -318.132972) (xy 89.761237 -318.134967)
			(xy 89.909496 -318.144935) (xy 90.057007 -318.162846) (xy 90.203343 -318.188649) (xy 90.348084 -318.222269)
			(xy 90.490811 -318.263611) (xy 90.631114 -318.312554) (xy 90.768587 -318.368957) (xy 90.902834 -318.432658)
			(xy 91.033469 -318.503474) (xy 91.160114 -318.581199) (xy 91.282404 -318.66561) (xy 91.399987 -318.756463)
			(xy 91.512524 -318.853497) (xy 91.619691 -318.956432) (xy 91.721178 -319.064971) (xy 91.816692 -319.1788)
			(xy 91.905959 -319.297593) (xy 91.98872 -319.421005) (xy 92.064738 -319.548683) (xy 92.133793 -319.680256)
			(xy 92.195686 -319.815347) (xy 92.250239 -319.953564) (xy 92.297294 -320.094511) (xy 92.336716 -320.237781)
			(xy 92.36839 -320.38296) (xy 92.392226 -320.529629) (xy 92.408155 -320.677367) (xy 92.416131 -320.825747)
			(xy 92.41663 -320.900044) (xy 142.982451 -320.900044) (xy 142.98644 -320.751504) (xy 142.998397 -320.603391)
			(xy 143.018287 -320.456134) (xy 143.046052 -320.310158) (xy 143.081613 -320.165881) (xy 143.124867 -320.023722)
			(xy 143.175689 -319.884089) (xy 143.233933 -319.747386) (xy 143.299431 -319.614006) (xy 143.371994 -319.484334)
			(xy 143.451412 -319.358744) (xy 143.537457 -319.237597) (xy 143.629881 -319.121244) (xy 143.728417 -319.01002)
			(xy 143.832781 -318.904245) (xy 143.942673 -318.804225) (xy 144.057774 -318.710247) (xy 144.177754 -318.622583)
			(xy 144.302267 -318.541486) (xy 144.430953 -318.467189) (xy 144.563442 -318.399907) (xy 144.699351 -318.339833)
			(xy 144.838289 -318.287141) (xy 144.979855 -318.241982) (xy 145.123641 -318.204487) (xy 145.269232 -318.174765)
			(xy 145.416208 -318.1529) (xy 145.564147 -318.138956) (xy 145.71262 -318.132972) (xy 145.861201 -318.134967)
			(xy 146.00946 -318.144935) (xy 146.156971 -318.162846) (xy 146.303307 -318.188649) (xy 146.448048 -318.222269)
			(xy 146.590775 -318.263611) (xy 146.731078 -318.312554) (xy 146.868551 -318.368957) (xy 147.002798 -318.432658)
			(xy 147.133433 -318.503474) (xy 147.260078 -318.581199) (xy 147.382368 -318.66561) (xy 147.426741 -318.699896)
			(xy 154.54428 -318.699896) (xy 154.54824 -318.650842) (xy 154.560017 -318.603058) (xy 154.579308 -318.557782)
			(xy 154.605611 -318.516186) (xy 154.638246 -318.479349) (xy 154.676367 -318.448224) (xy 154.718988 -318.423617)
			(xy 154.765004 -318.406165) (xy 154.813223 -318.396321) (xy 154.862398 -318.39434) (xy 154.911253 -318.400272)
			(xy 154.958524 -318.413964) (xy 155.002986 -318.435062) (xy 155.043489 -318.463018) (xy 155.078982 -318.49711)
			(xy 155.108547 -318.536454) (xy 155.131418 -318.580031) (xy 155.147002 -318.626712) (xy 155.154897 -318.675289)
			(xy 155.155392 -318.699896) (xy 156.4442 -318.699896) (xy 156.44816 -318.650842) (xy 156.459937 -318.603058)
			(xy 156.479228 -318.557782) (xy 156.505531 -318.516186) (xy 156.538166 -318.479349) (xy 156.576287 -318.448224)
			(xy 156.618908 -318.423617) (xy 156.664924 -318.406165) (xy 156.713143 -318.396321) (xy 156.762318 -318.39434)
			(xy 156.811173 -318.400272) (xy 156.858444 -318.413964) (xy 156.902906 -318.435062) (xy 156.943409 -318.463018)
			(xy 156.978902 -318.49711) (xy 157.008467 -318.536454) (xy 157.031338 -318.580031) (xy 157.046922 -318.626712)
			(xy 157.054817 -318.675289) (xy 157.055312 -318.699896) (xy 158.34412 -318.699896) (xy 158.34808 -318.650842)
			(xy 158.359857 -318.603058) (xy 158.379148 -318.557782) (xy 158.405451 -318.516186) (xy 158.438086 -318.479349)
			(xy 158.476207 -318.448224) (xy 158.518828 -318.423617) (xy 158.564844 -318.406165) (xy 158.613063 -318.396321)
			(xy 158.662238 -318.39434) (xy 158.711093 -318.400272) (xy 158.758364 -318.413964) (xy 158.802826 -318.435062)
			(xy 158.843329 -318.463018) (xy 158.878822 -318.49711) (xy 158.908387 -318.536454) (xy 158.931258 -318.580031)
			(xy 158.946842 -318.626712) (xy 158.954737 -318.675289) (xy 158.955232 -318.699896) (xy 160.24404 -318.699896)
			(xy 160.248 -318.650842) (xy 160.259777 -318.603058) (xy 160.279068 -318.557782) (xy 160.305371 -318.516186)
			(xy 160.338006 -318.479349) (xy 160.376127 -318.448224) (xy 160.418748 -318.423617) (xy 160.464764 -318.406165)
			(xy 160.512983 -318.396321) (xy 160.562158 -318.39434) (xy 160.611013 -318.400272) (xy 160.658284 -318.413964)
			(xy 160.702746 -318.435062) (xy 160.743249 -318.463018) (xy 160.778742 -318.49711) (xy 160.808307 -318.536454)
			(xy 160.831178 -318.580031) (xy 160.846762 -318.626712) (xy 160.854657 -318.675289) (xy 160.855152 -318.699896)
			(xy 162.144214 -318.699896) (xy 162.148174 -318.650842) (xy 162.159951 -318.603058) (xy 162.179242 -318.557782)
			(xy 162.205545 -318.516186) (xy 162.23818 -318.479349) (xy 162.276301 -318.448224) (xy 162.318922 -318.423617)
			(xy 162.364938 -318.406165) (xy 162.413157 -318.396321) (xy 162.462332 -318.39434) (xy 162.511187 -318.400272)
			(xy 162.558458 -318.413964) (xy 162.60292 -318.435062) (xy 162.643423 -318.463018) (xy 162.678916 -318.49711)
			(xy 162.708481 -318.536454) (xy 162.731352 -318.580031) (xy 162.746936 -318.626712) (xy 162.754831 -318.675289)
			(xy 162.755326 -318.699896) (xy 164.044134 -318.699896) (xy 164.048094 -318.650842) (xy 164.059871 -318.603058)
			(xy 164.079162 -318.557782) (xy 164.105465 -318.516186) (xy 164.1381 -318.479349) (xy 164.176221 -318.448224)
			(xy 164.218842 -318.423617) (xy 164.264858 -318.406165) (xy 164.313077 -318.396321) (xy 164.362252 -318.39434)
			(xy 164.411107 -318.400272) (xy 164.458378 -318.413964) (xy 164.50284 -318.435062) (xy 164.543343 -318.463018)
			(xy 164.578836 -318.49711) (xy 164.608401 -318.536454) (xy 164.631272 -318.580031) (xy 164.646856 -318.626712)
			(xy 164.654751 -318.675289) (xy 164.655246 -318.699896) (xy 165.944054 -318.699896) (xy 165.948014 -318.650842)
			(xy 165.959791 -318.603058) (xy 165.979082 -318.557782) (xy 166.005385 -318.516186) (xy 166.03802 -318.479349)
			(xy 166.076141 -318.448224) (xy 166.118762 -318.423617) (xy 166.164778 -318.406165) (xy 166.212997 -318.396321)
			(xy 166.262172 -318.39434) (xy 166.311027 -318.400272) (xy 166.358298 -318.413964) (xy 166.40276 -318.435062)
			(xy 166.443263 -318.463018) (xy 166.478756 -318.49711) (xy 166.508321 -318.536454) (xy 166.531192 -318.580031)
			(xy 166.546776 -318.626712) (xy 166.554671 -318.675289) (xy 166.555166 -318.699896) (xy 167.844228 -318.699896)
			(xy 167.848188 -318.650842) (xy 167.859965 -318.603058) (xy 167.879256 -318.557782) (xy 167.905559 -318.516186)
			(xy 167.938194 -318.479349) (xy 167.976315 -318.448224) (xy 168.018936 -318.423617) (xy 168.064952 -318.406165)
			(xy 168.113171 -318.396321) (xy 168.162346 -318.39434) (xy 168.211201 -318.400272) (xy 168.258472 -318.413964)
			(xy 168.302934 -318.435062) (xy 168.343437 -318.463018) (xy 168.37893 -318.49711) (xy 168.408495 -318.536454)
			(xy 168.431366 -318.580031) (xy 168.44695 -318.626712) (xy 168.454845 -318.675289) (xy 168.45534 -318.699896)
			(xy 169.744148 -318.699896) (xy 169.748108 -318.650842) (xy 169.759885 -318.603058) (xy 169.779176 -318.557782)
			(xy 169.805479 -318.516186) (xy 169.838114 -318.479349) (xy 169.876235 -318.448224) (xy 169.918856 -318.423617)
			(xy 169.964872 -318.406165) (xy 170.013091 -318.396321) (xy 170.062266 -318.39434) (xy 170.111121 -318.400272)
			(xy 170.158392 -318.413964) (xy 170.202854 -318.435062) (xy 170.243357 -318.463018) (xy 170.27885 -318.49711)
			(xy 170.308415 -318.536454) (xy 170.331286 -318.580031) (xy 170.34687 -318.626712) (xy 170.354765 -318.675289)
			(xy 170.35526 -318.699896) (xy 171.644068 -318.699896) (xy 171.648028 -318.650842) (xy 171.659805 -318.603058)
			(xy 171.679096 -318.557782) (xy 171.705399 -318.516186) (xy 171.738034 -318.479349) (xy 171.776155 -318.448224)
			(xy 171.818776 -318.423617) (xy 171.864792 -318.406165) (xy 171.913011 -318.396321) (xy 171.962186 -318.39434)
			(xy 172.011041 -318.400272) (xy 172.058312 -318.413964) (xy 172.102774 -318.435062) (xy 172.143277 -318.463018)
			(xy 172.17877 -318.49711) (xy 172.208335 -318.536454) (xy 172.231206 -318.580031) (xy 172.24679 -318.626712)
			(xy 172.254685 -318.675289) (xy 172.25518 -318.699896) (xy 173.544242 -318.699896) (xy 173.548202 -318.650842)
			(xy 173.559979 -318.603058) (xy 173.57927 -318.557782) (xy 173.605573 -318.516186) (xy 173.638208 -318.479349)
			(xy 173.676329 -318.448224) (xy 173.71895 -318.423617) (xy 173.764966 -318.406165) (xy 173.813185 -318.396321)
			(xy 173.86236 -318.39434) (xy 173.911215 -318.400272) (xy 173.958486 -318.413964) (xy 174.002948 -318.435062)
			(xy 174.043451 -318.463018) (xy 174.078944 -318.49711) (xy 174.108509 -318.536454) (xy 174.13138 -318.580031)
			(xy 174.146964 -318.626712) (xy 174.154859 -318.675289) (xy 174.155354 -318.699896) (xy 175.444162 -318.699896)
			(xy 175.448122 -318.650842) (xy 175.459899 -318.603058) (xy 175.47919 -318.557782) (xy 175.505493 -318.516186)
			(xy 175.538128 -318.479349) (xy 175.576249 -318.448224) (xy 175.61887 -318.423617) (xy 175.664886 -318.406165)
			(xy 175.713105 -318.396321) (xy 175.76228 -318.39434) (xy 175.811135 -318.400272) (xy 175.858406 -318.413964)
			(xy 175.902868 -318.435062) (xy 175.943371 -318.463018) (xy 175.978864 -318.49711) (xy 176.008429 -318.536454)
			(xy 176.0313 -318.580031) (xy 176.046884 -318.626712) (xy 176.054779 -318.675289) (xy 176.055274 -318.699896)
			(xy 177.344082 -318.699896) (xy 177.348042 -318.650842) (xy 177.359819 -318.603058) (xy 177.37911 -318.557782)
			(xy 177.405413 -318.516186) (xy 177.438048 -318.479349) (xy 177.476169 -318.448224) (xy 177.51879 -318.423617)
			(xy 177.564806 -318.406165) (xy 177.613025 -318.396321) (xy 177.6622 -318.39434) (xy 177.711055 -318.400272)
			(xy 177.758326 -318.413964) (xy 177.802788 -318.435062) (xy 177.843291 -318.463018) (xy 177.878784 -318.49711)
			(xy 177.908349 -318.536454) (xy 177.93122 -318.580031) (xy 177.946804 -318.626712) (xy 177.954699 -318.675289)
			(xy 177.955194 -318.699896) (xy 179.244256 -318.699896) (xy 179.248216 -318.650842) (xy 179.259993 -318.603058)
			(xy 179.279284 -318.557782) (xy 179.305587 -318.516186) (xy 179.338222 -318.479349) (xy 179.376343 -318.448224)
			(xy 179.418964 -318.423617) (xy 179.46498 -318.406165) (xy 179.513199 -318.396321) (xy 179.562374 -318.39434)
			(xy 179.611229 -318.400272) (xy 179.6585 -318.413964) (xy 179.702962 -318.435062) (xy 179.743465 -318.463018)
			(xy 179.778958 -318.49711) (xy 179.808523 -318.536454) (xy 179.831394 -318.580031) (xy 179.846978 -318.626712)
			(xy 179.854873 -318.675289) (xy 179.855368 -318.699896) (xy 181.144176 -318.699896) (xy 181.148136 -318.650842)
			(xy 181.159913 -318.603058) (xy 181.179204 -318.557782) (xy 181.205507 -318.516186) (xy 181.238142 -318.479349)
			(xy 181.276263 -318.448224) (xy 181.318884 -318.423617) (xy 181.3649 -318.406165) (xy 181.413119 -318.396321)
			(xy 181.462294 -318.39434) (xy 181.511149 -318.400272) (xy 181.55842 -318.413964) (xy 181.602882 -318.435062)
			(xy 181.643385 -318.463018) (xy 181.678878 -318.49711) (xy 181.708443 -318.536454) (xy 181.731314 -318.580031)
			(xy 181.746898 -318.626712) (xy 181.754793 -318.675289) (xy 181.755288 -318.699896) (xy 183.044096 -318.699896)
			(xy 183.048056 -318.650842) (xy 183.059833 -318.603058) (xy 183.079124 -318.557782) (xy 183.105427 -318.516186)
			(xy 183.138062 -318.479349) (xy 183.176183 -318.448224) (xy 183.218804 -318.423617) (xy 183.26482 -318.406165)
			(xy 183.313039 -318.396321) (xy 183.362214 -318.39434) (xy 183.411069 -318.400272) (xy 183.45834 -318.413964)
			(xy 183.502802 -318.435062) (xy 183.543305 -318.463018) (xy 183.578798 -318.49711) (xy 183.608363 -318.536454)
			(xy 183.631234 -318.580031) (xy 183.646818 -318.626712) (xy 183.654713 -318.675289) (xy 183.655208 -318.699896)
			(xy 184.94427 -318.699896) (xy 184.94823 -318.650842) (xy 184.960007 -318.603058) (xy 184.979298 -318.557782)
			(xy 185.005601 -318.516186) (xy 185.038236 -318.479349) (xy 185.076357 -318.448224) (xy 185.118978 -318.423617)
			(xy 185.164994 -318.406165) (xy 185.213213 -318.396321) (xy 185.262388 -318.39434) (xy 185.311243 -318.400272)
			(xy 185.358514 -318.413964) (xy 185.402976 -318.435062) (xy 185.443479 -318.463018) (xy 185.478972 -318.49711)
			(xy 185.508537 -318.536454) (xy 185.531408 -318.580031) (xy 185.546992 -318.626712) (xy 185.554887 -318.675289)
			(xy 185.555382 -318.699896) (xy 186.84419 -318.699896) (xy 186.84815 -318.650842) (xy 186.859927 -318.603058)
			(xy 186.879218 -318.557782) (xy 186.905521 -318.516186) (xy 186.938156 -318.479349) (xy 186.976277 -318.448224)
			(xy 187.018898 -318.423617) (xy 187.064914 -318.406165) (xy 187.113133 -318.396321) (xy 187.162308 -318.39434)
			(xy 187.211163 -318.400272) (xy 187.258434 -318.413964) (xy 187.302896 -318.435062) (xy 187.343399 -318.463018)
			(xy 187.378892 -318.49711) (xy 187.408457 -318.536454) (xy 187.431328 -318.580031) (xy 187.446912 -318.626712)
			(xy 187.454807 -318.675289) (xy 187.455302 -318.699896) (xy 188.74411 -318.699896) (xy 188.74807 -318.650842)
			(xy 188.759847 -318.603058) (xy 188.779138 -318.557782) (xy 188.805441 -318.516186) (xy 188.838076 -318.479349)
			(xy 188.876197 -318.448224) (xy 188.918818 -318.423617) (xy 188.964834 -318.406165) (xy 189.013053 -318.396321)
			(xy 189.062228 -318.39434) (xy 189.111083 -318.400272) (xy 189.158354 -318.413964) (xy 189.202816 -318.435062)
			(xy 189.243319 -318.463018) (xy 189.278812 -318.49711) (xy 189.308377 -318.536454) (xy 189.331248 -318.580031)
			(xy 189.346832 -318.626712) (xy 189.354727 -318.675289) (xy 189.355222 -318.699896) (xy 190.644284 -318.699896)
			(xy 190.648244 -318.650842) (xy 190.660021 -318.603058) (xy 190.679312 -318.557782) (xy 190.705615 -318.516186)
			(xy 190.73825 -318.479349) (xy 190.776371 -318.448224) (xy 190.818992 -318.423617) (xy 190.865008 -318.406165)
			(xy 190.913227 -318.396321) (xy 190.962402 -318.39434) (xy 191.011257 -318.400272) (xy 191.058528 -318.413964)
			(xy 191.10299 -318.435062) (xy 191.143493 -318.463018) (xy 191.178986 -318.49711) (xy 191.208551 -318.536454)
			(xy 191.231422 -318.580031) (xy 191.247006 -318.626712) (xy 191.254901 -318.675289) (xy 191.255396 -318.699896)
			(xy 192.544204 -318.699896) (xy 192.548164 -318.650842) (xy 192.559941 -318.603058) (xy 192.579232 -318.557782)
			(xy 192.605535 -318.516186) (xy 192.63817 -318.479349) (xy 192.676291 -318.448224) (xy 192.718912 -318.423617)
			(xy 192.764928 -318.406165) (xy 192.813147 -318.396321) (xy 192.862322 -318.39434) (xy 192.911177 -318.400272)
			(xy 192.958448 -318.413964) (xy 193.00291 -318.435062) (xy 193.043413 -318.463018) (xy 193.078906 -318.49711)
			(xy 193.108471 -318.536454) (xy 193.131342 -318.580031) (xy 193.146926 -318.626712) (xy 193.154821 -318.675289)
			(xy 193.155316 -318.699896) (xy 194.444124 -318.699896) (xy 194.448084 -318.650842) (xy 194.459861 -318.603058)
			(xy 194.479152 -318.557782) (xy 194.505455 -318.516186) (xy 194.53809 -318.479349) (xy 194.576211 -318.448224)
			(xy 194.618832 -318.423617) (xy 194.664848 -318.406165) (xy 194.713067 -318.396321) (xy 194.762242 -318.39434)
			(xy 194.811097 -318.400272) (xy 194.858368 -318.413964) (xy 194.90283 -318.435062) (xy 194.943333 -318.463018)
			(xy 194.978826 -318.49711) (xy 195.008391 -318.536454) (xy 195.031262 -318.580031) (xy 195.046846 -318.626712)
			(xy 195.054741 -318.675289) (xy 195.055236 -318.699896) (xy 196.344044 -318.699896) (xy 196.348004 -318.650842)
			(xy 196.359781 -318.603058) (xy 196.379072 -318.557782) (xy 196.405375 -318.516186) (xy 196.43801 -318.479349)
			(xy 196.476131 -318.448224) (xy 196.518752 -318.423617) (xy 196.564768 -318.406165) (xy 196.612987 -318.396321)
			(xy 196.662162 -318.39434) (xy 196.711017 -318.400272) (xy 196.758288 -318.413964) (xy 196.80275 -318.435062)
			(xy 196.843253 -318.463018) (xy 196.878746 -318.49711) (xy 196.908311 -318.536454) (xy 196.931182 -318.580031)
			(xy 196.946766 -318.626712) (xy 196.954661 -318.675289) (xy 196.955156 -318.699896) (xy 196.954661 -318.724503)
			(xy 196.946766 -318.77308) (xy 196.931182 -318.819761) (xy 196.908311 -318.863338) (xy 196.878746 -318.902682)
			(xy 196.843253 -318.936774) (xy 196.80275 -318.96473) (xy 196.758288 -318.985828) (xy 196.711017 -318.99952)
			(xy 196.662162 -319.005452) (xy 196.612987 -319.003471) (xy 196.564768 -318.993627) (xy 196.518752 -318.976175)
			(xy 196.476131 -318.951568) (xy 196.43801 -318.920443) (xy 196.405375 -318.883606) (xy 196.379072 -318.84201)
			(xy 196.359781 -318.796734) (xy 196.348004 -318.74895) (xy 196.344044 -318.699896) (xy 195.055236 -318.699896)
			(xy 195.054741 -318.724503) (xy 195.046846 -318.77308) (xy 195.031262 -318.819761) (xy 195.008391 -318.863338)
			(xy 194.978826 -318.902682) (xy 194.943333 -318.936774) (xy 194.90283 -318.96473) (xy 194.858368 -318.985828)
			(xy 194.811097 -318.99952) (xy 194.762242 -319.005452) (xy 194.713067 -319.003471) (xy 194.664848 -318.993627)
			(xy 194.618832 -318.976175) (xy 194.576211 -318.951568) (xy 194.53809 -318.920443) (xy 194.505455 -318.883606)
			(xy 194.479152 -318.84201) (xy 194.459861 -318.796734) (xy 194.448084 -318.74895) (xy 194.444124 -318.699896)
			(xy 193.155316 -318.699896) (xy 193.154821 -318.724503) (xy 193.146926 -318.77308) (xy 193.131342 -318.819761)
			(xy 193.108471 -318.863338) (xy 193.078906 -318.902682) (xy 193.043413 -318.936774) (xy 193.00291 -318.96473)
			(xy 192.958448 -318.985828) (xy 192.911177 -318.99952) (xy 192.862322 -319.005452) (xy 192.813147 -319.003471)
			(xy 192.764928 -318.993627) (xy 192.718912 -318.976175) (xy 192.676291 -318.951568) (xy 192.63817 -318.920443)
			(xy 192.605535 -318.883606) (xy 192.579232 -318.84201) (xy 192.559941 -318.796734) (xy 192.548164 -318.74895)
			(xy 192.544204 -318.699896) (xy 191.255396 -318.699896) (xy 191.254901 -318.724503) (xy 191.247006 -318.77308)
			(xy 191.231422 -318.819761) (xy 191.208551 -318.863338) (xy 191.178986 -318.902682) (xy 191.143493 -318.936774)
			(xy 191.10299 -318.96473) (xy 191.058528 -318.985828) (xy 191.011257 -318.99952) (xy 190.962402 -319.005452)
			(xy 190.913227 -319.003471) (xy 190.865008 -318.993627) (xy 190.818992 -318.976175) (xy 190.776371 -318.951568)
			(xy 190.73825 -318.920443) (xy 190.705615 -318.883606) (xy 190.679312 -318.84201) (xy 190.660021 -318.796734)
			(xy 190.648244 -318.74895) (xy 190.644284 -318.699896) (xy 189.355222 -318.699896) (xy 189.354727 -318.724503)
			(xy 189.346832 -318.77308) (xy 189.331248 -318.819761) (xy 189.308377 -318.863338) (xy 189.278812 -318.902682)
			(xy 189.243319 -318.936774) (xy 189.202816 -318.96473) (xy 189.158354 -318.985828) (xy 189.111083 -318.99952)
			(xy 189.062228 -319.005452) (xy 189.013053 -319.003471) (xy 188.964834 -318.993627) (xy 188.918818 -318.976175)
			(xy 188.876197 -318.951568) (xy 188.838076 -318.920443) (xy 188.805441 -318.883606) (xy 188.779138 -318.84201)
			(xy 188.759847 -318.796734) (xy 188.74807 -318.74895) (xy 188.74411 -318.699896) (xy 187.455302 -318.699896)
			(xy 187.454807 -318.724503) (xy 187.446912 -318.77308) (xy 187.431328 -318.819761) (xy 187.408457 -318.863338)
			(xy 187.378892 -318.902682) (xy 187.343399 -318.936774) (xy 187.302896 -318.96473) (xy 187.258434 -318.985828)
			(xy 187.211163 -318.99952) (xy 187.162308 -319.005452) (xy 187.113133 -319.003471) (xy 187.064914 -318.993627)
			(xy 187.018898 -318.976175) (xy 186.976277 -318.951568) (xy 186.938156 -318.920443) (xy 186.905521 -318.883606)
			(xy 186.879218 -318.84201) (xy 186.859927 -318.796734) (xy 186.84815 -318.74895) (xy 186.84419 -318.699896)
			(xy 185.555382 -318.699896) (xy 185.554887 -318.724503) (xy 185.546992 -318.77308) (xy 185.531408 -318.819761)
			(xy 185.508537 -318.863338) (xy 185.478972 -318.902682) (xy 185.443479 -318.936774) (xy 185.402976 -318.96473)
			(xy 185.358514 -318.985828) (xy 185.311243 -318.99952) (xy 185.262388 -319.005452) (xy 185.213213 -319.003471)
			(xy 185.164994 -318.993627) (xy 185.118978 -318.976175) (xy 185.076357 -318.951568) (xy 185.038236 -318.920443)
			(xy 185.005601 -318.883606) (xy 184.979298 -318.84201) (xy 184.960007 -318.796734) (xy 184.94823 -318.74895)
			(xy 184.94427 -318.699896) (xy 183.655208 -318.699896) (xy 183.654713 -318.724503) (xy 183.646818 -318.77308)
			(xy 183.631234 -318.819761) (xy 183.608363 -318.863338) (xy 183.578798 -318.902682) (xy 183.543305 -318.936774)
			(xy 183.502802 -318.96473) (xy 183.45834 -318.985828) (xy 183.411069 -318.99952) (xy 183.362214 -319.005452)
			(xy 183.313039 -319.003471) (xy 183.26482 -318.993627) (xy 183.218804 -318.976175) (xy 183.176183 -318.951568)
			(xy 183.138062 -318.920443) (xy 183.105427 -318.883606) (xy 183.079124 -318.84201) (xy 183.059833 -318.796734)
			(xy 183.048056 -318.74895) (xy 183.044096 -318.699896) (xy 181.755288 -318.699896) (xy 181.754793 -318.724503)
			(xy 181.746898 -318.77308) (xy 181.731314 -318.819761) (xy 181.708443 -318.863338) (xy 181.678878 -318.902682)
			(xy 181.643385 -318.936774) (xy 181.602882 -318.96473) (xy 181.55842 -318.985828) (xy 181.511149 -318.99952)
			(xy 181.462294 -319.005452) (xy 181.413119 -319.003471) (xy 181.3649 -318.993627) (xy 181.318884 -318.976175)
			(xy 181.276263 -318.951568) (xy 181.238142 -318.920443) (xy 181.205507 -318.883606) (xy 181.179204 -318.84201)
			(xy 181.159913 -318.796734) (xy 181.148136 -318.74895) (xy 181.144176 -318.699896) (xy 179.855368 -318.699896)
			(xy 179.854873 -318.724503) (xy 179.846978 -318.77308) (xy 179.831394 -318.819761) (xy 179.808523 -318.863338)
			(xy 179.778958 -318.902682) (xy 179.743465 -318.936774) (xy 179.702962 -318.96473) (xy 179.6585 -318.985828)
			(xy 179.611229 -318.99952) (xy 179.562374 -319.005452) (xy 179.513199 -319.003471) (xy 179.46498 -318.993627)
			(xy 179.418964 -318.976175) (xy 179.376343 -318.951568) (xy 179.338222 -318.920443) (xy 179.305587 -318.883606)
			(xy 179.279284 -318.84201) (xy 179.259993 -318.796734) (xy 179.248216 -318.74895) (xy 179.244256 -318.699896)
			(xy 177.955194 -318.699896) (xy 177.954699 -318.724503) (xy 177.946804 -318.77308) (xy 177.93122 -318.819761)
			(xy 177.908349 -318.863338) (xy 177.878784 -318.902682) (xy 177.843291 -318.936774) (xy 177.802788 -318.96473)
			(xy 177.758326 -318.985828) (xy 177.711055 -318.99952) (xy 177.6622 -319.005452) (xy 177.613025 -319.003471)
			(xy 177.564806 -318.993627) (xy 177.51879 -318.976175) (xy 177.476169 -318.951568) (xy 177.438048 -318.920443)
			(xy 177.405413 -318.883606) (xy 177.37911 -318.84201) (xy 177.359819 -318.796734) (xy 177.348042 -318.74895)
			(xy 177.344082 -318.699896) (xy 176.055274 -318.699896) (xy 176.054779 -318.724503) (xy 176.046884 -318.77308)
			(xy 176.0313 -318.819761) (xy 176.008429 -318.863338) (xy 175.978864 -318.902682) (xy 175.943371 -318.936774)
			(xy 175.902868 -318.96473) (xy 175.858406 -318.985828) (xy 175.811135 -318.99952) (xy 175.76228 -319.005452)
			(xy 175.713105 -319.003471) (xy 175.664886 -318.993627) (xy 175.61887 -318.976175) (xy 175.576249 -318.951568)
			(xy 175.538128 -318.920443) (xy 175.505493 -318.883606) (xy 175.47919 -318.84201) (xy 175.459899 -318.796734)
			(xy 175.448122 -318.74895) (xy 175.444162 -318.699896) (xy 174.155354 -318.699896) (xy 174.154859 -318.724503)
			(xy 174.146964 -318.77308) (xy 174.13138 -318.819761) (xy 174.108509 -318.863338) (xy 174.078944 -318.902682)
			(xy 174.043451 -318.936774) (xy 174.002948 -318.96473) (xy 173.958486 -318.985828) (xy 173.911215 -318.99952)
			(xy 173.86236 -319.005452) (xy 173.813185 -319.003471) (xy 173.764966 -318.993627) (xy 173.71895 -318.976175)
			(xy 173.676329 -318.951568) (xy 173.638208 -318.920443) (xy 173.605573 -318.883606) (xy 173.57927 -318.84201)
			(xy 173.559979 -318.796734) (xy 173.548202 -318.74895) (xy 173.544242 -318.699896) (xy 172.25518 -318.699896)
			(xy 172.254685 -318.724503) (xy 172.24679 -318.77308) (xy 172.231206 -318.819761) (xy 172.208335 -318.863338)
			(xy 172.17877 -318.902682) (xy 172.143277 -318.936774) (xy 172.102774 -318.96473) (xy 172.058312 -318.985828)
			(xy 172.011041 -318.99952) (xy 171.962186 -319.005452) (xy 171.913011 -319.003471) (xy 171.864792 -318.993627)
			(xy 171.818776 -318.976175) (xy 171.776155 -318.951568) (xy 171.738034 -318.920443) (xy 171.705399 -318.883606)
			(xy 171.679096 -318.84201) (xy 171.659805 -318.796734) (xy 171.648028 -318.74895) (xy 171.644068 -318.699896)
			(xy 170.35526 -318.699896) (xy 170.354765 -318.724503) (xy 170.34687 -318.77308) (xy 170.331286 -318.819761)
			(xy 170.308415 -318.863338) (xy 170.27885 -318.902682) (xy 170.243357 -318.936774) (xy 170.202854 -318.96473)
			(xy 170.158392 -318.985828) (xy 170.111121 -318.99952) (xy 170.062266 -319.005452) (xy 170.013091 -319.003471)
			(xy 169.964872 -318.993627) (xy 169.918856 -318.976175) (xy 169.876235 -318.951568) (xy 169.838114 -318.920443)
			(xy 169.805479 -318.883606) (xy 169.779176 -318.84201) (xy 169.759885 -318.796734) (xy 169.748108 -318.74895)
			(xy 169.744148 -318.699896) (xy 168.45534 -318.699896) (xy 168.454845 -318.724503) (xy 168.44695 -318.77308)
			(xy 168.431366 -318.819761) (xy 168.408495 -318.863338) (xy 168.37893 -318.902682) (xy 168.343437 -318.936774)
			(xy 168.302934 -318.96473) (xy 168.258472 -318.985828) (xy 168.211201 -318.99952) (xy 168.162346 -319.005452)
			(xy 168.113171 -319.003471) (xy 168.064952 -318.993627) (xy 168.018936 -318.976175) (xy 167.976315 -318.951568)
			(xy 167.938194 -318.920443) (xy 167.905559 -318.883606) (xy 167.879256 -318.84201) (xy 167.859965 -318.796734)
			(xy 167.848188 -318.74895) (xy 167.844228 -318.699896) (xy 166.555166 -318.699896) (xy 166.554671 -318.724503)
			(xy 166.546776 -318.77308) (xy 166.531192 -318.819761) (xy 166.508321 -318.863338) (xy 166.478756 -318.902682)
			(xy 166.443263 -318.936774) (xy 166.40276 -318.96473) (xy 166.358298 -318.985828) (xy 166.311027 -318.99952)
			(xy 166.262172 -319.005452) (xy 166.212997 -319.003471) (xy 166.164778 -318.993627) (xy 166.118762 -318.976175)
			(xy 166.076141 -318.951568) (xy 166.03802 -318.920443) (xy 166.005385 -318.883606) (xy 165.979082 -318.84201)
			(xy 165.959791 -318.796734) (xy 165.948014 -318.74895) (xy 165.944054 -318.699896) (xy 164.655246 -318.699896)
			(xy 164.654751 -318.724503) (xy 164.646856 -318.77308) (xy 164.631272 -318.819761) (xy 164.608401 -318.863338)
			(xy 164.578836 -318.902682) (xy 164.543343 -318.936774) (xy 164.50284 -318.96473) (xy 164.458378 -318.985828)
			(xy 164.411107 -318.99952) (xy 164.362252 -319.005452) (xy 164.313077 -319.003471) (xy 164.264858 -318.993627)
			(xy 164.218842 -318.976175) (xy 164.176221 -318.951568) (xy 164.1381 -318.920443) (xy 164.105465 -318.883606)
			(xy 164.079162 -318.84201) (xy 164.059871 -318.796734) (xy 164.048094 -318.74895) (xy 164.044134 -318.699896)
			(xy 162.755326 -318.699896) (xy 162.754831 -318.724503) (xy 162.746936 -318.77308) (xy 162.731352 -318.819761)
			(xy 162.708481 -318.863338) (xy 162.678916 -318.902682) (xy 162.643423 -318.936774) (xy 162.60292 -318.96473)
			(xy 162.558458 -318.985828) (xy 162.511187 -318.99952) (xy 162.462332 -319.005452) (xy 162.413157 -319.003471)
			(xy 162.364938 -318.993627) (xy 162.318922 -318.976175) (xy 162.276301 -318.951568) (xy 162.23818 -318.920443)
			(xy 162.205545 -318.883606) (xy 162.179242 -318.84201) (xy 162.159951 -318.796734) (xy 162.148174 -318.74895)
			(xy 162.144214 -318.699896) (xy 160.855152 -318.699896) (xy 160.854657 -318.724503) (xy 160.846762 -318.77308)
			(xy 160.831178 -318.819761) (xy 160.808307 -318.863338) (xy 160.778742 -318.902682) (xy 160.743249 -318.936774)
			(xy 160.702746 -318.96473) (xy 160.658284 -318.985828) (xy 160.611013 -318.99952) (xy 160.562158 -319.005452)
			(xy 160.512983 -319.003471) (xy 160.464764 -318.993627) (xy 160.418748 -318.976175) (xy 160.376127 -318.951568)
			(xy 160.338006 -318.920443) (xy 160.305371 -318.883606) (xy 160.279068 -318.84201) (xy 160.259777 -318.796734)
			(xy 160.248 -318.74895) (xy 160.24404 -318.699896) (xy 158.955232 -318.699896) (xy 158.954737 -318.724503)
			(xy 158.946842 -318.77308) (xy 158.931258 -318.819761) (xy 158.908387 -318.863338) (xy 158.878822 -318.902682)
			(xy 158.843329 -318.936774) (xy 158.802826 -318.96473) (xy 158.758364 -318.985828) (xy 158.711093 -318.99952)
			(xy 158.662238 -319.005452) (xy 158.613063 -319.003471) (xy 158.564844 -318.993627) (xy 158.518828 -318.976175)
			(xy 158.476207 -318.951568) (xy 158.438086 -318.920443) (xy 158.405451 -318.883606) (xy 158.379148 -318.84201)
			(xy 158.359857 -318.796734) (xy 158.34808 -318.74895) (xy 158.34412 -318.699896) (xy 157.055312 -318.699896)
			(xy 157.054817 -318.724503) (xy 157.046922 -318.77308) (xy 157.031338 -318.819761) (xy 157.008467 -318.863338)
			(xy 156.978902 -318.902682) (xy 156.943409 -318.936774) (xy 156.902906 -318.96473) (xy 156.858444 -318.985828)
			(xy 156.811173 -318.99952) (xy 156.762318 -319.005452) (xy 156.713143 -319.003471) (xy 156.664924 -318.993627)
			(xy 156.618908 -318.976175) (xy 156.576287 -318.951568) (xy 156.538166 -318.920443) (xy 156.505531 -318.883606)
			(xy 156.479228 -318.84201) (xy 156.459937 -318.796734) (xy 156.44816 -318.74895) (xy 156.4442 -318.699896)
			(xy 155.155392 -318.699896) (xy 155.154897 -318.724503) (xy 155.147002 -318.77308) (xy 155.131418 -318.819761)
			(xy 155.108547 -318.863338) (xy 155.078982 -318.902682) (xy 155.043489 -318.936774) (xy 155.002986 -318.96473)
			(xy 154.958524 -318.985828) (xy 154.911253 -318.99952) (xy 154.862398 -319.005452) (xy 154.813223 -319.003471)
			(xy 154.765004 -318.993627) (xy 154.718988 -318.976175) (xy 154.676367 -318.951568) (xy 154.638246 -318.920443)
			(xy 154.605611 -318.883606) (xy 154.579308 -318.84201) (xy 154.560017 -318.796734) (xy 154.54824 -318.74895)
			(xy 154.54428 -318.699896) (xy 147.426741 -318.699896) (xy 147.499951 -318.756463) (xy 147.612488 -318.853497)
			(xy 147.719655 -318.956432) (xy 147.821142 -319.064971) (xy 147.916656 -319.1788) (xy 148.005923 -319.297593)
			(xy 148.088684 -319.421005) (xy 148.164702 -319.548683) (xy 148.233757 -319.680256) (xy 148.29565 -319.815347)
			(xy 148.350203 -319.953564) (xy 148.397258 -320.094511) (xy 148.43668 -320.237781) (xy 148.468354 -320.38296)
			(xy 148.49219 -320.529629) (xy 148.508119 -320.677367) (xy 148.516095 -320.825747) (xy 148.516594 -320.900044)
			(xy 202.982331 -320.900044) (xy 202.98632 -320.751504) (xy 202.998277 -320.603391) (xy 203.018167 -320.456134)
			(xy 203.045932 -320.310158) (xy 203.081493 -320.165881) (xy 203.124747 -320.023722) (xy 203.175569 -319.884089)
			(xy 203.233813 -319.747386) (xy 203.299311 -319.614006) (xy 203.371874 -319.484334) (xy 203.451292 -319.358744)
			(xy 203.537337 -319.237597) (xy 203.629761 -319.121244) (xy 203.728297 -319.01002) (xy 203.832661 -318.904245)
			(xy 203.942553 -318.804225) (xy 204.057654 -318.710247) (xy 204.177634 -318.622583) (xy 204.302147 -318.541486)
			(xy 204.430833 -318.467189) (xy 204.563322 -318.399907) (xy 204.699231 -318.339833) (xy 204.838169 -318.287141)
			(xy 204.979735 -318.241982) (xy 205.123521 -318.204487) (xy 205.269112 -318.174765) (xy 205.416088 -318.1529)
			(xy 205.564027 -318.138956) (xy 205.7125 -318.132972) (xy 205.861081 -318.134967) (xy 206.00934 -318.144935)
			(xy 206.156851 -318.162846) (xy 206.303187 -318.188649) (xy 206.447928 -318.222269) (xy 206.590655 -318.263611)
			(xy 206.730958 -318.312554) (xy 206.868431 -318.368957) (xy 207.002678 -318.432658) (xy 207.133313 -318.503474)
			(xy 207.259958 -318.581199) (xy 207.382248 -318.66561) (xy 207.499831 -318.756463) (xy 207.612368 -318.853497)
			(xy 207.719535 -318.956432) (xy 207.821022 -319.064971) (xy 207.916536 -319.1788) (xy 208.005803 -319.297593)
			(xy 208.088564 -319.421005) (xy 208.164582 -319.548683) (xy 208.233637 -319.680256) (xy 208.29553 -319.815347)
			(xy 208.350083 -319.953564) (xy 208.397138 -320.094511) (xy 208.43656 -320.237781) (xy 208.468234 -320.38296)
			(xy 208.49207 -320.529629) (xy 208.507999 -320.677367) (xy 208.515975 -320.825747) (xy 208.516474 -320.900044)
			(xy 259.082549 -320.900044) (xy 259.086538 -320.751504) (xy 259.098495 -320.603391) (xy 259.118385 -320.456134)
			(xy 259.14615 -320.310158) (xy 259.181711 -320.165881) (xy 259.224965 -320.023722) (xy 259.275787 -319.884089)
			(xy 259.334031 -319.747386) (xy 259.399529 -319.614006) (xy 259.472092 -319.484334) (xy 259.55151 -319.358744)
			(xy 259.637555 -319.237597) (xy 259.729979 -319.121244) (xy 259.828515 -319.01002) (xy 259.932879 -318.904245)
			(xy 260.042771 -318.804225) (xy 260.157872 -318.710247) (xy 260.277852 -318.622583) (xy 260.402365 -318.541486)
			(xy 260.531051 -318.467189) (xy 260.66354 -318.399907) (xy 260.799449 -318.339833) (xy 260.938387 -318.287141)
			(xy 261.079953 -318.241982) (xy 261.223739 -318.204487) (xy 261.36933 -318.174765) (xy 261.516306 -318.1529)
			(xy 261.664245 -318.138956) (xy 261.812718 -318.132972) (xy 261.961299 -318.134967) (xy 262.109558 -318.144935)
			(xy 262.257069 -318.162846) (xy 262.403405 -318.188649) (xy 262.548146 -318.222269) (xy 262.690873 -318.263611)
			(xy 262.831176 -318.312554) (xy 262.968649 -318.368957) (xy 263.102896 -318.432658) (xy 263.233531 -318.503474)
			(xy 263.360176 -318.581199) (xy 263.482466 -318.66561) (xy 263.526839 -318.699896) (xy 270.644124 -318.699896)
			(xy 270.648084 -318.650842) (xy 270.659861 -318.603058) (xy 270.679152 -318.557782) (xy 270.705455 -318.516186)
			(xy 270.73809 -318.479349) (xy 270.776211 -318.448224) (xy 270.818832 -318.423617) (xy 270.864848 -318.406165)
			(xy 270.913067 -318.396321) (xy 270.962242 -318.39434) (xy 271.011097 -318.400272) (xy 271.058368 -318.413964)
			(xy 271.10283 -318.435062) (xy 271.143333 -318.463018) (xy 271.178826 -318.49711) (xy 271.208391 -318.536454)
			(xy 271.231262 -318.580031) (xy 271.246846 -318.626712) (xy 271.254741 -318.675289) (xy 271.255236 -318.699896)
			(xy 272.544044 -318.699896) (xy 272.548004 -318.650842) (xy 272.559781 -318.603058) (xy 272.579072 -318.557782)
			(xy 272.605375 -318.516186) (xy 272.63801 -318.479349) (xy 272.676131 -318.448224) (xy 272.718752 -318.423617)
			(xy 272.764768 -318.406165) (xy 272.812987 -318.396321) (xy 272.862162 -318.39434) (xy 272.911017 -318.400272)
			(xy 272.958288 -318.413964) (xy 273.00275 -318.435062) (xy 273.043253 -318.463018) (xy 273.078746 -318.49711)
			(xy 273.108311 -318.536454) (xy 273.131182 -318.580031) (xy 273.146766 -318.626712) (xy 273.154661 -318.675289)
			(xy 273.155156 -318.699896) (xy 274.443964 -318.699896) (xy 274.447924 -318.650842) (xy 274.459701 -318.603058)
			(xy 274.478992 -318.557782) (xy 274.505295 -318.516186) (xy 274.53793 -318.479349) (xy 274.576051 -318.448224)
			(xy 274.618672 -318.423617) (xy 274.664688 -318.406165) (xy 274.712907 -318.396321) (xy 274.762082 -318.39434)
			(xy 274.810937 -318.400272) (xy 274.858208 -318.413964) (xy 274.90267 -318.435062) (xy 274.943173 -318.463018)
			(xy 274.978666 -318.49711) (xy 275.008231 -318.536454) (xy 275.031102 -318.580031) (xy 275.046686 -318.626712)
			(xy 275.054581 -318.675289) (xy 275.055076 -318.699896) (xy 276.343884 -318.699896) (xy 276.347844 -318.650842)
			(xy 276.359621 -318.603058) (xy 276.378912 -318.557782) (xy 276.405215 -318.516186) (xy 276.43785 -318.479349)
			(xy 276.475971 -318.448224) (xy 276.518592 -318.423617) (xy 276.564608 -318.406165) (xy 276.612827 -318.396321)
			(xy 276.662002 -318.39434) (xy 276.710857 -318.400272) (xy 276.758128 -318.413964) (xy 276.80259 -318.435062)
			(xy 276.843093 -318.463018) (xy 276.878586 -318.49711) (xy 276.908151 -318.536454) (xy 276.931022 -318.580031)
			(xy 276.946606 -318.626712) (xy 276.954501 -318.675289) (xy 276.954996 -318.699896) (xy 278.244058 -318.699896)
			(xy 278.248018 -318.650842) (xy 278.259795 -318.603058) (xy 278.279086 -318.557782) (xy 278.305389 -318.516186)
			(xy 278.338024 -318.479349) (xy 278.376145 -318.448224) (xy 278.418766 -318.423617) (xy 278.464782 -318.406165)
			(xy 278.513001 -318.396321) (xy 278.562176 -318.39434) (xy 278.611031 -318.400272) (xy 278.658302 -318.413964)
			(xy 278.702764 -318.435062) (xy 278.743267 -318.463018) (xy 278.77876 -318.49711) (xy 278.808325 -318.536454)
			(xy 278.831196 -318.580031) (xy 278.84678 -318.626712) (xy 278.854675 -318.675289) (xy 278.85517 -318.699896)
			(xy 280.143978 -318.699896) (xy 280.147938 -318.650842) (xy 280.159715 -318.603058) (xy 280.179006 -318.557782)
			(xy 280.205309 -318.516186) (xy 280.237944 -318.479349) (xy 280.276065 -318.448224) (xy 280.318686 -318.423617)
			(xy 280.364702 -318.406165) (xy 280.412921 -318.396321) (xy 280.462096 -318.39434) (xy 280.510951 -318.400272)
			(xy 280.558222 -318.413964) (xy 280.602684 -318.435062) (xy 280.643187 -318.463018) (xy 280.67868 -318.49711)
			(xy 280.708245 -318.536454) (xy 280.731116 -318.580031) (xy 280.7467 -318.626712) (xy 280.754595 -318.675289)
			(xy 280.75509 -318.699896) (xy 282.043898 -318.699896) (xy 282.047858 -318.650842) (xy 282.059635 -318.603058)
			(xy 282.078926 -318.557782) (xy 282.105229 -318.516186) (xy 282.137864 -318.479349) (xy 282.175985 -318.448224)
			(xy 282.218606 -318.423617) (xy 282.264622 -318.406165) (xy 282.312841 -318.396321) (xy 282.362016 -318.39434)
			(xy 282.410871 -318.400272) (xy 282.458142 -318.413964) (xy 282.502604 -318.435062) (xy 282.543107 -318.463018)
			(xy 282.5786 -318.49711) (xy 282.608165 -318.536454) (xy 282.631036 -318.580031) (xy 282.64662 -318.626712)
			(xy 282.654515 -318.675289) (xy 282.65501 -318.699896) (xy 283.944072 -318.699896) (xy 283.948032 -318.650842)
			(xy 283.959809 -318.603058) (xy 283.9791 -318.557782) (xy 284.005403 -318.516186) (xy 284.038038 -318.479349)
			(xy 284.076159 -318.448224) (xy 284.11878 -318.423617) (xy 284.164796 -318.406165) (xy 284.213015 -318.396321)
			(xy 284.26219 -318.39434) (xy 284.311045 -318.400272) (xy 284.358316 -318.413964) (xy 284.402778 -318.435062)
			(xy 284.443281 -318.463018) (xy 284.478774 -318.49711) (xy 284.508339 -318.536454) (xy 284.53121 -318.580031)
			(xy 284.546794 -318.626712) (xy 284.554689 -318.675289) (xy 284.555184 -318.699896) (xy 285.843992 -318.699896)
			(xy 285.847952 -318.650842) (xy 285.859729 -318.603058) (xy 285.87902 -318.557782) (xy 285.905323 -318.516186)
			(xy 285.937958 -318.479349) (xy 285.976079 -318.448224) (xy 286.0187 -318.423617) (xy 286.064716 -318.406165)
			(xy 286.112935 -318.396321) (xy 286.16211 -318.39434) (xy 286.210965 -318.400272) (xy 286.258236 -318.413964)
			(xy 286.302698 -318.435062) (xy 286.343201 -318.463018) (xy 286.378694 -318.49711) (xy 286.408259 -318.536454)
			(xy 286.43113 -318.580031) (xy 286.446714 -318.626712) (xy 286.454609 -318.675289) (xy 286.455104 -318.699896)
			(xy 287.743912 -318.699896) (xy 287.747872 -318.650842) (xy 287.759649 -318.603058) (xy 287.77894 -318.557782)
			(xy 287.805243 -318.516186) (xy 287.837878 -318.479349) (xy 287.875999 -318.448224) (xy 287.91862 -318.423617)
			(xy 287.964636 -318.406165) (xy 288.012855 -318.396321) (xy 288.06203 -318.39434) (xy 288.110885 -318.400272)
			(xy 288.158156 -318.413964) (xy 288.202618 -318.435062) (xy 288.243121 -318.463018) (xy 288.278614 -318.49711)
			(xy 288.308179 -318.536454) (xy 288.33105 -318.580031) (xy 288.346634 -318.626712) (xy 288.354529 -318.675289)
			(xy 288.355024 -318.699896) (xy 289.644086 -318.699896) (xy 289.648046 -318.650842) (xy 289.659823 -318.603058)
			(xy 289.679114 -318.557782) (xy 289.705417 -318.516186) (xy 289.738052 -318.479349) (xy 289.776173 -318.448224)
			(xy 289.818794 -318.423617) (xy 289.86481 -318.406165) (xy 289.913029 -318.396321) (xy 289.962204 -318.39434)
			(xy 290.011059 -318.400272) (xy 290.05833 -318.413964) (xy 290.102792 -318.435062) (xy 290.143295 -318.463018)
			(xy 290.178788 -318.49711) (xy 290.208353 -318.536454) (xy 290.231224 -318.580031) (xy 290.246808 -318.626712)
			(xy 290.254703 -318.675289) (xy 290.255198 -318.699896) (xy 291.544006 -318.699896) (xy 291.547966 -318.650842)
			(xy 291.559743 -318.603058) (xy 291.579034 -318.557782) (xy 291.605337 -318.516186) (xy 291.637972 -318.479349)
			(xy 291.676093 -318.448224) (xy 291.718714 -318.423617) (xy 291.76473 -318.406165) (xy 291.812949 -318.396321)
			(xy 291.862124 -318.39434) (xy 291.910979 -318.400272) (xy 291.95825 -318.413964) (xy 292.002712 -318.435062)
			(xy 292.043215 -318.463018) (xy 292.078708 -318.49711) (xy 292.108273 -318.536454) (xy 292.131144 -318.580031)
			(xy 292.146728 -318.626712) (xy 292.154623 -318.675289) (xy 292.155118 -318.699896) (xy 293.443926 -318.699896)
			(xy 293.447886 -318.650842) (xy 293.459663 -318.603058) (xy 293.478954 -318.557782) (xy 293.505257 -318.516186)
			(xy 293.537892 -318.479349) (xy 293.576013 -318.448224) (xy 293.618634 -318.423617) (xy 293.66465 -318.406165)
			(xy 293.712869 -318.396321) (xy 293.762044 -318.39434) (xy 293.810899 -318.400272) (xy 293.85817 -318.413964)
			(xy 293.902632 -318.435062) (xy 293.943135 -318.463018) (xy 293.978628 -318.49711) (xy 294.008193 -318.536454)
			(xy 294.031064 -318.580031) (xy 294.046648 -318.626712) (xy 294.054543 -318.675289) (xy 294.055038 -318.699896)
			(xy 295.3441 -318.699896) (xy 295.34806 -318.650842) (xy 295.359837 -318.603058) (xy 295.379128 -318.557782)
			(xy 295.405431 -318.516186) (xy 295.438066 -318.479349) (xy 295.476187 -318.448224) (xy 295.518808 -318.423617)
			(xy 295.564824 -318.406165) (xy 295.613043 -318.396321) (xy 295.662218 -318.39434) (xy 295.711073 -318.400272)
			(xy 295.758344 -318.413964) (xy 295.802806 -318.435062) (xy 295.843309 -318.463018) (xy 295.878802 -318.49711)
			(xy 295.908367 -318.536454) (xy 295.931238 -318.580031) (xy 295.946822 -318.626712) (xy 295.954717 -318.675289)
			(xy 295.955212 -318.699896) (xy 297.24402 -318.699896) (xy 297.24798 -318.650842) (xy 297.259757 -318.603058)
			(xy 297.279048 -318.557782) (xy 297.305351 -318.516186) (xy 297.337986 -318.479349) (xy 297.376107 -318.448224)
			(xy 297.418728 -318.423617) (xy 297.464744 -318.406165) (xy 297.512963 -318.396321) (xy 297.562138 -318.39434)
			(xy 297.610993 -318.400272) (xy 297.658264 -318.413964) (xy 297.702726 -318.435062) (xy 297.743229 -318.463018)
			(xy 297.778722 -318.49711) (xy 297.808287 -318.536454) (xy 297.831158 -318.580031) (xy 297.846742 -318.626712)
			(xy 297.854637 -318.675289) (xy 297.855132 -318.699896) (xy 299.14394 -318.699896) (xy 299.1479 -318.650842)
			(xy 299.159677 -318.603058) (xy 299.178968 -318.557782) (xy 299.205271 -318.516186) (xy 299.237906 -318.479349)
			(xy 299.276027 -318.448224) (xy 299.318648 -318.423617) (xy 299.364664 -318.406165) (xy 299.412883 -318.396321)
			(xy 299.462058 -318.39434) (xy 299.510913 -318.400272) (xy 299.558184 -318.413964) (xy 299.602646 -318.435062)
			(xy 299.643149 -318.463018) (xy 299.678642 -318.49711) (xy 299.708207 -318.536454) (xy 299.731078 -318.580031)
			(xy 299.746662 -318.626712) (xy 299.754557 -318.675289) (xy 299.755052 -318.699896) (xy 301.044114 -318.699896)
			(xy 301.048074 -318.650842) (xy 301.059851 -318.603058) (xy 301.079142 -318.557782) (xy 301.105445 -318.516186)
			(xy 301.13808 -318.479349) (xy 301.176201 -318.448224) (xy 301.218822 -318.423617) (xy 301.264838 -318.406165)
			(xy 301.313057 -318.396321) (xy 301.362232 -318.39434) (xy 301.411087 -318.400272) (xy 301.458358 -318.413964)
			(xy 301.50282 -318.435062) (xy 301.543323 -318.463018) (xy 301.578816 -318.49711) (xy 301.608381 -318.536454)
			(xy 301.631252 -318.580031) (xy 301.646836 -318.626712) (xy 301.654731 -318.675289) (xy 301.655226 -318.699896)
			(xy 302.944034 -318.699896) (xy 302.947994 -318.650842) (xy 302.959771 -318.603058) (xy 302.979062 -318.557782)
			(xy 303.005365 -318.516186) (xy 303.038 -318.479349) (xy 303.076121 -318.448224) (xy 303.118742 -318.423617)
			(xy 303.164758 -318.406165) (xy 303.212977 -318.396321) (xy 303.262152 -318.39434) (xy 303.311007 -318.400272)
			(xy 303.358278 -318.413964) (xy 303.40274 -318.435062) (xy 303.443243 -318.463018) (xy 303.478736 -318.49711)
			(xy 303.508301 -318.536454) (xy 303.531172 -318.580031) (xy 303.546756 -318.626712) (xy 303.554651 -318.675289)
			(xy 303.555146 -318.699896) (xy 304.843954 -318.699896) (xy 304.847914 -318.650842) (xy 304.859691 -318.603058)
			(xy 304.878982 -318.557782) (xy 304.905285 -318.516186) (xy 304.93792 -318.479349) (xy 304.976041 -318.448224)
			(xy 305.018662 -318.423617) (xy 305.064678 -318.406165) (xy 305.112897 -318.396321) (xy 305.162072 -318.39434)
			(xy 305.210927 -318.400272) (xy 305.258198 -318.413964) (xy 305.30266 -318.435062) (xy 305.343163 -318.463018)
			(xy 305.378656 -318.49711) (xy 305.408221 -318.536454) (xy 305.431092 -318.580031) (xy 305.446676 -318.626712)
			(xy 305.454571 -318.675289) (xy 305.455066 -318.699896) (xy 306.744128 -318.699896) (xy 306.748088 -318.650842)
			(xy 306.759865 -318.603058) (xy 306.779156 -318.557782) (xy 306.805459 -318.516186) (xy 306.838094 -318.479349)
			(xy 306.876215 -318.448224) (xy 306.918836 -318.423617) (xy 306.964852 -318.406165) (xy 307.013071 -318.396321)
			(xy 307.062246 -318.39434) (xy 307.111101 -318.400272) (xy 307.158372 -318.413964) (xy 307.202834 -318.435062)
			(xy 307.243337 -318.463018) (xy 307.27883 -318.49711) (xy 307.308395 -318.536454) (xy 307.331266 -318.580031)
			(xy 307.34685 -318.626712) (xy 307.354745 -318.675289) (xy 307.35524 -318.699896) (xy 308.644048 -318.699896)
			(xy 308.648008 -318.650842) (xy 308.659785 -318.603058) (xy 308.679076 -318.557782) (xy 308.705379 -318.516186)
			(xy 308.738014 -318.479349) (xy 308.776135 -318.448224) (xy 308.818756 -318.423617) (xy 308.864772 -318.406165)
			(xy 308.912991 -318.396321) (xy 308.962166 -318.39434) (xy 309.011021 -318.400272) (xy 309.058292 -318.413964)
			(xy 309.102754 -318.435062) (xy 309.143257 -318.463018) (xy 309.17875 -318.49711) (xy 309.208315 -318.536454)
			(xy 309.231186 -318.580031) (xy 309.24677 -318.626712) (xy 309.254665 -318.675289) (xy 309.25516 -318.699896)
			(xy 310.543968 -318.699896) (xy 310.547928 -318.650842) (xy 310.559705 -318.603058) (xy 310.578996 -318.557782)
			(xy 310.605299 -318.516186) (xy 310.637934 -318.479349) (xy 310.676055 -318.448224) (xy 310.718676 -318.423617)
			(xy 310.764692 -318.406165) (xy 310.812911 -318.396321) (xy 310.862086 -318.39434) (xy 310.910941 -318.400272)
			(xy 310.958212 -318.413964) (xy 311.002674 -318.435062) (xy 311.043177 -318.463018) (xy 311.07867 -318.49711)
			(xy 311.108235 -318.536454) (xy 311.131106 -318.580031) (xy 311.14669 -318.626712) (xy 311.154585 -318.675289)
			(xy 311.15508 -318.699896) (xy 312.443888 -318.699896) (xy 312.447848 -318.650842) (xy 312.459625 -318.603058)
			(xy 312.478916 -318.557782) (xy 312.505219 -318.516186) (xy 312.537854 -318.479349) (xy 312.575975 -318.448224)
			(xy 312.618596 -318.423617) (xy 312.664612 -318.406165) (xy 312.712831 -318.396321) (xy 312.762006 -318.39434)
			(xy 312.810861 -318.400272) (xy 312.858132 -318.413964) (xy 312.902594 -318.435062) (xy 312.943097 -318.463018)
			(xy 312.97859 -318.49711) (xy 313.008155 -318.536454) (xy 313.031026 -318.580031) (xy 313.04661 -318.626712)
			(xy 313.054505 -318.675289) (xy 313.055 -318.699896) (xy 313.054505 -318.724503) (xy 313.04661 -318.77308)
			(xy 313.031026 -318.819761) (xy 313.008155 -318.863338) (xy 312.97859 -318.902682) (xy 312.943097 -318.936774)
			(xy 312.902594 -318.96473) (xy 312.858132 -318.985828) (xy 312.810861 -318.99952) (xy 312.762006 -319.005452)
			(xy 312.712831 -319.003471) (xy 312.664612 -318.993627) (xy 312.618596 -318.976175) (xy 312.575975 -318.951568)
			(xy 312.537854 -318.920443) (xy 312.505219 -318.883606) (xy 312.478916 -318.84201) (xy 312.459625 -318.796734)
			(xy 312.447848 -318.74895) (xy 312.443888 -318.699896) (xy 311.15508 -318.699896) (xy 311.154585 -318.724503)
			(xy 311.14669 -318.77308) (xy 311.131106 -318.819761) (xy 311.108235 -318.863338) (xy 311.07867 -318.902682)
			(xy 311.043177 -318.936774) (xy 311.002674 -318.96473) (xy 310.958212 -318.985828) (xy 310.910941 -318.99952)
			(xy 310.862086 -319.005452) (xy 310.812911 -319.003471) (xy 310.764692 -318.993627) (xy 310.718676 -318.976175)
			(xy 310.676055 -318.951568) (xy 310.637934 -318.920443) (xy 310.605299 -318.883606) (xy 310.578996 -318.84201)
			(xy 310.559705 -318.796734) (xy 310.547928 -318.74895) (xy 310.543968 -318.699896) (xy 309.25516 -318.699896)
			(xy 309.254665 -318.724503) (xy 309.24677 -318.77308) (xy 309.231186 -318.819761) (xy 309.208315 -318.863338)
			(xy 309.17875 -318.902682) (xy 309.143257 -318.936774) (xy 309.102754 -318.96473) (xy 309.058292 -318.985828)
			(xy 309.011021 -318.99952) (xy 308.962166 -319.005452) (xy 308.912991 -319.003471) (xy 308.864772 -318.993627)
			(xy 308.818756 -318.976175) (xy 308.776135 -318.951568) (xy 308.738014 -318.920443) (xy 308.705379 -318.883606)
			(xy 308.679076 -318.84201) (xy 308.659785 -318.796734) (xy 308.648008 -318.74895) (xy 308.644048 -318.699896)
			(xy 307.35524 -318.699896) (xy 307.354745 -318.724503) (xy 307.34685 -318.77308) (xy 307.331266 -318.819761)
			(xy 307.308395 -318.863338) (xy 307.27883 -318.902682) (xy 307.243337 -318.936774) (xy 307.202834 -318.96473)
			(xy 307.158372 -318.985828) (xy 307.111101 -318.99952) (xy 307.062246 -319.005452) (xy 307.013071 -319.003471)
			(xy 306.964852 -318.993627) (xy 306.918836 -318.976175) (xy 306.876215 -318.951568) (xy 306.838094 -318.920443)
			(xy 306.805459 -318.883606) (xy 306.779156 -318.84201) (xy 306.759865 -318.796734) (xy 306.748088 -318.74895)
			(xy 306.744128 -318.699896) (xy 305.455066 -318.699896) (xy 305.454571 -318.724503) (xy 305.446676 -318.77308)
			(xy 305.431092 -318.819761) (xy 305.408221 -318.863338) (xy 305.378656 -318.902682) (xy 305.343163 -318.936774)
			(xy 305.30266 -318.96473) (xy 305.258198 -318.985828) (xy 305.210927 -318.99952) (xy 305.162072 -319.005452)
			(xy 305.112897 -319.003471) (xy 305.064678 -318.993627) (xy 305.018662 -318.976175) (xy 304.976041 -318.951568)
			(xy 304.93792 -318.920443) (xy 304.905285 -318.883606) (xy 304.878982 -318.84201) (xy 304.859691 -318.796734)
			(xy 304.847914 -318.74895) (xy 304.843954 -318.699896) (xy 303.555146 -318.699896) (xy 303.554651 -318.724503)
			(xy 303.546756 -318.77308) (xy 303.531172 -318.819761) (xy 303.508301 -318.863338) (xy 303.478736 -318.902682)
			(xy 303.443243 -318.936774) (xy 303.40274 -318.96473) (xy 303.358278 -318.985828) (xy 303.311007 -318.99952)
			(xy 303.262152 -319.005452) (xy 303.212977 -319.003471) (xy 303.164758 -318.993627) (xy 303.118742 -318.976175)
			(xy 303.076121 -318.951568) (xy 303.038 -318.920443) (xy 303.005365 -318.883606) (xy 302.979062 -318.84201)
			(xy 302.959771 -318.796734) (xy 302.947994 -318.74895) (xy 302.944034 -318.699896) (xy 301.655226 -318.699896)
			(xy 301.654731 -318.724503) (xy 301.646836 -318.77308) (xy 301.631252 -318.819761) (xy 301.608381 -318.863338)
			(xy 301.578816 -318.902682) (xy 301.543323 -318.936774) (xy 301.50282 -318.96473) (xy 301.458358 -318.985828)
			(xy 301.411087 -318.99952) (xy 301.362232 -319.005452) (xy 301.313057 -319.003471) (xy 301.264838 -318.993627)
			(xy 301.218822 -318.976175) (xy 301.176201 -318.951568) (xy 301.13808 -318.920443) (xy 301.105445 -318.883606)
			(xy 301.079142 -318.84201) (xy 301.059851 -318.796734) (xy 301.048074 -318.74895) (xy 301.044114 -318.699896)
			(xy 299.755052 -318.699896) (xy 299.754557 -318.724503) (xy 299.746662 -318.77308) (xy 299.731078 -318.819761)
			(xy 299.708207 -318.863338) (xy 299.678642 -318.902682) (xy 299.643149 -318.936774) (xy 299.602646 -318.96473)
			(xy 299.558184 -318.985828) (xy 299.510913 -318.99952) (xy 299.462058 -319.005452) (xy 299.412883 -319.003471)
			(xy 299.364664 -318.993627) (xy 299.318648 -318.976175) (xy 299.276027 -318.951568) (xy 299.237906 -318.920443)
			(xy 299.205271 -318.883606) (xy 299.178968 -318.84201) (xy 299.159677 -318.796734) (xy 299.1479 -318.74895)
			(xy 299.14394 -318.699896) (xy 297.855132 -318.699896) (xy 297.854637 -318.724503) (xy 297.846742 -318.77308)
			(xy 297.831158 -318.819761) (xy 297.808287 -318.863338) (xy 297.778722 -318.902682) (xy 297.743229 -318.936774)
			(xy 297.702726 -318.96473) (xy 297.658264 -318.985828) (xy 297.610993 -318.99952) (xy 297.562138 -319.005452)
			(xy 297.512963 -319.003471) (xy 297.464744 -318.993627) (xy 297.418728 -318.976175) (xy 297.376107 -318.951568)
			(xy 297.337986 -318.920443) (xy 297.305351 -318.883606) (xy 297.279048 -318.84201) (xy 297.259757 -318.796734)
			(xy 297.24798 -318.74895) (xy 297.24402 -318.699896) (xy 295.955212 -318.699896) (xy 295.954717 -318.724503)
			(xy 295.946822 -318.77308) (xy 295.931238 -318.819761) (xy 295.908367 -318.863338) (xy 295.878802 -318.902682)
			(xy 295.843309 -318.936774) (xy 295.802806 -318.96473) (xy 295.758344 -318.985828) (xy 295.711073 -318.99952)
			(xy 295.662218 -319.005452) (xy 295.613043 -319.003471) (xy 295.564824 -318.993627) (xy 295.518808 -318.976175)
			(xy 295.476187 -318.951568) (xy 295.438066 -318.920443) (xy 295.405431 -318.883606) (xy 295.379128 -318.84201)
			(xy 295.359837 -318.796734) (xy 295.34806 -318.74895) (xy 295.3441 -318.699896) (xy 294.055038 -318.699896)
			(xy 294.054543 -318.724503) (xy 294.046648 -318.77308) (xy 294.031064 -318.819761) (xy 294.008193 -318.863338)
			(xy 293.978628 -318.902682) (xy 293.943135 -318.936774) (xy 293.902632 -318.96473) (xy 293.85817 -318.985828)
			(xy 293.810899 -318.99952) (xy 293.762044 -319.005452) (xy 293.712869 -319.003471) (xy 293.66465 -318.993627)
			(xy 293.618634 -318.976175) (xy 293.576013 -318.951568) (xy 293.537892 -318.920443) (xy 293.505257 -318.883606)
			(xy 293.478954 -318.84201) (xy 293.459663 -318.796734) (xy 293.447886 -318.74895) (xy 293.443926 -318.699896)
			(xy 292.155118 -318.699896) (xy 292.154623 -318.724503) (xy 292.146728 -318.77308) (xy 292.131144 -318.819761)
			(xy 292.108273 -318.863338) (xy 292.078708 -318.902682) (xy 292.043215 -318.936774) (xy 292.002712 -318.96473)
			(xy 291.95825 -318.985828) (xy 291.910979 -318.99952) (xy 291.862124 -319.005452) (xy 291.812949 -319.003471)
			(xy 291.76473 -318.993627) (xy 291.718714 -318.976175) (xy 291.676093 -318.951568) (xy 291.637972 -318.920443)
			(xy 291.605337 -318.883606) (xy 291.579034 -318.84201) (xy 291.559743 -318.796734) (xy 291.547966 -318.74895)
			(xy 291.544006 -318.699896) (xy 290.255198 -318.699896) (xy 290.254703 -318.724503) (xy 290.246808 -318.77308)
			(xy 290.231224 -318.819761) (xy 290.208353 -318.863338) (xy 290.178788 -318.902682) (xy 290.143295 -318.936774)
			(xy 290.102792 -318.96473) (xy 290.05833 -318.985828) (xy 290.011059 -318.99952) (xy 289.962204 -319.005452)
			(xy 289.913029 -319.003471) (xy 289.86481 -318.993627) (xy 289.818794 -318.976175) (xy 289.776173 -318.951568)
			(xy 289.738052 -318.920443) (xy 289.705417 -318.883606) (xy 289.679114 -318.84201) (xy 289.659823 -318.796734)
			(xy 289.648046 -318.74895) (xy 289.644086 -318.699896) (xy 288.355024 -318.699896) (xy 288.354529 -318.724503)
			(xy 288.346634 -318.77308) (xy 288.33105 -318.819761) (xy 288.308179 -318.863338) (xy 288.278614 -318.902682)
			(xy 288.243121 -318.936774) (xy 288.202618 -318.96473) (xy 288.158156 -318.985828) (xy 288.110885 -318.99952)
			(xy 288.06203 -319.005452) (xy 288.012855 -319.003471) (xy 287.964636 -318.993627) (xy 287.91862 -318.976175)
			(xy 287.875999 -318.951568) (xy 287.837878 -318.920443) (xy 287.805243 -318.883606) (xy 287.77894 -318.84201)
			(xy 287.759649 -318.796734) (xy 287.747872 -318.74895) (xy 287.743912 -318.699896) (xy 286.455104 -318.699896)
			(xy 286.454609 -318.724503) (xy 286.446714 -318.77308) (xy 286.43113 -318.819761) (xy 286.408259 -318.863338)
			(xy 286.378694 -318.902682) (xy 286.343201 -318.936774) (xy 286.302698 -318.96473) (xy 286.258236 -318.985828)
			(xy 286.210965 -318.99952) (xy 286.16211 -319.005452) (xy 286.112935 -319.003471) (xy 286.064716 -318.993627)
			(xy 286.0187 -318.976175) (xy 285.976079 -318.951568) (xy 285.937958 -318.920443) (xy 285.905323 -318.883606)
			(xy 285.87902 -318.84201) (xy 285.859729 -318.796734) (xy 285.847952 -318.74895) (xy 285.843992 -318.699896)
			(xy 284.555184 -318.699896) (xy 284.554689 -318.724503) (xy 284.546794 -318.77308) (xy 284.53121 -318.819761)
			(xy 284.508339 -318.863338) (xy 284.478774 -318.902682) (xy 284.443281 -318.936774) (xy 284.402778 -318.96473)
			(xy 284.358316 -318.985828) (xy 284.311045 -318.99952) (xy 284.26219 -319.005452) (xy 284.213015 -319.003471)
			(xy 284.164796 -318.993627) (xy 284.11878 -318.976175) (xy 284.076159 -318.951568) (xy 284.038038 -318.920443)
			(xy 284.005403 -318.883606) (xy 283.9791 -318.84201) (xy 283.959809 -318.796734) (xy 283.948032 -318.74895)
			(xy 283.944072 -318.699896) (xy 282.65501 -318.699896) (xy 282.654515 -318.724503) (xy 282.64662 -318.77308)
			(xy 282.631036 -318.819761) (xy 282.608165 -318.863338) (xy 282.5786 -318.902682) (xy 282.543107 -318.936774)
			(xy 282.502604 -318.96473) (xy 282.458142 -318.985828) (xy 282.410871 -318.99952) (xy 282.362016 -319.005452)
			(xy 282.312841 -319.003471) (xy 282.264622 -318.993627) (xy 282.218606 -318.976175) (xy 282.175985 -318.951568)
			(xy 282.137864 -318.920443) (xy 282.105229 -318.883606) (xy 282.078926 -318.84201) (xy 282.059635 -318.796734)
			(xy 282.047858 -318.74895) (xy 282.043898 -318.699896) (xy 280.75509 -318.699896) (xy 280.754595 -318.724503)
			(xy 280.7467 -318.77308) (xy 280.731116 -318.819761) (xy 280.708245 -318.863338) (xy 280.67868 -318.902682)
			(xy 280.643187 -318.936774) (xy 280.602684 -318.96473) (xy 280.558222 -318.985828) (xy 280.510951 -318.99952)
			(xy 280.462096 -319.005452) (xy 280.412921 -319.003471) (xy 280.364702 -318.993627) (xy 280.318686 -318.976175)
			(xy 280.276065 -318.951568) (xy 280.237944 -318.920443) (xy 280.205309 -318.883606) (xy 280.179006 -318.84201)
			(xy 280.159715 -318.796734) (xy 280.147938 -318.74895) (xy 280.143978 -318.699896) (xy 278.85517 -318.699896)
			(xy 278.854675 -318.724503) (xy 278.84678 -318.77308) (xy 278.831196 -318.819761) (xy 278.808325 -318.863338)
			(xy 278.77876 -318.902682) (xy 278.743267 -318.936774) (xy 278.702764 -318.96473) (xy 278.658302 -318.985828)
			(xy 278.611031 -318.99952) (xy 278.562176 -319.005452) (xy 278.513001 -319.003471) (xy 278.464782 -318.993627)
			(xy 278.418766 -318.976175) (xy 278.376145 -318.951568) (xy 278.338024 -318.920443) (xy 278.305389 -318.883606)
			(xy 278.279086 -318.84201) (xy 278.259795 -318.796734) (xy 278.248018 -318.74895) (xy 278.244058 -318.699896)
			(xy 276.954996 -318.699896) (xy 276.954501 -318.724503) (xy 276.946606 -318.77308) (xy 276.931022 -318.819761)
			(xy 276.908151 -318.863338) (xy 276.878586 -318.902682) (xy 276.843093 -318.936774) (xy 276.80259 -318.96473)
			(xy 276.758128 -318.985828) (xy 276.710857 -318.99952) (xy 276.662002 -319.005452) (xy 276.612827 -319.003471)
			(xy 276.564608 -318.993627) (xy 276.518592 -318.976175) (xy 276.475971 -318.951568) (xy 276.43785 -318.920443)
			(xy 276.405215 -318.883606) (xy 276.378912 -318.84201) (xy 276.359621 -318.796734) (xy 276.347844 -318.74895)
			(xy 276.343884 -318.699896) (xy 275.055076 -318.699896) (xy 275.054581 -318.724503) (xy 275.046686 -318.77308)
			(xy 275.031102 -318.819761) (xy 275.008231 -318.863338) (xy 274.978666 -318.902682) (xy 274.943173 -318.936774)
			(xy 274.90267 -318.96473) (xy 274.858208 -318.985828) (xy 274.810937 -318.99952) (xy 274.762082 -319.005452)
			(xy 274.712907 -319.003471) (xy 274.664688 -318.993627) (xy 274.618672 -318.976175) (xy 274.576051 -318.951568)
			(xy 274.53793 -318.920443) (xy 274.505295 -318.883606) (xy 274.478992 -318.84201) (xy 274.459701 -318.796734)
			(xy 274.447924 -318.74895) (xy 274.443964 -318.699896) (xy 273.155156 -318.699896) (xy 273.154661 -318.724503)
			(xy 273.146766 -318.77308) (xy 273.131182 -318.819761) (xy 273.108311 -318.863338) (xy 273.078746 -318.902682)
			(xy 273.043253 -318.936774) (xy 273.00275 -318.96473) (xy 272.958288 -318.985828) (xy 272.911017 -318.99952)
			(xy 272.862162 -319.005452) (xy 272.812987 -319.003471) (xy 272.764768 -318.993627) (xy 272.718752 -318.976175)
			(xy 272.676131 -318.951568) (xy 272.63801 -318.920443) (xy 272.605375 -318.883606) (xy 272.579072 -318.84201)
			(xy 272.559781 -318.796734) (xy 272.548004 -318.74895) (xy 272.544044 -318.699896) (xy 271.255236 -318.699896)
			(xy 271.254741 -318.724503) (xy 271.246846 -318.77308) (xy 271.231262 -318.819761) (xy 271.208391 -318.863338)
			(xy 271.178826 -318.902682) (xy 271.143333 -318.936774) (xy 271.10283 -318.96473) (xy 271.058368 -318.985828)
			(xy 271.011097 -318.99952) (xy 270.962242 -319.005452) (xy 270.913067 -319.003471) (xy 270.864848 -318.993627)
			(xy 270.818832 -318.976175) (xy 270.776211 -318.951568) (xy 270.73809 -318.920443) (xy 270.705455 -318.883606)
			(xy 270.679152 -318.84201) (xy 270.659861 -318.796734) (xy 270.648084 -318.74895) (xy 270.644124 -318.699896)
			(xy 263.526839 -318.699896) (xy 263.600049 -318.756463) (xy 263.712586 -318.853497) (xy 263.819753 -318.956432)
			(xy 263.92124 -319.064971) (xy 264.016754 -319.1788) (xy 264.106021 -319.297593) (xy 264.188782 -319.421005)
			(xy 264.2648 -319.548683) (xy 264.333855 -319.680256) (xy 264.395748 -319.815347) (xy 264.450301 -319.953564)
			(xy 264.497356 -320.094511) (xy 264.536778 -320.237781) (xy 264.568452 -320.38296) (xy 264.592288 -320.529629)
			(xy 264.608217 -320.677367) (xy 264.616193 -320.825747) (xy 264.616692 -320.900044) (xy 319.082429 -320.900044)
			(xy 319.086418 -320.751504) (xy 319.098375 -320.603391) (xy 319.118265 -320.456134) (xy 319.14603 -320.310158)
			(xy 319.181591 -320.165881) (xy 319.224845 -320.023722) (xy 319.275667 -319.884089) (xy 319.333911 -319.747386)
			(xy 319.399409 -319.614006) (xy 319.471972 -319.484334) (xy 319.55139 -319.358744) (xy 319.637435 -319.237597)
			(xy 319.729859 -319.121244) (xy 319.828395 -319.01002) (xy 319.932759 -318.904245) (xy 320.042651 -318.804225)
			(xy 320.157752 -318.710247) (xy 320.277732 -318.622583) (xy 320.402245 -318.541486) (xy 320.530931 -318.467189)
			(xy 320.66342 -318.399907) (xy 320.799329 -318.339833) (xy 320.938267 -318.287141) (xy 321.079833 -318.241982)
			(xy 321.223619 -318.204487) (xy 321.36921 -318.174765) (xy 321.516186 -318.1529) (xy 321.664125 -318.138956)
			(xy 321.812598 -318.132972) (xy 321.961179 -318.134967) (xy 322.109438 -318.144935) (xy 322.256949 -318.162846)
			(xy 322.403285 -318.188649) (xy 322.548026 -318.222269) (xy 322.690753 -318.263611) (xy 322.831056 -318.312554)
			(xy 322.968529 -318.368957) (xy 323.102776 -318.432658) (xy 323.233411 -318.503474) (xy 323.360056 -318.581199)
			(xy 323.482346 -318.66561) (xy 323.599929 -318.756463) (xy 323.712466 -318.853497) (xy 323.819633 -318.956432)
			(xy 323.92112 -319.064971) (xy 324.016634 -319.1788) (xy 324.105901 -319.297593) (xy 324.188662 -319.421005)
			(xy 324.26468 -319.548683) (xy 324.333735 -319.680256) (xy 324.395628 -319.815347) (xy 324.450181 -319.953564)
			(xy 324.497236 -320.094511) (xy 324.536658 -320.237781) (xy 324.568332 -320.38296) (xy 324.592168 -320.529629)
			(xy 324.608097 -320.677367) (xy 324.616073 -320.825747) (xy 324.616572 -320.900044) (xy 375.182393 -320.900044)
			(xy 375.186382 -320.751504) (xy 375.198339 -320.603391) (xy 375.218229 -320.456134) (xy 375.245994 -320.310158)
			(xy 375.281555 -320.165881) (xy 375.324809 -320.023722) (xy 375.375631 -319.884089) (xy 375.433875 -319.747386)
			(xy 375.499373 -319.614006) (xy 375.571936 -319.484334) (xy 375.651354 -319.358744) (xy 375.737399 -319.237597)
			(xy 375.829823 -319.121244) (xy 375.928359 -319.01002) (xy 376.032723 -318.904245) (xy 376.142615 -318.804225)
			(xy 376.257716 -318.710247) (xy 376.377696 -318.622583) (xy 376.502209 -318.541486) (xy 376.630895 -318.467189)
			(xy 376.763384 -318.399907) (xy 376.899293 -318.339833) (xy 377.038231 -318.287141) (xy 377.179797 -318.241982)
			(xy 377.323583 -318.204487) (xy 377.469174 -318.174765) (xy 377.61615 -318.1529) (xy 377.764089 -318.138956)
			(xy 377.912562 -318.132972) (xy 378.061143 -318.134967) (xy 378.209402 -318.144935) (xy 378.356913 -318.162846)
			(xy 378.503249 -318.188649) (xy 378.64799 -318.222269) (xy 378.790717 -318.263611) (xy 378.93102 -318.312554)
			(xy 379.068493 -318.368957) (xy 379.20274 -318.432658) (xy 379.333375 -318.503474) (xy 379.46002 -318.581199)
			(xy 379.58231 -318.66561) (xy 379.626683 -318.699896) (xy 386.744222 -318.699896) (xy 386.748182 -318.650842)
			(xy 386.759959 -318.603058) (xy 386.77925 -318.557782) (xy 386.805553 -318.516186) (xy 386.838188 -318.479349)
			(xy 386.876309 -318.448224) (xy 386.91893 -318.423617) (xy 386.964946 -318.406165) (xy 387.013165 -318.396321)
			(xy 387.06234 -318.39434) (xy 387.111195 -318.400272) (xy 387.158466 -318.413964) (xy 387.202928 -318.435062)
			(xy 387.243431 -318.463018) (xy 387.278924 -318.49711) (xy 387.308489 -318.536454) (xy 387.33136 -318.580031)
			(xy 387.346944 -318.626712) (xy 387.354839 -318.675289) (xy 387.355334 -318.699896) (xy 388.644142 -318.699896)
			(xy 388.648102 -318.650842) (xy 388.659879 -318.603058) (xy 388.67917 -318.557782) (xy 388.705473 -318.516186)
			(xy 388.738108 -318.479349) (xy 388.776229 -318.448224) (xy 388.81885 -318.423617) (xy 388.864866 -318.406165)
			(xy 388.913085 -318.396321) (xy 388.96226 -318.39434) (xy 389.011115 -318.400272) (xy 389.058386 -318.413964)
			(xy 389.102848 -318.435062) (xy 389.143351 -318.463018) (xy 389.178844 -318.49711) (xy 389.208409 -318.536454)
			(xy 389.23128 -318.580031) (xy 389.246864 -318.626712) (xy 389.254759 -318.675289) (xy 389.255254 -318.699896)
			(xy 390.544062 -318.699896) (xy 390.548022 -318.650842) (xy 390.559799 -318.603058) (xy 390.57909 -318.557782)
			(xy 390.605393 -318.516186) (xy 390.638028 -318.479349) (xy 390.676149 -318.448224) (xy 390.71877 -318.423617)
			(xy 390.764786 -318.406165) (xy 390.813005 -318.396321) (xy 390.86218 -318.39434) (xy 390.911035 -318.400272)
			(xy 390.958306 -318.413964) (xy 391.002768 -318.435062) (xy 391.043271 -318.463018) (xy 391.078764 -318.49711)
			(xy 391.108329 -318.536454) (xy 391.1312 -318.580031) (xy 391.146784 -318.626712) (xy 391.154679 -318.675289)
			(xy 391.155174 -318.699896) (xy 392.443982 -318.699896) (xy 392.447942 -318.650842) (xy 392.459719 -318.603058)
			(xy 392.47901 -318.557782) (xy 392.505313 -318.516186) (xy 392.537948 -318.479349) (xy 392.576069 -318.448224)
			(xy 392.61869 -318.423617) (xy 392.664706 -318.406165) (xy 392.712925 -318.396321) (xy 392.7621 -318.39434)
			(xy 392.810955 -318.400272) (xy 392.858226 -318.413964) (xy 392.902688 -318.435062) (xy 392.943191 -318.463018)
			(xy 392.978684 -318.49711) (xy 393.008249 -318.536454) (xy 393.03112 -318.580031) (xy 393.046704 -318.626712)
			(xy 393.054599 -318.675289) (xy 393.055094 -318.699896) (xy 394.344156 -318.699896) (xy 394.348116 -318.650842)
			(xy 394.359893 -318.603058) (xy 394.379184 -318.557782) (xy 394.405487 -318.516186) (xy 394.438122 -318.479349)
			(xy 394.476243 -318.448224) (xy 394.518864 -318.423617) (xy 394.56488 -318.406165) (xy 394.613099 -318.396321)
			(xy 394.662274 -318.39434) (xy 394.711129 -318.400272) (xy 394.7584 -318.413964) (xy 394.802862 -318.435062)
			(xy 394.843365 -318.463018) (xy 394.878858 -318.49711) (xy 394.908423 -318.536454) (xy 394.931294 -318.580031)
			(xy 394.946878 -318.626712) (xy 394.954773 -318.675289) (xy 394.955268 -318.699896) (xy 396.244076 -318.699896)
			(xy 396.248036 -318.650842) (xy 396.259813 -318.603058) (xy 396.279104 -318.557782) (xy 396.305407 -318.516186)
			(xy 396.338042 -318.479349) (xy 396.376163 -318.448224) (xy 396.418784 -318.423617) (xy 396.4648 -318.406165)
			(xy 396.513019 -318.396321) (xy 396.562194 -318.39434) (xy 396.611049 -318.400272) (xy 396.65832 -318.413964)
			(xy 396.702782 -318.435062) (xy 396.743285 -318.463018) (xy 396.778778 -318.49711) (xy 396.808343 -318.536454)
			(xy 396.831214 -318.580031) (xy 396.846798 -318.626712) (xy 396.854693 -318.675289) (xy 396.855188 -318.699896)
			(xy 398.143996 -318.699896) (xy 398.147956 -318.650842) (xy 398.159733 -318.603058) (xy 398.179024 -318.557782)
			(xy 398.205327 -318.516186) (xy 398.237962 -318.479349) (xy 398.276083 -318.448224) (xy 398.318704 -318.423617)
			(xy 398.36472 -318.406165) (xy 398.412939 -318.396321) (xy 398.462114 -318.39434) (xy 398.510969 -318.400272)
			(xy 398.55824 -318.413964) (xy 398.602702 -318.435062) (xy 398.643205 -318.463018) (xy 398.678698 -318.49711)
			(xy 398.708263 -318.536454) (xy 398.731134 -318.580031) (xy 398.746718 -318.626712) (xy 398.754613 -318.675289)
			(xy 398.755108 -318.699896) (xy 400.04417 -318.699896) (xy 400.04813 -318.650842) (xy 400.059907 -318.603058)
			(xy 400.079198 -318.557782) (xy 400.105501 -318.516186) (xy 400.138136 -318.479349) (xy 400.176257 -318.448224)
			(xy 400.218878 -318.423617) (xy 400.264894 -318.406165) (xy 400.313113 -318.396321) (xy 400.362288 -318.39434)
			(xy 400.411143 -318.400272) (xy 400.458414 -318.413964) (xy 400.502876 -318.435062) (xy 400.543379 -318.463018)
			(xy 400.578872 -318.49711) (xy 400.608437 -318.536454) (xy 400.631308 -318.580031) (xy 400.646892 -318.626712)
			(xy 400.654787 -318.675289) (xy 400.655282 -318.699896) (xy 401.94409 -318.699896) (xy 401.94805 -318.650842)
			(xy 401.959827 -318.603058) (xy 401.979118 -318.557782) (xy 402.005421 -318.516186) (xy 402.038056 -318.479349)
			(xy 402.076177 -318.448224) (xy 402.118798 -318.423617) (xy 402.164814 -318.406165) (xy 402.213033 -318.396321)
			(xy 402.262208 -318.39434) (xy 402.311063 -318.400272) (xy 402.358334 -318.413964) (xy 402.402796 -318.435062)
			(xy 402.443299 -318.463018) (xy 402.478792 -318.49711) (xy 402.508357 -318.536454) (xy 402.531228 -318.580031)
			(xy 402.546812 -318.626712) (xy 402.554707 -318.675289) (xy 402.555202 -318.699896) (xy 403.84401 -318.699896)
			(xy 403.84797 -318.650842) (xy 403.859747 -318.603058) (xy 403.879038 -318.557782) (xy 403.905341 -318.516186)
			(xy 403.937976 -318.479349) (xy 403.976097 -318.448224) (xy 404.018718 -318.423617) (xy 404.064734 -318.406165)
			(xy 404.112953 -318.396321) (xy 404.162128 -318.39434) (xy 404.210983 -318.400272) (xy 404.258254 -318.413964)
			(xy 404.302716 -318.435062) (xy 404.343219 -318.463018) (xy 404.378712 -318.49711) (xy 404.408277 -318.536454)
			(xy 404.431148 -318.580031) (xy 404.446732 -318.626712) (xy 404.454627 -318.675289) (xy 404.455122 -318.699896)
			(xy 405.744184 -318.699896) (xy 405.748144 -318.650842) (xy 405.759921 -318.603058) (xy 405.779212 -318.557782)
			(xy 405.805515 -318.516186) (xy 405.83815 -318.479349) (xy 405.876271 -318.448224) (xy 405.918892 -318.423617)
			(xy 405.964908 -318.406165) (xy 406.013127 -318.396321) (xy 406.062302 -318.39434) (xy 406.111157 -318.400272)
			(xy 406.158428 -318.413964) (xy 406.20289 -318.435062) (xy 406.243393 -318.463018) (xy 406.278886 -318.49711)
			(xy 406.308451 -318.536454) (xy 406.331322 -318.580031) (xy 406.346906 -318.626712) (xy 406.354801 -318.675289)
			(xy 406.355296 -318.699896) (xy 407.644104 -318.699896) (xy 407.648064 -318.650842) (xy 407.659841 -318.603058)
			(xy 407.679132 -318.557782) (xy 407.705435 -318.516186) (xy 407.73807 -318.479349) (xy 407.776191 -318.448224)
			(xy 407.818812 -318.423617) (xy 407.864828 -318.406165) (xy 407.913047 -318.396321) (xy 407.962222 -318.39434)
			(xy 408.011077 -318.400272) (xy 408.058348 -318.413964) (xy 408.10281 -318.435062) (xy 408.143313 -318.463018)
			(xy 408.178806 -318.49711) (xy 408.208371 -318.536454) (xy 408.231242 -318.580031) (xy 408.246826 -318.626712)
			(xy 408.254721 -318.675289) (xy 408.255216 -318.699896) (xy 409.544024 -318.699896) (xy 409.547984 -318.650842)
			(xy 409.559761 -318.603058) (xy 409.579052 -318.557782) (xy 409.605355 -318.516186) (xy 409.63799 -318.479349)
			(xy 409.676111 -318.448224) (xy 409.718732 -318.423617) (xy 409.764748 -318.406165) (xy 409.812967 -318.396321)
			(xy 409.862142 -318.39434) (xy 409.910997 -318.400272) (xy 409.958268 -318.413964) (xy 410.00273 -318.435062)
			(xy 410.043233 -318.463018) (xy 410.078726 -318.49711) (xy 410.108291 -318.536454) (xy 410.131162 -318.580031)
			(xy 410.146746 -318.626712) (xy 410.154641 -318.675289) (xy 410.155136 -318.699896) (xy 411.444198 -318.699896)
			(xy 411.448158 -318.650842) (xy 411.459935 -318.603058) (xy 411.479226 -318.557782) (xy 411.505529 -318.516186)
			(xy 411.538164 -318.479349) (xy 411.576285 -318.448224) (xy 411.618906 -318.423617) (xy 411.664922 -318.406165)
			(xy 411.713141 -318.396321) (xy 411.762316 -318.39434) (xy 411.811171 -318.400272) (xy 411.858442 -318.413964)
			(xy 411.902904 -318.435062) (xy 411.943407 -318.463018) (xy 411.9789 -318.49711) (xy 412.008465 -318.536454)
			(xy 412.031336 -318.580031) (xy 412.04692 -318.626712) (xy 412.054815 -318.675289) (xy 412.05531 -318.699896)
			(xy 413.344118 -318.699896) (xy 413.348078 -318.650842) (xy 413.359855 -318.603058) (xy 413.379146 -318.557782)
			(xy 413.405449 -318.516186) (xy 413.438084 -318.479349) (xy 413.476205 -318.448224) (xy 413.518826 -318.423617)
			(xy 413.564842 -318.406165) (xy 413.613061 -318.396321) (xy 413.662236 -318.39434) (xy 413.711091 -318.400272)
			(xy 413.758362 -318.413964) (xy 413.802824 -318.435062) (xy 413.843327 -318.463018) (xy 413.87882 -318.49711)
			(xy 413.908385 -318.536454) (xy 413.931256 -318.580031) (xy 413.94684 -318.626712) (xy 413.954735 -318.675289)
			(xy 413.95523 -318.699896) (xy 415.244038 -318.699896) (xy 415.247998 -318.650842) (xy 415.259775 -318.603058)
			(xy 415.279066 -318.557782) (xy 415.305369 -318.516186) (xy 415.338004 -318.479349) (xy 415.376125 -318.448224)
			(xy 415.418746 -318.423617) (xy 415.464762 -318.406165) (xy 415.512981 -318.396321) (xy 415.562156 -318.39434)
			(xy 415.611011 -318.400272) (xy 415.658282 -318.413964) (xy 415.702744 -318.435062) (xy 415.743247 -318.463018)
			(xy 415.77874 -318.49711) (xy 415.808305 -318.536454) (xy 415.831176 -318.580031) (xy 415.84676 -318.626712)
			(xy 415.854655 -318.675289) (xy 415.85515 -318.699896) (xy 417.144212 -318.699896) (xy 417.148172 -318.650842)
			(xy 417.159949 -318.603058) (xy 417.17924 -318.557782) (xy 417.205543 -318.516186) (xy 417.238178 -318.479349)
			(xy 417.276299 -318.448224) (xy 417.31892 -318.423617) (xy 417.364936 -318.406165) (xy 417.413155 -318.396321)
			(xy 417.46233 -318.39434) (xy 417.511185 -318.400272) (xy 417.558456 -318.413964) (xy 417.602918 -318.435062)
			(xy 417.643421 -318.463018) (xy 417.678914 -318.49711) (xy 417.708479 -318.536454) (xy 417.73135 -318.580031)
			(xy 417.746934 -318.626712) (xy 417.754829 -318.675289) (xy 417.755324 -318.699896) (xy 419.044132 -318.699896)
			(xy 419.048092 -318.650842) (xy 419.059869 -318.603058) (xy 419.07916 -318.557782) (xy 419.105463 -318.516186)
			(xy 419.138098 -318.479349) (xy 419.176219 -318.448224) (xy 419.21884 -318.423617) (xy 419.264856 -318.406165)
			(xy 419.313075 -318.396321) (xy 419.36225 -318.39434) (xy 419.411105 -318.400272) (xy 419.458376 -318.413964)
			(xy 419.502838 -318.435062) (xy 419.543341 -318.463018) (xy 419.578834 -318.49711) (xy 419.608399 -318.536454)
			(xy 419.63127 -318.580031) (xy 419.646854 -318.626712) (xy 419.654749 -318.675289) (xy 419.655244 -318.699896)
			(xy 420.944052 -318.699896) (xy 420.948012 -318.650842) (xy 420.959789 -318.603058) (xy 420.97908 -318.557782)
			(xy 421.005383 -318.516186) (xy 421.038018 -318.479349) (xy 421.076139 -318.448224) (xy 421.11876 -318.423617)
			(xy 421.164776 -318.406165) (xy 421.212995 -318.396321) (xy 421.26217 -318.39434) (xy 421.311025 -318.400272)
			(xy 421.358296 -318.413964) (xy 421.402758 -318.435062) (xy 421.443261 -318.463018) (xy 421.478754 -318.49711)
			(xy 421.508319 -318.536454) (xy 421.53119 -318.580031) (xy 421.546774 -318.626712) (xy 421.554669 -318.675289)
			(xy 421.555164 -318.699896) (xy 422.844226 -318.699896) (xy 422.848186 -318.650842) (xy 422.859963 -318.603058)
			(xy 422.879254 -318.557782) (xy 422.905557 -318.516186) (xy 422.938192 -318.479349) (xy 422.976313 -318.448224)
			(xy 423.018934 -318.423617) (xy 423.06495 -318.406165) (xy 423.113169 -318.396321) (xy 423.162344 -318.39434)
			(xy 423.211199 -318.400272) (xy 423.25847 -318.413964) (xy 423.302932 -318.435062) (xy 423.343435 -318.463018)
			(xy 423.378928 -318.49711) (xy 423.408493 -318.536454) (xy 423.431364 -318.580031) (xy 423.446948 -318.626712)
			(xy 423.454843 -318.675289) (xy 423.455338 -318.699896) (xy 424.744146 -318.699896) (xy 424.748106 -318.650842)
			(xy 424.759883 -318.603058) (xy 424.779174 -318.557782) (xy 424.805477 -318.516186) (xy 424.838112 -318.479349)
			(xy 424.876233 -318.448224) (xy 424.918854 -318.423617) (xy 424.96487 -318.406165) (xy 425.013089 -318.396321)
			(xy 425.062264 -318.39434) (xy 425.111119 -318.400272) (xy 425.15839 -318.413964) (xy 425.202852 -318.435062)
			(xy 425.243355 -318.463018) (xy 425.278848 -318.49711) (xy 425.308413 -318.536454) (xy 425.331284 -318.580031)
			(xy 425.346868 -318.626712) (xy 425.354763 -318.675289) (xy 425.355258 -318.699896) (xy 426.644066 -318.699896)
			(xy 426.648026 -318.650842) (xy 426.659803 -318.603058) (xy 426.679094 -318.557782) (xy 426.705397 -318.516186)
			(xy 426.738032 -318.479349) (xy 426.776153 -318.448224) (xy 426.818774 -318.423617) (xy 426.86479 -318.406165)
			(xy 426.913009 -318.396321) (xy 426.962184 -318.39434) (xy 427.011039 -318.400272) (xy 427.05831 -318.413964)
			(xy 427.102772 -318.435062) (xy 427.143275 -318.463018) (xy 427.178768 -318.49711) (xy 427.208333 -318.536454)
			(xy 427.231204 -318.580031) (xy 427.246788 -318.626712) (xy 427.254683 -318.675289) (xy 427.255178 -318.699896)
			(xy 428.543986 -318.699896) (xy 428.547946 -318.650842) (xy 428.559723 -318.603058) (xy 428.579014 -318.557782)
			(xy 428.605317 -318.516186) (xy 428.637952 -318.479349) (xy 428.676073 -318.448224) (xy 428.718694 -318.423617)
			(xy 428.76471 -318.406165) (xy 428.812929 -318.396321) (xy 428.862104 -318.39434) (xy 428.910959 -318.400272)
			(xy 428.95823 -318.413964) (xy 429.002692 -318.435062) (xy 429.043195 -318.463018) (xy 429.078688 -318.49711)
			(xy 429.108253 -318.536454) (xy 429.131124 -318.580031) (xy 429.146708 -318.626712) (xy 429.154603 -318.675289)
			(xy 429.155098 -318.699896) (xy 429.154603 -318.724503) (xy 429.146708 -318.77308) (xy 429.131124 -318.819761)
			(xy 429.108253 -318.863338) (xy 429.078688 -318.902682) (xy 429.043195 -318.936774) (xy 429.002692 -318.96473)
			(xy 428.95823 -318.985828) (xy 428.910959 -318.99952) (xy 428.862104 -319.005452) (xy 428.812929 -319.003471)
			(xy 428.76471 -318.993627) (xy 428.718694 -318.976175) (xy 428.676073 -318.951568) (xy 428.637952 -318.920443)
			(xy 428.605317 -318.883606) (xy 428.579014 -318.84201) (xy 428.559723 -318.796734) (xy 428.547946 -318.74895)
			(xy 428.543986 -318.699896) (xy 427.255178 -318.699896) (xy 427.254683 -318.724503) (xy 427.246788 -318.77308)
			(xy 427.231204 -318.819761) (xy 427.208333 -318.863338) (xy 427.178768 -318.902682) (xy 427.143275 -318.936774)
			(xy 427.102772 -318.96473) (xy 427.05831 -318.985828) (xy 427.011039 -318.99952) (xy 426.962184 -319.005452)
			(xy 426.913009 -319.003471) (xy 426.86479 -318.993627) (xy 426.818774 -318.976175) (xy 426.776153 -318.951568)
			(xy 426.738032 -318.920443) (xy 426.705397 -318.883606) (xy 426.679094 -318.84201) (xy 426.659803 -318.796734)
			(xy 426.648026 -318.74895) (xy 426.644066 -318.699896) (xy 425.355258 -318.699896) (xy 425.354763 -318.724503)
			(xy 425.346868 -318.77308) (xy 425.331284 -318.819761) (xy 425.308413 -318.863338) (xy 425.278848 -318.902682)
			(xy 425.243355 -318.936774) (xy 425.202852 -318.96473) (xy 425.15839 -318.985828) (xy 425.111119 -318.99952)
			(xy 425.062264 -319.005452) (xy 425.013089 -319.003471) (xy 424.96487 -318.993627) (xy 424.918854 -318.976175)
			(xy 424.876233 -318.951568) (xy 424.838112 -318.920443) (xy 424.805477 -318.883606) (xy 424.779174 -318.84201)
			(xy 424.759883 -318.796734) (xy 424.748106 -318.74895) (xy 424.744146 -318.699896) (xy 423.455338 -318.699896)
			(xy 423.454843 -318.724503) (xy 423.446948 -318.77308) (xy 423.431364 -318.819761) (xy 423.408493 -318.863338)
			(xy 423.378928 -318.902682) (xy 423.343435 -318.936774) (xy 423.302932 -318.96473) (xy 423.25847 -318.985828)
			(xy 423.211199 -318.99952) (xy 423.162344 -319.005452) (xy 423.113169 -319.003471) (xy 423.06495 -318.993627)
			(xy 423.018934 -318.976175) (xy 422.976313 -318.951568) (xy 422.938192 -318.920443) (xy 422.905557 -318.883606)
			(xy 422.879254 -318.84201) (xy 422.859963 -318.796734) (xy 422.848186 -318.74895) (xy 422.844226 -318.699896)
			(xy 421.555164 -318.699896) (xy 421.554669 -318.724503) (xy 421.546774 -318.77308) (xy 421.53119 -318.819761)
			(xy 421.508319 -318.863338) (xy 421.478754 -318.902682) (xy 421.443261 -318.936774) (xy 421.402758 -318.96473)
			(xy 421.358296 -318.985828) (xy 421.311025 -318.99952) (xy 421.26217 -319.005452) (xy 421.212995 -319.003471)
			(xy 421.164776 -318.993627) (xy 421.11876 -318.976175) (xy 421.076139 -318.951568) (xy 421.038018 -318.920443)
			(xy 421.005383 -318.883606) (xy 420.97908 -318.84201) (xy 420.959789 -318.796734) (xy 420.948012 -318.74895)
			(xy 420.944052 -318.699896) (xy 419.655244 -318.699896) (xy 419.654749 -318.724503) (xy 419.646854 -318.77308)
			(xy 419.63127 -318.819761) (xy 419.608399 -318.863338) (xy 419.578834 -318.902682) (xy 419.543341 -318.936774)
			(xy 419.502838 -318.96473) (xy 419.458376 -318.985828) (xy 419.411105 -318.99952) (xy 419.36225 -319.005452)
			(xy 419.313075 -319.003471) (xy 419.264856 -318.993627) (xy 419.21884 -318.976175) (xy 419.176219 -318.951568)
			(xy 419.138098 -318.920443) (xy 419.105463 -318.883606) (xy 419.07916 -318.84201) (xy 419.059869 -318.796734)
			(xy 419.048092 -318.74895) (xy 419.044132 -318.699896) (xy 417.755324 -318.699896) (xy 417.754829 -318.724503)
			(xy 417.746934 -318.77308) (xy 417.73135 -318.819761) (xy 417.708479 -318.863338) (xy 417.678914 -318.902682)
			(xy 417.643421 -318.936774) (xy 417.602918 -318.96473) (xy 417.558456 -318.985828) (xy 417.511185 -318.99952)
			(xy 417.46233 -319.005452) (xy 417.413155 -319.003471) (xy 417.364936 -318.993627) (xy 417.31892 -318.976175)
			(xy 417.276299 -318.951568) (xy 417.238178 -318.920443) (xy 417.205543 -318.883606) (xy 417.17924 -318.84201)
			(xy 417.159949 -318.796734) (xy 417.148172 -318.74895) (xy 417.144212 -318.699896) (xy 415.85515 -318.699896)
			(xy 415.854655 -318.724503) (xy 415.84676 -318.77308) (xy 415.831176 -318.819761) (xy 415.808305 -318.863338)
			(xy 415.77874 -318.902682) (xy 415.743247 -318.936774) (xy 415.702744 -318.96473) (xy 415.658282 -318.985828)
			(xy 415.611011 -318.99952) (xy 415.562156 -319.005452) (xy 415.512981 -319.003471) (xy 415.464762 -318.993627)
			(xy 415.418746 -318.976175) (xy 415.376125 -318.951568) (xy 415.338004 -318.920443) (xy 415.305369 -318.883606)
			(xy 415.279066 -318.84201) (xy 415.259775 -318.796734) (xy 415.247998 -318.74895) (xy 415.244038 -318.699896)
			(xy 413.95523 -318.699896) (xy 413.954735 -318.724503) (xy 413.94684 -318.77308) (xy 413.931256 -318.819761)
			(xy 413.908385 -318.863338) (xy 413.87882 -318.902682) (xy 413.843327 -318.936774) (xy 413.802824 -318.96473)
			(xy 413.758362 -318.985828) (xy 413.711091 -318.99952) (xy 413.662236 -319.005452) (xy 413.613061 -319.003471)
			(xy 413.564842 -318.993627) (xy 413.518826 -318.976175) (xy 413.476205 -318.951568) (xy 413.438084 -318.920443)
			(xy 413.405449 -318.883606) (xy 413.379146 -318.84201) (xy 413.359855 -318.796734) (xy 413.348078 -318.74895)
			(xy 413.344118 -318.699896) (xy 412.05531 -318.699896) (xy 412.054815 -318.724503) (xy 412.04692 -318.77308)
			(xy 412.031336 -318.819761) (xy 412.008465 -318.863338) (xy 411.9789 -318.902682) (xy 411.943407 -318.936774)
			(xy 411.902904 -318.96473) (xy 411.858442 -318.985828) (xy 411.811171 -318.99952) (xy 411.762316 -319.005452)
			(xy 411.713141 -319.003471) (xy 411.664922 -318.993627) (xy 411.618906 -318.976175) (xy 411.576285 -318.951568)
			(xy 411.538164 -318.920443) (xy 411.505529 -318.883606) (xy 411.479226 -318.84201) (xy 411.459935 -318.796734)
			(xy 411.448158 -318.74895) (xy 411.444198 -318.699896) (xy 410.155136 -318.699896) (xy 410.154641 -318.724503)
			(xy 410.146746 -318.77308) (xy 410.131162 -318.819761) (xy 410.108291 -318.863338) (xy 410.078726 -318.902682)
			(xy 410.043233 -318.936774) (xy 410.00273 -318.96473) (xy 409.958268 -318.985828) (xy 409.910997 -318.99952)
			(xy 409.862142 -319.005452) (xy 409.812967 -319.003471) (xy 409.764748 -318.993627) (xy 409.718732 -318.976175)
			(xy 409.676111 -318.951568) (xy 409.63799 -318.920443) (xy 409.605355 -318.883606) (xy 409.579052 -318.84201)
			(xy 409.559761 -318.796734) (xy 409.547984 -318.74895) (xy 409.544024 -318.699896) (xy 408.255216 -318.699896)
			(xy 408.254721 -318.724503) (xy 408.246826 -318.77308) (xy 408.231242 -318.819761) (xy 408.208371 -318.863338)
			(xy 408.178806 -318.902682) (xy 408.143313 -318.936774) (xy 408.10281 -318.96473) (xy 408.058348 -318.985828)
			(xy 408.011077 -318.99952) (xy 407.962222 -319.005452) (xy 407.913047 -319.003471) (xy 407.864828 -318.993627)
			(xy 407.818812 -318.976175) (xy 407.776191 -318.951568) (xy 407.73807 -318.920443) (xy 407.705435 -318.883606)
			(xy 407.679132 -318.84201) (xy 407.659841 -318.796734) (xy 407.648064 -318.74895) (xy 407.644104 -318.699896)
			(xy 406.355296 -318.699896) (xy 406.354801 -318.724503) (xy 406.346906 -318.77308) (xy 406.331322 -318.819761)
			(xy 406.308451 -318.863338) (xy 406.278886 -318.902682) (xy 406.243393 -318.936774) (xy 406.20289 -318.96473)
			(xy 406.158428 -318.985828) (xy 406.111157 -318.99952) (xy 406.062302 -319.005452) (xy 406.013127 -319.003471)
			(xy 405.964908 -318.993627) (xy 405.918892 -318.976175) (xy 405.876271 -318.951568) (xy 405.83815 -318.920443)
			(xy 405.805515 -318.883606) (xy 405.779212 -318.84201) (xy 405.759921 -318.796734) (xy 405.748144 -318.74895)
			(xy 405.744184 -318.699896) (xy 404.455122 -318.699896) (xy 404.454627 -318.724503) (xy 404.446732 -318.77308)
			(xy 404.431148 -318.819761) (xy 404.408277 -318.863338) (xy 404.378712 -318.902682) (xy 404.343219 -318.936774)
			(xy 404.302716 -318.96473) (xy 404.258254 -318.985828) (xy 404.210983 -318.99952) (xy 404.162128 -319.005452)
			(xy 404.112953 -319.003471) (xy 404.064734 -318.993627) (xy 404.018718 -318.976175) (xy 403.976097 -318.951568)
			(xy 403.937976 -318.920443) (xy 403.905341 -318.883606) (xy 403.879038 -318.84201) (xy 403.859747 -318.796734)
			(xy 403.84797 -318.74895) (xy 403.84401 -318.699896) (xy 402.555202 -318.699896) (xy 402.554707 -318.724503)
			(xy 402.546812 -318.77308) (xy 402.531228 -318.819761) (xy 402.508357 -318.863338) (xy 402.478792 -318.902682)
			(xy 402.443299 -318.936774) (xy 402.402796 -318.96473) (xy 402.358334 -318.985828) (xy 402.311063 -318.99952)
			(xy 402.262208 -319.005452) (xy 402.213033 -319.003471) (xy 402.164814 -318.993627) (xy 402.118798 -318.976175)
			(xy 402.076177 -318.951568) (xy 402.038056 -318.920443) (xy 402.005421 -318.883606) (xy 401.979118 -318.84201)
			(xy 401.959827 -318.796734) (xy 401.94805 -318.74895) (xy 401.94409 -318.699896) (xy 400.655282 -318.699896)
			(xy 400.654787 -318.724503) (xy 400.646892 -318.77308) (xy 400.631308 -318.819761) (xy 400.608437 -318.863338)
			(xy 400.578872 -318.902682) (xy 400.543379 -318.936774) (xy 400.502876 -318.96473) (xy 400.458414 -318.985828)
			(xy 400.411143 -318.99952) (xy 400.362288 -319.005452) (xy 400.313113 -319.003471) (xy 400.264894 -318.993627)
			(xy 400.218878 -318.976175) (xy 400.176257 -318.951568) (xy 400.138136 -318.920443) (xy 400.105501 -318.883606)
			(xy 400.079198 -318.84201) (xy 400.059907 -318.796734) (xy 400.04813 -318.74895) (xy 400.04417 -318.699896)
			(xy 398.755108 -318.699896) (xy 398.754613 -318.724503) (xy 398.746718 -318.77308) (xy 398.731134 -318.819761)
			(xy 398.708263 -318.863338) (xy 398.678698 -318.902682) (xy 398.643205 -318.936774) (xy 398.602702 -318.96473)
			(xy 398.55824 -318.985828) (xy 398.510969 -318.99952) (xy 398.462114 -319.005452) (xy 398.412939 -319.003471)
			(xy 398.36472 -318.993627) (xy 398.318704 -318.976175) (xy 398.276083 -318.951568) (xy 398.237962 -318.920443)
			(xy 398.205327 -318.883606) (xy 398.179024 -318.84201) (xy 398.159733 -318.796734) (xy 398.147956 -318.74895)
			(xy 398.143996 -318.699896) (xy 396.855188 -318.699896) (xy 396.854693 -318.724503) (xy 396.846798 -318.77308)
			(xy 396.831214 -318.819761) (xy 396.808343 -318.863338) (xy 396.778778 -318.902682) (xy 396.743285 -318.936774)
			(xy 396.702782 -318.96473) (xy 396.65832 -318.985828) (xy 396.611049 -318.99952) (xy 396.562194 -319.005452)
			(xy 396.513019 -319.003471) (xy 396.4648 -318.993627) (xy 396.418784 -318.976175) (xy 396.376163 -318.951568)
			(xy 396.338042 -318.920443) (xy 396.305407 -318.883606) (xy 396.279104 -318.84201) (xy 396.259813 -318.796734)
			(xy 396.248036 -318.74895) (xy 396.244076 -318.699896) (xy 394.955268 -318.699896) (xy 394.954773 -318.724503)
			(xy 394.946878 -318.77308) (xy 394.931294 -318.819761) (xy 394.908423 -318.863338) (xy 394.878858 -318.902682)
			(xy 394.843365 -318.936774) (xy 394.802862 -318.96473) (xy 394.7584 -318.985828) (xy 394.711129 -318.99952)
			(xy 394.662274 -319.005452) (xy 394.613099 -319.003471) (xy 394.56488 -318.993627) (xy 394.518864 -318.976175)
			(xy 394.476243 -318.951568) (xy 394.438122 -318.920443) (xy 394.405487 -318.883606) (xy 394.379184 -318.84201)
			(xy 394.359893 -318.796734) (xy 394.348116 -318.74895) (xy 394.344156 -318.699896) (xy 393.055094 -318.699896)
			(xy 393.054599 -318.724503) (xy 393.046704 -318.77308) (xy 393.03112 -318.819761) (xy 393.008249 -318.863338)
			(xy 392.978684 -318.902682) (xy 392.943191 -318.936774) (xy 392.902688 -318.96473) (xy 392.858226 -318.985828)
			(xy 392.810955 -318.99952) (xy 392.7621 -319.005452) (xy 392.712925 -319.003471) (xy 392.664706 -318.993627)
			(xy 392.61869 -318.976175) (xy 392.576069 -318.951568) (xy 392.537948 -318.920443) (xy 392.505313 -318.883606)
			(xy 392.47901 -318.84201) (xy 392.459719 -318.796734) (xy 392.447942 -318.74895) (xy 392.443982 -318.699896)
			(xy 391.155174 -318.699896) (xy 391.154679 -318.724503) (xy 391.146784 -318.77308) (xy 391.1312 -318.819761)
			(xy 391.108329 -318.863338) (xy 391.078764 -318.902682) (xy 391.043271 -318.936774) (xy 391.002768 -318.96473)
			(xy 390.958306 -318.985828) (xy 390.911035 -318.99952) (xy 390.86218 -319.005452) (xy 390.813005 -319.003471)
			(xy 390.764786 -318.993627) (xy 390.71877 -318.976175) (xy 390.676149 -318.951568) (xy 390.638028 -318.920443)
			(xy 390.605393 -318.883606) (xy 390.57909 -318.84201) (xy 390.559799 -318.796734) (xy 390.548022 -318.74895)
			(xy 390.544062 -318.699896) (xy 389.255254 -318.699896) (xy 389.254759 -318.724503) (xy 389.246864 -318.77308)
			(xy 389.23128 -318.819761) (xy 389.208409 -318.863338) (xy 389.178844 -318.902682) (xy 389.143351 -318.936774)
			(xy 389.102848 -318.96473) (xy 389.058386 -318.985828) (xy 389.011115 -318.99952) (xy 388.96226 -319.005452)
			(xy 388.913085 -319.003471) (xy 388.864866 -318.993627) (xy 388.81885 -318.976175) (xy 388.776229 -318.951568)
			(xy 388.738108 -318.920443) (xy 388.705473 -318.883606) (xy 388.67917 -318.84201) (xy 388.659879 -318.796734)
			(xy 388.648102 -318.74895) (xy 388.644142 -318.699896) (xy 387.355334 -318.699896) (xy 387.354839 -318.724503)
			(xy 387.346944 -318.77308) (xy 387.33136 -318.819761) (xy 387.308489 -318.863338) (xy 387.278924 -318.902682)
			(xy 387.243431 -318.936774) (xy 387.202928 -318.96473) (xy 387.158466 -318.985828) (xy 387.111195 -318.99952)
			(xy 387.06234 -319.005452) (xy 387.013165 -319.003471) (xy 386.964946 -318.993627) (xy 386.91893 -318.976175)
			(xy 386.876309 -318.951568) (xy 386.838188 -318.920443) (xy 386.805553 -318.883606) (xy 386.77925 -318.84201)
			(xy 386.759959 -318.796734) (xy 386.748182 -318.74895) (xy 386.744222 -318.699896) (xy 379.626683 -318.699896)
			(xy 379.699893 -318.756463) (xy 379.81243 -318.853497) (xy 379.919597 -318.956432) (xy 380.021084 -319.064971)
			(xy 380.116598 -319.1788) (xy 380.205865 -319.297593) (xy 380.288626 -319.421005) (xy 380.364644 -319.548683)
			(xy 380.433699 -319.680256) (xy 380.495592 -319.815347) (xy 380.550145 -319.953564) (xy 380.5972 -320.094511)
			(xy 380.636622 -320.237781) (xy 380.668296 -320.38296) (xy 380.692132 -320.529629) (xy 380.708061 -320.677367)
			(xy 380.716037 -320.825747) (xy 380.716536 -320.900044) (xy 435.182527 -320.900044) (xy 435.186516 -320.751504)
			(xy 435.198473 -320.603391) (xy 435.218363 -320.456134) (xy 435.246128 -320.310158) (xy 435.281689 -320.165881)
			(xy 435.324943 -320.023722) (xy 435.375765 -319.884089) (xy 435.434009 -319.747386) (xy 435.499507 -319.614006)
			(xy 435.57207 -319.484334) (xy 435.651488 -319.358744) (xy 435.737533 -319.237597) (xy 435.829957 -319.121244)
			(xy 435.928493 -319.01002) (xy 436.032857 -318.904245) (xy 436.142749 -318.804225) (xy 436.25785 -318.710247)
			(xy 436.37783 -318.622583) (xy 436.502343 -318.541486) (xy 436.631029 -318.467189) (xy 436.763518 -318.399907)
			(xy 436.899427 -318.339833) (xy 437.038365 -318.287141) (xy 437.179931 -318.241982) (xy 437.323717 -318.204487)
			(xy 437.469308 -318.174765) (xy 437.616284 -318.1529) (xy 437.764223 -318.138956) (xy 437.912696 -318.132972)
			(xy 438.061277 -318.134967) (xy 438.209536 -318.144935) (xy 438.357047 -318.162846) (xy 438.503383 -318.188649)
			(xy 438.648124 -318.222269) (xy 438.790851 -318.263611) (xy 438.931154 -318.312554) (xy 439.068627 -318.368957)
			(xy 439.202874 -318.432658) (xy 439.333509 -318.503474) (xy 439.460154 -318.581199) (xy 439.582444 -318.66561)
			(xy 439.700027 -318.756463) (xy 439.812564 -318.853497) (xy 439.919731 -318.956432) (xy 440.021218 -319.064971)
			(xy 440.116732 -319.1788) (xy 440.205999 -319.297593) (xy 440.28876 -319.421005) (xy 440.364778 -319.548683)
			(xy 440.433833 -319.680256) (xy 440.495726 -319.815347) (xy 440.550279 -319.953564) (xy 440.597334 -320.094511)
			(xy 440.636756 -320.237781) (xy 440.66843 -320.38296) (xy 440.692266 -320.529629) (xy 440.708195 -320.677367)
			(xy 440.716171 -320.825747) (xy 440.71667 -320.900044) (xy 440.716171 -320.974341) (xy 440.708195 -321.122721)
			(xy 440.692266 -321.270459) (xy 440.66843 -321.417128) (xy 440.636756 -321.562307) (xy 440.597334 -321.705577)
			(xy 440.550279 -321.846524) (xy 440.495726 -321.984741) (xy 440.433833 -322.119832) (xy 440.364778 -322.251405)
			(xy 440.28876 -322.379083) (xy 440.205999 -322.502495) (xy 440.116732 -322.621288) (xy 440.021218 -322.735117)
			(xy 439.919731 -322.843656) (xy 439.812564 -322.946591) (xy 439.700027 -323.043625) (xy 439.582444 -323.134478)
			(xy 439.460154 -323.218889) (xy 439.333509 -323.296614) (xy 439.202874 -323.36743) (xy 439.068627 -323.431131)
			(xy 438.931154 -323.487534) (xy 438.790851 -323.536477) (xy 438.648124 -323.577819) (xy 438.503383 -323.611439)
			(xy 438.357047 -323.637242) (xy 438.209536 -323.655153) (xy 438.061277 -323.665121) (xy 437.912696 -323.667116)
			(xy 437.764223 -323.661132) (xy 437.616284 -323.647188) (xy 437.469308 -323.625323) (xy 437.323717 -323.595601)
			(xy 437.179931 -323.558106) (xy 437.038365 -323.512947) (xy 436.899427 -323.460255) (xy 436.763518 -323.400181)
			(xy 436.631029 -323.332899) (xy 436.502343 -323.258602) (xy 436.37783 -323.177505) (xy 436.25785 -323.089841)
			(xy 436.142749 -322.995863) (xy 436.032857 -322.895843) (xy 435.928493 -322.790068) (xy 435.829957 -322.678844)
			(xy 435.737533 -322.562491) (xy 435.651488 -322.441344) (xy 435.57207 -322.315754) (xy 435.499507 -322.186082)
			(xy 435.434009 -322.052702) (xy 435.375765 -321.915999) (xy 435.324943 -321.776366) (xy 435.281689 -321.634207)
			(xy 435.246128 -321.48993) (xy 435.218363 -321.343954) (xy 435.198473 -321.196697) (xy 435.186516 -321.048584)
			(xy 435.182527 -320.900044) (xy 380.716536 -320.900044) (xy 380.716037 -320.974341) (xy 380.708061 -321.122721)
			(xy 380.692132 -321.270459) (xy 380.668296 -321.417128) (xy 380.636622 -321.562307) (xy 380.5972 -321.705577)
			(xy 380.550145 -321.846524) (xy 380.495592 -321.984741) (xy 380.433699 -322.119832) (xy 380.364644 -322.251405)
			(xy 380.288626 -322.379083) (xy 380.205865 -322.502495) (xy 380.116598 -322.621288) (xy 380.021084 -322.735117)
			(xy 379.919597 -322.843656) (xy 379.81243 -322.946591) (xy 379.699893 -323.043625) (xy 379.58231 -323.134478)
			(xy 379.46002 -323.218889) (xy 379.333375 -323.296614) (xy 379.20274 -323.36743) (xy 379.068493 -323.431131)
			(xy 378.93102 -323.487534) (xy 378.790717 -323.536477) (xy 378.64799 -323.577819) (xy 378.503249 -323.611439)
			(xy 378.356913 -323.637242) (xy 378.209402 -323.655153) (xy 378.061143 -323.665121) (xy 377.912562 -323.667116)
			(xy 377.764089 -323.661132) (xy 377.61615 -323.647188) (xy 377.469174 -323.625323) (xy 377.323583 -323.595601)
			(xy 377.179797 -323.558106) (xy 377.038231 -323.512947) (xy 376.899293 -323.460255) (xy 376.763384 -323.400181)
			(xy 376.630895 -323.332899) (xy 376.502209 -323.258602) (xy 376.377696 -323.177505) (xy 376.257716 -323.089841)
			(xy 376.142615 -322.995863) (xy 376.032723 -322.895843) (xy 375.928359 -322.790068) (xy 375.829823 -322.678844)
			(xy 375.737399 -322.562491) (xy 375.651354 -322.441344) (xy 375.571936 -322.315754) (xy 375.499373 -322.186082)
			(xy 375.433875 -322.052702) (xy 375.375631 -321.915999) (xy 375.324809 -321.776366) (xy 375.281555 -321.634207)
			(xy 375.245994 -321.48993) (xy 375.218229 -321.343954) (xy 375.198339 -321.196697) (xy 375.186382 -321.048584)
			(xy 375.182393 -320.900044) (xy 324.616572 -320.900044) (xy 324.616073 -320.974341) (xy 324.608097 -321.122721)
			(xy 324.592168 -321.270459) (xy 324.568332 -321.417128) (xy 324.536658 -321.562307) (xy 324.497236 -321.705577)
			(xy 324.450181 -321.846524) (xy 324.395628 -321.984741) (xy 324.333735 -322.119832) (xy 324.26468 -322.251405)
			(xy 324.188662 -322.379083) (xy 324.105901 -322.502495) (xy 324.016634 -322.621288) (xy 323.92112 -322.735117)
			(xy 323.819633 -322.843656) (xy 323.712466 -322.946591) (xy 323.599929 -323.043625) (xy 323.482346 -323.134478)
			(xy 323.360056 -323.218889) (xy 323.233411 -323.296614) (xy 323.102776 -323.36743) (xy 322.968529 -323.431131)
			(xy 322.831056 -323.487534) (xy 322.690753 -323.536477) (xy 322.548026 -323.577819) (xy 322.403285 -323.611439)
			(xy 322.256949 -323.637242) (xy 322.109438 -323.655153) (xy 321.961179 -323.665121) (xy 321.812598 -323.667116)
			(xy 321.664125 -323.661132) (xy 321.516186 -323.647188) (xy 321.36921 -323.625323) (xy 321.223619 -323.595601)
			(xy 321.079833 -323.558106) (xy 320.938267 -323.512947) (xy 320.799329 -323.460255) (xy 320.66342 -323.400181)
			(xy 320.530931 -323.332899) (xy 320.402245 -323.258602) (xy 320.277732 -323.177505) (xy 320.157752 -323.089841)
			(xy 320.042651 -322.995863) (xy 319.932759 -322.895843) (xy 319.828395 -322.790068) (xy 319.729859 -322.678844)
			(xy 319.637435 -322.562491) (xy 319.55139 -322.441344) (xy 319.471972 -322.315754) (xy 319.399409 -322.186082)
			(xy 319.333911 -322.052702) (xy 319.275667 -321.915999) (xy 319.224845 -321.776366) (xy 319.181591 -321.634207)
			(xy 319.14603 -321.48993) (xy 319.118265 -321.343954) (xy 319.098375 -321.196697) (xy 319.086418 -321.048584)
			(xy 319.082429 -320.900044) (xy 264.616692 -320.900044) (xy 264.616193 -320.974341) (xy 264.608217 -321.122721)
			(xy 264.592288 -321.270459) (xy 264.568452 -321.417128) (xy 264.536778 -321.562307) (xy 264.497356 -321.705577)
			(xy 264.450301 -321.846524) (xy 264.395748 -321.984741) (xy 264.333855 -322.119832) (xy 264.2648 -322.251405)
			(xy 264.188782 -322.379083) (xy 264.106021 -322.502495) (xy 264.016754 -322.621288) (xy 263.92124 -322.735117)
			(xy 263.819753 -322.843656) (xy 263.712586 -322.946591) (xy 263.600049 -323.043625) (xy 263.482466 -323.134478)
			(xy 263.360176 -323.218889) (xy 263.233531 -323.296614) (xy 263.102896 -323.36743) (xy 262.968649 -323.431131)
			(xy 262.831176 -323.487534) (xy 262.690873 -323.536477) (xy 262.548146 -323.577819) (xy 262.403405 -323.611439)
			(xy 262.257069 -323.637242) (xy 262.109558 -323.655153) (xy 261.961299 -323.665121) (xy 261.812718 -323.667116)
			(xy 261.664245 -323.661132) (xy 261.516306 -323.647188) (xy 261.36933 -323.625323) (xy 261.223739 -323.595601)
			(xy 261.079953 -323.558106) (xy 260.938387 -323.512947) (xy 260.799449 -323.460255) (xy 260.66354 -323.400181)
			(xy 260.531051 -323.332899) (xy 260.402365 -323.258602) (xy 260.277852 -323.177505) (xy 260.157872 -323.089841)
			(xy 260.042771 -322.995863) (xy 259.932879 -322.895843) (xy 259.828515 -322.790068) (xy 259.729979 -322.678844)
			(xy 259.637555 -322.562491) (xy 259.55151 -322.441344) (xy 259.472092 -322.315754) (xy 259.399529 -322.186082)
			(xy 259.334031 -322.052702) (xy 259.275787 -321.915999) (xy 259.224965 -321.776366) (xy 259.181711 -321.634207)
			(xy 259.14615 -321.48993) (xy 259.118385 -321.343954) (xy 259.098495 -321.196697) (xy 259.086538 -321.048584)
			(xy 259.082549 -320.900044) (xy 208.516474 -320.900044) (xy 208.515975 -320.974341) (xy 208.507999 -321.122721)
			(xy 208.49207 -321.270459) (xy 208.468234 -321.417128) (xy 208.43656 -321.562307) (xy 208.397138 -321.705577)
			(xy 208.350083 -321.846524) (xy 208.29553 -321.984741) (xy 208.233637 -322.119832) (xy 208.164582 -322.251405)
			(xy 208.088564 -322.379083) (xy 208.005803 -322.502495) (xy 207.916536 -322.621288) (xy 207.821022 -322.735117)
			(xy 207.719535 -322.843656) (xy 207.612368 -322.946591) (xy 207.499831 -323.043625) (xy 207.382248 -323.134478)
			(xy 207.259958 -323.218889) (xy 207.133313 -323.296614) (xy 207.002678 -323.36743) (xy 206.868431 -323.431131)
			(xy 206.730958 -323.487534) (xy 206.590655 -323.536477) (xy 206.447928 -323.577819) (xy 206.303187 -323.611439)
			(xy 206.156851 -323.637242) (xy 206.00934 -323.655153) (xy 205.861081 -323.665121) (xy 205.7125 -323.667116)
			(xy 205.564027 -323.661132) (xy 205.416088 -323.647188) (xy 205.269112 -323.625323) (xy 205.123521 -323.595601)
			(xy 204.979735 -323.558106) (xy 204.838169 -323.512947) (xy 204.699231 -323.460255) (xy 204.563322 -323.400181)
			(xy 204.430833 -323.332899) (xy 204.302147 -323.258602) (xy 204.177634 -323.177505) (xy 204.057654 -323.089841)
			(xy 203.942553 -322.995863) (xy 203.832661 -322.895843) (xy 203.728297 -322.790068) (xy 203.629761 -322.678844)
			(xy 203.537337 -322.562491) (xy 203.451292 -322.441344) (xy 203.371874 -322.315754) (xy 203.299311 -322.186082)
			(xy 203.233813 -322.052702) (xy 203.175569 -321.915999) (xy 203.124747 -321.776366) (xy 203.081493 -321.634207)
			(xy 203.045932 -321.48993) (xy 203.018167 -321.343954) (xy 202.998277 -321.196697) (xy 202.98632 -321.048584)
			(xy 202.982331 -320.900044) (xy 148.516594 -320.900044) (xy 148.516095 -320.974341) (xy 148.508119 -321.122721)
			(xy 148.49219 -321.270459) (xy 148.468354 -321.417128) (xy 148.43668 -321.562307) (xy 148.397258 -321.705577)
			(xy 148.350203 -321.846524) (xy 148.29565 -321.984741) (xy 148.233757 -322.119832) (xy 148.164702 -322.251405)
			(xy 148.088684 -322.379083) (xy 148.005923 -322.502495) (xy 147.916656 -322.621288) (xy 147.821142 -322.735117)
			(xy 147.719655 -322.843656) (xy 147.612488 -322.946591) (xy 147.499951 -323.043625) (xy 147.382368 -323.134478)
			(xy 147.260078 -323.218889) (xy 147.133433 -323.296614) (xy 147.002798 -323.36743) (xy 146.868551 -323.431131)
			(xy 146.731078 -323.487534) (xy 146.590775 -323.536477) (xy 146.448048 -323.577819) (xy 146.303307 -323.611439)
			(xy 146.156971 -323.637242) (xy 146.00946 -323.655153) (xy 145.861201 -323.665121) (xy 145.71262 -323.667116)
			(xy 145.564147 -323.661132) (xy 145.416208 -323.647188) (xy 145.269232 -323.625323) (xy 145.123641 -323.595601)
			(xy 144.979855 -323.558106) (xy 144.838289 -323.512947) (xy 144.699351 -323.460255) (xy 144.563442 -323.400181)
			(xy 144.430953 -323.332899) (xy 144.302267 -323.258602) (xy 144.177754 -323.177505) (xy 144.057774 -323.089841)
			(xy 143.942673 -322.995863) (xy 143.832781 -322.895843) (xy 143.728417 -322.790068) (xy 143.629881 -322.678844)
			(xy 143.537457 -322.562491) (xy 143.451412 -322.441344) (xy 143.371994 -322.315754) (xy 143.299431 -322.186082)
			(xy 143.233933 -322.052702) (xy 143.175689 -321.915999) (xy 143.124867 -321.776366) (xy 143.081613 -321.634207)
			(xy 143.046052 -321.48993) (xy 143.018287 -321.343954) (xy 142.998397 -321.196697) (xy 142.98644 -321.048584)
			(xy 142.982451 -320.900044) (xy 92.41663 -320.900044) (xy 92.416131 -320.974341) (xy 92.408155 -321.122721)
			(xy 92.392226 -321.270459) (xy 92.36839 -321.417128) (xy 92.336716 -321.562307) (xy 92.297294 -321.705577)
			(xy 92.250239 -321.846524) (xy 92.195686 -321.984741) (xy 92.133793 -322.119832) (xy 92.064738 -322.251405)
			(xy 91.98872 -322.379083) (xy 91.905959 -322.502495) (xy 91.816692 -322.621288) (xy 91.721178 -322.735117)
			(xy 91.619691 -322.843656) (xy 91.512524 -322.946591) (xy 91.399987 -323.043625) (xy 91.282404 -323.134478)
			(xy 91.160114 -323.218889) (xy 91.033469 -323.296614) (xy 90.902834 -323.36743) (xy 90.768587 -323.431131)
			(xy 90.631114 -323.487534) (xy 90.490811 -323.536477) (xy 90.348084 -323.577819) (xy 90.203343 -323.611439)
			(xy 90.057007 -323.637242) (xy 89.909496 -323.655153) (xy 89.761237 -323.665121) (xy 89.612656 -323.667116)
			(xy 89.464183 -323.661132) (xy 89.316244 -323.647188) (xy 89.169268 -323.625323) (xy 89.023677 -323.595601)
			(xy 88.879891 -323.558106) (xy 88.738325 -323.512947) (xy 88.599387 -323.460255) (xy 88.463478 -323.400181)
			(xy 88.330989 -323.332899) (xy 88.202303 -323.258602) (xy 88.07779 -323.177505) (xy 87.95781 -323.089841)
			(xy 87.842709 -322.995863) (xy 87.732817 -322.895843) (xy 87.628453 -322.790068) (xy 87.529917 -322.678844)
			(xy 87.437493 -322.562491) (xy 87.351448 -322.441344) (xy 87.27203 -322.315754) (xy 87.199467 -322.186082)
			(xy 87.133969 -322.052702) (xy 87.075725 -321.915999) (xy 87.024903 -321.776366) (xy 86.981649 -321.634207)
			(xy 86.946088 -321.48993) (xy 86.918323 -321.343954) (xy 86.898433 -321.196697) (xy 86.886476 -321.048584)
			(xy 86.882487 -320.900044) (xy 32.416496 -320.900044) (xy 32.415997 -320.974341) (xy 32.408021 -321.122721)
			(xy 32.392092 -321.270459) (xy 32.368256 -321.417128) (xy 32.336582 -321.562307) (xy 32.29716 -321.705577)
			(xy 32.250105 -321.846524) (xy 32.195552 -321.984741) (xy 32.133659 -322.119832) (xy 32.064604 -322.251405)
			(xy 31.988586 -322.379083) (xy 31.905825 -322.502495) (xy 31.816558 -322.621288) (xy 31.721044 -322.735117)
			(xy 31.619557 -322.843656) (xy 31.51239 -322.946591) (xy 31.399853 -323.043625) (xy 31.28227 -323.134478)
			(xy 31.15998 -323.218889) (xy 31.033335 -323.296614) (xy 30.9027 -323.36743) (xy 30.768453 -323.431131)
			(xy 30.63098 -323.487534) (xy 30.490677 -323.536477) (xy 30.34795 -323.577819) (xy 30.203209 -323.611439)
			(xy 30.056873 -323.637242) (xy 29.909362 -323.655153) (xy 29.761103 -323.665121) (xy 29.612522 -323.667116)
			(xy 29.464049 -323.661132) (xy 29.31611 -323.647188) (xy 29.169134 -323.625323) (xy 29.023543 -323.595601)
			(xy 28.879757 -323.558106) (xy 28.738191 -323.512947) (xy 28.599253 -323.460255) (xy 28.463344 -323.400181)
			(xy 28.330855 -323.332899) (xy 28.202169 -323.258602) (xy 28.077656 -323.177505) (xy 27.957676 -323.089841)
			(xy 27.842575 -322.995863) (xy 27.732683 -322.895843) (xy 27.628319 -322.790068) (xy 27.529783 -322.678844)
			(xy 27.437359 -322.562491) (xy 27.351314 -322.441344) (xy 27.271896 -322.315754) (xy 27.199333 -322.186082)
			(xy 27.133835 -322.052702) (xy 27.075591 -321.915999) (xy 27.024769 -321.776366) (xy 26.981515 -321.634207)
			(xy 26.945954 -321.48993) (xy 26.918189 -321.343954) (xy 26.898299 -321.196697) (xy 26.886342 -321.048584)
			(xy 26.882353 -320.900044) (xy 0.509016 -320.900044) (xy 0.509016 -330.416662) (xy 97.355152 -330.416662)
			(xy 97.355152 -329.553062) (xy 97.355642 -329.523078) (xy 97.36347 -329.463622) (xy 97.378991 -329.405697)
			(xy 97.40194 -329.350293) (xy 97.431924 -329.298359) (xy 97.46843 -329.250783) (xy 97.510835 -329.208378)
			(xy 97.558411 -329.171872) (xy 97.610345 -329.141888) (xy 97.665749 -329.118939) (xy 97.723674 -329.103418)
			(xy 97.78313 -329.09559) (xy 97.843098 -329.09559) (xy 97.902554 -329.103418) (xy 97.960479 -329.118939)
			(xy 98.015883 -329.141888) (xy 98.067817 -329.171872) (xy 98.115393 -329.208378) (xy 98.157798 -329.250783)
			(xy 98.194304 -329.298359) (xy 98.224288 -329.350293) (xy 98.247237 -329.405697) (xy 98.262758 -329.463622)
			(xy 98.270586 -329.523078) (xy 98.271076 -329.553062) (xy 98.271076 -330.416662) (xy 98.270586 -330.446646)
			(xy 98.262758 -330.506102) (xy 98.247237 -330.564027) (xy 98.224288 -330.619431) (xy 98.194304 -330.671365)
			(xy 98.157798 -330.718941) (xy 98.115393 -330.761346) (xy 98.067817 -330.797852) (xy 98.015883 -330.827836)
			(xy 97.960479 -330.850785) (xy 97.902554 -330.866306) (xy 97.843098 -330.874134) (xy 97.78313 -330.874134)
			(xy 97.723674 -330.866306) (xy 97.665749 -330.850785) (xy 97.610345 -330.827836) (xy 97.558411 -330.797852)
			(xy 97.510835 -330.761346) (xy 97.46843 -330.718941) (xy 97.431924 -330.671365) (xy 97.40194 -330.619431)
			(xy 97.378991 -330.564027) (xy 97.36347 -330.506102) (xy 97.355642 -330.446646) (xy 97.355152 -330.416662)
			(xy 0.509016 -330.416662) (xy 0.509016 -331.53223) (xy 114.955828 -331.53223) (xy 114.955828 -330.66863)
			(xy 114.956318 -330.638646) (xy 114.964146 -330.57919) (xy 114.979667 -330.521265) (xy 115.002616 -330.465861)
			(xy 115.0326 -330.413927) (xy 115.069106 -330.366351) (xy 115.111511 -330.323946) (xy 115.159087 -330.28744)
			(xy 115.211021 -330.257456) (xy 115.266425 -330.234507) (xy 115.32435 -330.218986) (xy 115.383806 -330.211158)
			(xy 115.443774 -330.211158) (xy 115.50323 -330.218986) (xy 115.561155 -330.234507) (xy 115.616559 -330.257456)
			(xy 115.668493 -330.28744) (xy 115.716069 -330.323946) (xy 115.758474 -330.366351) (xy 115.79498 -330.413927)
			(xy 115.824964 -330.465861) (xy 115.847913 -330.521265) (xy 115.863434 -330.57919) (xy 115.871262 -330.638646)
			(xy 115.871752 -330.66863) (xy 115.871752 -331.53223) (xy 115.871262 -331.562214) (xy 115.863434 -331.62167)
			(xy 115.847913 -331.679595) (xy 115.824964 -331.734999) (xy 115.79498 -331.786933) (xy 115.758474 -331.834509)
			(xy 115.716069 -331.876914) (xy 115.668493 -331.91342) (xy 115.616559 -331.943404) (xy 115.561155 -331.966353)
			(xy 115.50323 -331.981874) (xy 115.443774 -331.989702) (xy 115.383806 -331.989702) (xy 115.32435 -331.981874)
			(xy 115.266425 -331.966353) (xy 115.211021 -331.943404) (xy 115.159087 -331.91342) (xy 115.111511 -331.876914)
			(xy 115.069106 -331.834509) (xy 115.0326 -331.786933) (xy 115.002616 -331.734999) (xy 114.979667 -331.679595)
			(xy 114.964146 -331.62167) (xy 114.956318 -331.562214) (xy 114.955828 -331.53223) (xy 0.509016 -331.53223)
			(xy 0.509016 -333.950056) (xy 93.5736 -333.950056) (xy 93.5736 -333.086456) (xy 93.57409 -333.056488)
			(xy 93.581913 -332.997066) (xy 93.597426 -332.939173) (xy 93.620362 -332.8838) (xy 93.650329 -332.831894)
			(xy 93.686816 -332.784344) (xy 93.729196 -332.741964) (xy 93.776746 -332.705477) (xy 93.828652 -332.67551)
			(xy 93.884025 -332.652574) (xy 93.941918 -332.637061) (xy 94.00134 -332.629238) (xy 94.061276 -332.629238)
			(xy 94.120698 -332.637061) (xy 94.178591 -332.652574) (xy 94.233964 -332.67551) (xy 94.28587 -332.705477)
			(xy 94.33342 -332.741964) (xy 94.3758 -332.784344) (xy 94.412287 -332.831894) (xy 94.442254 -332.8838)
			(xy 94.46519 -332.939173) (xy 94.46736 -332.947271) (xy 365.368753 -332.947271) (xy 365.368753 -332.887329)
			(xy 365.376578 -332.827899) (xy 365.392093 -332.77) (xy 365.415033 -332.71462) (xy 365.445006 -332.66271)
			(xy 365.481498 -332.615155) (xy 365.523886 -332.572772) (xy 365.571443 -332.536283) (xy 365.623356 -332.506315)
			(xy 365.678737 -332.48338) (xy 365.736639 -332.46787) (xy 365.796069 -332.460051) (xy 365.82604 -332.459584)
			(xy 366.68964 -332.459584) (xy 366.719605 -332.460093) (xy 366.779023 -332.46792) (xy 366.836911 -332.483435)
			(xy 366.892278 -332.506374) (xy 366.944178 -332.536342) (xy 366.991723 -332.572828) (xy 367.034098 -332.615207)
			(xy 367.07058 -332.662755) (xy 367.100544 -332.714658) (xy 367.123478 -332.770027) (xy 367.138988 -332.827916)
			(xy 367.14681 -332.887335) (xy 367.14681 -332.947265) (xy 367.138988 -333.006684) (xy 367.123478 -333.064573)
			(xy 367.100544 -333.119942) (xy 367.07058 -333.171845) (xy 367.034098 -333.219393) (xy 366.991723 -333.261772)
			(xy 366.944178 -333.298258) (xy 366.892278 -333.328226) (xy 366.836911 -333.351165) (xy 366.779023 -333.36668)
			(xy 366.719605 -333.374507) (xy 366.68964 -333.375) (xy 365.82604 -333.375) (xy 365.796069 -333.374549)
			(xy 365.736639 -333.36673) (xy 365.678737 -333.35122) (xy 365.623356 -333.328285) (xy 365.571443 -333.298317)
			(xy 365.523886 -333.261828) (xy 365.481498 -333.219445) (xy 365.445006 -333.17189) (xy 365.415033 -333.11998)
			(xy 365.392093 -333.0646) (xy 365.376578 -333.006701) (xy 365.368753 -332.947271) (xy 94.46736 -332.947271)
			(xy 94.480703 -332.997066) (xy 94.488526 -333.056488) (xy 94.489016 -333.086456) (xy 94.489016 -333.950056)
			(xy 94.488526 -333.980024) (xy 94.480703 -334.039446) (xy 94.46519 -334.097339) (xy 94.442254 -334.152712)
			(xy 94.412287 -334.204618) (xy 94.3758 -334.252168) (xy 94.33342 -334.294548) (xy 94.28587 -334.331035)
			(xy 94.233964 -334.361002) (xy 94.178591 -334.383938) (xy 94.120698 -334.399451) (xy 94.061276 -334.407274)
			(xy 94.00134 -334.407274) (xy 93.941918 -334.399451) (xy 93.884025 -334.383938) (xy 93.828652 -334.361002)
			(xy 93.776746 -334.331035) (xy 93.729196 -334.294548) (xy 93.686816 -334.252168) (xy 93.650329 -334.204618)
			(xy 93.620362 -334.152712) (xy 93.597426 -334.097339) (xy 93.581913 -334.039446) (xy 93.57409 -333.980024)
			(xy 93.5736 -333.950056) (xy 0.509016 -333.950056) (xy 0.509016 -337.266026) (xy 234.403392 -337.266026)
			(xy 234.403392 -336.402426) (xy 234.403882 -336.372458) (xy 234.411705 -336.313036) (xy 234.427218 -336.255143)
			(xy 234.450154 -336.19977) (xy 234.480121 -336.147864) (xy 234.516608 -336.100314) (xy 234.558988 -336.057934)
			(xy 234.606538 -336.021447) (xy 234.658444 -335.99148) (xy 234.713817 -335.968544) (xy 234.77171 -335.953031)
			(xy 234.831132 -335.945208) (xy 234.891068 -335.945208) (xy 234.95049 -335.953031) (xy 235.008383 -335.968544)
			(xy 235.063756 -335.99148) (xy 235.115662 -336.021447) (xy 235.163212 -336.057934) (xy 235.205592 -336.100314)
			(xy 235.242079 -336.147864) (xy 235.272046 -336.19977) (xy 235.294982 -336.255143) (xy 235.310495 -336.313036)
			(xy 235.318318 -336.372458) (xy 235.318808 -336.402426) (xy 235.318808 -337.266026) (xy 235.318318 -337.295994)
			(xy 235.310495 -337.355416) (xy 235.294982 -337.413309) (xy 235.272046 -337.468682) (xy 235.242079 -337.520588)
			(xy 235.205592 -337.568138) (xy 235.163212 -337.610518) (xy 235.115662 -337.647005) (xy 235.063756 -337.676972)
			(xy 235.008383 -337.699908) (xy 234.95049 -337.715421) (xy 234.891068 -337.723244) (xy 234.831132 -337.723244)
			(xy 234.77171 -337.715421) (xy 234.713817 -337.699908) (xy 234.658444 -337.676972) (xy 234.606538 -337.647005)
			(xy 234.558988 -337.610518) (xy 234.516608 -337.568138) (xy 234.480121 -337.520588) (xy 234.450154 -337.468682)
			(xy 234.427218 -337.413309) (xy 234.411705 -337.355416) (xy 234.403882 -337.295994) (xy 234.403392 -337.266026)
			(xy 0.509016 -337.266026) (xy 0.509016 -342.466769) (xy 18.951172 -342.466769) (xy 18.951172 -342.412231)
			(xy 18.958934 -342.358247) (xy 18.974299 -342.305917) (xy 18.996956 -342.256307) (xy 19.026441 -342.210426)
			(xy 19.062157 -342.169208) (xy 19.103374 -342.133493) (xy 19.149255 -342.104007) (xy 19.198865 -342.08135)
			(xy 19.251195 -342.065985) (xy 19.305179 -342.058223) (xy 19.332448 -342.057736) (xy 20.196048 -342.057736)
			(xy 20.223319 -342.058203) (xy 20.277306 -342.065965) (xy 20.329638 -342.081331) (xy 20.379252 -342.103989)
			(xy 20.425135 -342.133476) (xy 20.466355 -342.169193) (xy 20.502073 -342.210413) (xy 20.53156 -342.256297)
			(xy 20.554218 -342.30591) (xy 20.569584 -342.358242) (xy 20.577347 -342.412229) (xy 20.577347 -342.466771)
			(xy 20.577347 -342.466772) (xy 22.0601 -342.466772) (xy 22.0601 -342.412228) (xy 22.067862 -342.358241)
			(xy 22.083229 -342.305907) (xy 22.105887 -342.256293) (xy 22.135375 -342.210409) (xy 22.171094 -342.169188)
			(xy 22.212315 -342.133471) (xy 22.2582 -342.103983) (xy 22.307815 -342.081326) (xy 22.360148 -342.06596)
			(xy 22.414136 -342.058199) (xy 22.441408 -342.057736) (xy 23.305008 -342.057736) (xy 23.332277 -342.058227)
			(xy 23.386259 -342.06599) (xy 23.438588 -342.081355) (xy 23.488197 -342.104012) (xy 23.534076 -342.133498)
			(xy 23.575293 -342.169213) (xy 23.611007 -342.21043) (xy 23.640492 -342.256311) (xy 23.663147 -342.30592)
			(xy 23.678512 -342.358249) (xy 23.686274 -342.412231) (xy 23.686274 -342.466768) (xy 25.169122 -342.466768)
			(xy 25.169122 -342.412232) (xy 25.176883 -342.358251) (xy 25.192247 -342.305924) (xy 25.214901 -342.256315)
			(xy 25.244384 -342.210436) (xy 25.280096 -342.169219) (xy 25.32131 -342.133503) (xy 25.367187 -342.104016)
			(xy 25.416794 -342.081358) (xy 25.46912 -342.06599) (xy 25.5231 -342.058225) (xy 25.550368 -342.057736)
			(xy 26.413968 -342.057736) (xy 26.44124 -342.058201) (xy 26.49523 -342.06596) (xy 26.547567 -342.081323)
			(xy 26.597184 -342.103979) (xy 26.643071 -342.133465) (xy 26.684295 -342.169183) (xy 26.720015 -342.210403)
			(xy 26.749506 -342.256288) (xy 26.772166 -342.305903) (xy 26.787533 -342.358238) (xy 26.795296 -342.412228)
			(xy 26.795296 -342.466772) (xy 28.278 -342.466772) (xy 28.278 -342.412228) (xy 28.285762 -342.358238)
			(xy 28.30113 -342.305903) (xy 28.32379 -342.256288) (xy 28.35328 -342.210402) (xy 28.389001 -342.169181)
			(xy 28.430225 -342.133464) (xy 28.476112 -342.103977) (xy 28.525729 -342.08132) (xy 28.578065 -342.065957)
			(xy 28.632056 -342.058198) (xy 28.659328 -342.057736) (xy 29.522928 -342.057736) (xy 29.550196 -342.058228)
			(xy 29.604176 -342.065993) (xy 29.656502 -342.081361) (xy 29.706109 -342.104019) (xy 29.751986 -342.133505)
			(xy 29.7932 -342.16922) (xy 29.828912 -342.210437) (xy 29.858395 -342.256316) (xy 29.881049 -342.305924)
			(xy 29.896413 -342.358251) (xy 29.904174 -342.412232) (xy 29.904174 -342.466768) (xy 29.904174 -342.466769)
			(xy 31.387022 -342.466769) (xy 31.387022 -342.412231) (xy 31.394784 -342.358248) (xy 31.410149 -342.305919)
			(xy 31.432804 -342.25631) (xy 31.462289 -342.210429) (xy 31.498003 -342.169212) (xy 31.53922 -342.133496)
			(xy 31.585099 -342.10401) (xy 31.634708 -342.081353) (xy 31.687036 -342.065986) (xy 31.741019 -342.058223)
			(xy 31.768288 -342.057736) (xy 32.631888 -342.057736) (xy 32.659159 -342.058203) (xy 32.713147 -342.065963)
			(xy 32.765481 -342.081329) (xy 32.815096 -342.103985) (xy 32.86098 -342.133472) (xy 32.902202 -342.16919)
			(xy 32.93792 -342.21041) (xy 32.967409 -342.256294) (xy 32.990067 -342.305908) (xy 33.005434 -342.358241)
			(xy 33.013196 -342.412229) (xy 33.013196 -342.466771) (xy 33.013196 -342.466773) (xy 34.4959 -342.466773)
			(xy 34.4959 -342.412227) (xy 34.503663 -342.358235) (xy 34.519032 -342.305899) (xy 34.541693 -342.256282)
			(xy 34.571185 -342.210396) (xy 34.606908 -342.169174) (xy 34.648134 -342.133456) (xy 34.694024 -342.10397)
			(xy 34.743644 -342.081315) (xy 34.795982 -342.065953) (xy 34.849975 -342.058196) (xy 34.877248 -342.057736)
			(xy 35.740848 -342.057736) (xy 35.768115 -342.05823) (xy 35.822093 -342.065997) (xy 35.874417 -342.081366)
			(xy 35.92402 -342.104025) (xy 35.969895 -342.133512) (xy 36.011107 -342.169227) (xy 36.046817 -342.210443)
			(xy 36.076298 -342.256322) (xy 36.098951 -342.305928) (xy 36.114313 -342.358254) (xy 36.122074 -342.412233)
			(xy 36.122074 -342.466767) (xy 36.122073 -342.466772) (xy 37.6049 -342.466772) (xy 37.6049 -342.412228)
			(xy 37.612662 -342.358241) (xy 37.628029 -342.305907) (xy 37.650687 -342.256293) (xy 37.680175 -342.210409)
			(xy 37.715894 -342.169188) (xy 37.757115 -342.133471) (xy 37.803 -342.103983) (xy 37.852615 -342.081326)
			(xy 37.904948 -342.06596) (xy 37.958936 -342.058199) (xy 37.986208 -342.057736) (xy 38.849808 -342.057736)
			(xy 38.877077 -342.058227) (xy 38.931059 -342.06599) (xy 38.983388 -342.081355) (xy 39.032997 -342.104012)
			(xy 39.078876 -342.133498) (xy 39.120093 -342.169213) (xy 39.155807 -342.21043) (xy 39.185292 -342.256311)
			(xy 39.207947 -342.30592) (xy 39.223312 -342.358249) (xy 39.231074 -342.412231) (xy 39.231074 -342.466768)
			(xy 40.713922 -342.466768) (xy 40.713922 -342.412232) (xy 40.721683 -342.358251) (xy 40.737047 -342.305924)
			(xy 40.759701 -342.256315) (xy 40.789184 -342.210436) (xy 40.824896 -342.169219) (xy 40.86611 -342.133503)
			(xy 40.911987 -342.104016) (xy 40.961594 -342.081358) (xy 41.01392 -342.06599) (xy 41.0679 -342.058225)
			(xy 41.095168 -342.057736) (xy 41.958768 -342.057736) (xy 41.98604 -342.058201) (xy 42.04003 -342.06596)
			(xy 42.092367 -342.081323) (xy 42.141984 -342.103979) (xy 42.187871 -342.133465) (xy 42.229095 -342.169183)
			(xy 42.264815 -342.210403) (xy 42.294306 -342.256288) (xy 42.316966 -342.305903) (xy 42.332333 -342.358238)
			(xy 42.340096 -342.412228) (xy 42.340096 -342.466772) (xy 43.8228 -342.466772) (xy 43.8228 -342.412228)
			(xy 43.830562 -342.358238) (xy 43.84593 -342.305903) (xy 43.86859 -342.256288) (xy 43.89808 -342.210402)
			(xy 43.933801 -342.169181) (xy 43.975025 -342.133464) (xy 44.020912 -342.103977) (xy 44.070529 -342.08132)
			(xy 44.122865 -342.065957) (xy 44.176856 -342.058198) (xy 44.204128 -342.057736) (xy 45.067728 -342.057736)
			(xy 45.094996 -342.058228) (xy 45.148976 -342.065993) (xy 45.201302 -342.081361) (xy 45.250909 -342.104019)
			(xy 45.296786 -342.133505) (xy 45.338 -342.16922) (xy 45.373712 -342.210437) (xy 45.403195 -342.256316)
			(xy 45.425849 -342.305924) (xy 45.441213 -342.358251) (xy 45.448974 -342.412232) (xy 45.448974 -342.466768)
			(xy 45.448974 -342.466769) (xy 46.931822 -342.466769) (xy 46.931822 -342.412231) (xy 46.939584 -342.358248)
			(xy 46.954949 -342.305919) (xy 46.977604 -342.25631) (xy 47.007089 -342.210429) (xy 47.042803 -342.169212)
			(xy 47.08402 -342.133496) (xy 47.129899 -342.10401) (xy 47.179508 -342.081353) (xy 47.231836 -342.065986)
			(xy 47.285819 -342.058223) (xy 47.313088 -342.057736) (xy 48.176688 -342.057736) (xy 48.203959 -342.058203)
			(xy 48.257947 -342.065963) (xy 48.310281 -342.081329) (xy 48.359896 -342.103985) (xy 48.40578 -342.133472)
			(xy 48.447002 -342.16919) (xy 48.48272 -342.21041) (xy 48.512209 -342.256294) (xy 48.534867 -342.305908)
			(xy 48.550234 -342.358241) (xy 48.557996 -342.412229) (xy 48.557996 -342.466771) (xy 48.557996 -342.466773)
			(xy 50.0407 -342.466773) (xy 50.0407 -342.412227) (xy 50.048463 -342.358235) (xy 50.063832 -342.305899)
			(xy 50.086493 -342.256282) (xy 50.115985 -342.210396) (xy 50.151708 -342.169174) (xy 50.192934 -342.133456)
			(xy 50.238824 -342.10397) (xy 50.288444 -342.081315) (xy 50.340782 -342.065953) (xy 50.394775 -342.058196)
			(xy 50.422048 -342.057736) (xy 51.285648 -342.057736) (xy 51.312915 -342.05823) (xy 51.366893 -342.065997)
			(xy 51.419217 -342.081366) (xy 51.46882 -342.104025) (xy 51.514695 -342.133512) (xy 51.555907 -342.169227)
			(xy 51.591617 -342.210443) (xy 51.621098 -342.256322) (xy 51.643751 -342.305928) (xy 51.659113 -342.358254)
			(xy 51.666874 -342.412233) (xy 51.666874 -342.466767) (xy 51.666873 -342.466773) (xy 60.9909 -342.466773)
			(xy 60.9909 -342.412227) (xy 60.998663 -342.358236) (xy 61.014031 -342.3059) (xy 61.036692 -342.256284)
			(xy 61.066184 -342.210398) (xy 61.101906 -342.169176) (xy 61.143131 -342.133459) (xy 61.18902 -342.103972)
			(xy 61.238639 -342.081317) (xy 61.290977 -342.065954) (xy 61.344969 -342.058197) (xy 61.372242 -342.057736)
			(xy 62.235842 -342.057736) (xy 62.263109 -342.058229) (xy 62.317088 -342.065996) (xy 62.369412 -342.081365)
			(xy 62.419017 -342.104023) (xy 62.464892 -342.13351) (xy 62.506105 -342.169225) (xy 62.541815 -342.210441)
			(xy 62.571297 -342.25632) (xy 62.59395 -342.305927) (xy 62.609313 -342.358253) (xy 62.617074 -342.412233)
			(xy 62.617074 -342.466767) (xy 62.617073 -342.466771) (xy 64.099899 -342.466771) (xy 64.099899 -342.412229)
			(xy 64.107662 -342.358241) (xy 64.123028 -342.305908) (xy 64.145686 -342.256295) (xy 64.175174 -342.210411)
			(xy 64.210892 -342.16919) (xy 64.252112 -342.133473) (xy 64.297997 -342.103985) (xy 64.34761 -342.081327)
			(xy 64.399943 -342.065961) (xy 64.453931 -342.058199) (xy 64.481202 -342.057736) (xy 65.344802 -342.057736)
			(xy 65.372071 -342.058227) (xy 65.426054 -342.065988) (xy 65.478383 -342.081354) (xy 65.527993 -342.10401)
			(xy 65.573873 -342.133496) (xy 65.615091 -342.169211) (xy 65.650805 -342.210428) (xy 65.680291 -342.256309)
			(xy 65.702947 -342.305919) (xy 65.718312 -342.358248) (xy 65.726074 -342.412231) (xy 65.726074 -342.466768)
			(xy 67.208922 -342.466768) (xy 67.208922 -342.412232) (xy 67.216683 -342.358252) (xy 67.232047 -342.305925)
			(xy 67.2547 -342.256317) (xy 67.284183 -342.210438) (xy 67.319894 -342.169221) (xy 67.361107 -342.133505)
			(xy 67.406984 -342.104018) (xy 67.456589 -342.08136) (xy 67.508914 -342.065991) (xy 67.562894 -342.058225)
			(xy 67.590162 -342.057736) (xy 68.453762 -342.057736) (xy 68.481035 -342.058201) (xy 68.535025 -342.065959)
			(xy 68.587362 -342.081321) (xy 68.63698 -342.103977) (xy 68.682868 -342.133463) (xy 68.724093 -342.16918)
			(xy 68.759814 -342.210401) (xy 68.789305 -342.256287) (xy 68.811965 -342.305902) (xy 68.827333 -342.358237)
			(xy 68.835096 -342.412227) (xy 68.835096 -342.466772) (xy 70.3178 -342.466772) (xy 70.3178 -342.412228)
			(xy 70.325562 -342.358239) (xy 70.34093 -342.305904) (xy 70.363589 -342.256289) (xy 70.393079 -342.210404)
			(xy 70.428799 -342.169183) (xy 70.470022 -342.133466) (xy 70.515909 -342.103979) (xy 70.565525 -342.081322)
			(xy 70.61786 -342.065958) (xy 70.67185 -342.058198) (xy 70.699122 -342.057736) (xy 71.562722 -342.057736)
			(xy 71.58999 -342.058228) (xy 71.643971 -342.065992) (xy 71.696298 -342.081359) (xy 71.745905 -342.104017)
			(xy 71.791783 -342.133503) (xy 71.832998 -342.169218) (xy 71.86871 -342.210435) (xy 71.898194 -342.256314)
			(xy 71.920848 -342.305923) (xy 71.936213 -342.35825) (xy 71.943974 -342.412232) (xy 71.943974 -342.466768)
			(xy 71.943974 -342.466769) (xy 73.426822 -342.466769) (xy 73.426822 -342.412231) (xy 73.434584 -342.358249)
			(xy 73.449948 -342.305921) (xy 73.472603 -342.256311) (xy 73.502087 -342.210431) (xy 73.537801 -342.169214)
			(xy 73.579017 -342.133498) (xy 73.624896 -342.104012) (xy 73.674504 -342.081354) (xy 73.726831 -342.065987)
			(xy 73.780813 -342.058224) (xy 73.808082 -342.057736) (xy 74.671682 -342.057736) (xy 74.698954 -342.058202)
			(xy 74.752942 -342.065962) (xy 74.805277 -342.081327) (xy 74.854892 -342.103983) (xy 74.900778 -342.13347)
			(xy 74.942 -342.169188) (xy 74.977719 -342.210408) (xy 75.007208 -342.256292) (xy 75.029867 -342.305906)
			(xy 75.045234 -342.35824) (xy 75.052996 -342.412228) (xy 75.052996 -342.466772) (xy 75.052996 -342.466773)
			(xy 76.5357 -342.466773) (xy 76.5357 -342.412227) (xy 76.543463 -342.358236) (xy 76.558831 -342.3059)
			(xy 76.581492 -342.256284) (xy 76.610984 -342.210398) (xy 76.646706 -342.169176) (xy 76.687931 -342.133459)
			(xy 76.73382 -342.103972) (xy 76.783439 -342.081317) (xy 76.835777 -342.065954) (xy 76.889769 -342.058197)
			(xy 76.917042 -342.057736) (xy 77.780642 -342.057736) (xy 77.807909 -342.058229) (xy 77.861888 -342.065996)
			(xy 77.914212 -342.081365) (xy 77.963817 -342.104023) (xy 78.009692 -342.13351) (xy 78.050905 -342.169225)
			(xy 78.086615 -342.210441) (xy 78.116097 -342.25632) (xy 78.13875 -342.305927) (xy 78.154113 -342.358253)
			(xy 78.161874 -342.412233) (xy 78.161874 -342.466767) (xy 78.161873 -342.466771) (xy 79.644699 -342.466771)
			(xy 79.644699 -342.412229) (xy 79.652462 -342.358241) (xy 79.667828 -342.305908) (xy 79.690486 -342.256295)
			(xy 79.719974 -342.210411) (xy 79.755692 -342.16919) (xy 79.796912 -342.133473) (xy 79.842797 -342.103985)
			(xy 79.89241 -342.081327) (xy 79.944743 -342.065961) (xy 79.998731 -342.058199) (xy 80.026002 -342.057736)
			(xy 80.889602 -342.057736) (xy 80.916871 -342.058227) (xy 80.970854 -342.065988) (xy 81.023183 -342.081354)
			(xy 81.072793 -342.10401) (xy 81.118673 -342.133496) (xy 81.159891 -342.169211) (xy 81.195605 -342.210428)
			(xy 81.225091 -342.256309) (xy 81.247747 -342.305919) (xy 81.263112 -342.358248) (xy 81.270874 -342.412231)
			(xy 81.270874 -342.466768) (xy 82.753722 -342.466768) (xy 82.753722 -342.412232) (xy 82.761483 -342.358252)
			(xy 82.776847 -342.305925) (xy 82.7995 -342.256317) (xy 82.828983 -342.210438) (xy 82.864694 -342.169221)
			(xy 82.905907 -342.133505) (xy 82.951784 -342.104018) (xy 83.001389 -342.08136) (xy 83.053714 -342.065991)
			(xy 83.107694 -342.058225) (xy 83.134962 -342.057736) (xy 83.998562 -342.057736) (xy 84.025835 -342.058201)
			(xy 84.079825 -342.065959) (xy 84.132162 -342.081321) (xy 84.18178 -342.103977) (xy 84.227668 -342.133463)
			(xy 84.268893 -342.16918) (xy 84.304614 -342.210401) (xy 84.334105 -342.256287) (xy 84.356765 -342.305902)
			(xy 84.372133 -342.358237) (xy 84.379896 -342.412227) (xy 84.379896 -342.466772) (xy 85.8626 -342.466772)
			(xy 85.8626 -342.412228) (xy 85.870362 -342.358239) (xy 85.88573 -342.305904) (xy 85.908389 -342.256289)
			(xy 85.937879 -342.210404) (xy 85.973599 -342.169183) (xy 86.014822 -342.133466) (xy 86.060709 -342.103979)
			(xy 86.110325 -342.081322) (xy 86.16266 -342.065958) (xy 86.21665 -342.058198) (xy 86.243922 -342.057736)
			(xy 87.107522 -342.057736) (xy 87.13479 -342.058228) (xy 87.188771 -342.065992) (xy 87.241098 -342.081359)
			(xy 87.290705 -342.104017) (xy 87.336583 -342.133503) (xy 87.377798 -342.169218) (xy 87.41351 -342.210435)
			(xy 87.442994 -342.256314) (xy 87.465648 -342.305923) (xy 87.481013 -342.35825) (xy 87.488774 -342.412232)
			(xy 87.488774 -342.466768) (xy 87.488774 -342.466769) (xy 88.971622 -342.466769) (xy 88.971622 -342.412231)
			(xy 88.979384 -342.358249) (xy 88.994748 -342.305921) (xy 89.017403 -342.256311) (xy 89.046887 -342.210431)
			(xy 89.082601 -342.169214) (xy 89.123817 -342.133498) (xy 89.169696 -342.104012) (xy 89.219304 -342.081354)
			(xy 89.271631 -342.065987) (xy 89.325613 -342.058224) (xy 89.352882 -342.057736) (xy 90.216482 -342.057736)
			(xy 90.243754 -342.058202) (xy 90.297742 -342.065962) (xy 90.350077 -342.081327) (xy 90.399692 -342.103983)
			(xy 90.445578 -342.13347) (xy 90.4868 -342.169188) (xy 90.522519 -342.210408) (xy 90.552008 -342.256292)
			(xy 90.574667 -342.305906) (xy 90.590034 -342.35824) (xy 90.597796 -342.412228) (xy 90.597796 -342.466772)
			(xy 90.597796 -342.466773) (xy 92.0805 -342.466773) (xy 92.0805 -342.412227) (xy 92.088263 -342.358236)
			(xy 92.103631 -342.3059) (xy 92.126292 -342.256284) (xy 92.155784 -342.210398) (xy 92.191506 -342.169176)
			(xy 92.232731 -342.133459) (xy 92.27862 -342.103972) (xy 92.328239 -342.081317) (xy 92.380577 -342.065954)
			(xy 92.434569 -342.058197) (xy 92.461842 -342.057736) (xy 93.325442 -342.057736) (xy 93.352709 -342.058229)
			(xy 93.406688 -342.065996) (xy 93.459012 -342.081365) (xy 93.508617 -342.104023) (xy 93.554492 -342.13351)
			(xy 93.595705 -342.169225) (xy 93.631415 -342.210441) (xy 93.660897 -342.25632) (xy 93.68355 -342.305927)
			(xy 93.698913 -342.358253) (xy 93.706674 -342.412233) (xy 93.706674 -342.466767) (xy 93.698913 -342.520747)
			(xy 93.68355 -342.573073) (xy 93.660897 -342.62268) (xy 93.631415 -342.668559) (xy 93.60914 -342.694268)
			(xy 102.35157 -342.694268) (xy 102.35157 -342.634332) (xy 102.359393 -342.574909) (xy 102.374905 -342.517016)
			(xy 102.397841 -342.461642) (xy 102.427809 -342.409736) (xy 102.464294 -342.362185) (xy 102.506675 -342.319804)
			(xy 102.554224 -342.283316) (xy 102.60613 -342.253347) (xy 102.661502 -342.23041) (xy 102.719395 -342.214896)
			(xy 102.778818 -342.207071) (xy 102.808786 -342.20658) (xy 103.672386 -342.20658) (xy 103.702355 -342.207072)
			(xy 103.76178 -342.214894) (xy 103.819676 -342.230405) (xy 103.875051 -342.253341) (xy 103.926959 -342.283309)
			(xy 103.974512 -342.319796) (xy 104.016895 -342.362178) (xy 104.053383 -342.409729) (xy 104.083352 -342.461636)
			(xy 104.085479 -342.466772) (xy 111.4808 -342.466772) (xy 111.4808 -342.412228) (xy 111.488562 -342.358241)
			(xy 111.503929 -342.305907) (xy 111.526587 -342.256293) (xy 111.556075 -342.210409) (xy 111.591794 -342.169188)
			(xy 111.633015 -342.133471) (xy 111.6789 -342.103983) (xy 111.728515 -342.081326) (xy 111.780848 -342.06596)
			(xy 111.834836 -342.058199) (xy 111.862108 -342.057736) (xy 112.725708 -342.057736) (xy 112.752977 -342.058227)
			(xy 112.806959 -342.06599) (xy 112.859288 -342.081355) (xy 112.908897 -342.104012) (xy 112.954776 -342.133498)
			(xy 112.995993 -342.169213) (xy 113.031707 -342.21043) (xy 113.061192 -342.256311) (xy 113.083847 -342.30592)
			(xy 113.099212 -342.358249) (xy 113.106974 -342.412231) (xy 113.106974 -342.466768) (xy 114.589822 -342.466768)
			(xy 114.589822 -342.412232) (xy 114.597583 -342.358251) (xy 114.612947 -342.305924) (xy 114.635601 -342.256315)
			(xy 114.665084 -342.210436) (xy 114.700796 -342.169219) (xy 114.74201 -342.133503) (xy 114.787887 -342.104016)
			(xy 114.837494 -342.081358) (xy 114.88982 -342.06599) (xy 114.9438 -342.058225) (xy 114.971068 -342.057736)
			(xy 115.834668 -342.057736) (xy 115.86194 -342.058201) (xy 115.91593 -342.06596) (xy 115.968267 -342.081323)
			(xy 116.017884 -342.103979) (xy 116.063771 -342.133465) (xy 116.104995 -342.169183) (xy 116.140715 -342.210403)
			(xy 116.170206 -342.256288) (xy 116.192866 -342.305903) (xy 116.208233 -342.358238) (xy 116.215996 -342.412228)
			(xy 116.215996 -342.466772) (xy 117.6987 -342.466772) (xy 117.6987 -342.412228) (xy 117.706462 -342.358238)
			(xy 117.72183 -342.305903) (xy 117.74449 -342.256288) (xy 117.77398 -342.210402) (xy 117.809701 -342.169181)
			(xy 117.850925 -342.133464) (xy 117.896812 -342.103977) (xy 117.946429 -342.08132) (xy 117.998765 -342.065957)
			(xy 118.052756 -342.058198) (xy 118.080028 -342.057736) (xy 118.943628 -342.057736) (xy 118.970896 -342.058228)
			(xy 119.024876 -342.065993) (xy 119.077202 -342.081361) (xy 119.126809 -342.104019) (xy 119.172686 -342.133505)
			(xy 119.2139 -342.16922) (xy 119.249612 -342.210437) (xy 119.279095 -342.256316) (xy 119.301749 -342.305924)
			(xy 119.317113 -342.358251) (xy 119.324874 -342.412232) (xy 119.324874 -342.466768) (xy 119.324874 -342.466769)
			(xy 120.807722 -342.466769) (xy 120.807722 -342.412231) (xy 120.815484 -342.358248) (xy 120.830849 -342.305919)
			(xy 120.853504 -342.25631) (xy 120.882989 -342.210429) (xy 120.918703 -342.169212) (xy 120.95992 -342.133496)
			(xy 121.005799 -342.10401) (xy 121.055408 -342.081353) (xy 121.107736 -342.065986) (xy 121.161719 -342.058223)
			(xy 121.188988 -342.057736) (xy 122.052588 -342.057736) (xy 122.079859 -342.058203) (xy 122.133847 -342.065963)
			(xy 122.186181 -342.081329) (xy 122.235796 -342.103985) (xy 122.28168 -342.133472) (xy 122.322902 -342.16919)
			(xy 122.35862 -342.21041) (xy 122.388109 -342.256294) (xy 122.410767 -342.305908) (xy 122.426134 -342.358241)
			(xy 122.433896 -342.412229) (xy 122.433896 -342.466771) (xy 122.433896 -342.466773) (xy 123.9166 -342.466773)
			(xy 123.9166 -342.412227) (xy 123.924363 -342.358235) (xy 123.939732 -342.305899) (xy 123.962393 -342.256282)
			(xy 123.991885 -342.210396) (xy 124.027608 -342.169174) (xy 124.068834 -342.133456) (xy 124.114724 -342.10397)
			(xy 124.164344 -342.081315) (xy 124.216682 -342.065953) (xy 124.270675 -342.058196) (xy 124.297948 -342.057736)
			(xy 125.161548 -342.057736) (xy 125.188815 -342.05823) (xy 125.242793 -342.065997) (xy 125.295117 -342.081366)
			(xy 125.34472 -342.104025) (xy 125.390595 -342.133512) (xy 125.431807 -342.169227) (xy 125.467517 -342.210443)
			(xy 125.496998 -342.256322) (xy 125.519651 -342.305928) (xy 125.535013 -342.358254) (xy 125.542774 -342.412233)
			(xy 125.542774 -342.466767) (xy 125.542773 -342.466772) (xy 127.0256 -342.466772) (xy 127.0256 -342.412228)
			(xy 127.033362 -342.358241) (xy 127.048729 -342.305907) (xy 127.071387 -342.256293) (xy 127.100875 -342.210409)
			(xy 127.136594 -342.169188) (xy 127.177815 -342.133471) (xy 127.2237 -342.103983) (xy 127.273315 -342.081326)
			(xy 127.325648 -342.06596) (xy 127.379636 -342.058199) (xy 127.406908 -342.057736) (xy 128.270508 -342.057736)
			(xy 128.297777 -342.058227) (xy 128.351759 -342.06599) (xy 128.404088 -342.081355) (xy 128.453697 -342.104012)
			(xy 128.499576 -342.133498) (xy 128.540793 -342.169213) (xy 128.576507 -342.21043) (xy 128.605992 -342.256311)
			(xy 128.628647 -342.30592) (xy 128.644012 -342.358249) (xy 128.651774 -342.412231) (xy 128.651774 -342.466768)
			(xy 130.134622 -342.466768) (xy 130.134622 -342.412232) (xy 130.142383 -342.358251) (xy 130.157747 -342.305924)
			(xy 130.180401 -342.256315) (xy 130.209884 -342.210436) (xy 130.245596 -342.169219) (xy 130.28681 -342.133503)
			(xy 130.332687 -342.104016) (xy 130.382294 -342.081358) (xy 130.43462 -342.06599) (xy 130.4886 -342.058225)
			(xy 130.515868 -342.057736) (xy 131.379468 -342.057736) (xy 131.40674 -342.058201) (xy 131.46073 -342.06596)
			(xy 131.513067 -342.081323) (xy 131.562684 -342.103979) (xy 131.608571 -342.133465) (xy 131.649795 -342.169183)
			(xy 131.685515 -342.210403) (xy 131.715006 -342.256288) (xy 131.737666 -342.305903) (xy 131.753033 -342.358238)
			(xy 131.760796 -342.412228) (xy 131.760796 -342.466772) (xy 133.2435 -342.466772) (xy 133.2435 -342.412228)
			(xy 133.251262 -342.358238) (xy 133.26663 -342.305903) (xy 133.28929 -342.256288) (xy 133.31878 -342.210402)
			(xy 133.354501 -342.169181) (xy 133.395725 -342.133464) (xy 133.441612 -342.103977) (xy 133.491229 -342.08132)
			(xy 133.543565 -342.065957) (xy 133.597556 -342.058198) (xy 133.624828 -342.057736) (xy 134.488428 -342.057736)
			(xy 134.515696 -342.058228) (xy 134.569676 -342.065993) (xy 134.622002 -342.081361) (xy 134.671609 -342.104019)
			(xy 134.717486 -342.133505) (xy 134.7587 -342.16922) (xy 134.794412 -342.210437) (xy 134.823895 -342.256316)
			(xy 134.846549 -342.305924) (xy 134.861913 -342.358251) (xy 134.869674 -342.412232) (xy 134.869674 -342.466768)
			(xy 134.869674 -342.466769) (xy 136.352522 -342.466769) (xy 136.352522 -342.412231) (xy 136.360284 -342.358248)
			(xy 136.375649 -342.305919) (xy 136.398304 -342.25631) (xy 136.427789 -342.210429) (xy 136.463503 -342.169212)
			(xy 136.50472 -342.133496) (xy 136.550599 -342.10401) (xy 136.600208 -342.081353) (xy 136.652536 -342.065986)
			(xy 136.706519 -342.058223) (xy 136.733788 -342.057736) (xy 137.597388 -342.057736) (xy 137.624659 -342.058203)
			(xy 137.678647 -342.065963) (xy 137.730981 -342.081329) (xy 137.780596 -342.103985) (xy 137.82648 -342.133472)
			(xy 137.867702 -342.16919) (xy 137.90342 -342.21041) (xy 137.932909 -342.256294) (xy 137.955567 -342.305908)
			(xy 137.970934 -342.358241) (xy 137.978696 -342.412229) (xy 137.978696 -342.466771) (xy 137.978696 -342.466773)
			(xy 139.4614 -342.466773) (xy 139.4614 -342.412227) (xy 139.469163 -342.358235) (xy 139.484532 -342.305899)
			(xy 139.507193 -342.256282) (xy 139.536685 -342.210396) (xy 139.572408 -342.169174) (xy 139.613634 -342.133456)
			(xy 139.659524 -342.10397) (xy 139.709144 -342.081315) (xy 139.761482 -342.065953) (xy 139.815475 -342.058196)
			(xy 139.842748 -342.057736) (xy 140.706348 -342.057736) (xy 140.733615 -342.05823) (xy 140.787593 -342.065997)
			(xy 140.839917 -342.081366) (xy 140.88952 -342.104025) (xy 140.935395 -342.133512) (xy 140.976607 -342.169227)
			(xy 141.012317 -342.210443) (xy 141.041798 -342.256322) (xy 141.064451 -342.305928) (xy 141.079813 -342.358254)
			(xy 141.087574 -342.412233) (xy 141.087574 -342.466767) (xy 141.087573 -342.466772) (xy 142.5704 -342.466772)
			(xy 142.5704 -342.412228) (xy 142.578162 -342.358241) (xy 142.593529 -342.305907) (xy 142.616187 -342.256293)
			(xy 142.645675 -342.210409) (xy 142.681394 -342.169188) (xy 142.722615 -342.133471) (xy 142.7685 -342.103983)
			(xy 142.818115 -342.081326) (xy 142.870448 -342.06596) (xy 142.924436 -342.058199) (xy 142.951708 -342.057736)
			(xy 143.815308 -342.057736) (xy 143.842577 -342.058227) (xy 143.896559 -342.06599) (xy 143.948888 -342.081355)
			(xy 143.998497 -342.104012) (xy 144.044376 -342.133498) (xy 144.085593 -342.169213) (xy 144.121307 -342.21043)
			(xy 144.150792 -342.256311) (xy 144.173447 -342.30592) (xy 144.188812 -342.358249) (xy 144.196574 -342.412231)
			(xy 144.196574 -342.466768) (xy 164.913822 -342.466768) (xy 164.913822 -342.412232) (xy 164.921583 -342.35825)
			(xy 164.936947 -342.305923) (xy 164.959602 -342.256314) (xy 164.989085 -342.210434) (xy 165.024797 -342.169217)
			(xy 165.066012 -342.133502) (xy 165.11189 -342.104015) (xy 165.161496 -342.081357) (xy 165.213823 -342.065989)
			(xy 165.267804 -342.058224) (xy 165.295072 -342.057736) (xy 166.158672 -342.057736) (xy 166.185944 -342.058202)
			(xy 166.239934 -342.06596) (xy 166.29227 -342.081324) (xy 166.341886 -342.10398) (xy 166.387773 -342.133467)
			(xy 166.428996 -342.169184) (xy 166.464716 -342.210405) (xy 166.494207 -342.256289) (xy 166.516866 -342.305904)
			(xy 166.532234 -342.358239) (xy 166.539996 -342.412228) (xy 166.539996 -342.466772) (xy 166.539996 -342.466773)
			(xy 168.0227 -342.466773) (xy 168.0227 -342.412227) (xy 168.030463 -342.358237) (xy 168.045831 -342.305902)
			(xy 168.068491 -342.256286) (xy 168.097981 -342.210401) (xy 168.133702 -342.16918) (xy 168.174927 -342.133462)
			(xy 168.220815 -342.103975) (xy 168.270432 -342.081319) (xy 168.322769 -342.065956) (xy 168.376759 -342.058197)
			(xy 168.404032 -342.057736) (xy 169.267632 -342.057736) (xy 169.2949 -342.058229) (xy 169.34888 -342.065994)
			(xy 169.401205 -342.081362) (xy 169.450811 -342.10402) (xy 169.496688 -342.133506) (xy 169.537901 -342.169222)
			(xy 169.573613 -342.210438) (xy 169.603095 -342.256317) (xy 169.625749 -342.305925) (xy 169.641113 -342.358252)
			(xy 169.648874 -342.412232) (xy 169.648874 -342.466768) (xy 169.648874 -342.466769) (xy 171.131722 -342.466769)
			(xy 171.131722 -342.412231) (xy 171.139484 -342.358248) (xy 171.154849 -342.305918) (xy 171.177505 -342.256309)
			(xy 171.20699 -342.210428) (xy 171.242705 -342.16921) (xy 171.283921 -342.133495) (xy 171.329802 -342.104009)
			(xy 171.379411 -342.081352) (xy 171.43174 -342.065986) (xy 171.485723 -342.058223) (xy 171.512992 -342.057736)
			(xy 172.376592 -342.057736) (xy 172.403863 -342.058203) (xy 172.457851 -342.065964) (xy 172.510184 -342.08133)
			(xy 172.559798 -342.103987) (xy 172.605682 -342.133474) (xy 172.646903 -342.169191) (xy 172.682621 -342.210411)
			(xy 172.71211 -342.256295) (xy 172.734768 -342.305908) (xy 172.750134 -342.358241) (xy 172.757896 -342.412229)
			(xy 172.757896 -342.466767) (xy 174.240722 -342.466767) (xy 174.240722 -342.412233) (xy 174.248483 -342.358253)
			(xy 174.263846 -342.305927) (xy 174.286499 -342.25632) (xy 174.31598 -342.210441) (xy 174.35169 -342.169224)
			(xy 174.392902 -342.133509) (xy 174.438778 -342.104022) (xy 174.488382 -342.081363) (xy 174.540706 -342.065993)
			(xy 174.594685 -342.058226) (xy 174.621952 -342.057736) (xy 175.485552 -342.057736) (xy 175.512825 -342.0582)
			(xy 175.566817 -342.065957) (xy 175.619155 -342.081319) (xy 175.668774 -342.103974) (xy 175.714663 -342.13346)
			(xy 175.755889 -342.169177) (xy 175.791612 -342.210398) (xy 175.821103 -342.256284) (xy 175.843764 -342.3059)
			(xy 175.859133 -342.358236) (xy 175.866896 -342.412227) (xy 175.866896 -342.466772) (xy 177.3496 -342.466772)
			(xy 177.3496 -342.412228) (xy 177.357362 -342.35824) (xy 177.372729 -342.305906) (xy 177.395388 -342.256292)
			(xy 177.424876 -342.210407) (xy 177.460595 -342.169187) (xy 177.501817 -342.133469) (xy 177.547703 -342.103982)
			(xy 177.597317 -342.081325) (xy 177.649652 -342.065959) (xy 177.70364 -342.058199) (xy 177.730912 -342.057736)
			(xy 178.594512 -342.057736) (xy 178.621781 -342.058227) (xy 178.675763 -342.06599) (xy 178.728091 -342.081357)
			(xy 178.777699 -342.104013) (xy 178.823578 -342.133499) (xy 178.864794 -342.169214) (xy 178.900508 -342.210432)
			(xy 178.929992 -342.256312) (xy 178.952648 -342.305921) (xy 178.968012 -342.358249) (xy 178.975774 -342.412231)
			(xy 178.975774 -342.466768) (xy 180.458622 -342.466768) (xy 180.458622 -342.412232) (xy 180.466383 -342.35825)
			(xy 180.481747 -342.305923) (xy 180.504402 -342.256314) (xy 180.533885 -342.210434) (xy 180.569597 -342.169217)
			(xy 180.610812 -342.133502) (xy 180.65669 -342.104015) (xy 180.706296 -342.081357) (xy 180.758623 -342.065989)
			(xy 180.812604 -342.058224) (xy 180.839872 -342.057736) (xy 181.703472 -342.057736) (xy 181.730744 -342.058202)
			(xy 181.784734 -342.06596) (xy 181.83707 -342.081324) (xy 181.886686 -342.10398) (xy 181.932573 -342.133467)
			(xy 181.973796 -342.169184) (xy 182.009516 -342.210405) (xy 182.039007 -342.256289) (xy 182.061666 -342.305904)
			(xy 182.077034 -342.358239) (xy 182.084796 -342.412228) (xy 182.084796 -342.466772) (xy 182.084796 -342.466773)
			(xy 183.5675 -342.466773) (xy 183.5675 -342.412227) (xy 183.575263 -342.358237) (xy 183.590631 -342.305902)
			(xy 183.613291 -342.256286) (xy 183.642781 -342.210401) (xy 183.678502 -342.16918) (xy 183.719727 -342.133462)
			(xy 183.765615 -342.103975) (xy 183.815232 -342.081319) (xy 183.867569 -342.065956) (xy 183.921559 -342.058197)
			(xy 183.948832 -342.057736) (xy 184.812432 -342.057736) (xy 184.8397 -342.058229) (xy 184.89368 -342.065994)
			(xy 184.946005 -342.081362) (xy 184.995611 -342.10402) (xy 185.041488 -342.133506) (xy 185.082701 -342.169222)
			(xy 185.118413 -342.210438) (xy 185.147895 -342.256317) (xy 185.170549 -342.305925) (xy 185.185913 -342.358252)
			(xy 185.193674 -342.412232) (xy 185.193674 -342.466768) (xy 185.193674 -342.466769) (xy 186.676522 -342.466769)
			(xy 186.676522 -342.412231) (xy 186.684284 -342.358248) (xy 186.699649 -342.305918) (xy 186.722305 -342.256309)
			(xy 186.75179 -342.210428) (xy 186.787505 -342.16921) (xy 186.828721 -342.133495) (xy 186.874602 -342.104009)
			(xy 186.924211 -342.081352) (xy 186.97654 -342.065986) (xy 187.030523 -342.058223) (xy 187.057792 -342.057736)
			(xy 187.921392 -342.057736) (xy 187.948663 -342.058203) (xy 188.002651 -342.065964) (xy 188.054984 -342.08133)
			(xy 188.104598 -342.103987) (xy 188.150482 -342.133474) (xy 188.191703 -342.169191) (xy 188.227421 -342.210411)
			(xy 188.25691 -342.256295) (xy 188.279568 -342.305908) (xy 188.294934 -342.358241) (xy 188.302696 -342.412229)
			(xy 188.302696 -342.466767) (xy 189.785522 -342.466767) (xy 189.785522 -342.412233) (xy 189.793283 -342.358253)
			(xy 189.808646 -342.305927) (xy 189.831299 -342.25632) (xy 189.86078 -342.210441) (xy 189.89649 -342.169224)
			(xy 189.937702 -342.133509) (xy 189.983578 -342.104022) (xy 190.033182 -342.081363) (xy 190.085506 -342.065993)
			(xy 190.139485 -342.058226) (xy 190.166752 -342.057736) (xy 191.030352 -342.057736) (xy 191.057625 -342.0582)
			(xy 191.111617 -342.065957) (xy 191.163955 -342.081319) (xy 191.213574 -342.103974) (xy 191.259463 -342.13346)
			(xy 191.300689 -342.169177) (xy 191.336412 -342.210398) (xy 191.365903 -342.256284) (xy 191.388564 -342.3059)
			(xy 191.403933 -342.358236) (xy 191.411696 -342.412227) (xy 191.411696 -342.466772) (xy 192.8944 -342.466772)
			(xy 192.8944 -342.412228) (xy 192.902162 -342.35824) (xy 192.917529 -342.305906) (xy 192.940188 -342.256292)
			(xy 192.969676 -342.210407) (xy 193.005395 -342.169187) (xy 193.046617 -342.133469) (xy 193.092503 -342.103982)
			(xy 193.142117 -342.081325) (xy 193.194452 -342.065959) (xy 193.24844 -342.058199) (xy 193.275712 -342.057736)
			(xy 194.139312 -342.057736) (xy 194.166581 -342.058227) (xy 194.220563 -342.06599) (xy 194.272891 -342.081357)
			(xy 194.322499 -342.104013) (xy 194.368378 -342.133499) (xy 194.409594 -342.169214) (xy 194.445308 -342.210432)
			(xy 194.474792 -342.256312) (xy 194.497448 -342.305921) (xy 194.512812 -342.358249) (xy 194.520574 -342.412231)
			(xy 194.520574 -342.466768) (xy 196.003422 -342.466768) (xy 196.003422 -342.412232) (xy 196.011183 -342.35825)
			(xy 196.026547 -342.305923) (xy 196.049202 -342.256314) (xy 196.078685 -342.210434) (xy 196.114397 -342.169217)
			(xy 196.155612 -342.133502) (xy 196.20149 -342.104015) (xy 196.251096 -342.081357) (xy 196.303423 -342.065989)
			(xy 196.357404 -342.058224) (xy 196.384672 -342.057736) (xy 197.248272 -342.057736) (xy 197.275544 -342.058202)
			(xy 197.28821 -342.060022) (xy 255.91262 -342.060022) (xy 255.91262 -341.196422) (xy 255.91311 -341.166438)
			(xy 255.920938 -341.106982) (xy 255.936459 -341.049057) (xy 255.959408 -340.993653) (xy 255.989392 -340.941719)
			(xy 256.025898 -340.894143) (xy 256.068303 -340.851738) (xy 256.115879 -340.815232) (xy 256.167813 -340.785248)
			(xy 256.223217 -340.762299) (xy 256.281142 -340.746778) (xy 256.340598 -340.73895) (xy 256.400566 -340.73895)
			(xy 256.460022 -340.746778) (xy 256.517947 -340.762299) (xy 256.573351 -340.785248) (xy 256.625285 -340.815232)
			(xy 256.672861 -340.851738) (xy 256.715266 -340.894143) (xy 256.751772 -340.941719) (xy 256.781756 -340.993653)
			(xy 256.804705 -341.049057) (xy 256.820226 -341.106982) (xy 256.828054 -341.166438) (xy 256.828544 -341.196422)
			(xy 256.828544 -342.060022) (xy 256.828054 -342.090006) (xy 256.820226 -342.149462) (xy 256.804705 -342.207387)
			(xy 256.781756 -342.262791) (xy 256.751772 -342.314725) (xy 256.715266 -342.362301) (xy 256.672861 -342.404706)
			(xy 256.625285 -342.441212) (xy 256.581015 -342.466771) (xy 267.515799 -342.466771) (xy 267.515799 -342.412229)
			(xy 267.523562 -342.358241) (xy 267.538928 -342.305908) (xy 267.561586 -342.256295) (xy 267.591074 -342.210411)
			(xy 267.626792 -342.16919) (xy 267.668012 -342.133473) (xy 267.713897 -342.103985) (xy 267.76351 -342.081327)
			(xy 267.815843 -342.065961) (xy 267.869831 -342.058199) (xy 267.897102 -342.057736) (xy 268.760702 -342.057736)
			(xy 268.787971 -342.058227) (xy 268.841954 -342.065988) (xy 268.894283 -342.081354) (xy 268.943893 -342.10401)
			(xy 268.989773 -342.133496) (xy 269.030991 -342.169211) (xy 269.066705 -342.210428) (xy 269.096191 -342.256309)
			(xy 269.118847 -342.305919) (xy 269.134212 -342.358248) (xy 269.141974 -342.412231) (xy 269.141974 -342.466768)
			(xy 270.624822 -342.466768) (xy 270.624822 -342.412232) (xy 270.632583 -342.358252) (xy 270.647947 -342.305925)
			(xy 270.6706 -342.256317) (xy 270.700083 -342.210438) (xy 270.735794 -342.169221) (xy 270.777007 -342.133505)
			(xy 270.822884 -342.104018) (xy 270.872489 -342.08136) (xy 270.924814 -342.065991) (xy 270.978794 -342.058225)
			(xy 271.006062 -342.057736) (xy 271.869662 -342.057736) (xy 271.896935 -342.058201) (xy 271.950925 -342.065959)
			(xy 272.003262 -342.081321) (xy 272.05288 -342.103977) (xy 272.098768 -342.133463) (xy 272.139993 -342.16918)
			(xy 272.175714 -342.210401) (xy 272.205205 -342.256287) (xy 272.227865 -342.305902) (xy 272.243233 -342.358237)
			(xy 272.250996 -342.412227) (xy 272.250996 -342.466772) (xy 273.7337 -342.466772) (xy 273.7337 -342.412228)
			(xy 273.741462 -342.358239) (xy 273.75683 -342.305904) (xy 273.779489 -342.256289) (xy 273.808979 -342.210404)
			(xy 273.844699 -342.169183) (xy 273.885922 -342.133466) (xy 273.931809 -342.103979) (xy 273.981425 -342.081322)
			(xy 274.03376 -342.065958) (xy 274.08775 -342.058198) (xy 274.115022 -342.057736) (xy 274.978622 -342.057736)
			(xy 275.00589 -342.058228) (xy 275.059871 -342.065992) (xy 275.112198 -342.081359) (xy 275.161805 -342.104017)
			(xy 275.207683 -342.133503) (xy 275.248898 -342.169218) (xy 275.28461 -342.210435) (xy 275.314094 -342.256314)
			(xy 275.336748 -342.305923) (xy 275.352113 -342.35825) (xy 275.359874 -342.412232) (xy 275.359874 -342.466768)
			(xy 275.359874 -342.466769) (xy 276.842722 -342.466769) (xy 276.842722 -342.412231) (xy 276.850484 -342.358249)
			(xy 276.865848 -342.305921) (xy 276.888503 -342.256311) (xy 276.917987 -342.210431) (xy 276.953701 -342.169214)
			(xy 276.994917 -342.133498) (xy 277.040796 -342.104012) (xy 277.090404 -342.081354) (xy 277.142731 -342.065987)
			(xy 277.196713 -342.058224) (xy 277.223982 -342.057736) (xy 278.087582 -342.057736) (xy 278.114854 -342.058202)
			(xy 278.168842 -342.065962) (xy 278.221177 -342.081327) (xy 278.270792 -342.103983) (xy 278.316678 -342.13347)
			(xy 278.3579 -342.169188) (xy 278.393619 -342.210408) (xy 278.423108 -342.256292) (xy 278.445767 -342.305906)
			(xy 278.461134 -342.35824) (xy 278.468896 -342.412228) (xy 278.468896 -342.466772) (xy 278.468896 -342.466773)
			(xy 279.9516 -342.466773) (xy 279.9516 -342.412227) (xy 279.959363 -342.358236) (xy 279.974731 -342.3059)
			(xy 279.997392 -342.256284) (xy 280.026884 -342.210398) (xy 280.062606 -342.169176) (xy 280.103831 -342.133459)
			(xy 280.14972 -342.103972) (xy 280.199339 -342.081317) (xy 280.251677 -342.065954) (xy 280.305669 -342.058197)
			(xy 280.332942 -342.057736) (xy 281.196542 -342.057736) (xy 281.223809 -342.058229) (xy 281.277788 -342.065996)
			(xy 281.330112 -342.081365) (xy 281.379717 -342.104023) (xy 281.425592 -342.13351) (xy 281.466805 -342.169225)
			(xy 281.502515 -342.210441) (xy 281.531997 -342.25632) (xy 281.55465 -342.305927) (xy 281.570013 -342.358253)
			(xy 281.577774 -342.412233) (xy 281.577774 -342.466767) (xy 281.577773 -342.466771) (xy 283.060599 -342.466771)
			(xy 283.060599 -342.412229) (xy 283.068362 -342.358241) (xy 283.083728 -342.305908) (xy 283.106386 -342.256295)
			(xy 283.135874 -342.210411) (xy 283.171592 -342.16919) (xy 283.212812 -342.133473) (xy 283.258697 -342.103985)
			(xy 283.30831 -342.081327) (xy 283.360643 -342.065961) (xy 283.414631 -342.058199) (xy 283.441902 -342.057736)
			(xy 284.305502 -342.057736) (xy 284.332771 -342.058227) (xy 284.386754 -342.065988) (xy 284.439083 -342.081354)
			(xy 284.488693 -342.10401) (xy 284.534573 -342.133496) (xy 284.575791 -342.169211) (xy 284.611505 -342.210428)
			(xy 284.640991 -342.256309) (xy 284.663647 -342.305919) (xy 284.679012 -342.358248) (xy 284.686774 -342.412231)
			(xy 284.686774 -342.466768) (xy 286.169622 -342.466768) (xy 286.169622 -342.412232) (xy 286.177383 -342.358252)
			(xy 286.192747 -342.305925) (xy 286.2154 -342.256317) (xy 286.244883 -342.210438) (xy 286.280594 -342.169221)
			(xy 286.321807 -342.133505) (xy 286.367684 -342.104018) (xy 286.417289 -342.08136) (xy 286.469614 -342.065991)
			(xy 286.523594 -342.058225) (xy 286.550862 -342.057736) (xy 287.414462 -342.057736) (xy 287.441735 -342.058201)
			(xy 287.495725 -342.065959) (xy 287.548062 -342.081321) (xy 287.59768 -342.103977) (xy 287.643568 -342.133463)
			(xy 287.684793 -342.16918) (xy 287.720514 -342.210401) (xy 287.750005 -342.256287) (xy 287.772665 -342.305902)
			(xy 287.788033 -342.358237) (xy 287.795796 -342.412227) (xy 287.795796 -342.466772) (xy 289.2785 -342.466772)
			(xy 289.2785 -342.412228) (xy 289.286262 -342.358239) (xy 289.30163 -342.305904) (xy 289.324289 -342.256289)
			(xy 289.353779 -342.210404) (xy 289.389499 -342.169183) (xy 289.430722 -342.133466) (xy 289.476609 -342.103979)
			(xy 289.526225 -342.081322) (xy 289.57856 -342.065958) (xy 289.63255 -342.058198) (xy 289.659822 -342.057736)
			(xy 290.523422 -342.057736) (xy 290.55069 -342.058228) (xy 290.604671 -342.065992) (xy 290.656998 -342.081359)
			(xy 290.706605 -342.104017) (xy 290.752483 -342.133503) (xy 290.793698 -342.169218) (xy 290.82941 -342.210435)
			(xy 290.858894 -342.256314) (xy 290.881548 -342.305923) (xy 290.896913 -342.35825) (xy 290.904674 -342.412232)
			(xy 290.904674 -342.466768) (xy 290.904674 -342.466769) (xy 292.387522 -342.466769) (xy 292.387522 -342.412231)
			(xy 292.395284 -342.358249) (xy 292.410648 -342.305921) (xy 292.433303 -342.256311) (xy 292.462787 -342.210431)
			(xy 292.498501 -342.169214) (xy 292.539717 -342.133498) (xy 292.585596 -342.104012) (xy 292.635204 -342.081354)
			(xy 292.687531 -342.065987) (xy 292.741513 -342.058224) (xy 292.768782 -342.057736) (xy 293.632382 -342.057736)
			(xy 293.659654 -342.058202) (xy 293.713642 -342.065962) (xy 293.765977 -342.081327) (xy 293.815592 -342.103983)
			(xy 293.861478 -342.13347) (xy 293.9027 -342.169188) (xy 293.938419 -342.210408) (xy 293.967908 -342.256292)
			(xy 293.990567 -342.305906) (xy 294.005934 -342.35824) (xy 294.013696 -342.412228) (xy 294.013696 -342.466772)
			(xy 294.013696 -342.466773) (xy 295.4964 -342.466773) (xy 295.4964 -342.412227) (xy 295.504163 -342.358236)
			(xy 295.519531 -342.3059) (xy 295.542192 -342.256284) (xy 295.571684 -342.210398) (xy 295.607406 -342.169176)
			(xy 295.648631 -342.133459) (xy 295.69452 -342.103972) (xy 295.744139 -342.081317) (xy 295.796477 -342.065954)
			(xy 295.850469 -342.058197) (xy 295.877742 -342.057736) (xy 296.741342 -342.057736) (xy 296.768609 -342.058229)
			(xy 296.822588 -342.065996) (xy 296.874912 -342.081365) (xy 296.924517 -342.104023) (xy 296.970392 -342.13351)
			(xy 297.011605 -342.169225) (xy 297.047315 -342.210441) (xy 297.076797 -342.25632) (xy 297.09945 -342.305927)
			(xy 297.114813 -342.358253) (xy 297.122574 -342.412233) (xy 297.122574 -342.466767) (xy 297.122573 -342.466771)
			(xy 298.605399 -342.466771) (xy 298.605399 -342.412229) (xy 298.613162 -342.358241) (xy 298.628528 -342.305908)
			(xy 298.651186 -342.256295) (xy 298.680674 -342.210411) (xy 298.716392 -342.16919) (xy 298.757612 -342.133473)
			(xy 298.803497 -342.103985) (xy 298.85311 -342.081327) (xy 298.905443 -342.065961) (xy 298.959431 -342.058199)
			(xy 298.986702 -342.057736) (xy 299.850302 -342.057736) (xy 299.877571 -342.058227) (xy 299.931554 -342.065988)
			(xy 299.983883 -342.081354) (xy 300.033493 -342.10401) (xy 300.079373 -342.133496) (xy 300.120591 -342.169211)
			(xy 300.156305 -342.210428) (xy 300.185791 -342.256309) (xy 300.208447 -342.305919) (xy 300.223812 -342.358248)
			(xy 300.231574 -342.412231) (xy 300.231574 -342.466769) (xy 300.231574 -342.466771) (xy 312.1215 -342.466771)
			(xy 312.1215 -342.412229) (xy 312.129262 -342.358241) (xy 312.144628 -342.305908) (xy 312.167286 -342.256294)
			(xy 312.196774 -342.21041) (xy 312.232493 -342.16919) (xy 312.273713 -342.133472) (xy 312.319598 -342.103984)
			(xy 312.369212 -342.081327) (xy 312.421545 -342.065961) (xy 312.475533 -342.058199) (xy 312.502804 -342.057736)
			(xy 313.366404 -342.057736) (xy 313.393673 -342.058227) (xy 313.447656 -342.065989) (xy 313.499985 -342.081354)
			(xy 313.549594 -342.104011) (xy 313.595474 -342.133497) (xy 313.636691 -342.169212) (xy 313.672406 -342.210429)
			(xy 313.701891 -342.256309) (xy 313.724547 -342.305919) (xy 313.739912 -342.358248) (xy 313.747674 -342.412231)
			(xy 313.747674 -342.466768) (xy 315.230522 -342.466768) (xy 315.230522 -342.412232) (xy 315.238283 -342.358251)
			(xy 315.253647 -342.305924) (xy 315.2763 -342.256316) (xy 315.305783 -342.210437) (xy 315.341495 -342.16922)
			(xy 315.382708 -342.133505) (xy 315.428585 -342.104018) (xy 315.478191 -342.081359) (xy 315.530516 -342.065991)
			(xy 315.584496 -342.058225) (xy 315.611764 -342.057736) (xy 316.475364 -342.057736) (xy 316.502637 -342.058201)
			(xy 316.556627 -342.065959) (xy 316.608964 -342.081322) (xy 316.658581 -342.103977) (xy 316.704469 -342.133464)
			(xy 316.745693 -342.169181) (xy 316.781414 -342.210402) (xy 316.810905 -342.256287) (xy 316.833565 -342.305902)
			(xy 316.848933 -342.358238) (xy 316.856696 -342.412228) (xy 316.856696 -342.466772) (xy 318.3394 -342.466772)
			(xy 318.3394 -342.412228) (xy 318.347162 -342.358239) (xy 318.36253 -342.305904) (xy 318.385189 -342.256289)
			(xy 318.414679 -342.210404) (xy 318.4504 -342.169183) (xy 318.491623 -342.133465) (xy 318.53751 -342.103978)
			(xy 318.587126 -342.081322) (xy 318.639462 -342.065957) (xy 318.693452 -342.058198) (xy 318.720724 -342.057736)
			(xy 319.584324 -342.057736) (xy 319.611592 -342.058228) (xy 319.665573 -342.065992) (xy 319.717899 -342.08136)
			(xy 319.767506 -342.104017) (xy 319.813384 -342.133504) (xy 319.854598 -342.169219) (xy 319.890311 -342.210435)
			(xy 319.919794 -342.256315) (xy 319.942449 -342.305923) (xy 319.957813 -342.358251) (xy 319.965574 -342.412232)
			(xy 319.965574 -342.466768) (xy 319.965574 -342.466769) (xy 321.448422 -342.466769) (xy 321.448422 -342.412231)
			(xy 321.456184 -342.358249) (xy 321.471548 -342.30592) (xy 321.494203 -342.256311) (xy 321.523688 -342.21043)
			(xy 321.559402 -342.169213) (xy 321.600618 -342.133498) (xy 321.646497 -342.104011) (xy 321.696105 -342.081354)
			(xy 321.748433 -342.065987) (xy 321.802415 -342.058224) (xy 321.829684 -342.057736) (xy 322.693284 -342.057736)
			(xy 322.720556 -342.058202) (xy 322.774544 -342.065963) (xy 322.826878 -342.081327) (xy 322.876493 -342.103984)
			(xy 322.922379 -342.133471) (xy 322.9636 -342.169188) (xy 322.999319 -342.210409) (xy 323.028808 -342.256293)
			(xy 323.051467 -342.305907) (xy 323.066834 -342.35824) (xy 323.074596 -342.412228) (xy 323.074596 -342.466772)
			(xy 323.074596 -342.466773) (xy 324.5573 -342.466773) (xy 324.5573 -342.412227) (xy 324.565063 -342.358236)
			(xy 324.580432 -342.305899) (xy 324.603092 -342.256283) (xy 324.632584 -342.210397) (xy 324.668307 -342.169176)
			(xy 324.709532 -342.133458) (xy 324.755422 -342.103971) (xy 324.805041 -342.081316) (xy 324.857379 -342.065954)
			(xy 324.911371 -342.058196) (xy 324.938644 -342.057736) (xy 325.802244 -342.057736) (xy 325.829511 -342.058229)
			(xy 325.88349 -342.065996) (xy 325.935814 -342.081365) (xy 325.985418 -342.104024) (xy 326.031293 -342.133511)
			(xy 326.072505 -342.169226) (xy 326.108216 -342.210442) (xy 326.137697 -342.256321) (xy 326.16035 -342.305928)
			(xy 326.175713 -342.358253) (xy 326.183474 -342.412233) (xy 326.183474 -342.466767) (xy 326.183473 -342.466771)
			(xy 327.6663 -342.466771) (xy 327.6663 -342.412229) (xy 327.674062 -342.358241) (xy 327.689428 -342.305908)
			(xy 327.712086 -342.256294) (xy 327.741574 -342.21041) (xy 327.777293 -342.16919) (xy 327.818513 -342.133472)
			(xy 327.864398 -342.103984) (xy 327.914012 -342.081327) (xy 327.966345 -342.065961) (xy 328.020333 -342.058199)
			(xy 328.047604 -342.057736) (xy 328.911204 -342.057736) (xy 328.938473 -342.058227) (xy 328.992456 -342.065989)
			(xy 329.044785 -342.081354) (xy 329.094394 -342.104011) (xy 329.140274 -342.133497) (xy 329.181491 -342.169212)
			(xy 329.217206 -342.210429) (xy 329.246691 -342.256309) (xy 329.269347 -342.305919) (xy 329.284712 -342.358248)
			(xy 329.292474 -342.412231) (xy 329.292474 -342.466768) (xy 330.775322 -342.466768) (xy 330.775322 -342.412232)
			(xy 330.783083 -342.358251) (xy 330.798447 -342.305924) (xy 330.8211 -342.256316) (xy 330.850583 -342.210437)
			(xy 330.886295 -342.16922) (xy 330.927508 -342.133505) (xy 330.973385 -342.104018) (xy 331.022991 -342.081359)
			(xy 331.075316 -342.065991) (xy 331.129296 -342.058225) (xy 331.156564 -342.057736) (xy 332.020164 -342.057736)
			(xy 332.047437 -342.058201) (xy 332.101427 -342.065959) (xy 332.153764 -342.081322) (xy 332.203381 -342.103977)
			(xy 332.249269 -342.133464) (xy 332.290493 -342.169181) (xy 332.326214 -342.210402) (xy 332.355705 -342.256287)
			(xy 332.378365 -342.305902) (xy 332.393733 -342.358238) (xy 332.401496 -342.412228) (xy 332.401496 -342.466772)
			(xy 333.8842 -342.466772) (xy 333.8842 -342.412228) (xy 333.891962 -342.358239) (xy 333.90733 -342.305904)
			(xy 333.929989 -342.256289) (xy 333.959479 -342.210404) (xy 333.9952 -342.169183) (xy 334.036423 -342.133465)
			(xy 334.08231 -342.103978) (xy 334.131926 -342.081322) (xy 334.184262 -342.065957) (xy 334.238252 -342.058198)
			(xy 334.265524 -342.057736) (xy 335.129124 -342.057736) (xy 335.156392 -342.058228) (xy 335.210373 -342.065992)
			(xy 335.262699 -342.08136) (xy 335.312306 -342.104017) (xy 335.358184 -342.133504) (xy 335.399398 -342.169219)
			(xy 335.435111 -342.210435) (xy 335.464594 -342.256315) (xy 335.487249 -342.305923) (xy 335.502613 -342.358251)
			(xy 335.510374 -342.412232) (xy 335.510374 -342.466768) (xy 335.510374 -342.466769) (xy 336.993222 -342.466769)
			(xy 336.993222 -342.412231) (xy 337.000984 -342.358249) (xy 337.016348 -342.30592) (xy 337.039003 -342.256311)
			(xy 337.068488 -342.21043) (xy 337.104202 -342.169213) (xy 337.145418 -342.133498) (xy 337.191297 -342.104011)
			(xy 337.240905 -342.081354) (xy 337.293233 -342.065987) (xy 337.347215 -342.058224) (xy 337.374484 -342.057736)
			(xy 338.238084 -342.057736) (xy 338.265356 -342.058202) (xy 338.319344 -342.065963) (xy 338.371678 -342.081327)
			(xy 338.421293 -342.103984) (xy 338.467179 -342.133471) (xy 338.5084 -342.169188) (xy 338.544119 -342.210409)
			(xy 338.573608 -342.256293) (xy 338.596267 -342.305907) (xy 338.611634 -342.35824) (xy 338.619396 -342.412228)
			(xy 338.619396 -342.466772) (xy 338.619396 -342.466773) (xy 340.1021 -342.466773) (xy 340.1021 -342.412227)
			(xy 340.109863 -342.358236) (xy 340.125232 -342.305899) (xy 340.147892 -342.256283) (xy 340.177384 -342.210397)
			(xy 340.213107 -342.169176) (xy 340.254332 -342.133458) (xy 340.300222 -342.103971) (xy 340.349841 -342.081316)
			(xy 340.402179 -342.065954) (xy 340.456171 -342.058196) (xy 340.483444 -342.057736) (xy 341.347044 -342.057736)
			(xy 341.374311 -342.058229) (xy 341.42829 -342.065996) (xy 341.480614 -342.081365) (xy 341.530218 -342.104024)
			(xy 341.576093 -342.133511) (xy 341.617305 -342.169226) (xy 341.653016 -342.210442) (xy 341.682497 -342.256321)
			(xy 341.70515 -342.305928) (xy 341.720513 -342.358253) (xy 341.728274 -342.412233) (xy 341.728274 -342.466767)
			(xy 341.728273 -342.466771) (xy 343.2111 -342.466771) (xy 343.2111 -342.412229) (xy 343.218862 -342.358241)
			(xy 343.234228 -342.305908) (xy 343.256886 -342.256294) (xy 343.286374 -342.21041) (xy 343.322093 -342.16919)
			(xy 343.363313 -342.133472) (xy 343.409198 -342.103984) (xy 343.458812 -342.081327) (xy 343.511145 -342.065961)
			(xy 343.565133 -342.058199) (xy 343.592404 -342.057736) (xy 344.456004 -342.057736) (xy 344.483273 -342.058227)
			(xy 344.537256 -342.065989) (xy 344.589585 -342.081354) (xy 344.639194 -342.104011) (xy 344.685074 -342.133497)
			(xy 344.726291 -342.169212) (xy 344.762006 -342.210429) (xy 344.791491 -342.256309) (xy 344.814147 -342.305919)
			(xy 344.829512 -342.358248) (xy 344.837274 -342.412231) (xy 344.837274 -342.466769) (xy 370.806722 -342.466769)
			(xy 370.806722 -342.412231) (xy 370.814484 -342.358249) (xy 370.829848 -342.305921) (xy 370.852503 -342.256312)
			(xy 370.881987 -342.210432) (xy 370.9177 -342.169214) (xy 370.958916 -342.133499) (xy 371.004794 -342.104012)
			(xy 371.054402 -342.081355) (xy 371.10673 -342.065988) (xy 371.160711 -342.058224) (xy 371.18798 -342.057736)
			(xy 372.05158 -342.057736) (xy 372.078852 -342.058202) (xy 372.132841 -342.065962) (xy 372.185175 -342.081326)
			(xy 372.234791 -342.103983) (xy 372.280677 -342.13347) (xy 372.321899 -342.169187) (xy 372.357618 -342.210407)
			(xy 372.387108 -342.256292) (xy 372.409767 -342.305906) (xy 372.425134 -342.35824) (xy 372.432896 -342.412228)
			(xy 372.432896 -342.466772) (xy 372.432896 -342.466773) (xy 373.9156 -342.466773) (xy 373.9156 -342.412227)
			(xy 373.923363 -342.358236) (xy 373.938731 -342.3059) (xy 373.961392 -342.256284) (xy 373.990883 -342.210398)
			(xy 374.026605 -342.169177) (xy 374.06783 -342.133459) (xy 374.113719 -342.103973) (xy 374.163338 -342.081317)
			(xy 374.215676 -342.065954) (xy 374.269667 -342.058197) (xy 374.29694 -342.057736) (xy 375.16054 -342.057736)
			(xy 375.187807 -342.058229) (xy 375.241786 -342.065995) (xy 375.294111 -342.081364) (xy 375.343716 -342.104022)
			(xy 375.389591 -342.133509) (xy 375.430804 -342.169224) (xy 375.466515 -342.210441) (xy 375.495997 -342.256319)
			(xy 375.51865 -342.305927) (xy 375.534013 -342.358253) (xy 375.541774 -342.412233) (xy 375.541774 -342.466767)
			(xy 375.541774 -342.46677) (xy 377.024622 -342.46677) (xy 377.024622 -342.41223) (xy 377.032384 -342.358247)
			(xy 377.04775 -342.305917) (xy 377.070406 -342.256306) (xy 377.099892 -342.210425) (xy 377.135607 -342.169207)
			(xy 377.176825 -342.133492) (xy 377.222706 -342.104006) (xy 377.272317 -342.08135) (xy 377.324647 -342.065984)
			(xy 377.37863 -342.058222) (xy 377.4059 -342.057736) (xy 378.2695 -342.057736) (xy 378.296769 -342.058226)
			(xy 378.350753 -342.065988) (xy 378.403082 -342.081353) (xy 378.452692 -342.104009) (xy 378.498572 -342.133495)
			(xy 378.53979 -342.16921) (xy 378.575505 -342.210428) (xy 378.604991 -342.256308) (xy 378.627647 -342.305918)
			(xy 378.643012 -342.358247) (xy 378.650774 -342.412231) (xy 378.650774 -342.466768) (xy 380.133622 -342.466768)
			(xy 380.133622 -342.412232) (xy 380.141383 -342.358252) (xy 380.156746 -342.305925) (xy 380.1794 -342.256318)
			(xy 380.208882 -342.210438) (xy 380.244593 -342.169222) (xy 380.285806 -342.133506) (xy 380.331682 -342.104019)
			(xy 380.381288 -342.08136) (xy 380.433613 -342.065991) (xy 380.487592 -342.058225) (xy 380.51486 -342.057736)
			(xy 381.37846 -342.057736) (xy 381.405733 -342.058201) (xy 381.459724 -342.065958) (xy 381.512061 -342.081321)
			(xy 381.561679 -342.103976) (xy 381.607567 -342.133463) (xy 381.648792 -342.16918) (xy 381.684513 -342.210401)
			(xy 381.714005 -342.256286) (xy 381.736665 -342.305902) (xy 381.752033 -342.358237) (xy 381.759796 -342.412227)
			(xy 381.759796 -342.466772) (xy 383.2425 -342.466772) (xy 383.2425 -342.412228) (xy 383.250262 -342.358239)
			(xy 383.26563 -342.305904) (xy 383.288289 -342.25629) (xy 383.317778 -342.210405) (xy 383.353498 -342.169184)
			(xy 383.394721 -342.133466) (xy 383.440607 -342.103979) (xy 383.490223 -342.081323) (xy 383.542559 -342.065958)
			(xy 383.596548 -342.058198) (xy 383.62382 -342.057736) (xy 384.48742 -342.057736) (xy 384.514688 -342.058228)
			(xy 384.568669 -342.065992) (xy 384.620996 -342.081359) (xy 384.670604 -342.104016) (xy 384.716482 -342.133502)
			(xy 384.757697 -342.169217) (xy 384.79341 -342.210434) (xy 384.822894 -342.256314) (xy 384.845548 -342.305922)
			(xy 384.860913 -342.35825) (xy 384.868674 -342.412232) (xy 384.868674 -342.466768) (xy 384.868674 -342.466769)
			(xy 386.351522 -342.466769) (xy 386.351522 -342.412231) (xy 386.359284 -342.358249) (xy 386.374648 -342.305921)
			(xy 386.397303 -342.256312) (xy 386.426787 -342.210432) (xy 386.4625 -342.169214) (xy 386.503716 -342.133499)
			(xy 386.549594 -342.104012) (xy 386.599202 -342.081355) (xy 386.65153 -342.065988) (xy 386.705511 -342.058224)
			(xy 386.73278 -342.057736) (xy 387.59638 -342.057736) (xy 387.623652 -342.058202) (xy 387.677641 -342.065962)
			(xy 387.729975 -342.081326) (xy 387.779591 -342.103983) (xy 387.825477 -342.13347) (xy 387.866699 -342.169187)
			(xy 387.902418 -342.210407) (xy 387.931908 -342.256292) (xy 387.954567 -342.305906) (xy 387.969934 -342.35824)
			(xy 387.977696 -342.412228) (xy 387.977696 -342.466772) (xy 387.977696 -342.466773) (xy 389.4604 -342.466773)
			(xy 389.4604 -342.412227) (xy 389.468163 -342.358236) (xy 389.483531 -342.3059) (xy 389.506192 -342.256284)
			(xy 389.535683 -342.210398) (xy 389.571405 -342.169177) (xy 389.61263 -342.133459) (xy 389.658519 -342.103973)
			(xy 389.708138 -342.081317) (xy 389.760476 -342.065954) (xy 389.814467 -342.058197) (xy 389.84174 -342.057736)
			(xy 390.70534 -342.057736) (xy 390.732607 -342.058229) (xy 390.786586 -342.065995) (xy 390.838911 -342.081364)
			(xy 390.888516 -342.104022) (xy 390.934391 -342.133509) (xy 390.975604 -342.169224) (xy 391.011315 -342.210441)
			(xy 391.040797 -342.256319) (xy 391.06345 -342.305927) (xy 391.078813 -342.358253) (xy 391.086574 -342.412233)
			(xy 391.086574 -342.466767) (xy 391.086574 -342.46677) (xy 392.569422 -342.46677) (xy 392.569422 -342.41223)
			(xy 392.577184 -342.358247) (xy 392.59255 -342.305917) (xy 392.615206 -342.256306) (xy 392.644692 -342.210425)
			(xy 392.680407 -342.169207) (xy 392.721625 -342.133492) (xy 392.767506 -342.104006) (xy 392.817117 -342.08135)
			(xy 392.869447 -342.065984) (xy 392.92343 -342.058222) (xy 392.9507 -342.057736) (xy 393.8143 -342.057736)
			(xy 393.841569 -342.058226) (xy 393.895553 -342.065988) (xy 393.947882 -342.081353) (xy 393.997492 -342.104009)
			(xy 394.043372 -342.133495) (xy 394.08459 -342.16921) (xy 394.120305 -342.210428) (xy 394.149791 -342.256308)
			(xy 394.172447 -342.305918) (xy 394.187812 -342.358247) (xy 394.195574 -342.412231) (xy 394.195574 -342.466768)
			(xy 395.678422 -342.466768) (xy 395.678422 -342.412232) (xy 395.686183 -342.358252) (xy 395.701546 -342.305925)
			(xy 395.7242 -342.256318) (xy 395.753682 -342.210438) (xy 395.789393 -342.169222) (xy 395.830606 -342.133506)
			(xy 395.876482 -342.104019) (xy 395.926088 -342.08136) (xy 395.978413 -342.065991) (xy 396.032392 -342.058225)
			(xy 396.05966 -342.057736) (xy 396.92326 -342.057736) (xy 396.950533 -342.058201) (xy 397.004524 -342.065958)
			(xy 397.056861 -342.081321) (xy 397.106479 -342.103976) (xy 397.152367 -342.133463) (xy 397.193592 -342.16918)
			(xy 397.229313 -342.210401) (xy 397.258805 -342.256286) (xy 397.281465 -342.305902) (xy 397.296833 -342.358237)
			(xy 397.304596 -342.412227) (xy 397.304596 -342.466772) (xy 398.7873 -342.466772) (xy 398.7873 -342.412228)
			(xy 398.795062 -342.358239) (xy 398.81043 -342.305904) (xy 398.833089 -342.25629) (xy 398.862578 -342.210405)
			(xy 398.898298 -342.169184) (xy 398.939521 -342.133466) (xy 398.985407 -342.103979) (xy 399.035023 -342.081323)
			(xy 399.087359 -342.065958) (xy 399.141348 -342.058198) (xy 399.16862 -342.057736) (xy 400.03222 -342.057736)
			(xy 400.059488 -342.058228) (xy 400.113469 -342.065992) (xy 400.165796 -342.081359) (xy 400.215404 -342.104016)
			(xy 400.261282 -342.133502) (xy 400.302497 -342.169217) (xy 400.33821 -342.210434) (xy 400.367694 -342.256314)
			(xy 400.390348 -342.305922) (xy 400.405713 -342.35825) (xy 400.413474 -342.412232) (xy 400.413474 -342.466768)
			(xy 400.413474 -342.466769) (xy 401.896322 -342.466769) (xy 401.896322 -342.412231) (xy 401.904084 -342.358249)
			(xy 401.919448 -342.305921) (xy 401.942103 -342.256312) (xy 401.971587 -342.210432) (xy 402.0073 -342.169214)
			(xy 402.048516 -342.133499) (xy 402.094394 -342.104012) (xy 402.144002 -342.081355) (xy 402.19633 -342.065988)
			(xy 402.250311 -342.058224) (xy 402.27758 -342.057736) (xy 403.14118 -342.057736) (xy 403.168452 -342.058202)
			(xy 403.222441 -342.065962) (xy 403.274775 -342.081326) (xy 403.324391 -342.103983) (xy 403.370277 -342.13347)
			(xy 403.411499 -342.169187) (xy 403.447218 -342.210407) (xy 403.476708 -342.256292) (xy 403.499367 -342.305906)
			(xy 403.514734 -342.35824) (xy 403.522496 -342.412228) (xy 403.522496 -342.466769) (xy 408.913822 -342.466769)
			(xy 408.913822 -342.412231) (xy 408.921584 -342.358248) (xy 408.936949 -342.305918) (xy 408.959605 -342.256309)
			(xy 408.98909 -342.210428) (xy 409.024805 -342.16921) (xy 409.066021 -342.133495) (xy 409.111902 -342.104009)
			(xy 409.161511 -342.081352) (xy 409.21384 -342.065986) (xy 409.267823 -342.058223) (xy 409.295092 -342.057736)
			(xy 410.158692 -342.057736) (xy 410.185963 -342.058203) (xy 410.239951 -342.065964) (xy 410.292284 -342.08133)
			(xy 410.341898 -342.103987) (xy 410.387782 -342.133474) (xy 410.429003 -342.169191) (xy 410.464721 -342.210411)
			(xy 410.49421 -342.256295) (xy 410.516868 -342.305908) (xy 410.532234 -342.358241) (xy 410.539996 -342.412229)
			(xy 410.539996 -342.466767) (xy 412.022822 -342.466767) (xy 412.022822 -342.412233) (xy 412.030583 -342.358253)
			(xy 412.045946 -342.305927) (xy 412.068599 -342.25632) (xy 412.09808 -342.210441) (xy 412.13379 -342.169224)
			(xy 412.175002 -342.133509) (xy 412.220878 -342.104022) (xy 412.270482 -342.081363) (xy 412.322806 -342.065993)
			(xy 412.376785 -342.058226) (xy 412.404052 -342.057736) (xy 413.267652 -342.057736) (xy 413.294925 -342.0582)
			(xy 413.348917 -342.065957) (xy 413.401255 -342.081319) (xy 413.450874 -342.103974) (xy 413.496763 -342.13346)
			(xy 413.537989 -342.169177) (xy 413.573712 -342.210398) (xy 413.603203 -342.256284) (xy 413.625864 -342.3059)
			(xy 413.641233 -342.358236) (xy 413.648996 -342.412227) (xy 413.648996 -342.466772) (xy 415.1317 -342.466772)
			(xy 415.1317 -342.412228) (xy 415.139462 -342.35824) (xy 415.154829 -342.305906) (xy 415.177488 -342.256292)
			(xy 415.206976 -342.210407) (xy 415.242695 -342.169187) (xy 415.283917 -342.133469) (xy 415.329803 -342.103982)
			(xy 415.379417 -342.081325) (xy 415.431752 -342.065959) (xy 415.48574 -342.058199) (xy 415.513012 -342.057736)
			(xy 416.376612 -342.057736) (xy 416.403881 -342.058227) (xy 416.457863 -342.06599) (xy 416.510191 -342.081357)
			(xy 416.559799 -342.104013) (xy 416.605678 -342.133499) (xy 416.646894 -342.169214) (xy 416.682608 -342.210432)
			(xy 416.712092 -342.256312) (xy 416.734748 -342.305921) (xy 416.750112 -342.358249) (xy 416.757874 -342.412231)
			(xy 416.757874 -342.466768) (xy 418.240722 -342.466768) (xy 418.240722 -342.412232) (xy 418.248483 -342.35825)
			(xy 418.263847 -342.305923) (xy 418.286502 -342.256314) (xy 418.315985 -342.210434) (xy 418.351697 -342.169217)
			(xy 418.392912 -342.133502) (xy 418.43879 -342.104015) (xy 418.488396 -342.081357) (xy 418.540723 -342.065989)
			(xy 418.594704 -342.058224) (xy 418.621972 -342.057736) (xy 419.485572 -342.057736) (xy 419.512844 -342.058202)
			(xy 419.566834 -342.06596) (xy 419.61917 -342.081324) (xy 419.668786 -342.10398) (xy 419.714673 -342.133467)
			(xy 419.755896 -342.169184) (xy 419.791616 -342.210405) (xy 419.821107 -342.256289) (xy 419.843766 -342.305904)
			(xy 419.859134 -342.358239) (xy 419.866896 -342.412228) (xy 419.866896 -342.466772) (xy 419.866896 -342.466773)
			(xy 421.3496 -342.466773) (xy 421.3496 -342.412227) (xy 421.357363 -342.358237) (xy 421.372731 -342.305902)
			(xy 421.395391 -342.256286) (xy 421.424881 -342.210401) (xy 421.460602 -342.16918) (xy 421.501827 -342.133462)
			(xy 421.547715 -342.103975) (xy 421.597332 -342.081319) (xy 421.649669 -342.065956) (xy 421.703659 -342.058197)
			(xy 421.730932 -342.057736) (xy 422.594532 -342.057736) (xy 422.6218 -342.058229) (xy 422.67578 -342.065994)
			(xy 422.728105 -342.081362) (xy 422.777711 -342.10402) (xy 422.823588 -342.133506) (xy 422.864801 -342.169222)
			(xy 422.900513 -342.210438) (xy 422.929995 -342.256317) (xy 422.952649 -342.305925) (xy 422.968013 -342.358252)
			(xy 422.975774 -342.412232) (xy 422.975774 -342.466768) (xy 422.975774 -342.466769) (xy 424.458622 -342.466769)
			(xy 424.458622 -342.412231) (xy 424.466384 -342.358248) (xy 424.481749 -342.305918) (xy 424.504405 -342.256309)
			(xy 424.53389 -342.210428) (xy 424.569605 -342.16921) (xy 424.610821 -342.133495) (xy 424.656702 -342.104009)
			(xy 424.706311 -342.081352) (xy 424.75864 -342.065986) (xy 424.812623 -342.058223) (xy 424.839892 -342.057736)
			(xy 425.703492 -342.057736) (xy 425.730763 -342.058203) (xy 425.784751 -342.065964) (xy 425.837084 -342.08133)
			(xy 425.886698 -342.103987) (xy 425.932582 -342.133474) (xy 425.973803 -342.169191) (xy 426.009521 -342.210411)
			(xy 426.03901 -342.256295) (xy 426.061668 -342.305908) (xy 426.077034 -342.358241) (xy 426.084796 -342.412229)
			(xy 426.084796 -342.466767) (xy 427.567622 -342.466767) (xy 427.567622 -342.412233) (xy 427.575383 -342.358253)
			(xy 427.590746 -342.305927) (xy 427.613399 -342.25632) (xy 427.64288 -342.210441) (xy 427.67859 -342.169224)
			(xy 427.719802 -342.133509) (xy 427.765678 -342.104022) (xy 427.815282 -342.081363) (xy 427.867606 -342.065993)
			(xy 427.921585 -342.058226) (xy 427.948852 -342.057736) (xy 428.812452 -342.057736) (xy 428.839725 -342.0582)
			(xy 428.893717 -342.065957) (xy 428.946055 -342.081319) (xy 428.995674 -342.103974) (xy 429.041563 -342.13346)
			(xy 429.082789 -342.169177) (xy 429.118512 -342.210398) (xy 429.148003 -342.256284) (xy 429.170664 -342.3059)
			(xy 429.186033 -342.358236) (xy 429.193796 -342.412227) (xy 429.193796 -342.466772) (xy 430.6765 -342.466772)
			(xy 430.6765 -342.412228) (xy 430.684262 -342.35824) (xy 430.699629 -342.305906) (xy 430.722288 -342.256292)
			(xy 430.751776 -342.210407) (xy 430.787495 -342.169187) (xy 430.828717 -342.133469) (xy 430.874603 -342.103982)
			(xy 430.924217 -342.081325) (xy 430.976552 -342.065959) (xy 431.03054 -342.058199) (xy 431.057812 -342.057736)
			(xy 431.921412 -342.057736) (xy 431.948681 -342.058227) (xy 432.002663 -342.06599) (xy 432.054991 -342.081357)
			(xy 432.104599 -342.104013) (xy 432.150478 -342.133499) (xy 432.191694 -342.169214) (xy 432.227408 -342.210432)
			(xy 432.256892 -342.256312) (xy 432.279548 -342.305921) (xy 432.294912 -342.358249) (xy 432.302674 -342.412231)
			(xy 432.302674 -342.466768) (xy 433.785522 -342.466768) (xy 433.785522 -342.412232) (xy 433.793283 -342.35825)
			(xy 433.808647 -342.305923) (xy 433.831302 -342.256314) (xy 433.860785 -342.210434) (xy 433.896497 -342.169217)
			(xy 433.937712 -342.133502) (xy 433.98359 -342.104015) (xy 434.033196 -342.081357) (xy 434.085523 -342.065989)
			(xy 434.139504 -342.058224) (xy 434.166772 -342.057736) (xy 435.030372 -342.057736) (xy 435.057644 -342.058202)
			(xy 435.111634 -342.06596) (xy 435.16397 -342.081324) (xy 435.213586 -342.10398) (xy 435.259473 -342.133467)
			(xy 435.300696 -342.169184) (xy 435.336416 -342.210405) (xy 435.365907 -342.256289) (xy 435.388566 -342.305904)
			(xy 435.403934 -342.358239) (xy 435.411696 -342.412228) (xy 435.411696 -342.466772) (xy 435.411696 -342.466773)
			(xy 436.8944 -342.466773) (xy 436.8944 -342.412227) (xy 436.902163 -342.358237) (xy 436.917531 -342.305902)
			(xy 436.940191 -342.256286) (xy 436.969681 -342.210401) (xy 437.005402 -342.16918) (xy 437.046627 -342.133462)
			(xy 437.092515 -342.103975) (xy 437.142132 -342.081319) (xy 437.194469 -342.065956) (xy 437.248459 -342.058197)
			(xy 437.275732 -342.057736) (xy 438.139332 -342.057736) (xy 438.1666 -342.058229) (xy 438.22058 -342.065994)
			(xy 438.272905 -342.081362) (xy 438.322511 -342.10402) (xy 438.368388 -342.133506) (xy 438.409601 -342.169222)
			(xy 438.445313 -342.210438) (xy 438.474795 -342.256317) (xy 438.497449 -342.305925) (xy 438.512813 -342.358252)
			(xy 438.520574 -342.412232) (xy 438.520574 -342.466768) (xy 438.520574 -342.466769) (xy 440.003422 -342.466769)
			(xy 440.003422 -342.412231) (xy 440.011184 -342.358248) (xy 440.026549 -342.305918) (xy 440.049205 -342.256309)
			(xy 440.07869 -342.210428) (xy 440.114405 -342.16921) (xy 440.155621 -342.133495) (xy 440.201502 -342.104009)
			(xy 440.251111 -342.081352) (xy 440.30344 -342.065986) (xy 440.357423 -342.058223) (xy 440.384692 -342.057736)
			(xy 441.248292 -342.057736) (xy 441.275563 -342.058203) (xy 441.329551 -342.065964) (xy 441.381884 -342.08133)
			(xy 441.431498 -342.103987) (xy 441.477382 -342.133474) (xy 441.518603 -342.169191) (xy 441.554321 -342.210411)
			(xy 441.58381 -342.256295) (xy 441.606468 -342.305908) (xy 441.621834 -342.358241) (xy 441.629596 -342.412229)
			(xy 441.629596 -342.466771) (xy 441.621834 -342.520759) (xy 441.606468 -342.573092) (xy 441.58381 -342.622705)
			(xy 441.554321 -342.668589) (xy 441.518603 -342.709809) (xy 441.477382 -342.745526) (xy 441.431498 -342.775013)
			(xy 441.381884 -342.79767) (xy 441.329551 -342.813036) (xy 441.275563 -342.820797) (xy 441.248292 -342.82126)
			(xy 440.384692 -342.82126) (xy 440.357423 -342.820777) (xy 440.30344 -342.813014) (xy 440.251111 -342.797648)
			(xy 440.201502 -342.774991) (xy 440.155621 -342.745505) (xy 440.114405 -342.70979) (xy 440.07869 -342.668572)
			(xy 440.049205 -342.622691) (xy 440.026549 -342.573082) (xy 440.011184 -342.520752) (xy 440.003422 -342.466769)
			(xy 438.520574 -342.466769) (xy 438.512813 -342.520748) (xy 438.497449 -342.573075) (xy 438.474795 -342.622683)
			(xy 438.445313 -342.668562) (xy 438.409601 -342.709778) (xy 438.368388 -342.745494) (xy 438.322511 -342.77498)
			(xy 438.272905 -342.797638) (xy 438.22058 -342.813006) (xy 438.1666 -342.820771) (xy 438.139332 -342.82126)
			(xy 437.275732 -342.82126) (xy 437.248459 -342.820803) (xy 437.194469 -342.813044) (xy 437.142132 -342.797681)
			(xy 437.092515 -342.775025) (xy 437.046627 -342.745538) (xy 437.005402 -342.70982) (xy 436.969681 -342.668599)
			(xy 436.940191 -342.622714) (xy 436.917531 -342.573098) (xy 436.902163 -342.520763) (xy 436.8944 -342.466773)
			(xy 435.411696 -342.466773) (xy 435.403934 -342.520761) (xy 435.388566 -342.573096) (xy 435.365907 -342.622711)
			(xy 435.336416 -342.668595) (xy 435.300696 -342.709816) (xy 435.259473 -342.745533) (xy 435.213586 -342.77502)
			(xy 435.16397 -342.797676) (xy 435.111634 -342.81304) (xy 435.057644 -342.820798) (xy 435.030372 -342.82126)
			(xy 434.166772 -342.82126) (xy 434.139504 -342.820776) (xy 434.085523 -342.813011) (xy 434.033196 -342.797643)
			(xy 433.98359 -342.774985) (xy 433.937712 -342.745498) (xy 433.896497 -342.709783) (xy 433.860785 -342.668566)
			(xy 433.831302 -342.622686) (xy 433.808647 -342.573077) (xy 433.793283 -342.52075) (xy 433.785522 -342.466768)
			(xy 432.302674 -342.466768) (xy 432.302674 -342.466769) (xy 432.294912 -342.520751) (xy 432.279548 -342.573079)
			(xy 432.256892 -342.622688) (xy 432.227408 -342.668568) (xy 432.191694 -342.709786) (xy 432.150478 -342.745501)
			(xy 432.104599 -342.774987) (xy 432.054991 -342.797643) (xy 432.002663 -342.81301) (xy 431.948681 -342.820773)
			(xy 431.921412 -342.82126) (xy 431.057812 -342.82126) (xy 431.03054 -342.820801) (xy 430.976552 -342.813041)
			(xy 430.924217 -342.797675) (xy 430.874603 -342.775018) (xy 430.828717 -342.745531) (xy 430.787495 -342.709813)
			(xy 430.751776 -342.668593) (xy 430.722288 -342.622708) (xy 430.699629 -342.573094) (xy 430.684262 -342.52076)
			(xy 430.6765 -342.466772) (xy 429.193796 -342.466772) (xy 429.193796 -342.466773) (xy 429.186033 -342.520764)
			(xy 429.170664 -342.5731) (xy 429.148003 -342.622716) (xy 429.118512 -342.668602) (xy 429.082789 -342.709823)
			(xy 429.041563 -342.74554) (xy 428.995674 -342.775026) (xy 428.946055 -342.797681) (xy 428.893717 -342.813043)
			(xy 428.839725 -342.8208) (xy 428.812452 -342.82126) (xy 427.948852 -342.82126) (xy 427.921585 -342.820774)
			(xy 427.867606 -342.813007) (xy 427.815282 -342.797637) (xy 427.765678 -342.774978) (xy 427.719802 -342.745491)
			(xy 427.67859 -342.709776) (xy 427.64288 -342.668559) (xy 427.613399 -342.62268) (xy 427.590746 -342.573073)
			(xy 427.575383 -342.520747) (xy 427.567622 -342.466767) (xy 426.084796 -342.466767) (xy 426.084796 -342.466771)
			(xy 426.077034 -342.520759) (xy 426.061668 -342.573092) (xy 426.03901 -342.622705) (xy 426.009521 -342.668589)
			(xy 425.973803 -342.709809) (xy 425.932582 -342.745526) (xy 425.886698 -342.775013) (xy 425.837084 -342.79767)
			(xy 425.784751 -342.813036) (xy 425.730763 -342.820797) (xy 425.703492 -342.82126) (xy 424.839892 -342.82126)
			(xy 424.812623 -342.820777) (xy 424.75864 -342.813014) (xy 424.706311 -342.797648) (xy 424.656702 -342.774991)
			(xy 424.610821 -342.745505) (xy 424.569605 -342.70979) (xy 424.53389 -342.668572) (xy 424.504405 -342.622691)
			(xy 424.481749 -342.573082) (xy 424.466384 -342.520752) (xy 424.458622 -342.466769) (xy 422.975774 -342.466769)
			(xy 422.968013 -342.520748) (xy 422.952649 -342.573075) (xy 422.929995 -342.622683) (xy 422.900513 -342.668562)
			(xy 422.864801 -342.709778) (xy 422.823588 -342.745494) (xy 422.777711 -342.77498) (xy 422.728105 -342.797638)
			(xy 422.67578 -342.813006) (xy 422.6218 -342.820771) (xy 422.594532 -342.82126) (xy 421.730932 -342.82126)
			(xy 421.703659 -342.820803) (xy 421.649669 -342.813044) (xy 421.597332 -342.797681) (xy 421.547715 -342.775025)
			(xy 421.501827 -342.745538) (xy 421.460602 -342.70982) (xy 421.424881 -342.668599) (xy 421.395391 -342.622714)
			(xy 421.372731 -342.573098) (xy 421.357363 -342.520763) (xy 421.3496 -342.466773) (xy 419.866896 -342.466773)
			(xy 419.859134 -342.520761) (xy 419.843766 -342.573096) (xy 419.821107 -342.622711) (xy 419.791616 -342.668595)
			(xy 419.755896 -342.709816) (xy 419.714673 -342.745533) (xy 419.668786 -342.77502) (xy 419.61917 -342.797676)
			(xy 419.566834 -342.81304) (xy 419.512844 -342.820798) (xy 419.485572 -342.82126) (xy 418.621972 -342.82126)
			(xy 418.594704 -342.820776) (xy 418.540723 -342.813011) (xy 418.488396 -342.797643) (xy 418.43879 -342.774985)
			(xy 418.392912 -342.745498) (xy 418.351697 -342.709783) (xy 418.315985 -342.668566) (xy 418.286502 -342.622686)
			(xy 418.263847 -342.573077) (xy 418.248483 -342.52075) (xy 418.240722 -342.466768) (xy 416.757874 -342.466768)
			(xy 416.757874 -342.466769) (xy 416.750112 -342.520751) (xy 416.734748 -342.573079) (xy 416.712092 -342.622688)
			(xy 416.682608 -342.668568) (xy 416.646894 -342.709786) (xy 416.605678 -342.745501) (xy 416.559799 -342.774987)
			(xy 416.510191 -342.797643) (xy 416.457863 -342.81301) (xy 416.403881 -342.820773) (xy 416.376612 -342.82126)
			(xy 415.513012 -342.82126) (xy 415.48574 -342.820801) (xy 415.431752 -342.813041) (xy 415.379417 -342.797675)
			(xy 415.329803 -342.775018) (xy 415.283917 -342.745531) (xy 415.242695 -342.709813) (xy 415.206976 -342.668593)
			(xy 415.177488 -342.622708) (xy 415.154829 -342.573094) (xy 415.139462 -342.52076) (xy 415.1317 -342.466772)
			(xy 413.648996 -342.466772) (xy 413.648996 -342.466773) (xy 413.641233 -342.520764) (xy 413.625864 -342.5731)
			(xy 413.603203 -342.622716) (xy 413.573712 -342.668602) (xy 413.537989 -342.709823) (xy 413.496763 -342.74554)
			(xy 413.450874 -342.775026) (xy 413.401255 -342.797681) (xy 413.348917 -342.813043) (xy 413.294925 -342.8208)
			(xy 413.267652 -342.82126) (xy 412.404052 -342.82126) (xy 412.376785 -342.820774) (xy 412.322806 -342.813007)
			(xy 412.270482 -342.797637) (xy 412.220878 -342.774978) (xy 412.175002 -342.745491) (xy 412.13379 -342.709776)
			(xy 412.09808 -342.668559) (xy 412.068599 -342.62268) (xy 412.045946 -342.573073) (xy 412.030583 -342.520747)
			(xy 412.022822 -342.466767) (xy 410.539996 -342.466767) (xy 410.539996 -342.466771) (xy 410.532234 -342.520759)
			(xy 410.516868 -342.573092) (xy 410.49421 -342.622705) (xy 410.464721 -342.668589) (xy 410.429003 -342.709809)
			(xy 410.387782 -342.745526) (xy 410.341898 -342.775013) (xy 410.292284 -342.79767) (xy 410.239951 -342.813036)
			(xy 410.185963 -342.820797) (xy 410.158692 -342.82126) (xy 409.295092 -342.82126) (xy 409.267823 -342.820777)
			(xy 409.21384 -342.813014) (xy 409.161511 -342.797648) (xy 409.111902 -342.774991) (xy 409.066021 -342.745505)
			(xy 409.024805 -342.70979) (xy 408.98909 -342.668572) (xy 408.959605 -342.622691) (xy 408.936949 -342.573082)
			(xy 408.921584 -342.520752) (xy 408.913822 -342.466769) (xy 403.522496 -342.466769) (xy 403.522496 -342.466772)
			(xy 403.514734 -342.52076) (xy 403.499367 -342.573094) (xy 403.476708 -342.622708) (xy 403.447218 -342.668593)
			(xy 403.411499 -342.709813) (xy 403.370277 -342.74553) (xy 403.324391 -342.775017) (xy 403.274775 -342.797674)
			(xy 403.222441 -342.813038) (xy 403.168452 -342.820798) (xy 403.14118 -342.82126) (xy 402.27758 -342.82126)
			(xy 402.250311 -342.820776) (xy 402.19633 -342.813012) (xy 402.144002 -342.797645) (xy 402.094394 -342.774988)
			(xy 402.048516 -342.745501) (xy 402.0073 -342.709786) (xy 401.971587 -342.668568) (xy 401.942103 -342.622688)
			(xy 401.919448 -342.573079) (xy 401.904084 -342.520751) (xy 401.896322 -342.466769) (xy 400.413474 -342.466769)
			(xy 400.405713 -342.52075) (xy 400.390348 -342.573078) (xy 400.367694 -342.622686) (xy 400.33821 -342.668566)
			(xy 400.302497 -342.709783) (xy 400.261282 -342.745498) (xy 400.215404 -342.774984) (xy 400.165796 -342.797641)
			(xy 400.113469 -342.813008) (xy 400.059488 -342.820772) (xy 400.03222 -342.82126) (xy 399.16862 -342.82126)
			(xy 399.141348 -342.820802) (xy 399.087359 -342.813042) (xy 399.035023 -342.797677) (xy 398.985407 -342.775021)
			(xy 398.939521 -342.745534) (xy 398.898298 -342.709816) (xy 398.862578 -342.668595) (xy 398.833089 -342.62271)
			(xy 398.81043 -342.573096) (xy 398.795062 -342.520761) (xy 398.7873 -342.466772) (xy 397.304596 -342.466772)
			(xy 397.304596 -342.466773) (xy 397.296833 -342.520763) (xy 397.281465 -342.573098) (xy 397.258805 -342.622714)
			(xy 397.229313 -342.668599) (xy 397.193592 -342.70982) (xy 397.152367 -342.745537) (xy 397.106479 -342.775024)
			(xy 397.056861 -342.797679) (xy 397.004524 -342.813042) (xy 396.950533 -342.820799) (xy 396.92326 -342.82126)
			(xy 396.05966 -342.82126) (xy 396.032392 -342.820775) (xy 395.978413 -342.813009) (xy 395.926088 -342.79764)
			(xy 395.876482 -342.774981) (xy 395.830606 -342.745494) (xy 395.789393 -342.709778) (xy 395.753682 -342.668562)
			(xy 395.7242 -342.622682) (xy 395.701546 -342.573075) (xy 395.686183 -342.520748) (xy 395.678422 -342.466768)
			(xy 394.195574 -342.466768) (xy 394.195574 -342.466769) (xy 394.187812 -342.520753) (xy 394.172447 -342.573082)
			(xy 394.149791 -342.622692) (xy 394.120305 -342.668572) (xy 394.08459 -342.70979) (xy 394.043372 -342.745505)
			(xy 393.997492 -342.774991) (xy 393.947882 -342.797647) (xy 393.895553 -342.813012) (xy 393.841569 -342.820774)
			(xy 393.8143 -342.82126) (xy 392.9507 -342.82126) (xy 392.92343 -342.820778) (xy 392.869447 -342.813016)
			(xy 392.817117 -342.79765) (xy 392.767506 -342.774994) (xy 392.721625 -342.745508) (xy 392.680407 -342.709793)
			(xy 392.644692 -342.668575) (xy 392.615206 -342.622694) (xy 392.59255 -342.573083) (xy 392.577184 -342.520753)
			(xy 392.569422 -342.46677) (xy 391.086574 -342.46677) (xy 391.078813 -342.520747) (xy 391.06345 -342.573073)
			(xy 391.040797 -342.622681) (xy 391.011315 -342.668559) (xy 390.975604 -342.709776) (xy 390.934391 -342.745491)
			(xy 390.888516 -342.774978) (xy 390.838911 -342.797636) (xy 390.786586 -342.813005) (xy 390.732607 -342.820771)
			(xy 390.70534 -342.82126) (xy 389.84174 -342.82126) (xy 389.814467 -342.820803) (xy 389.760476 -342.813046)
			(xy 389.708138 -342.797683) (xy 389.658519 -342.775027) (xy 389.61263 -342.745541) (xy 389.571405 -342.709823)
			(xy 389.535683 -342.668602) (xy 389.506192 -342.622716) (xy 389.483531 -342.5731) (xy 389.468163 -342.520764)
			(xy 389.4604 -342.466773) (xy 387.977696 -342.466773) (xy 387.969934 -342.52076) (xy 387.954567 -342.573094)
			(xy 387.931908 -342.622708) (xy 387.902418 -342.668593) (xy 387.866699 -342.709813) (xy 387.825477 -342.74553)
			(xy 387.779591 -342.775017) (xy 387.729975 -342.797674) (xy 387.677641 -342.813038) (xy 387.623652 -342.820798)
			(xy 387.59638 -342.82126) (xy 386.73278 -342.82126) (xy 386.705511 -342.820776) (xy 386.65153 -342.813012)
			(xy 386.599202 -342.797645) (xy 386.549594 -342.774988) (xy 386.503716 -342.745501) (xy 386.4625 -342.709786)
			(xy 386.426787 -342.668568) (xy 386.397303 -342.622688) (xy 386.374648 -342.573079) (xy 386.359284 -342.520751)
			(xy 386.351522 -342.466769) (xy 384.868674 -342.466769) (xy 384.860913 -342.52075) (xy 384.845548 -342.573078)
			(xy 384.822894 -342.622686) (xy 384.79341 -342.668566) (xy 384.757697 -342.709783) (xy 384.716482 -342.745498)
			(xy 384.670604 -342.774984) (xy 384.620996 -342.797641) (xy 384.568669 -342.813008) (xy 384.514688 -342.820772)
			(xy 384.48742 -342.82126) (xy 383.62382 -342.82126) (xy 383.596548 -342.820802) (xy 383.542559 -342.813042)
			(xy 383.490223 -342.797677) (xy 383.440607 -342.775021) (xy 383.394721 -342.745534) (xy 383.353498 -342.709816)
			(xy 383.317778 -342.668595) (xy 383.288289 -342.62271) (xy 383.26563 -342.573096) (xy 383.250262 -342.520761)
			(xy 383.2425 -342.466772) (xy 381.759796 -342.466772) (xy 381.759796 -342.466773) (xy 381.752033 -342.520763)
			(xy 381.736665 -342.573098) (xy 381.714005 -342.622714) (xy 381.684513 -342.668599) (xy 381.648792 -342.70982)
			(xy 381.607567 -342.745537) (xy 381.561679 -342.775024) (xy 381.512061 -342.797679) (xy 381.459724 -342.813042)
			(xy 381.405733 -342.820799) (xy 381.37846 -342.82126) (xy 380.51486 -342.82126) (xy 380.487592 -342.820775)
			(xy 380.433613 -342.813009) (xy 380.381288 -342.79764) (xy 380.331682 -342.774981) (xy 380.285806 -342.745494)
			(xy 380.244593 -342.709778) (xy 380.208882 -342.668562) (xy 380.1794 -342.622682) (xy 380.156746 -342.573075)
			(xy 380.141383 -342.520748) (xy 380.133622 -342.466768) (xy 378.650774 -342.466768) (xy 378.650774 -342.466769)
			(xy 378.643012 -342.520753) (xy 378.627647 -342.573082) (xy 378.604991 -342.622692) (xy 378.575505 -342.668572)
			(xy 378.53979 -342.70979) (xy 378.498572 -342.745505) (xy 378.452692 -342.774991) (xy 378.403082 -342.797647)
			(xy 378.350753 -342.813012) (xy 378.296769 -342.820774) (xy 378.2695 -342.82126) (xy 377.4059 -342.82126)
			(xy 377.37863 -342.820778) (xy 377.324647 -342.813016) (xy 377.272317 -342.79765) (xy 377.222706 -342.774994)
			(xy 377.176825 -342.745508) (xy 377.135607 -342.709793) (xy 377.099892 -342.668575) (xy 377.070406 -342.622694)
			(xy 377.04775 -342.573083) (xy 377.032384 -342.520753) (xy 377.024622 -342.46677) (xy 375.541774 -342.46677)
			(xy 375.534013 -342.520747) (xy 375.51865 -342.573073) (xy 375.495997 -342.622681) (xy 375.466515 -342.668559)
			(xy 375.430804 -342.709776) (xy 375.389591 -342.745491) (xy 375.343716 -342.774978) (xy 375.294111 -342.797636)
			(xy 375.241786 -342.813005) (xy 375.187807 -342.820771) (xy 375.16054 -342.82126) (xy 374.29694 -342.82126)
			(xy 374.269667 -342.820803) (xy 374.215676 -342.813046) (xy 374.163338 -342.797683) (xy 374.113719 -342.775027)
			(xy 374.06783 -342.745541) (xy 374.026605 -342.709823) (xy 373.990883 -342.668602) (xy 373.961392 -342.622716)
			(xy 373.938731 -342.5731) (xy 373.923363 -342.520764) (xy 373.9156 -342.466773) (xy 372.432896 -342.466773)
			(xy 372.425134 -342.52076) (xy 372.409767 -342.573094) (xy 372.387108 -342.622708) (xy 372.357618 -342.668593)
			(xy 372.321899 -342.709813) (xy 372.280677 -342.74553) (xy 372.234791 -342.775017) (xy 372.185175 -342.797674)
			(xy 372.132841 -342.813038) (xy 372.078852 -342.820798) (xy 372.05158 -342.82126) (xy 371.18798 -342.82126)
			(xy 371.160711 -342.820776) (xy 371.10673 -342.813012) (xy 371.054402 -342.797645) (xy 371.004794 -342.774988)
			(xy 370.958916 -342.745501) (xy 370.9177 -342.709786) (xy 370.881987 -342.668568) (xy 370.852503 -342.622688)
			(xy 370.829848 -342.573079) (xy 370.814484 -342.520751) (xy 370.806722 -342.466769) (xy 344.837274 -342.466769)
			(xy 344.829512 -342.520752) (xy 344.814147 -342.573081) (xy 344.791491 -342.622691) (xy 344.762006 -342.668571)
			(xy 344.726291 -342.709788) (xy 344.685074 -342.745503) (xy 344.639194 -342.774989) (xy 344.589585 -342.797646)
			(xy 344.537256 -342.813011) (xy 344.483273 -342.820773) (xy 344.456004 -342.82126) (xy 343.592404 -342.82126)
			(xy 343.565133 -342.820801) (xy 343.511145 -342.813039) (xy 343.458812 -342.797673) (xy 343.409198 -342.775016)
			(xy 343.363313 -342.745528) (xy 343.322093 -342.70981) (xy 343.286374 -342.66859) (xy 343.256886 -342.622706)
			(xy 343.234228 -342.573092) (xy 343.218862 -342.520759) (xy 343.2111 -342.466771) (xy 341.728273 -342.466771)
			(xy 341.720513 -342.520747) (xy 341.70515 -342.573072) (xy 341.682497 -342.622679) (xy 341.653016 -342.668558)
			(xy 341.617305 -342.709774) (xy 341.576093 -342.745489) (xy 341.530218 -342.774976) (xy 341.480614 -342.797635)
			(xy 341.42829 -342.813004) (xy 341.374311 -342.820771) (xy 341.347044 -342.82126) (xy 340.483444 -342.82126)
			(xy 340.456171 -342.820804) (xy 340.402179 -342.813046) (xy 340.349841 -342.797684) (xy 340.300222 -342.775029)
			(xy 340.254332 -342.745542) (xy 340.213107 -342.709824) (xy 340.177384 -342.668603) (xy 340.147892 -342.622717)
			(xy 340.125232 -342.573101) (xy 340.109863 -342.520764) (xy 340.1021 -342.466773) (xy 338.619396 -342.466773)
			(xy 338.611634 -342.52076) (xy 338.596267 -342.573093) (xy 338.573608 -342.622707) (xy 338.544119 -342.668591)
			(xy 338.5084 -342.709812) (xy 338.467179 -342.745529) (xy 338.421293 -342.775016) (xy 338.371678 -342.797673)
			(xy 338.319344 -342.813037) (xy 338.265356 -342.820798) (xy 338.238084 -342.82126) (xy 337.374484 -342.82126)
			(xy 337.347215 -342.820776) (xy 337.293233 -342.813013) (xy 337.240905 -342.797646) (xy 337.191297 -342.774989)
			(xy 337.145418 -342.745502) (xy 337.104202 -342.709787) (xy 337.068488 -342.66857) (xy 337.039003 -342.622689)
			(xy 337.016348 -342.57308) (xy 337.000984 -342.520751) (xy 336.993222 -342.466769) (xy 335.510374 -342.466769)
			(xy 335.502613 -342.520749) (xy 335.487249 -342.573077) (xy 335.464594 -342.622685) (xy 335.435111 -342.668565)
			(xy 335.399398 -342.709781) (xy 335.358184 -342.745496) (xy 335.312306 -342.774983) (xy 335.262699 -342.79764)
			(xy 335.210373 -342.813008) (xy 335.156392 -342.820772) (xy 335.129124 -342.82126) (xy 334.265524 -342.82126)
			(xy 334.238252 -342.820802) (xy 334.184262 -342.813043) (xy 334.131926 -342.797678) (xy 334.08231 -342.775022)
			(xy 334.036423 -342.745535) (xy 333.9952 -342.709817) (xy 333.959479 -342.668596) (xy 333.929989 -342.622711)
			(xy 333.90733 -342.573096) (xy 333.891962 -342.520761) (xy 333.8842 -342.466772) (xy 332.401496 -342.466772)
			(xy 332.393733 -342.520762) (xy 332.378365 -342.573098) (xy 332.355705 -342.622713) (xy 332.326214 -342.668598)
			(xy 332.290493 -342.709819) (xy 332.249269 -342.745536) (xy 332.203381 -342.775023) (xy 332.153764 -342.797678)
			(xy 332.101427 -342.813041) (xy 332.047437 -342.820799) (xy 332.020164 -342.82126) (xy 331.156564 -342.82126)
			(xy 331.129296 -342.820775) (xy 331.075316 -342.813009) (xy 331.022991 -342.797641) (xy 330.973385 -342.774982)
			(xy 330.927508 -342.745495) (xy 330.886295 -342.70978) (xy 330.850583 -342.668563) (xy 330.8211 -342.622684)
			(xy 330.798447 -342.573076) (xy 330.783083 -342.520749) (xy 330.775322 -342.466768) (xy 329.292474 -342.466768)
			(xy 329.292474 -342.466769) (xy 329.284712 -342.520752) (xy 329.269347 -342.573081) (xy 329.246691 -342.622691)
			(xy 329.217206 -342.668571) (xy 329.181491 -342.709788) (xy 329.140274 -342.745503) (xy 329.094394 -342.774989)
			(xy 329.044785 -342.797646) (xy 328.992456 -342.813011) (xy 328.938473 -342.820773) (xy 328.911204 -342.82126)
			(xy 328.047604 -342.82126) (xy 328.020333 -342.820801) (xy 327.966345 -342.813039) (xy 327.914012 -342.797673)
			(xy 327.864398 -342.775016) (xy 327.818513 -342.745528) (xy 327.777293 -342.70981) (xy 327.741574 -342.66859)
			(xy 327.712086 -342.622706) (xy 327.689428 -342.573092) (xy 327.674062 -342.520759) (xy 327.6663 -342.466771)
			(xy 326.183473 -342.466771) (xy 326.175713 -342.520747) (xy 326.16035 -342.573072) (xy 326.137697 -342.622679)
			(xy 326.108216 -342.668558) (xy 326.072505 -342.709774) (xy 326.031293 -342.745489) (xy 325.985418 -342.774976)
			(xy 325.935814 -342.797635) (xy 325.88349 -342.813004) (xy 325.829511 -342.820771) (xy 325.802244 -342.82126)
			(xy 324.938644 -342.82126) (xy 324.911371 -342.820804) (xy 324.857379 -342.813046) (xy 324.805041 -342.797684)
			(xy 324.755422 -342.775029) (xy 324.709532 -342.745542) (xy 324.668307 -342.709824) (xy 324.632584 -342.668603)
			(xy 324.603092 -342.622717) (xy 324.580432 -342.573101) (xy 324.565063 -342.520764) (xy 324.5573 -342.466773)
			(xy 323.074596 -342.466773) (xy 323.066834 -342.52076) (xy 323.051467 -342.573093) (xy 323.028808 -342.622707)
			(xy 322.999319 -342.668591) (xy 322.9636 -342.709812) (xy 322.922379 -342.745529) (xy 322.876493 -342.775016)
			(xy 322.826878 -342.797673) (xy 322.774544 -342.813037) (xy 322.720556 -342.820798) (xy 322.693284 -342.82126)
			(xy 321.829684 -342.82126) (xy 321.802415 -342.820776) (xy 321.748433 -342.813013) (xy 321.696105 -342.797646)
			(xy 321.646497 -342.774989) (xy 321.600618 -342.745502) (xy 321.559402 -342.709787) (xy 321.523688 -342.66857)
			(xy 321.494203 -342.622689) (xy 321.471548 -342.57308) (xy 321.456184 -342.520751) (xy 321.448422 -342.466769)
			(xy 319.965574 -342.466769) (xy 319.957813 -342.520749) (xy 319.942449 -342.573077) (xy 319.919794 -342.622685)
			(xy 319.890311 -342.668565) (xy 319.854598 -342.709781) (xy 319.813384 -342.745496) (xy 319.767506 -342.774983)
			(xy 319.717899 -342.79764) (xy 319.665573 -342.813008) (xy 319.611592 -342.820772) (xy 319.584324 -342.82126)
			(xy 318.720724 -342.82126) (xy 318.693452 -342.820802) (xy 318.639462 -342.813043) (xy 318.587126 -342.797678)
			(xy 318.53751 -342.775022) (xy 318.491623 -342.745535) (xy 318.4504 -342.709817) (xy 318.414679 -342.668596)
			(xy 318.385189 -342.622711) (xy 318.36253 -342.573096) (xy 318.347162 -342.520761) (xy 318.3394 -342.466772)
			(xy 316.856696 -342.466772) (xy 316.848933 -342.520762) (xy 316.833565 -342.573098) (xy 316.810905 -342.622713)
			(xy 316.781414 -342.668598) (xy 316.745693 -342.709819) (xy 316.704469 -342.745536) (xy 316.658581 -342.775023)
			(xy 316.608964 -342.797678) (xy 316.556627 -342.813041) (xy 316.502637 -342.820799) (xy 316.475364 -342.82126)
			(xy 315.611764 -342.82126) (xy 315.584496 -342.820775) (xy 315.530516 -342.813009) (xy 315.478191 -342.797641)
			(xy 315.428585 -342.774982) (xy 315.382708 -342.745495) (xy 315.341495 -342.70978) (xy 315.305783 -342.668563)
			(xy 315.2763 -342.622684) (xy 315.253647 -342.573076) (xy 315.238283 -342.520749) (xy 315.230522 -342.466768)
			(xy 313.747674 -342.466768) (xy 313.747674 -342.466769) (xy 313.739912 -342.520752) (xy 313.724547 -342.573081)
			(xy 313.701891 -342.622691) (xy 313.672406 -342.668571) (xy 313.636691 -342.709788) (xy 313.595474 -342.745503)
			(xy 313.549594 -342.774989) (xy 313.499985 -342.797646) (xy 313.447656 -342.813011) (xy 313.393673 -342.820773)
			(xy 313.366404 -342.82126) (xy 312.502804 -342.82126) (xy 312.475533 -342.820801) (xy 312.421545 -342.813039)
			(xy 312.369212 -342.797673) (xy 312.319598 -342.775016) (xy 312.273713 -342.745528) (xy 312.232493 -342.70981)
			(xy 312.196774 -342.66859) (xy 312.167286 -342.622706) (xy 312.144628 -342.573092) (xy 312.129262 -342.520759)
			(xy 312.1215 -342.466771) (xy 300.231574 -342.466771) (xy 300.223812 -342.520752) (xy 300.208447 -342.573081)
			(xy 300.185791 -342.622691) (xy 300.156305 -342.668572) (xy 300.120591 -342.709789) (xy 300.079373 -342.745504)
			(xy 300.033493 -342.77499) (xy 299.983883 -342.797646) (xy 299.931554 -342.813012) (xy 299.877571 -342.820773)
			(xy 299.850302 -342.82126) (xy 298.986702 -342.82126) (xy 298.959431 -342.820801) (xy 298.905443 -342.813039)
			(xy 298.85311 -342.797673) (xy 298.803497 -342.775015) (xy 298.757612 -342.745527) (xy 298.716392 -342.70981)
			(xy 298.680674 -342.668589) (xy 298.651186 -342.622705) (xy 298.628528 -342.573092) (xy 298.613162 -342.520759)
			(xy 298.605399 -342.466771) (xy 297.122573 -342.466771) (xy 297.114813 -342.520747) (xy 297.09945 -342.573073)
			(xy 297.076797 -342.62268) (xy 297.047315 -342.668559) (xy 297.011605 -342.709775) (xy 296.970392 -342.74549)
			(xy 296.924517 -342.774977) (xy 296.874912 -342.797635) (xy 296.822588 -342.813004) (xy 296.768609 -342.820771)
			(xy 296.741342 -342.82126) (xy 295.877742 -342.82126) (xy 295.850469 -342.820803) (xy 295.796477 -342.813046)
			(xy 295.744139 -342.797683) (xy 295.694521 -342.775028) (xy 295.648631 -342.745541) (xy 295.607406 -342.709824)
			(xy 295.571684 -342.668602) (xy 295.542192 -342.622716) (xy 295.519531 -342.5731) (xy 295.504163 -342.520764)
			(xy 295.4964 -342.466773) (xy 294.013696 -342.466773) (xy 294.005934 -342.52076) (xy 293.990567 -342.573094)
			(xy 293.967908 -342.622708) (xy 293.938419 -342.668592) (xy 293.9027 -342.709812) (xy 293.861478 -342.74553)
			(xy 293.815592 -342.775017) (xy 293.765977 -342.797673) (xy 293.713642 -342.813038) (xy 293.659654 -342.820798)
			(xy 293.632382 -342.82126) (xy 292.768782 -342.82126) (xy 292.741513 -342.820776) (xy 292.687531 -342.813013)
			(xy 292.635204 -342.797646) (xy 292.585596 -342.774988) (xy 292.539717 -342.745502) (xy 292.498501 -342.709786)
			(xy 292.462787 -342.668569) (xy 292.433303 -342.622689) (xy 292.410648 -342.573079) (xy 292.395284 -342.520751)
			(xy 292.387522 -342.466769) (xy 290.904674 -342.466769) (xy 290.896913 -342.52075) (xy 290.881548 -342.573077)
			(xy 290.858894 -342.622686) (xy 290.82941 -342.668565) (xy 290.793698 -342.709782) (xy 290.752483 -342.745497)
			(xy 290.706605 -342.774983) (xy 290.656998 -342.797641) (xy 290.604671 -342.813008) (xy 290.55069 -342.820772)
			(xy 290.523422 -342.82126) (xy 289.659822 -342.82126) (xy 289.63255 -342.820802) (xy 289.57856 -342.813042)
			(xy 289.526225 -342.797678) (xy 289.476609 -342.775021) (xy 289.430722 -342.745534) (xy 289.389499 -342.709817)
			(xy 289.353779 -342.668596) (xy 289.324289 -342.622711) (xy 289.30163 -342.573096) (xy 289.286262 -342.520761)
			(xy 289.2785 -342.466772) (xy 287.795796 -342.466772) (xy 287.795796 -342.466773) (xy 287.788033 -342.520763)
			(xy 287.772665 -342.573098) (xy 287.750005 -342.622713) (xy 287.720514 -342.668599) (xy 287.684793 -342.70982)
			(xy 287.643568 -342.745537) (xy 287.59768 -342.775023) (xy 287.548062 -342.797679) (xy 287.495725 -342.813041)
			(xy 287.441735 -342.820799) (xy 287.414462 -342.82126) (xy 286.550862 -342.82126) (xy 286.523594 -342.820775)
			(xy 286.469614 -342.813009) (xy 286.417289 -342.79764) (xy 286.367684 -342.774982) (xy 286.321807 -342.745495)
			(xy 286.280594 -342.709779) (xy 286.244883 -342.668562) (xy 286.2154 -342.622683) (xy 286.192747 -342.573075)
			(xy 286.177383 -342.520748) (xy 286.169622 -342.466768) (xy 284.686774 -342.466768) (xy 284.686774 -342.466769)
			(xy 284.679012 -342.520752) (xy 284.663647 -342.573081) (xy 284.640991 -342.622691) (xy 284.611505 -342.668572)
			(xy 284.575791 -342.709789) (xy 284.534573 -342.745504) (xy 284.488693 -342.77499) (xy 284.439083 -342.797646)
			(xy 284.386754 -342.813012) (xy 284.332771 -342.820773) (xy 284.305502 -342.82126) (xy 283.441902 -342.82126)
			(xy 283.414631 -342.820801) (xy 283.360643 -342.813039) (xy 283.30831 -342.797673) (xy 283.258697 -342.775015)
			(xy 283.212812 -342.745527) (xy 283.171592 -342.70981) (xy 283.135874 -342.668589) (xy 283.106386 -342.622705)
			(xy 283.083728 -342.573092) (xy 283.068362 -342.520759) (xy 283.060599 -342.466771) (xy 281.577773 -342.466771)
			(xy 281.570013 -342.520747) (xy 281.55465 -342.573073) (xy 281.531997 -342.62268) (xy 281.502515 -342.668559)
			(xy 281.466805 -342.709775) (xy 281.425592 -342.74549) (xy 281.379717 -342.774977) (xy 281.330112 -342.797635)
			(xy 281.277788 -342.813004) (xy 281.223809 -342.820771) (xy 281.196542 -342.82126) (xy 280.332942 -342.82126)
			(xy 280.305669 -342.820803) (xy 280.251677 -342.813046) (xy 280.199339 -342.797683) (xy 280.149721 -342.775028)
			(xy 280.103831 -342.745541) (xy 280.062606 -342.709824) (xy 280.026884 -342.668602) (xy 279.997392 -342.622716)
			(xy 279.974731 -342.5731) (xy 279.959363 -342.520764) (xy 279.9516 -342.466773) (xy 278.468896 -342.466773)
			(xy 278.461134 -342.52076) (xy 278.445767 -342.573094) (xy 278.423108 -342.622708) (xy 278.393619 -342.668592)
			(xy 278.3579 -342.709812) (xy 278.316678 -342.74553) (xy 278.270792 -342.775017) (xy 278.221177 -342.797673)
			(xy 278.168842 -342.813038) (xy 278.114854 -342.820798) (xy 278.087582 -342.82126) (xy 277.223982 -342.82126)
			(xy 277.196713 -342.820776) (xy 277.142731 -342.813013) (xy 277.090404 -342.797646) (xy 277.040796 -342.774988)
			(xy 276.994917 -342.745502) (xy 276.953701 -342.709786) (xy 276.917987 -342.668569) (xy 276.888503 -342.622689)
			(xy 276.865848 -342.573079) (xy 276.850484 -342.520751) (xy 276.842722 -342.466769) (xy 275.359874 -342.466769)
			(xy 275.352113 -342.52075) (xy 275.336748 -342.573077) (xy 275.314094 -342.622686) (xy 275.28461 -342.668565)
			(xy 275.248898 -342.709782) (xy 275.207683 -342.745497) (xy 275.161805 -342.774983) (xy 275.112198 -342.797641)
			(xy 275.059871 -342.813008) (xy 275.00589 -342.820772) (xy 274.978622 -342.82126) (xy 274.115022 -342.82126)
			(xy 274.08775 -342.820802) (xy 274.03376 -342.813042) (xy 273.981425 -342.797678) (xy 273.931809 -342.775021)
			(xy 273.885922 -342.745534) (xy 273.844699 -342.709817) (xy 273.808979 -342.668596) (xy 273.779489 -342.622711)
			(xy 273.75683 -342.573096) (xy 273.741462 -342.520761) (xy 273.7337 -342.466772) (xy 272.250996 -342.466772)
			(xy 272.250996 -342.466773) (xy 272.243233 -342.520763) (xy 272.227865 -342.573098) (xy 272.205205 -342.622713)
			(xy 272.175714 -342.668599) (xy 272.139993 -342.70982) (xy 272.098768 -342.745537) (xy 272.05288 -342.775023)
			(xy 272.003262 -342.797679) (xy 271.950925 -342.813041) (xy 271.896935 -342.820799) (xy 271.869662 -342.82126)
			(xy 271.006062 -342.82126) (xy 270.978794 -342.820775) (xy 270.924814 -342.813009) (xy 270.872489 -342.79764)
			(xy 270.822884 -342.774982) (xy 270.777007 -342.745495) (xy 270.735794 -342.709779) (xy 270.700083 -342.668562)
			(xy 270.6706 -342.622683) (xy 270.647947 -342.573075) (xy 270.632583 -342.520748) (xy 270.624822 -342.466768)
			(xy 269.141974 -342.466768) (xy 269.141974 -342.466769) (xy 269.134212 -342.520752) (xy 269.118847 -342.573081)
			(xy 269.096191 -342.622691) (xy 269.066705 -342.668572) (xy 269.030991 -342.709789) (xy 268.989773 -342.745504)
			(xy 268.943893 -342.77499) (xy 268.894283 -342.797646) (xy 268.841954 -342.813012) (xy 268.787971 -342.820773)
			(xy 268.760702 -342.82126) (xy 267.897102 -342.82126) (xy 267.869831 -342.820801) (xy 267.815843 -342.813039)
			(xy 267.76351 -342.797673) (xy 267.713897 -342.775015) (xy 267.668012 -342.745527) (xy 267.626792 -342.70981)
			(xy 267.591074 -342.668589) (xy 267.561586 -342.622705) (xy 267.538928 -342.573092) (xy 267.523562 -342.520759)
			(xy 267.515799 -342.466771) (xy 256.581015 -342.466771) (xy 256.573351 -342.471196) (xy 256.517947 -342.494145)
			(xy 256.460022 -342.509666) (xy 256.400566 -342.517494) (xy 256.340598 -342.517494) (xy 256.281142 -342.509666)
			(xy 256.223217 -342.494145) (xy 256.167813 -342.471196) (xy 256.115879 -342.441212) (xy 256.068303 -342.404706)
			(xy 256.025898 -342.362301) (xy 255.989392 -342.314725) (xy 255.959408 -342.262791) (xy 255.936459 -342.207387)
			(xy 255.920938 -342.149462) (xy 255.91311 -342.090006) (xy 255.91262 -342.060022) (xy 197.28821 -342.060022)
			(xy 197.329534 -342.06596) (xy 197.38187 -342.081324) (xy 197.431486 -342.10398) (xy 197.477373 -342.133467)
			(xy 197.518596 -342.169184) (xy 197.554316 -342.210405) (xy 197.583807 -342.256289) (xy 197.606466 -342.305904)
			(xy 197.621834 -342.358239) (xy 197.629596 -342.412228) (xy 197.629596 -342.466772) (xy 197.621834 -342.520761)
			(xy 197.606466 -342.573096) (xy 197.583807 -342.622711) (xy 197.554316 -342.668595) (xy 197.518596 -342.709816)
			(xy 197.477373 -342.745533) (xy 197.431486 -342.77502) (xy 197.38187 -342.797676) (xy 197.329534 -342.81304)
			(xy 197.275544 -342.820798) (xy 197.248272 -342.82126) (xy 196.384672 -342.82126) (xy 196.357404 -342.820776)
			(xy 196.303423 -342.813011) (xy 196.251096 -342.797643) (xy 196.20149 -342.774985) (xy 196.155612 -342.745498)
			(xy 196.114397 -342.709783) (xy 196.078685 -342.668566) (xy 196.049202 -342.622686) (xy 196.026547 -342.573077)
			(xy 196.011183 -342.52075) (xy 196.003422 -342.466768) (xy 194.520574 -342.466768) (xy 194.520574 -342.466769)
			(xy 194.512812 -342.520751) (xy 194.497448 -342.573079) (xy 194.474792 -342.622688) (xy 194.445308 -342.668568)
			(xy 194.409594 -342.709786) (xy 194.368378 -342.745501) (xy 194.322499 -342.774987) (xy 194.272891 -342.797643)
			(xy 194.220563 -342.81301) (xy 194.166581 -342.820773) (xy 194.139312 -342.82126) (xy 193.275712 -342.82126)
			(xy 193.24844 -342.820801) (xy 193.194452 -342.813041) (xy 193.142117 -342.797675) (xy 193.092503 -342.775018)
			(xy 193.046617 -342.745531) (xy 193.005395 -342.709813) (xy 192.969676 -342.668593) (xy 192.940188 -342.622708)
			(xy 192.917529 -342.573094) (xy 192.902162 -342.52076) (xy 192.8944 -342.466772) (xy 191.411696 -342.466772)
			(xy 191.411696 -342.466773) (xy 191.403933 -342.520764) (xy 191.388564 -342.5731) (xy 191.365903 -342.622716)
			(xy 191.336412 -342.668602) (xy 191.300689 -342.709823) (xy 191.259463 -342.74554) (xy 191.213574 -342.775026)
			(xy 191.163955 -342.797681) (xy 191.111617 -342.813043) (xy 191.057625 -342.8208) (xy 191.030352 -342.82126)
			(xy 190.166752 -342.82126) (xy 190.139485 -342.820774) (xy 190.085506 -342.813007) (xy 190.033182 -342.797637)
			(xy 189.983578 -342.774978) (xy 189.937702 -342.745491) (xy 189.89649 -342.709776) (xy 189.86078 -342.668559)
			(xy 189.831299 -342.62268) (xy 189.808646 -342.573073) (xy 189.793283 -342.520747) (xy 189.785522 -342.466767)
			(xy 188.302696 -342.466767) (xy 188.302696 -342.466771) (xy 188.294934 -342.520759) (xy 188.279568 -342.573092)
			(xy 188.25691 -342.622705) (xy 188.227421 -342.668589) (xy 188.191703 -342.709809) (xy 188.150482 -342.745526)
			(xy 188.104598 -342.775013) (xy 188.054984 -342.79767) (xy 188.002651 -342.813036) (xy 187.948663 -342.820797)
			(xy 187.921392 -342.82126) (xy 187.057792 -342.82126) (xy 187.030523 -342.820777) (xy 186.97654 -342.813014)
			(xy 186.924211 -342.797648) (xy 186.874602 -342.774991) (xy 186.828721 -342.745505) (xy 186.787505 -342.70979)
			(xy 186.75179 -342.668572) (xy 186.722305 -342.622691) (xy 186.699649 -342.573082) (xy 186.684284 -342.520752)
			(xy 186.676522 -342.466769) (xy 185.193674 -342.466769) (xy 185.185913 -342.520748) (xy 185.170549 -342.573075)
			(xy 185.147895 -342.622683) (xy 185.118413 -342.668562) (xy 185.082701 -342.709778) (xy 185.041488 -342.745494)
			(xy 184.995611 -342.77498) (xy 184.946005 -342.797638) (xy 184.89368 -342.813006) (xy 184.8397 -342.820771)
			(xy 184.812432 -342.82126) (xy 183.948832 -342.82126) (xy 183.921559 -342.820803) (xy 183.867569 -342.813044)
			(xy 183.815232 -342.797681) (xy 183.765615 -342.775025) (xy 183.719727 -342.745538) (xy 183.678502 -342.70982)
			(xy 183.642781 -342.668599) (xy 183.613291 -342.622714) (xy 183.590631 -342.573098) (xy 183.575263 -342.520763)
			(xy 183.5675 -342.466773) (xy 182.084796 -342.466773) (xy 182.077034 -342.520761) (xy 182.061666 -342.573096)
			(xy 182.039007 -342.622711) (xy 182.009516 -342.668595) (xy 181.973796 -342.709816) (xy 181.932573 -342.745533)
			(xy 181.886686 -342.77502) (xy 181.83707 -342.797676) (xy 181.784734 -342.81304) (xy 181.730744 -342.820798)
			(xy 181.703472 -342.82126) (xy 180.839872 -342.82126) (xy 180.812604 -342.820776) (xy 180.758623 -342.813011)
			(xy 180.706296 -342.797643) (xy 180.65669 -342.774985) (xy 180.610812 -342.745498) (xy 180.569597 -342.709783)
			(xy 180.533885 -342.668566) (xy 180.504402 -342.622686) (xy 180.481747 -342.573077) (xy 180.466383 -342.52075)
			(xy 180.458622 -342.466768) (xy 178.975774 -342.466768) (xy 178.975774 -342.466769) (xy 178.968012 -342.520751)
			(xy 178.952648 -342.573079) (xy 178.929992 -342.622688) (xy 178.900508 -342.668568) (xy 178.864794 -342.709786)
			(xy 178.823578 -342.745501) (xy 178.777699 -342.774987) (xy 178.728091 -342.797643) (xy 178.675763 -342.81301)
			(xy 178.621781 -342.820773) (xy 178.594512 -342.82126) (xy 177.730912 -342.82126) (xy 177.70364 -342.820801)
			(xy 177.649652 -342.813041) (xy 177.597317 -342.797675) (xy 177.547703 -342.775018) (xy 177.501817 -342.745531)
			(xy 177.460595 -342.709813) (xy 177.424876 -342.668593) (xy 177.395388 -342.622708) (xy 177.372729 -342.573094)
			(xy 177.357362 -342.52076) (xy 177.3496 -342.466772) (xy 175.866896 -342.466772) (xy 175.866896 -342.466773)
			(xy 175.859133 -342.520764) (xy 175.843764 -342.5731) (xy 175.821103 -342.622716) (xy 175.791612 -342.668602)
			(xy 175.755889 -342.709823) (xy 175.714663 -342.74554) (xy 175.668774 -342.775026) (xy 175.619155 -342.797681)
			(xy 175.566817 -342.813043) (xy 175.512825 -342.8208) (xy 175.485552 -342.82126) (xy 174.621952 -342.82126)
			(xy 174.594685 -342.820774) (xy 174.540706 -342.813007) (xy 174.488382 -342.797637) (xy 174.438778 -342.774978)
			(xy 174.392902 -342.745491) (xy 174.35169 -342.709776) (xy 174.31598 -342.668559) (xy 174.286499 -342.62268)
			(xy 174.263846 -342.573073) (xy 174.248483 -342.520747) (xy 174.240722 -342.466767) (xy 172.757896 -342.466767)
			(xy 172.757896 -342.466771) (xy 172.750134 -342.520759) (xy 172.734768 -342.573092) (xy 172.71211 -342.622705)
			(xy 172.682621 -342.668589) (xy 172.646903 -342.709809) (xy 172.605682 -342.745526) (xy 172.559798 -342.775013)
			(xy 172.510184 -342.79767) (xy 172.457851 -342.813036) (xy 172.403863 -342.820797) (xy 172.376592 -342.82126)
			(xy 171.512992 -342.82126) (xy 171.485723 -342.820777) (xy 171.43174 -342.813014) (xy 171.379411 -342.797648)
			(xy 171.329802 -342.774991) (xy 171.283921 -342.745505) (xy 171.242705 -342.70979) (xy 171.20699 -342.668572)
			(xy 171.177505 -342.622691) (xy 171.154849 -342.573082) (xy 171.139484 -342.520752) (xy 171.131722 -342.466769)
			(xy 169.648874 -342.466769) (xy 169.641113 -342.520748) (xy 169.625749 -342.573075) (xy 169.603095 -342.622683)
			(xy 169.573613 -342.668562) (xy 169.537901 -342.709778) (xy 169.496688 -342.745494) (xy 169.450811 -342.77498)
			(xy 169.401205 -342.797638) (xy 169.34888 -342.813006) (xy 169.2949 -342.820771) (xy 169.267632 -342.82126)
			(xy 168.404032 -342.82126) (xy 168.376759 -342.820803) (xy 168.322769 -342.813044) (xy 168.270432 -342.797681)
			(xy 168.220815 -342.775025) (xy 168.174927 -342.745538) (xy 168.133702 -342.70982) (xy 168.097981 -342.668599)
			(xy 168.068491 -342.622714) (xy 168.045831 -342.573098) (xy 168.030463 -342.520763) (xy 168.0227 -342.466773)
			(xy 166.539996 -342.466773) (xy 166.532234 -342.520761) (xy 166.516866 -342.573096) (xy 166.494207 -342.622711)
			(xy 166.464716 -342.668595) (xy 166.428996 -342.709816) (xy 166.387773 -342.745533) (xy 166.341886 -342.77502)
			(xy 166.29227 -342.797676) (xy 166.239934 -342.81304) (xy 166.185944 -342.820798) (xy 166.158672 -342.82126)
			(xy 165.295072 -342.82126) (xy 165.267804 -342.820776) (xy 165.213823 -342.813011) (xy 165.161496 -342.797643)
			(xy 165.11189 -342.774985) (xy 165.066012 -342.745498) (xy 165.024797 -342.709783) (xy 164.989085 -342.668566)
			(xy 164.959602 -342.622686) (xy 164.936947 -342.573077) (xy 164.921583 -342.52075) (xy 164.913822 -342.466768)
			(xy 144.196574 -342.466768) (xy 144.196574 -342.466769) (xy 144.188812 -342.520751) (xy 144.173447 -342.57308)
			(xy 144.150792 -342.622689) (xy 144.121307 -342.66857) (xy 144.085593 -342.709787) (xy 144.044376 -342.745502)
			(xy 143.998497 -342.774988) (xy 143.948888 -342.797645) (xy 143.896559 -342.81301) (xy 143.842577 -342.820773)
			(xy 143.815308 -342.82126) (xy 142.951708 -342.82126) (xy 142.924436 -342.820801) (xy 142.870448 -342.81304)
			(xy 142.818115 -342.797674) (xy 142.7685 -342.775017) (xy 142.722615 -342.745529) (xy 142.681394 -342.709812)
			(xy 142.645675 -342.668591) (xy 142.616187 -342.622707) (xy 142.593529 -342.573093) (xy 142.578162 -342.520759)
			(xy 142.5704 -342.466772) (xy 141.087573 -342.466772) (xy 141.079813 -342.520746) (xy 141.064451 -342.573072)
			(xy 141.041798 -342.622678) (xy 141.012317 -342.668557) (xy 140.976607 -342.709773) (xy 140.935395 -342.745488)
			(xy 140.88952 -342.774975) (xy 140.839917 -342.797634) (xy 140.787593 -342.813003) (xy 140.733615 -342.82077)
			(xy 140.706348 -342.82126) (xy 139.842748 -342.82126) (xy 139.815475 -342.820804) (xy 139.761482 -342.813047)
			(xy 139.709144 -342.797685) (xy 139.659524 -342.77503) (xy 139.613634 -342.745544) (xy 139.572408 -342.709826)
			(xy 139.536685 -342.668604) (xy 139.507193 -342.622718) (xy 139.484532 -342.573101) (xy 139.469163 -342.520765)
			(xy 139.4614 -342.466773) (xy 137.978696 -342.466773) (xy 137.970934 -342.520759) (xy 137.955567 -342.573092)
			(xy 137.932909 -342.622706) (xy 137.90342 -342.66859) (xy 137.867702 -342.70981) (xy 137.82648 -342.745528)
			(xy 137.780596 -342.775015) (xy 137.730981 -342.797671) (xy 137.678647 -342.813037) (xy 137.624659 -342.820797)
			(xy 137.597388 -342.82126) (xy 136.733788 -342.82126) (xy 136.706519 -342.820777) (xy 136.652536 -342.813014)
			(xy 136.600208 -342.797647) (xy 136.550599 -342.77499) (xy 136.50472 -342.745504) (xy 136.463503 -342.709788)
			(xy 136.427789 -342.668571) (xy 136.398304 -342.62269) (xy 136.375649 -342.573081) (xy 136.360284 -342.520752)
			(xy 136.352522 -342.466769) (xy 134.869674 -342.466769) (xy 134.861913 -342.520749) (xy 134.846549 -342.573076)
			(xy 134.823895 -342.622684) (xy 134.794412 -342.668563) (xy 134.7587 -342.70978) (xy 134.717486 -342.745495)
			(xy 134.671609 -342.774981) (xy 134.622002 -342.797639) (xy 134.569676 -342.813007) (xy 134.515696 -342.820772)
			(xy 134.488428 -342.82126) (xy 133.624828 -342.82126) (xy 133.597556 -342.820802) (xy 133.543565 -342.813043)
			(xy 133.491229 -342.79768) (xy 133.441612 -342.775023) (xy 133.395725 -342.745536) (xy 133.354501 -342.709819)
			(xy 133.31878 -342.668598) (xy 133.28929 -342.622712) (xy 133.26663 -342.573097) (xy 133.251262 -342.520762)
			(xy 133.2435 -342.466772) (xy 131.760796 -342.466772) (xy 131.753033 -342.520762) (xy 131.737666 -342.573097)
			(xy 131.715006 -342.622712) (xy 131.685515 -342.668597) (xy 131.649795 -342.709817) (xy 131.608571 -342.745535)
			(xy 131.562684 -342.775021) (xy 131.513067 -342.797677) (xy 131.46073 -342.81304) (xy 131.40674 -342.820799)
			(xy 131.379468 -342.82126) (xy 130.515868 -342.82126) (xy 130.4886 -342.820775) (xy 130.43462 -342.81301)
			(xy 130.382294 -342.797642) (xy 130.332687 -342.774984) (xy 130.28681 -342.745497) (xy 130.245596 -342.709781)
			(xy 130.209884 -342.668564) (xy 130.180401 -342.622685) (xy 130.157747 -342.573076) (xy 130.142383 -342.520749)
			(xy 130.134622 -342.466768) (xy 128.651774 -342.466768) (xy 128.651774 -342.466769) (xy 128.644012 -342.520751)
			(xy 128.628647 -342.57308) (xy 128.605992 -342.622689) (xy 128.576507 -342.66857) (xy 128.540793 -342.709787)
			(xy 128.499576 -342.745502) (xy 128.453697 -342.774988) (xy 128.404088 -342.797645) (xy 128.351759 -342.81301)
			(xy 128.297777 -342.820773) (xy 128.270508 -342.82126) (xy 127.406908 -342.82126) (xy 127.379636 -342.820801)
			(xy 127.325648 -342.81304) (xy 127.273315 -342.797674) (xy 127.2237 -342.775017) (xy 127.177815 -342.745529)
			(xy 127.136594 -342.709812) (xy 127.100875 -342.668591) (xy 127.071387 -342.622707) (xy 127.048729 -342.573093)
			(xy 127.033362 -342.520759) (xy 127.0256 -342.466772) (xy 125.542773 -342.466772) (xy 125.535013 -342.520746)
			(xy 125.519651 -342.573072) (xy 125.496998 -342.622678) (xy 125.467517 -342.668557) (xy 125.431807 -342.709773)
			(xy 125.390595 -342.745488) (xy 125.34472 -342.774975) (xy 125.295117 -342.797634) (xy 125.242793 -342.813003)
			(xy 125.188815 -342.82077) (xy 125.161548 -342.82126) (xy 124.297948 -342.82126) (xy 124.270675 -342.820804)
			(xy 124.216682 -342.813047) (xy 124.164344 -342.797685) (xy 124.114724 -342.77503) (xy 124.068834 -342.745544)
			(xy 124.027608 -342.709826) (xy 123.991885 -342.668604) (xy 123.962393 -342.622718) (xy 123.939732 -342.573101)
			(xy 123.924363 -342.520765) (xy 123.9166 -342.466773) (xy 122.433896 -342.466773) (xy 122.426134 -342.520759)
			(xy 122.410767 -342.573092) (xy 122.388109 -342.622706) (xy 122.35862 -342.66859) (xy 122.322902 -342.70981)
			(xy 122.28168 -342.745528) (xy 122.235796 -342.775015) (xy 122.186181 -342.797671) (xy 122.133847 -342.813037)
			(xy 122.079859 -342.820797) (xy 122.052588 -342.82126) (xy 121.188988 -342.82126) (xy 121.161719 -342.820777)
			(xy 121.107736 -342.813014) (xy 121.055408 -342.797647) (xy 121.005799 -342.77499) (xy 120.95992 -342.745504)
			(xy 120.918703 -342.709788) (xy 120.882989 -342.668571) (xy 120.853504 -342.62269) (xy 120.830849 -342.573081)
			(xy 120.815484 -342.520752) (xy 120.807722 -342.466769) (xy 119.324874 -342.466769) (xy 119.317113 -342.520749)
			(xy 119.301749 -342.573076) (xy 119.279095 -342.622684) (xy 119.249612 -342.668563) (xy 119.2139 -342.70978)
			(xy 119.172686 -342.745495) (xy 119.126809 -342.774981) (xy 119.077202 -342.797639) (xy 119.024876 -342.813007)
			(xy 118.970896 -342.820772) (xy 118.943628 -342.82126) (xy 118.080028 -342.82126) (xy 118.052756 -342.820802)
			(xy 117.998765 -342.813043) (xy 117.946429 -342.79768) (xy 117.896812 -342.775023) (xy 117.850925 -342.745536)
			(xy 117.809701 -342.709819) (xy 117.77398 -342.668598) (xy 117.74449 -342.622712) (xy 117.72183 -342.573097)
			(xy 117.706462 -342.520762) (xy 117.6987 -342.466772) (xy 116.215996 -342.466772) (xy 116.208233 -342.520762)
			(xy 116.192866 -342.573097) (xy 116.170206 -342.622712) (xy 116.140715 -342.668597) (xy 116.104995 -342.709817)
			(xy 116.063771 -342.745535) (xy 116.017884 -342.775021) (xy 115.968267 -342.797677) (xy 115.91593 -342.81304)
			(xy 115.86194 -342.820799) (xy 115.834668 -342.82126) (xy 114.971068 -342.82126) (xy 114.9438 -342.820775)
			(xy 114.88982 -342.81301) (xy 114.837494 -342.797642) (xy 114.787887 -342.774984) (xy 114.74201 -342.745497)
			(xy 114.700796 -342.709781) (xy 114.665084 -342.668564) (xy 114.635601 -342.622685) (xy 114.612947 -342.573076)
			(xy 114.597583 -342.520749) (xy 114.589822 -342.466768) (xy 113.106974 -342.466768) (xy 113.106974 -342.466769)
			(xy 113.099212 -342.520751) (xy 113.083847 -342.57308) (xy 113.061192 -342.622689) (xy 113.031707 -342.66857)
			(xy 112.995993 -342.709787) (xy 112.954776 -342.745502) (xy 112.908897 -342.774988) (xy 112.859288 -342.797645)
			(xy 112.806959 -342.81301) (xy 112.752977 -342.820773) (xy 112.725708 -342.82126) (xy 111.862108 -342.82126)
			(xy 111.834836 -342.820801) (xy 111.780848 -342.81304) (xy 111.728515 -342.797674) (xy 111.6789 -342.775017)
			(xy 111.633015 -342.745529) (xy 111.591794 -342.709812) (xy 111.556075 -342.668591) (xy 111.526587 -342.622707)
			(xy 111.503929 -342.573093) (xy 111.488562 -342.520759) (xy 111.4808 -342.466772) (xy 104.085479 -342.466772)
			(xy 104.10629 -342.517011) (xy 104.121803 -342.574906) (xy 104.129627 -342.634331) (xy 104.129627 -342.694269)
			(xy 104.121803 -342.753694) (xy 104.10629 -342.811589) (xy 104.083352 -342.866964) (xy 104.053383 -342.918871)
			(xy 104.016895 -342.966422) (xy 103.974512 -343.008804) (xy 103.926959 -343.045291) (xy 103.875051 -343.075259)
			(xy 103.819676 -343.098195) (xy 103.76178 -343.113706) (xy 103.702355 -343.121528) (xy 103.672386 -343.121996)
			(xy 102.808786 -343.121996) (xy 102.778818 -343.121529) (xy 102.719395 -343.113704) (xy 102.661502 -343.09819)
			(xy 102.60613 -343.075253) (xy 102.554224 -343.045284) (xy 102.506675 -343.008796) (xy 102.464294 -342.966415)
			(xy 102.427809 -342.918864) (xy 102.397841 -342.866958) (xy 102.374905 -342.811584) (xy 102.359393 -342.753691)
			(xy 102.35157 -342.694268) (xy 93.60914 -342.694268) (xy 93.595705 -342.709775) (xy 93.554492 -342.74549)
			(xy 93.508617 -342.774977) (xy 93.459012 -342.797635) (xy 93.406688 -342.813004) (xy 93.352709 -342.820771)
			(xy 93.325442 -342.82126) (xy 92.461842 -342.82126) (xy 92.434569 -342.820803) (xy 92.380577 -342.813046)
			(xy 92.328239 -342.797683) (xy 92.278621 -342.775028) (xy 92.232731 -342.745541) (xy 92.191506 -342.709824)
			(xy 92.155784 -342.668602) (xy 92.126292 -342.622716) (xy 92.103631 -342.5731) (xy 92.088263 -342.520764)
			(xy 92.0805 -342.466773) (xy 90.597796 -342.466773) (xy 90.590034 -342.52076) (xy 90.574667 -342.573094)
			(xy 90.552008 -342.622708) (xy 90.522519 -342.668592) (xy 90.4868 -342.709812) (xy 90.445578 -342.74553)
			(xy 90.399692 -342.775017) (xy 90.350077 -342.797673) (xy 90.297742 -342.813038) (xy 90.243754 -342.820798)
			(xy 90.216482 -342.82126) (xy 89.352882 -342.82126) (xy 89.325613 -342.820776) (xy 89.271631 -342.813013)
			(xy 89.219304 -342.797646) (xy 89.169696 -342.774988) (xy 89.123817 -342.745502) (xy 89.082601 -342.709786)
			(xy 89.046887 -342.668569) (xy 89.017403 -342.622689) (xy 88.994748 -342.573079) (xy 88.979384 -342.520751)
			(xy 88.971622 -342.466769) (xy 87.488774 -342.466769) (xy 87.481013 -342.52075) (xy 87.465648 -342.573077)
			(xy 87.442994 -342.622686) (xy 87.41351 -342.668565) (xy 87.377798 -342.709782) (xy 87.336583 -342.745497)
			(xy 87.290705 -342.774983) (xy 87.241098 -342.797641) (xy 87.188771 -342.813008) (xy 87.13479 -342.820772)
			(xy 87.107522 -342.82126) (xy 86.243922 -342.82126) (xy 86.21665 -342.820802) (xy 86.16266 -342.813042)
			(xy 86.110325 -342.797678) (xy 86.060709 -342.775021) (xy 86.014822 -342.745534) (xy 85.973599 -342.709817)
			(xy 85.937879 -342.668596) (xy 85.908389 -342.622711) (xy 85.88573 -342.573096) (xy 85.870362 -342.520761)
			(xy 85.8626 -342.466772) (xy 84.379896 -342.466772) (xy 84.379896 -342.466773) (xy 84.372133 -342.520763)
			(xy 84.356765 -342.573098) (xy 84.334105 -342.622713) (xy 84.304614 -342.668599) (xy 84.268893 -342.70982)
			(xy 84.227668 -342.745537) (xy 84.18178 -342.775023) (xy 84.132162 -342.797679) (xy 84.079825 -342.813041)
			(xy 84.025835 -342.820799) (xy 83.998562 -342.82126) (xy 83.134962 -342.82126) (xy 83.107694 -342.820775)
			(xy 83.053714 -342.813009) (xy 83.001389 -342.79764) (xy 82.951784 -342.774982) (xy 82.905907 -342.745495)
			(xy 82.864694 -342.709779) (xy 82.828983 -342.668562) (xy 82.7995 -342.622683) (xy 82.776847 -342.573075)
			(xy 82.761483 -342.520748) (xy 82.753722 -342.466768) (xy 81.270874 -342.466768) (xy 81.270874 -342.466769)
			(xy 81.263112 -342.520752) (xy 81.247747 -342.573081) (xy 81.225091 -342.622691) (xy 81.195605 -342.668572)
			(xy 81.159891 -342.709789) (xy 81.118673 -342.745504) (xy 81.072793 -342.77499) (xy 81.023183 -342.797646)
			(xy 80.970854 -342.813012) (xy 80.916871 -342.820773) (xy 80.889602 -342.82126) (xy 80.026002 -342.82126)
			(xy 79.998731 -342.820801) (xy 79.944743 -342.813039) (xy 79.89241 -342.797673) (xy 79.842797 -342.775015)
			(xy 79.796912 -342.745527) (xy 79.755692 -342.70981) (xy 79.719974 -342.668589) (xy 79.690486 -342.622705)
			(xy 79.667828 -342.573092) (xy 79.652462 -342.520759) (xy 79.644699 -342.466771) (xy 78.161873 -342.466771)
			(xy 78.154113 -342.520747) (xy 78.13875 -342.573073) (xy 78.116097 -342.62268) (xy 78.086615 -342.668559)
			(xy 78.050905 -342.709775) (xy 78.009692 -342.74549) (xy 77.963817 -342.774977) (xy 77.914212 -342.797635)
			(xy 77.861888 -342.813004) (xy 77.807909 -342.820771) (xy 77.780642 -342.82126) (xy 76.917042 -342.82126)
			(xy 76.889769 -342.820803) (xy 76.835777 -342.813046) (xy 76.783439 -342.797683) (xy 76.733821 -342.775028)
			(xy 76.687931 -342.745541) (xy 76.646706 -342.709824) (xy 76.610984 -342.668602) (xy 76.581492 -342.622716)
			(xy 76.558831 -342.5731) (xy 76.543463 -342.520764) (xy 76.5357 -342.466773) (xy 75.052996 -342.466773)
			(xy 75.045234 -342.52076) (xy 75.029867 -342.573094) (xy 75.007208 -342.622708) (xy 74.977719 -342.668592)
			(xy 74.942 -342.709812) (xy 74.900778 -342.74553) (xy 74.854892 -342.775017) (xy 74.805277 -342.797673)
			(xy 74.752942 -342.813038) (xy 74.698954 -342.820798) (xy 74.671682 -342.82126) (xy 73.808082 -342.82126)
			(xy 73.780813 -342.820776) (xy 73.726831 -342.813013) (xy 73.674504 -342.797646) (xy 73.624896 -342.774988)
			(xy 73.579017 -342.745502) (xy 73.537801 -342.709786) (xy 73.502087 -342.668569) (xy 73.472603 -342.622689)
			(xy 73.449948 -342.573079) (xy 73.434584 -342.520751) (xy 73.426822 -342.466769) (xy 71.943974 -342.466769)
			(xy 71.936213 -342.52075) (xy 71.920848 -342.573077) (xy 71.898194 -342.622686) (xy 71.86871 -342.668565)
			(xy 71.832998 -342.709782) (xy 71.791783 -342.745497) (xy 71.745905 -342.774983) (xy 71.696298 -342.797641)
			(xy 71.643971 -342.813008) (xy 71.58999 -342.820772) (xy 71.562722 -342.82126) (xy 70.699122 -342.82126)
			(xy 70.67185 -342.820802) (xy 70.61786 -342.813042) (xy 70.565525 -342.797678) (xy 70.515909 -342.775021)
			(xy 70.470022 -342.745534) (xy 70.428799 -342.709817) (xy 70.393079 -342.668596) (xy 70.363589 -342.622711)
			(xy 70.34093 -342.573096) (xy 70.325562 -342.520761) (xy 70.3178 -342.466772) (xy 68.835096 -342.466772)
			(xy 68.835096 -342.466773) (xy 68.827333 -342.520763) (xy 68.811965 -342.573098) (xy 68.789305 -342.622713)
			(xy 68.759814 -342.668599) (xy 68.724093 -342.70982) (xy 68.682868 -342.745537) (xy 68.63698 -342.775023)
			(xy 68.587362 -342.797679) (xy 68.535025 -342.813041) (xy 68.481035 -342.820799) (xy 68.453762 -342.82126)
			(xy 67.590162 -342.82126) (xy 67.562894 -342.820775) (xy 67.508914 -342.813009) (xy 67.456589 -342.79764)
			(xy 67.406984 -342.774982) (xy 67.361107 -342.745495) (xy 67.319894 -342.709779) (xy 67.284183 -342.668562)
			(xy 67.2547 -342.622683) (xy 67.232047 -342.573075) (xy 67.216683 -342.520748) (xy 67.208922 -342.466768)
			(xy 65.726074 -342.466768) (xy 65.726074 -342.466769) (xy 65.718312 -342.520752) (xy 65.702947 -342.573081)
			(xy 65.680291 -342.622691) (xy 65.650805 -342.668572) (xy 65.615091 -342.709789) (xy 65.573873 -342.745504)
			(xy 65.527993 -342.77499) (xy 65.478383 -342.797646) (xy 65.426054 -342.813012) (xy 65.372071 -342.820773)
			(xy 65.344802 -342.82126) (xy 64.481202 -342.82126) (xy 64.453931 -342.820801) (xy 64.399943 -342.813039)
			(xy 64.34761 -342.797673) (xy 64.297997 -342.775015) (xy 64.252112 -342.745527) (xy 64.210892 -342.70981)
			(xy 64.175174 -342.668589) (xy 64.145686 -342.622705) (xy 64.123028 -342.573092) (xy 64.107662 -342.520759)
			(xy 64.099899 -342.466771) (xy 62.617073 -342.466771) (xy 62.609313 -342.520747) (xy 62.59395 -342.573073)
			(xy 62.571297 -342.62268) (xy 62.541815 -342.668559) (xy 62.506105 -342.709775) (xy 62.464892 -342.74549)
			(xy 62.419017 -342.774977) (xy 62.369412 -342.797635) (xy 62.317088 -342.813004) (xy 62.263109 -342.820771)
			(xy 62.235842 -342.82126) (xy 61.372242 -342.82126) (xy 61.344969 -342.820803) (xy 61.290977 -342.813046)
			(xy 61.238639 -342.797683) (xy 61.189021 -342.775028) (xy 61.143131 -342.745541) (xy 61.101906 -342.709824)
			(xy 61.066184 -342.668602) (xy 61.036692 -342.622716) (xy 61.014031 -342.5731) (xy 60.998663 -342.520764)
			(xy 60.9909 -342.466773) (xy 51.666873 -342.466773) (xy 51.659113 -342.520746) (xy 51.643751 -342.573072)
			(xy 51.621098 -342.622678) (xy 51.591617 -342.668557) (xy 51.555907 -342.709773) (xy 51.514695 -342.745488)
			(xy 51.46882 -342.774975) (xy 51.419217 -342.797634) (xy 51.366893 -342.813003) (xy 51.312915 -342.82077)
			(xy 51.285648 -342.82126) (xy 50.422048 -342.82126) (xy 50.394775 -342.820804) (xy 50.340782 -342.813047)
			(xy 50.288444 -342.797685) (xy 50.238824 -342.77503) (xy 50.192934 -342.745544) (xy 50.151708 -342.709826)
			(xy 50.115985 -342.668604) (xy 50.086493 -342.622718) (xy 50.063832 -342.573101) (xy 50.048463 -342.520765)
			(xy 50.0407 -342.466773) (xy 48.557996 -342.466773) (xy 48.550234 -342.520759) (xy 48.534867 -342.573092)
			(xy 48.512209 -342.622706) (xy 48.48272 -342.66859) (xy 48.447002 -342.70981) (xy 48.40578 -342.745528)
			(xy 48.359896 -342.775015) (xy 48.310281 -342.797671) (xy 48.257947 -342.813037) (xy 48.203959 -342.820797)
			(xy 48.176688 -342.82126) (xy 47.313088 -342.82126) (xy 47.285819 -342.820777) (xy 47.231836 -342.813014)
			(xy 47.179508 -342.797647) (xy 47.129899 -342.77499) (xy 47.08402 -342.745504) (xy 47.042803 -342.709788)
			(xy 47.007089 -342.668571) (xy 46.977604 -342.62269) (xy 46.954949 -342.573081) (xy 46.939584 -342.520752)
			(xy 46.931822 -342.466769) (xy 45.448974 -342.466769) (xy 45.441213 -342.520749) (xy 45.425849 -342.573076)
			(xy 45.403195 -342.622684) (xy 45.373712 -342.668563) (xy 45.338 -342.70978) (xy 45.296786 -342.745495)
			(xy 45.250909 -342.774981) (xy 45.201302 -342.797639) (xy 45.148976 -342.813007) (xy 45.094996 -342.820772)
			(xy 45.067728 -342.82126) (xy 44.204128 -342.82126) (xy 44.176856 -342.820802) (xy 44.122865 -342.813043)
			(xy 44.070529 -342.79768) (xy 44.020912 -342.775023) (xy 43.975025 -342.745536) (xy 43.933801 -342.709819)
			(xy 43.89808 -342.668598) (xy 43.86859 -342.622712) (xy 43.84593 -342.573097) (xy 43.830562 -342.520762)
			(xy 43.8228 -342.466772) (xy 42.340096 -342.466772) (xy 42.332333 -342.520762) (xy 42.316966 -342.573097)
			(xy 42.294306 -342.622712) (xy 42.264815 -342.668597) (xy 42.229095 -342.709817) (xy 42.187871 -342.745535)
			(xy 42.141984 -342.775021) (xy 42.092367 -342.797677) (xy 42.04003 -342.81304) (xy 41.98604 -342.820799)
			(xy 41.958768 -342.82126) (xy 41.095168 -342.82126) (xy 41.0679 -342.820775) (xy 41.01392 -342.81301)
			(xy 40.961594 -342.797642) (xy 40.911987 -342.774984) (xy 40.86611 -342.745497) (xy 40.824896 -342.709781)
			(xy 40.789184 -342.668564) (xy 40.759701 -342.622685) (xy 40.737047 -342.573076) (xy 40.721683 -342.520749)
			(xy 40.713922 -342.466768) (xy 39.231074 -342.466768) (xy 39.231074 -342.466769) (xy 39.223312 -342.520751)
			(xy 39.207947 -342.57308) (xy 39.185292 -342.622689) (xy 39.155807 -342.66857) (xy 39.120093 -342.709787)
			(xy 39.078876 -342.745502) (xy 39.032997 -342.774988) (xy 38.983388 -342.797645) (xy 38.931059 -342.81301)
			(xy 38.877077 -342.820773) (xy 38.849808 -342.82126) (xy 37.986208 -342.82126) (xy 37.958936 -342.820801)
			(xy 37.904948 -342.81304) (xy 37.852615 -342.797674) (xy 37.803 -342.775017) (xy 37.757115 -342.745529)
			(xy 37.715894 -342.709812) (xy 37.680175 -342.668591) (xy 37.650687 -342.622707) (xy 37.628029 -342.573093)
			(xy 37.612662 -342.520759) (xy 37.6049 -342.466772) (xy 36.122073 -342.466772) (xy 36.114313 -342.520746)
			(xy 36.098951 -342.573072) (xy 36.076298 -342.622678) (xy 36.046817 -342.668557) (xy 36.011107 -342.709773)
			(xy 35.969895 -342.745488) (xy 35.92402 -342.774975) (xy 35.874417 -342.797634) (xy 35.822093 -342.813003)
			(xy 35.768115 -342.82077) (xy 35.740848 -342.82126) (xy 34.877248 -342.82126) (xy 34.849975 -342.820804)
			(xy 34.795982 -342.813047) (xy 34.743644 -342.797685) (xy 34.694024 -342.77503) (xy 34.648134 -342.745544)
			(xy 34.606908 -342.709826) (xy 34.571185 -342.668604) (xy 34.541693 -342.622718) (xy 34.519032 -342.573101)
			(xy 34.503663 -342.520765) (xy 34.4959 -342.466773) (xy 33.013196 -342.466773) (xy 33.005434 -342.520759)
			(xy 32.990067 -342.573092) (xy 32.967409 -342.622706) (xy 32.93792 -342.66859) (xy 32.902202 -342.70981)
			(xy 32.86098 -342.745528) (xy 32.815096 -342.775015) (xy 32.765481 -342.797671) (xy 32.713147 -342.813037)
			(xy 32.659159 -342.820797) (xy 32.631888 -342.82126) (xy 31.768288 -342.82126) (xy 31.741019 -342.820777)
			(xy 31.687036 -342.813014) (xy 31.634708 -342.797647) (xy 31.585099 -342.77499) (xy 31.53922 -342.745504)
			(xy 31.498003 -342.709788) (xy 31.462289 -342.668571) (xy 31.432804 -342.62269) (xy 31.410149 -342.573081)
			(xy 31.394784 -342.520752) (xy 31.387022 -342.466769) (xy 29.904174 -342.466769) (xy 29.896413 -342.520749)
			(xy 29.881049 -342.573076) (xy 29.858395 -342.622684) (xy 29.828912 -342.668563) (xy 29.7932 -342.70978)
			(xy 29.751986 -342.745495) (xy 29.706109 -342.774981) (xy 29.656502 -342.797639) (xy 29.604176 -342.813007)
			(xy 29.550196 -342.820772) (xy 29.522928 -342.82126) (xy 28.659328 -342.82126) (xy 28.632056 -342.820802)
			(xy 28.578065 -342.813043) (xy 28.525729 -342.79768) (xy 28.476112 -342.775023) (xy 28.430225 -342.745536)
			(xy 28.389001 -342.709819) (xy 28.35328 -342.668598) (xy 28.32379 -342.622712) (xy 28.30113 -342.573097)
			(xy 28.285762 -342.520762) (xy 28.278 -342.466772) (xy 26.795296 -342.466772) (xy 26.787533 -342.520762)
			(xy 26.772166 -342.573097) (xy 26.749506 -342.622712) (xy 26.720015 -342.668597) (xy 26.684295 -342.709817)
			(xy 26.643071 -342.745535) (xy 26.597184 -342.775021) (xy 26.547567 -342.797677) (xy 26.49523 -342.81304)
			(xy 26.44124 -342.820799) (xy 26.413968 -342.82126) (xy 25.550368 -342.82126) (xy 25.5231 -342.820775)
			(xy 25.46912 -342.81301) (xy 25.416794 -342.797642) (xy 25.367187 -342.774984) (xy 25.32131 -342.745497)
			(xy 25.280096 -342.709781) (xy 25.244384 -342.668564) (xy 25.214901 -342.622685) (xy 25.192247 -342.573076)
			(xy 25.176883 -342.520749) (xy 25.169122 -342.466768) (xy 23.686274 -342.466768) (xy 23.686274 -342.466769)
			(xy 23.678512 -342.520751) (xy 23.663147 -342.57308) (xy 23.640492 -342.622689) (xy 23.611007 -342.66857)
			(xy 23.575293 -342.709787) (xy 23.534076 -342.745502) (xy 23.488197 -342.774988) (xy 23.438588 -342.797645)
			(xy 23.386259 -342.81301) (xy 23.332277 -342.820773) (xy 23.305008 -342.82126) (xy 22.441408 -342.82126)
			(xy 22.414136 -342.820801) (xy 22.360148 -342.81304) (xy 22.307815 -342.797674) (xy 22.2582 -342.775017)
			(xy 22.212315 -342.745529) (xy 22.171094 -342.709812) (xy 22.135375 -342.668591) (xy 22.105887 -342.622707)
			(xy 22.083229 -342.573093) (xy 22.067862 -342.520759) (xy 22.0601 -342.466772) (xy 20.577347 -342.466772)
			(xy 20.569584 -342.520758) (xy 20.554218 -342.57309) (xy 20.53156 -342.622703) (xy 20.502073 -342.668587)
			(xy 20.466355 -342.709807) (xy 20.425135 -342.745524) (xy 20.379252 -342.775011) (xy 20.329638 -342.797669)
			(xy 20.277306 -342.813035) (xy 20.223319 -342.820797) (xy 20.196048 -342.82126) (xy 19.332448 -342.82126)
			(xy 19.305179 -342.820777) (xy 19.251195 -342.813015) (xy 19.198865 -342.79765) (xy 19.149255 -342.774993)
			(xy 19.103374 -342.745507) (xy 19.062157 -342.709792) (xy 19.026441 -342.668574) (xy 18.996956 -342.622693)
			(xy 18.974299 -342.573083) (xy 18.958934 -342.520753) (xy 18.951172 -342.466769) (xy 0.509016 -342.466769)
			(xy 0.509016 -344.320622) (xy 19.115532 -344.320622) (xy 19.115532 -343.584022) (xy 19.115982 -343.573853)
			(xy 19.123759 -343.55506) (xy 19.138136 -343.540674) (xy 19.156925 -343.532887) (xy 19.167094 -343.53246)
			(xy 19.409918 -343.53246) (xy 19.73961 -343.748614) (xy 19.750648 -343.754115) (xy 19.775277 -343.754774)
			(xy 19.7866 -343.749884) (xy 20.10156 -343.544652) (xy 20.10791 -343.540588) (xy 20.108418 -343.54008)
			(xy 20.12061 -343.53246) (xy 20.363434 -343.53246) (xy 20.373597 -343.532906) (xy 20.392371 -343.540696)
			(xy 20.406736 -343.555076) (xy 20.414505 -343.573859) (xy 20.414996 -343.584022) (xy 20.414996 -344.320622)
			(xy 22.224492 -344.320622) (xy 22.224492 -343.584022) (xy 22.22505 -343.573871) (xy 22.232809 -343.555111)
			(xy 22.247154 -343.540747) (xy 22.265904 -343.532963) (xy 22.276054 -343.53246) (xy 22.518878 -343.53246)
			(xy 22.84857 -343.748614) (xy 22.859619 -343.754088) (xy 22.884238 -343.754764) (xy 22.89556 -343.749884)
			(xy 23.21052 -343.544652) (xy 23.21687 -343.540588) (xy 23.217378 -343.54008) (xy 23.22957 -343.53246)
			(xy 23.472394 -343.53246) (xy 23.482568 -343.532869) (xy 23.501367 -343.540656) (xy 23.515753 -343.555047)
			(xy 23.523534 -343.573848) (xy 23.523956 -343.584022) (xy 23.523956 -344.320622) (xy 25.333452 -344.320622)
			(xy 25.333452 -343.584022) (xy 25.333882 -343.57385) (xy 25.341663 -343.555053) (xy 25.356047 -343.540667)
			(xy 25.374842 -343.532884) (xy 25.385014 -343.53246) (xy 25.627838 -343.53246) (xy 25.95753 -343.748614)
			(xy 25.968563 -343.754128) (xy 25.993197 -343.754779) (xy 26.00452 -343.749884) (xy 26.31948 -343.544652)
			(xy 26.32583 -343.540588) (xy 26.326338 -343.54008) (xy 26.33853 -343.53246) (xy 26.581354 -343.53246)
			(xy 26.591525 -343.532902) (xy 26.610323 -343.540676) (xy 26.624711 -343.555057) (xy 26.632493 -343.573851)
			(xy 26.632916 -343.584022) (xy 26.632916 -344.320622) (xy 28.442412 -344.320622) (xy 28.442412 -343.584022)
			(xy 28.442951 -343.573869) (xy 28.450713 -343.555105) (xy 28.465065 -343.54074) (xy 28.483821 -343.53296)
			(xy 28.493974 -343.53246) (xy 28.736798 -343.53246) (xy 29.06649 -343.748614) (xy 29.077534 -343.754101)
			(xy 29.102158 -343.754769) (xy 29.11348 -343.749884) (xy 29.42844 -343.544652) (xy 29.43479 -343.540588)
			(xy 29.435298 -343.54008) (xy 29.44749 -343.53246) (xy 29.690314 -343.53246) (xy 29.700489 -343.532853)
			(xy 29.719288 -343.540647) (xy 29.733673 -343.555042) (xy 29.741454 -343.573846) (xy 29.741876 -343.584022)
			(xy 29.741876 -344.320622) (xy 31.551372 -344.320622) (xy 31.551372 -343.584022) (xy 31.551783 -343.573848)
			(xy 31.559567 -343.555047) (xy 31.573957 -343.54066) (xy 31.59276 -343.532881) (xy 31.602934 -343.53246)
			(xy 31.845758 -343.53246) (xy 32.17545 -343.748614) (xy 32.186504 -343.754075) (xy 32.211118 -343.75476)
			(xy 32.22244 -343.749884) (xy 32.5374 -343.544652) (xy 32.54375 -343.540588) (xy 32.544258 -343.54008)
			(xy 32.55645 -343.53246) (xy 32.799274 -343.53246) (xy 32.809447 -343.532886) (xy 32.828245 -343.540666)
			(xy 32.842631 -343.555052) (xy 32.850413 -343.573849) (xy 32.850836 -343.584022) (xy 32.850836 -344.320622)
			(xy 34.660332 -344.320622) (xy 34.660332 -343.584022) (xy 34.660782 -343.573853) (xy 34.668559 -343.55506)
			(xy 34.682936 -343.540674) (xy 34.701725 -343.532887) (xy 34.711894 -343.53246) (xy 34.954718 -343.53246)
			(xy 35.28441 -343.748614) (xy 35.295448 -343.754115) (xy 35.320077 -343.754774) (xy 35.3314 -343.749884)
			(xy 35.64636 -343.544652) (xy 35.65271 -343.540588) (xy 35.653218 -343.54008) (xy 35.66541 -343.53246)
			(xy 35.908234 -343.53246) (xy 35.918397 -343.532906) (xy 35.937171 -343.540696) (xy 35.951536 -343.555076)
			(xy 35.959305 -343.573859) (xy 35.959796 -343.584022) (xy 35.959796 -344.320622) (xy 37.769292 -344.320622)
			(xy 37.769292 -343.584022) (xy 37.76985 -343.573871) (xy 37.777609 -343.555111) (xy 37.791954 -343.540747)
			(xy 37.810704 -343.532963) (xy 37.820854 -343.53246) (xy 38.063678 -343.53246) (xy 38.39337 -343.748614)
			(xy 38.404419 -343.754088) (xy 38.429038 -343.754764) (xy 38.44036 -343.749884) (xy 38.75532 -343.544652)
			(xy 38.76167 -343.540588) (xy 38.762178 -343.54008) (xy 38.77437 -343.53246) (xy 39.017194 -343.53246)
			(xy 39.027368 -343.532869) (xy 39.046167 -343.540656) (xy 39.060553 -343.555047) (xy 39.068334 -343.573848)
			(xy 39.068756 -343.584022) (xy 39.068756 -344.320622) (xy 40.878252 -344.320622) (xy 40.878252 -343.584022)
			(xy 40.878682 -343.57385) (xy 40.886463 -343.555053) (xy 40.900847 -343.540667) (xy 40.919642 -343.532884)
			(xy 40.929814 -343.53246) (xy 41.172638 -343.53246) (xy 41.50233 -343.748614) (xy 41.513363 -343.754128)
			(xy 41.537997 -343.754779) (xy 41.54932 -343.749884) (xy 41.86428 -343.544652) (xy 41.87063 -343.540588)
			(xy 41.871138 -343.54008) (xy 41.88333 -343.53246) (xy 42.126154 -343.53246) (xy 42.136325 -343.532902)
			(xy 42.155123 -343.540676) (xy 42.169511 -343.555057) (xy 42.177293 -343.573851) (xy 42.177716 -343.584022)
			(xy 42.177716 -344.320622) (xy 43.987212 -344.320622) (xy 43.987212 -343.584022) (xy 43.987751 -343.573869)
			(xy 43.995513 -343.555105) (xy 44.009865 -343.54074) (xy 44.028621 -343.53296) (xy 44.038774 -343.53246)
			(xy 44.281598 -343.53246) (xy 44.61129 -343.748614) (xy 44.622334 -343.754101) (xy 44.646958 -343.754769)
			(xy 44.65828 -343.749884) (xy 44.97324 -343.544652) (xy 44.97959 -343.540588) (xy 44.980098 -343.54008)
			(xy 44.99229 -343.53246) (xy 45.235114 -343.53246) (xy 45.245289 -343.532853) (xy 45.264088 -343.540647)
			(xy 45.278473 -343.555042) (xy 45.286254 -343.573846) (xy 45.286676 -343.584022) (xy 45.286676 -344.320622)
			(xy 47.096172 -344.320622) (xy 47.096172 -343.584022) (xy 47.096583 -343.573848) (xy 47.104367 -343.555047)
			(xy 47.118757 -343.54066) (xy 47.13756 -343.532881) (xy 47.147734 -343.53246) (xy 47.390558 -343.53246)
			(xy 47.72025 -343.748614) (xy 47.731304 -343.754075) (xy 47.755918 -343.75476) (xy 47.76724 -343.749884)
			(xy 48.0822 -343.544652) (xy 48.08855 -343.540588) (xy 48.089058 -343.54008) (xy 48.10125 -343.53246)
			(xy 48.344074 -343.53246) (xy 48.354247 -343.532886) (xy 48.373045 -343.540666) (xy 48.387431 -343.555052)
			(xy 48.395213 -343.573849) (xy 48.395636 -343.584022) (xy 48.395636 -344.320622) (xy 50.205132 -344.320622)
			(xy 50.205132 -343.584022) (xy 50.205582 -343.573853) (xy 50.213359 -343.55506) (xy 50.227736 -343.540674)
			(xy 50.246525 -343.532887) (xy 50.256694 -343.53246) (xy 50.499518 -343.53246) (xy 50.82921 -343.748614)
			(xy 50.840248 -343.754115) (xy 50.864877 -343.754774) (xy 50.8762 -343.749884) (xy 51.19116 -343.544652)
			(xy 51.19751 -343.540588) (xy 51.198018 -343.54008) (xy 51.21021 -343.53246) (xy 51.453034 -343.53246)
			(xy 51.463197 -343.532906) (xy 51.481971 -343.540696) (xy 51.496336 -343.555076) (xy 51.504105 -343.573859)
			(xy 51.504596 -343.584022) (xy 51.504596 -344.320622) (xy 61.155072 -344.320622) (xy 61.155072 -343.584022)
			(xy 61.155488 -343.573816) (xy 61.16332 -343.554967) (xy 61.17779 -343.540571) (xy 61.19668 -343.532837)
			(xy 61.206888 -343.53246) (xy 61.449712 -343.53246) (xy 61.779404 -343.748614) (xy 61.790444 -343.754111)
			(xy 61.815071 -343.754773) (xy 61.826394 -343.749884) (xy 62.141354 -343.544652) (xy 62.147704 -343.540588)
			(xy 62.148212 -343.54008) (xy 62.160404 -343.53246) (xy 62.403228 -343.53246) (xy 62.413403 -343.532951)
			(xy 62.432213 -343.540722) (xy 62.446638 -343.555077) (xy 62.454499 -343.573849) (xy 62.455044 -343.584022)
			(xy 62.455044 -344.320622) (xy 64.264032 -344.320622) (xy 64.264032 -343.584022) (xy 64.264488 -343.573821)
			(xy 64.272312 -343.554979) (xy 64.286769 -343.540585) (xy 64.305645 -343.532843) (xy 64.315848 -343.53246)
			(xy 64.558672 -343.53246) (xy 64.888364 -343.748614) (xy 64.899414 -343.754084) (xy 64.924032 -343.754763)
			(xy 64.935354 -343.749884) (xy 65.250314 -343.544652) (xy 65.256664 -343.540588) (xy 65.257172 -343.54008)
			(xy 65.269364 -343.53246) (xy 65.512188 -343.53246) (xy 65.522361 -343.532984) (xy 65.541169 -343.540741)
			(xy 65.555596 -343.555087) (xy 65.563458 -343.573852) (xy 65.564004 -343.584022) (xy 65.564004 -344.320622)
			(xy 67.372992 -344.320622) (xy 67.372992 -343.584022) (xy 67.373487 -343.573826) (xy 67.381303 -343.554992)
			(xy 67.395748 -343.540599) (xy 67.414611 -343.53285) (xy 67.424808 -343.53246) (xy 67.667632 -343.53246)
			(xy 67.997324 -343.748614) (xy 68.008359 -343.754124) (xy 68.032991 -343.754778) (xy 68.044314 -343.749884)
			(xy 68.359274 -343.544652) (xy 68.365624 -343.540588) (xy 68.366132 -343.54008) (xy 68.378324 -343.53246)
			(xy 68.621148 -343.53246) (xy 68.631325 -343.532935) (xy 68.650134 -343.540712) (xy 68.664559 -343.555073)
			(xy 68.672419 -343.573848) (xy 68.672964 -343.584022) (xy 68.672964 -344.320622) (xy 70.481952 -344.320622)
			(xy 70.481952 -343.584022) (xy 70.482388 -343.573818) (xy 70.490216 -343.554973) (xy 70.50468 -343.540578)
			(xy 70.523563 -343.53284) (xy 70.533768 -343.53246) (xy 70.776592 -343.53246) (xy 71.106284 -343.748614)
			(xy 71.117329 -343.754097) (xy 71.141952 -343.754768) (xy 71.153274 -343.749884) (xy 71.468234 -343.544652)
			(xy 71.474584 -343.540588) (xy 71.475092 -343.54008) (xy 71.487284 -343.53246) (xy 71.730108 -343.53246)
			(xy 71.740282 -343.532968) (xy 71.759091 -343.540732) (xy 71.773517 -343.555083) (xy 71.781378 -343.573851)
			(xy 71.781924 -343.584022) (xy 71.781924 -344.320622) (xy 73.590912 -344.320622) (xy 73.590912 -343.584022)
			(xy 73.591387 -343.573823) (xy 73.599207 -343.554986) (xy 73.613659 -343.540592) (xy 73.632528 -343.532847)
			(xy 73.642728 -343.53246) (xy 73.885552 -343.53246) (xy 74.215244 -343.748614) (xy 74.226274 -343.754137)
			(xy 74.250911 -343.754782) (xy 74.262234 -343.749884) (xy 74.577194 -343.544652) (xy 74.583544 -343.540588)
			(xy 74.584052 -343.54008) (xy 74.596244 -343.53246) (xy 74.839068 -343.53246) (xy 74.84924 -343.533)
			(xy 74.868048 -343.540751) (xy 74.882475 -343.555092) (xy 74.890338 -343.573854) (xy 74.890884 -343.584022)
			(xy 74.890884 -344.320622) (xy 76.699872 -344.320622) (xy 76.699872 -343.584022) (xy 76.700288 -343.573816)
			(xy 76.70812 -343.554967) (xy 76.72259 -343.540571) (xy 76.74148 -343.532837) (xy 76.751688 -343.53246)
			(xy 76.994512 -343.53246) (xy 77.324204 -343.748614) (xy 77.335244 -343.754111) (xy 77.359871 -343.754773)
			(xy 77.371194 -343.749884) (xy 77.686154 -343.544652) (xy 77.692504 -343.540588) (xy 77.693012 -343.54008)
			(xy 77.705204 -343.53246) (xy 77.948028 -343.53246) (xy 77.958203 -343.532951) (xy 77.977013 -343.540722)
			(xy 77.991438 -343.555077) (xy 77.999299 -343.573849) (xy 77.999844 -343.584022) (xy 77.999844 -344.320622)
			(xy 79.808832 -344.320622) (xy 79.808832 -343.584022) (xy 79.809288 -343.573821) (xy 79.817112 -343.554979)
			(xy 79.831569 -343.540585) (xy 79.850445 -343.532843) (xy 79.860648 -343.53246) (xy 80.103472 -343.53246)
			(xy 80.433164 -343.748614) (xy 80.444214 -343.754084) (xy 80.468832 -343.754763) (xy 80.480154 -343.749884)
			(xy 80.795114 -343.544652) (xy 80.801464 -343.540588) (xy 80.801972 -343.54008) (xy 80.814164 -343.53246)
			(xy 81.056988 -343.53246) (xy 81.067161 -343.532984) (xy 81.085969 -343.540741) (xy 81.100396 -343.555087)
			(xy 81.108258 -343.573852) (xy 81.108804 -343.584022) (xy 81.108804 -344.320622) (xy 82.917792 -344.320622)
			(xy 82.917792 -343.584022) (xy 82.918287 -343.573826) (xy 82.926103 -343.554992) (xy 82.940548 -343.540599)
			(xy 82.959411 -343.53285) (xy 82.969608 -343.53246) (xy 83.212432 -343.53246) (xy 83.542124 -343.748614)
			(xy 83.553159 -343.754124) (xy 83.577791 -343.754778) (xy 83.589114 -343.749884) (xy 83.904074 -343.544652)
			(xy 83.910424 -343.540588) (xy 83.910932 -343.54008) (xy 83.923124 -343.53246) (xy 84.165948 -343.53246)
			(xy 84.176125 -343.532935) (xy 84.194934 -343.540712) (xy 84.209359 -343.555073) (xy 84.217219 -343.573848)
			(xy 84.217764 -343.584022) (xy 84.217764 -344.320622) (xy 86.026752 -344.320622) (xy 86.026752 -343.584022)
			(xy 86.027188 -343.573818) (xy 86.035016 -343.554973) (xy 86.04948 -343.540578) (xy 86.068363 -343.53284)
			(xy 86.078568 -343.53246) (xy 86.321392 -343.53246) (xy 86.651084 -343.748614) (xy 86.662129 -343.754097)
			(xy 86.686752 -343.754768) (xy 86.698074 -343.749884) (xy 87.013034 -343.544652) (xy 87.019384 -343.540588)
			(xy 87.019892 -343.54008) (xy 87.032084 -343.53246) (xy 87.274908 -343.53246) (xy 87.285082 -343.532968)
			(xy 87.303891 -343.540732) (xy 87.318317 -343.555083) (xy 87.326178 -343.573851) (xy 87.326724 -343.584022)
			(xy 87.326724 -344.320622) (xy 89.135712 -344.320622) (xy 89.135712 -343.584022) (xy 89.136187 -343.573823)
			(xy 89.144007 -343.554986) (xy 89.158459 -343.540592) (xy 89.177328 -343.532847) (xy 89.187528 -343.53246)
			(xy 89.430352 -343.53246) (xy 89.760044 -343.748614) (xy 89.771074 -343.754137) (xy 89.795711 -343.754782)
			(xy 89.807034 -343.749884) (xy 90.121994 -343.544652) (xy 90.128344 -343.540588) (xy 90.128852 -343.54008)
			(xy 90.141044 -343.53246) (xy 90.383868 -343.53246) (xy 90.39404 -343.533) (xy 90.412848 -343.540751)
			(xy 90.427275 -343.555092) (xy 90.435138 -343.573854) (xy 90.435684 -343.584022) (xy 90.435684 -344.320622)
			(xy 92.244672 -344.320622) (xy 92.244672 -343.584022) (xy 92.245088 -343.573816) (xy 92.25292 -343.554967)
			(xy 92.26739 -343.540571) (xy 92.28628 -343.532837) (xy 92.296488 -343.53246) (xy 92.539312 -343.53246)
			(xy 92.869004 -343.748614) (xy 92.880044 -343.754111) (xy 92.904671 -343.754773) (xy 92.915994 -343.749884)
			(xy 93.230954 -343.544652) (xy 93.237304 -343.540588) (xy 93.237812 -343.54008) (xy 93.250004 -343.53246)
			(xy 93.492828 -343.53246) (xy 93.503003 -343.532951) (xy 93.521813 -343.540722) (xy 93.536238 -343.555077)
			(xy 93.544099 -343.573849) (xy 93.544644 -343.584022) (xy 93.544644 -344.320622) (xy 111.645192 -344.320622)
			(xy 111.645192 -343.584022) (xy 111.64575 -343.573871) (xy 111.653509 -343.555111) (xy 111.667854 -343.540747)
			(xy 111.686604 -343.532963) (xy 111.696754 -343.53246) (xy 111.939578 -343.53246) (xy 112.26927 -343.748614)
			(xy 112.280319 -343.754088) (xy 112.304938 -343.754764) (xy 112.31626 -343.749884) (xy 112.63122 -343.544652)
			(xy 112.63757 -343.540588) (xy 112.638078 -343.54008) (xy 112.65027 -343.53246) (xy 112.893094 -343.53246)
			(xy 112.903268 -343.532869) (xy 112.922067 -343.540656) (xy 112.936453 -343.555047) (xy 112.944234 -343.573848)
			(xy 112.944656 -343.584022) (xy 112.944656 -344.320622) (xy 114.754152 -344.320622) (xy 114.754152 -343.584022)
			(xy 114.754582 -343.57385) (xy 114.762363 -343.555053) (xy 114.776747 -343.540667) (xy 114.795542 -343.532884)
			(xy 114.805714 -343.53246) (xy 115.048538 -343.53246) (xy 115.37823 -343.748614) (xy 115.389263 -343.754128)
			(xy 115.413897 -343.754779) (xy 115.42522 -343.749884) (xy 115.74018 -343.544652) (xy 115.74653 -343.540588)
			(xy 115.747038 -343.54008) (xy 115.75923 -343.53246) (xy 116.002054 -343.53246) (xy 116.012225 -343.532902)
			(xy 116.031023 -343.540676) (xy 116.045411 -343.555057) (xy 116.053193 -343.573851) (xy 116.053616 -343.584022)
			(xy 116.053616 -344.320622) (xy 117.863112 -344.320622) (xy 117.863112 -343.584022) (xy 117.863651 -343.573869)
			(xy 117.871413 -343.555105) (xy 117.885765 -343.54074) (xy 117.904521 -343.53296) (xy 117.914674 -343.53246)
			(xy 118.157498 -343.53246) (xy 118.48719 -343.748614) (xy 118.498234 -343.754101) (xy 118.522858 -343.754769)
			(xy 118.53418 -343.749884) (xy 118.84914 -343.544652) (xy 118.85549 -343.540588) (xy 118.855998 -343.54008)
			(xy 118.86819 -343.53246) (xy 119.111014 -343.53246) (xy 119.121189 -343.532853) (xy 119.139988 -343.540647)
			(xy 119.154373 -343.555042) (xy 119.162154 -343.573846) (xy 119.162576 -343.584022) (xy 119.162576 -344.320622)
			(xy 120.972072 -344.320622) (xy 120.972072 -343.584022) (xy 120.972483 -343.573848) (xy 120.980267 -343.555047)
			(xy 120.994657 -343.54066) (xy 121.01346 -343.532881) (xy 121.023634 -343.53246) (xy 121.266458 -343.53246)
			(xy 121.59615 -343.748614) (xy 121.607204 -343.754075) (xy 121.631818 -343.75476) (xy 121.64314 -343.749884)
			(xy 121.9581 -343.544652) (xy 121.96445 -343.540588) (xy 121.964958 -343.54008) (xy 121.97715 -343.53246)
			(xy 122.219974 -343.53246) (xy 122.230147 -343.532886) (xy 122.248945 -343.540666) (xy 122.263331 -343.555052)
			(xy 122.271113 -343.573849) (xy 122.271536 -343.584022) (xy 122.271536 -344.320622) (xy 124.081032 -344.320622)
			(xy 124.081032 -343.584022) (xy 124.081482 -343.573853) (xy 124.089259 -343.55506) (xy 124.103636 -343.540674)
			(xy 124.122425 -343.532887) (xy 124.132594 -343.53246) (xy 124.375418 -343.53246) (xy 124.70511 -343.748614)
			(xy 124.716148 -343.754115) (xy 124.740777 -343.754774) (xy 124.7521 -343.749884) (xy 125.06706 -343.544652)
			(xy 125.07341 -343.540588) (xy 125.073918 -343.54008) (xy 125.08611 -343.53246) (xy 125.328934 -343.53246)
			(xy 125.339097 -343.532906) (xy 125.357871 -343.540696) (xy 125.372236 -343.555076) (xy 125.380005 -343.573859)
			(xy 125.380496 -343.584022) (xy 125.380496 -344.320622) (xy 127.189992 -344.320622) (xy 127.189992 -343.584022)
			(xy 127.19055 -343.573871) (xy 127.198309 -343.555111) (xy 127.212654 -343.540747) (xy 127.231404 -343.532963)
			(xy 127.241554 -343.53246) (xy 127.484378 -343.53246) (xy 127.81407 -343.748614) (xy 127.825119 -343.754088)
			(xy 127.849738 -343.754764) (xy 127.86106 -343.749884) (xy 128.17602 -343.544652) (xy 128.18237 -343.540588)
			(xy 128.182878 -343.54008) (xy 128.19507 -343.53246) (xy 128.437894 -343.53246) (xy 128.448068 -343.532869)
			(xy 128.466867 -343.540656) (xy 128.481253 -343.555047) (xy 128.489034 -343.573848) (xy 128.489456 -343.584022)
			(xy 128.489456 -344.320622) (xy 130.298952 -344.320622) (xy 130.298952 -343.584022) (xy 130.299382 -343.57385)
			(xy 130.307163 -343.555053) (xy 130.321547 -343.540667) (xy 130.340342 -343.532884) (xy 130.350514 -343.53246)
			(xy 130.593338 -343.53246) (xy 130.92303 -343.748614) (xy 130.934063 -343.754128) (xy 130.958697 -343.754779)
			(xy 130.97002 -343.749884) (xy 131.28498 -343.544652) (xy 131.29133 -343.540588) (xy 131.291838 -343.54008)
			(xy 131.30403 -343.53246) (xy 131.546854 -343.53246) (xy 131.557025 -343.532902) (xy 131.575823 -343.540676)
			(xy 131.590211 -343.555057) (xy 131.597993 -343.573851) (xy 131.598416 -343.584022) (xy 131.598416 -344.320622)
			(xy 133.407912 -344.320622) (xy 133.407912 -343.584022) (xy 133.408451 -343.573869) (xy 133.416213 -343.555105)
			(xy 133.430565 -343.54074) (xy 133.449321 -343.53296) (xy 133.459474 -343.53246) (xy 133.702298 -343.53246)
			(xy 134.03199 -343.748614) (xy 134.043034 -343.754101) (xy 134.067658 -343.754769) (xy 134.07898 -343.749884)
			(xy 134.39394 -343.544652) (xy 134.40029 -343.540588) (xy 134.400798 -343.54008) (xy 134.41299 -343.53246)
			(xy 134.655814 -343.53246) (xy 134.665989 -343.532853) (xy 134.684788 -343.540647) (xy 134.699173 -343.555042)
			(xy 134.706954 -343.573846) (xy 134.707376 -343.584022) (xy 134.707376 -344.320622) (xy 136.516872 -344.320622)
			(xy 136.516872 -343.584022) (xy 136.517283 -343.573848) (xy 136.525067 -343.555047) (xy 136.539457 -343.54066)
			(xy 136.55826 -343.532881) (xy 136.568434 -343.53246) (xy 136.811258 -343.53246) (xy 137.14095 -343.748614)
			(xy 137.152004 -343.754075) (xy 137.176618 -343.75476) (xy 137.18794 -343.749884) (xy 137.5029 -343.544652)
			(xy 137.50925 -343.540588) (xy 137.509758 -343.54008) (xy 137.52195 -343.53246) (xy 137.764774 -343.53246)
			(xy 137.774947 -343.532886) (xy 137.793745 -343.540666) (xy 137.808131 -343.555052) (xy 137.815913 -343.573849)
			(xy 137.816336 -343.584022) (xy 137.816336 -344.320622) (xy 139.625832 -344.320622) (xy 139.625832 -343.584022)
			(xy 139.626282 -343.573853) (xy 139.634059 -343.55506) (xy 139.648436 -343.540674) (xy 139.667225 -343.532887)
			(xy 139.677394 -343.53246) (xy 139.920218 -343.53246) (xy 140.24991 -343.748614) (xy 140.260948 -343.754115)
			(xy 140.285577 -343.754774) (xy 140.2969 -343.749884) (xy 140.61186 -343.544652) (xy 140.61821 -343.540588)
			(xy 140.618718 -343.54008) (xy 140.63091 -343.53246) (xy 140.873734 -343.53246) (xy 140.883897 -343.532906)
			(xy 140.902671 -343.540696) (xy 140.917036 -343.555076) (xy 140.924805 -343.573859) (xy 140.925296 -343.584022)
			(xy 140.925296 -344.320622) (xy 142.734792 -344.320622) (xy 142.734792 -343.584022) (xy 142.73535 -343.573871)
			(xy 142.743109 -343.555111) (xy 142.757454 -343.540747) (xy 142.776204 -343.532963) (xy 142.786354 -343.53246)
			(xy 143.029178 -343.53246) (xy 143.35887 -343.748614) (xy 143.369919 -343.754088) (xy 143.394538 -343.754764)
			(xy 143.40586 -343.749884) (xy 143.72082 -343.544652) (xy 143.72717 -343.540588) (xy 143.727678 -343.54008)
			(xy 143.73987 -343.53246) (xy 143.982694 -343.53246) (xy 143.992868 -343.532869) (xy 144.011667 -343.540656)
			(xy 144.026053 -343.555047) (xy 144.033834 -343.573848) (xy 144.034256 -343.584022) (xy 144.034256 -344.320622)
			(xy 165.078156 -344.320622) (xy 165.078156 -343.584022) (xy 165.078583 -343.57385) (xy 165.086364 -343.555052)
			(xy 165.100749 -343.540666) (xy 165.119546 -343.532883) (xy 165.129718 -343.53246) (xy 165.372542 -343.53246)
			(xy 165.702234 -343.748614) (xy 165.713266 -343.754131) (xy 165.737901 -343.75478) (xy 165.749224 -343.749884)
			(xy 166.064184 -343.544652) (xy 166.070534 -343.540588) (xy 166.071042 -343.54008) (xy 166.083234 -343.53246)
			(xy 166.326058 -343.53246) (xy 166.33623 -343.532899) (xy 166.355028 -343.540674) (xy 166.369415 -343.555056)
			(xy 166.377197 -343.573851) (xy 166.37762 -343.584022) (xy 166.37762 -344.320622) (xy 168.187116 -344.320622)
			(xy 168.187116 -343.584022) (xy 168.187651 -343.573868) (xy 168.195414 -343.555104) (xy 168.209767 -343.540739)
			(xy 168.228525 -343.532959) (xy 168.238678 -343.53246) (xy 168.481502 -343.53246) (xy 168.811194 -343.748614)
			(xy 168.822236 -343.754104) (xy 168.846862 -343.75477) (xy 168.858184 -343.749884) (xy 169.173144 -343.544652)
			(xy 169.179494 -343.540588) (xy 169.180002 -343.54008) (xy 169.192194 -343.53246) (xy 169.435018 -343.53246)
			(xy 169.445193 -343.53285) (xy 169.463993 -343.540645) (xy 169.478378 -343.555041) (xy 169.486158 -343.573846)
			(xy 169.48658 -343.584022) (xy 169.48658 -344.320622) (xy 171.296076 -344.320622) (xy 171.296076 -343.584022)
			(xy 171.296483 -343.573847) (xy 171.304268 -343.555046) (xy 171.318659 -343.540659) (xy 171.337463 -343.53288)
			(xy 171.347638 -343.53246) (xy 171.590462 -343.53246) (xy 171.920154 -343.748614) (xy 171.931207 -343.754077)
			(xy 171.955822 -343.754761) (xy 171.967144 -343.749884) (xy 172.282104 -343.544652) (xy 172.288454 -343.540588)
			(xy 172.288962 -343.54008) (xy 172.301154 -343.53246) (xy 172.543978 -343.53246) (xy 172.554151 -343.532883)
			(xy 172.572949 -343.540664) (xy 172.587336 -343.555051) (xy 172.595117 -343.573849) (xy 172.59554 -343.584022)
			(xy 172.59554 -344.320622) (xy 174.405036 -344.320622) (xy 174.405036 -343.584022) (xy 174.405482 -343.573852)
			(xy 174.413259 -343.555058) (xy 174.427638 -343.540673) (xy 174.446428 -343.532887) (xy 174.456598 -343.53246)
			(xy 174.699422 -343.53246) (xy 175.029114 -343.748614) (xy 175.040151 -343.754118) (xy 175.064781 -343.754775)
			(xy 175.076104 -343.749884) (xy 175.391064 -343.544652) (xy 175.397414 -343.540588) (xy 175.397922 -343.54008)
			(xy 175.410114 -343.53246) (xy 175.652938 -343.53246) (xy 175.663101 -343.532903) (xy 175.681875 -343.540694)
			(xy 175.69624 -343.555075) (xy 175.704009 -343.573858) (xy 175.7045 -343.584022) (xy 175.7045 -344.320622)
			(xy 177.513996 -344.320622) (xy 177.513996 -343.584022) (xy 177.51455 -343.573871) (xy 177.52231 -343.55511)
			(xy 177.536656 -343.540746) (xy 177.555407 -343.532963) (xy 177.565558 -343.53246) (xy 177.808382 -343.53246)
			(xy 178.138074 -343.748614) (xy 178.149122 -343.754091) (xy 178.173742 -343.754765) (xy 178.185064 -343.749884)
			(xy 178.500024 -343.544652) (xy 178.506374 -343.540588) (xy 178.506882 -343.54008) (xy 178.519074 -343.53246)
			(xy 178.761898 -343.53246) (xy 178.772072 -343.532866) (xy 178.790871 -343.540654) (xy 178.805257 -343.555046)
			(xy 178.813038 -343.573848) (xy 178.81346 -343.584022) (xy 178.81346 -344.320622) (xy 180.622956 -344.320622)
			(xy 180.622956 -343.584022) (xy 180.623383 -343.57385) (xy 180.631164 -343.555052) (xy 180.645549 -343.540666)
			(xy 180.664346 -343.532883) (xy 180.674518 -343.53246) (xy 180.917342 -343.53246) (xy 181.247034 -343.748614)
			(xy 181.258066 -343.754131) (xy 181.282701 -343.75478) (xy 181.294024 -343.749884) (xy 181.608984 -343.544652)
			(xy 181.615334 -343.540588) (xy 181.615842 -343.54008) (xy 181.628034 -343.53246) (xy 181.870858 -343.53246)
			(xy 181.88103 -343.532899) (xy 181.899828 -343.540674) (xy 181.914215 -343.555056) (xy 181.921997 -343.573851)
			(xy 181.92242 -343.584022) (xy 181.92242 -344.320622) (xy 183.731916 -344.320622) (xy 183.731916 -343.584022)
			(xy 183.732451 -343.573868) (xy 183.740214 -343.555104) (xy 183.754567 -343.540739) (xy 183.773325 -343.532959)
			(xy 183.783478 -343.53246) (xy 184.026302 -343.53246) (xy 184.355994 -343.748614) (xy 184.367036 -343.754104)
			(xy 184.391662 -343.75477) (xy 184.402984 -343.749884) (xy 184.717944 -343.544652) (xy 184.724294 -343.540588)
			(xy 184.724802 -343.54008) (xy 184.736994 -343.53246) (xy 184.979818 -343.53246) (xy 184.989993 -343.53285)
			(xy 185.008793 -343.540645) (xy 185.023178 -343.555041) (xy 185.030958 -343.573846) (xy 185.03138 -343.584022)
			(xy 185.03138 -344.320622) (xy 186.840876 -344.320622) (xy 186.840876 -343.584022) (xy 186.841283 -343.573847)
			(xy 186.849068 -343.555046) (xy 186.863459 -343.540659) (xy 186.882263 -343.53288) (xy 186.892438 -343.53246)
			(xy 187.135262 -343.53246) (xy 187.464954 -343.748614) (xy 187.476007 -343.754077) (xy 187.500622 -343.754761)
			(xy 187.511944 -343.749884) (xy 187.826904 -343.544652) (xy 187.833254 -343.540588) (xy 187.833762 -343.54008)
			(xy 187.845954 -343.53246) (xy 188.088778 -343.53246) (xy 188.098951 -343.532883) (xy 188.117749 -343.540664)
			(xy 188.132136 -343.555051) (xy 188.139917 -343.573849) (xy 188.14034 -343.584022) (xy 188.14034 -344.320622)
			(xy 189.949836 -344.320622) (xy 189.949836 -343.584022) (xy 189.950282 -343.573852) (xy 189.958059 -343.555058)
			(xy 189.972438 -343.540673) (xy 189.991228 -343.532887) (xy 190.001398 -343.53246) (xy 190.244222 -343.53246)
			(xy 190.573914 -343.748614) (xy 190.584951 -343.754118) (xy 190.609581 -343.754775) (xy 190.620904 -343.749884)
			(xy 190.935864 -343.544652) (xy 190.942214 -343.540588) (xy 190.942722 -343.54008) (xy 190.954914 -343.53246)
			(xy 191.197738 -343.53246) (xy 191.207901 -343.532903) (xy 191.226675 -343.540694) (xy 191.24104 -343.555075)
			(xy 191.248809 -343.573858) (xy 191.2493 -343.584022) (xy 191.2493 -344.320622) (xy 193.058796 -344.320622)
			(xy 193.058796 -343.584022) (xy 193.05935 -343.573871) (xy 193.06711 -343.55511) (xy 193.081456 -343.540746)
			(xy 193.100207 -343.532963) (xy 193.110358 -343.53246) (xy 193.353182 -343.53246) (xy 193.682874 -343.748614)
			(xy 193.693922 -343.754091) (xy 193.718542 -343.754765) (xy 193.729864 -343.749884) (xy 194.044824 -343.544652)
			(xy 194.051174 -343.540588) (xy 194.051682 -343.54008) (xy 194.063874 -343.53246) (xy 194.306698 -343.53246)
			(xy 194.316872 -343.532866) (xy 194.335671 -343.540654) (xy 194.350057 -343.555046) (xy 194.357838 -343.573848)
			(xy 194.35826 -343.584022) (xy 194.35826 -344.320622) (xy 196.167756 -344.320622) (xy 196.167756 -343.584022)
			(xy 196.168183 -343.57385) (xy 196.175964 -343.555052) (xy 196.190349 -343.540666) (xy 196.209146 -343.532883)
			(xy 196.219318 -343.53246) (xy 196.462142 -343.53246) (xy 196.791834 -343.748614) (xy 196.802866 -343.754131)
			(xy 196.827501 -343.75478) (xy 196.838824 -343.749884) (xy 197.153784 -343.544652) (xy 197.160134 -343.540588)
			(xy 197.160642 -343.54008) (xy 197.172834 -343.53246) (xy 197.415658 -343.53246) (xy 197.42583 -343.532899)
			(xy 197.444628 -343.540674) (xy 197.459015 -343.555056) (xy 197.466797 -343.573851) (xy 197.46722 -343.584022)
			(xy 197.46722 -344.320622) (xy 267.679932 -344.320622) (xy 267.679932 -343.584022) (xy 267.680388 -343.573821)
			(xy 267.688212 -343.554979) (xy 267.702669 -343.540585) (xy 267.721545 -343.532843) (xy 267.731748 -343.53246)
			(xy 267.974572 -343.53246) (xy 268.304264 -343.748614) (xy 268.315314 -343.754084) (xy 268.339932 -343.754763)
			(xy 268.351254 -343.749884) (xy 268.666214 -343.544652) (xy 268.672564 -343.540588) (xy 268.673072 -343.54008)
			(xy 268.685264 -343.53246) (xy 268.928088 -343.53246) (xy 268.938261 -343.532984) (xy 268.957069 -343.540741)
			(xy 268.971496 -343.555087) (xy 268.979358 -343.573852) (xy 268.979904 -343.584022) (xy 268.979904 -344.320622)
			(xy 270.788892 -344.320622) (xy 270.788892 -343.584022) (xy 270.789387 -343.573826) (xy 270.797203 -343.554992)
			(xy 270.811648 -343.540599) (xy 270.830511 -343.53285) (xy 270.840708 -343.53246) (xy 271.083532 -343.53246)
			(xy 271.413224 -343.748614) (xy 271.424259 -343.754124) (xy 271.448891 -343.754778) (xy 271.460214 -343.749884)
			(xy 271.775174 -343.544652) (xy 271.781524 -343.540588) (xy 271.782032 -343.54008) (xy 271.794224 -343.53246)
			(xy 272.037048 -343.53246) (xy 272.047225 -343.532935) (xy 272.066034 -343.540712) (xy 272.080459 -343.555073)
			(xy 272.088319 -343.573848) (xy 272.088864 -343.584022) (xy 272.088864 -344.320622) (xy 273.897852 -344.320622)
			(xy 273.897852 -343.584022) (xy 273.898288 -343.573818) (xy 273.906116 -343.554973) (xy 273.92058 -343.540578)
			(xy 273.939463 -343.53284) (xy 273.949668 -343.53246) (xy 274.192492 -343.53246) (xy 274.522184 -343.748614)
			(xy 274.533229 -343.754097) (xy 274.557852 -343.754768) (xy 274.569174 -343.749884) (xy 274.884134 -343.544652)
			(xy 274.890484 -343.540588) (xy 274.890992 -343.54008) (xy 274.903184 -343.53246) (xy 275.146008 -343.53246)
			(xy 275.156182 -343.532968) (xy 275.174991 -343.540732) (xy 275.189417 -343.555083) (xy 275.197278 -343.573851)
			(xy 275.197824 -343.584022) (xy 275.197824 -344.320622) (xy 277.006812 -344.320622) (xy 277.006812 -343.584022)
			(xy 277.007287 -343.573823) (xy 277.015107 -343.554986) (xy 277.029559 -343.540592) (xy 277.048428 -343.532847)
			(xy 277.058628 -343.53246) (xy 277.301452 -343.53246) (xy 277.631144 -343.748614) (xy 277.642174 -343.754137)
			(xy 277.666811 -343.754782) (xy 277.678134 -343.749884) (xy 277.993094 -343.544652) (xy 277.999444 -343.540588)
			(xy 277.999952 -343.54008) (xy 278.012144 -343.53246) (xy 278.254968 -343.53246) (xy 278.26514 -343.533)
			(xy 278.283948 -343.540751) (xy 278.298375 -343.555092) (xy 278.306238 -343.573854) (xy 278.306784 -343.584022)
			(xy 278.306784 -344.320622) (xy 280.115772 -344.320622) (xy 280.115772 -343.584022) (xy 280.116188 -343.573816)
			(xy 280.12402 -343.554967) (xy 280.13849 -343.540571) (xy 280.15738 -343.532837) (xy 280.167588 -343.53246)
			(xy 280.410412 -343.53246) (xy 280.740104 -343.748614) (xy 280.751144 -343.754111) (xy 280.775771 -343.754773)
			(xy 280.787094 -343.749884) (xy 281.102054 -343.544652) (xy 281.108404 -343.540588) (xy 281.108912 -343.54008)
			(xy 281.121104 -343.53246) (xy 281.363928 -343.53246) (xy 281.374103 -343.532951) (xy 281.392913 -343.540722)
			(xy 281.407338 -343.555077) (xy 281.415199 -343.573849) (xy 281.415744 -343.584022) (xy 281.415744 -344.320622)
			(xy 283.224732 -344.320622) (xy 283.224732 -343.584022) (xy 283.225188 -343.573821) (xy 283.233012 -343.554979)
			(xy 283.247469 -343.540585) (xy 283.266345 -343.532843) (xy 283.276548 -343.53246) (xy 283.519372 -343.53246)
			(xy 283.849064 -343.748614) (xy 283.860114 -343.754084) (xy 283.884732 -343.754763) (xy 283.896054 -343.749884)
			(xy 284.211014 -343.544652) (xy 284.217364 -343.540588) (xy 284.217872 -343.54008) (xy 284.230064 -343.53246)
			(xy 284.472888 -343.53246) (xy 284.483061 -343.532984) (xy 284.501869 -343.540741) (xy 284.516296 -343.555087)
			(xy 284.524158 -343.573852) (xy 284.524704 -343.584022) (xy 284.524704 -344.320622) (xy 286.333692 -344.320622)
			(xy 286.333692 -343.584022) (xy 286.334187 -343.573826) (xy 286.342003 -343.554992) (xy 286.356448 -343.540599)
			(xy 286.375311 -343.53285) (xy 286.385508 -343.53246) (xy 286.628332 -343.53246) (xy 286.958024 -343.748614)
			(xy 286.969059 -343.754124) (xy 286.993691 -343.754778) (xy 287.005014 -343.749884) (xy 287.319974 -343.544652)
			(xy 287.326324 -343.540588) (xy 287.326832 -343.54008) (xy 287.339024 -343.53246) (xy 287.581848 -343.53246)
			(xy 287.592025 -343.532935) (xy 287.610834 -343.540712) (xy 287.625259 -343.555073) (xy 287.633119 -343.573848)
			(xy 287.633664 -343.584022) (xy 287.633664 -344.320622) (xy 289.442652 -344.320622) (xy 289.442652 -343.584022)
			(xy 289.443088 -343.573818) (xy 289.450916 -343.554973) (xy 289.46538 -343.540578) (xy 289.484263 -343.53284)
			(xy 289.494468 -343.53246) (xy 289.737292 -343.53246) (xy 290.066984 -343.748614) (xy 290.078029 -343.754097)
			(xy 290.102652 -343.754768) (xy 290.113974 -343.749884) (xy 290.428934 -343.544652) (xy 290.435284 -343.540588)
			(xy 290.435792 -343.54008) (xy 290.447984 -343.53246) (xy 290.690808 -343.53246) (xy 290.700982 -343.532968)
			(xy 290.719791 -343.540732) (xy 290.734217 -343.555083) (xy 290.742078 -343.573851) (xy 290.742624 -343.584022)
			(xy 290.742624 -344.320622) (xy 292.551612 -344.320622) (xy 292.551612 -343.584022) (xy 292.552087 -343.573823)
			(xy 292.559907 -343.554986) (xy 292.574359 -343.540592) (xy 292.593228 -343.532847) (xy 292.603428 -343.53246)
			(xy 292.846252 -343.53246) (xy 293.175944 -343.748614) (xy 293.186974 -343.754137) (xy 293.211611 -343.754782)
			(xy 293.222934 -343.749884) (xy 293.537894 -343.544652) (xy 293.544244 -343.540588) (xy 293.544752 -343.54008)
			(xy 293.556944 -343.53246) (xy 293.799768 -343.53246) (xy 293.80994 -343.533) (xy 293.828748 -343.540751)
			(xy 293.843175 -343.555092) (xy 293.851038 -343.573854) (xy 293.851584 -343.584022) (xy 293.851584 -344.320622)
			(xy 295.660572 -344.320622) (xy 295.660572 -343.584022) (xy 295.660988 -343.573816) (xy 295.66882 -343.554967)
			(xy 295.68329 -343.540571) (xy 295.70218 -343.532837) (xy 295.712388 -343.53246) (xy 295.955212 -343.53246)
			(xy 296.284904 -343.748614) (xy 296.295944 -343.754111) (xy 296.320571 -343.754773) (xy 296.331894 -343.749884)
			(xy 296.646854 -343.544652) (xy 296.653204 -343.540588) (xy 296.653712 -343.54008) (xy 296.665904 -343.53246)
			(xy 296.908728 -343.53246) (xy 296.918903 -343.532951) (xy 296.937713 -343.540722) (xy 296.952138 -343.555077)
			(xy 296.959999 -343.573849) (xy 296.960544 -343.584022) (xy 296.960544 -344.320622) (xy 298.769532 -344.320622)
			(xy 298.769532 -343.584022) (xy 298.769988 -343.573821) (xy 298.777812 -343.554979) (xy 298.792269 -343.540585)
			(xy 298.811145 -343.532843) (xy 298.821348 -343.53246) (xy 299.064172 -343.53246) (xy 299.393864 -343.748614)
			(xy 299.404914 -343.754084) (xy 299.429532 -343.754763) (xy 299.440854 -343.749884) (xy 299.755814 -343.544652)
			(xy 299.762164 -343.540588) (xy 299.762672 -343.54008) (xy 299.774864 -343.53246) (xy 300.017688 -343.53246)
			(xy 300.027861 -343.532984) (xy 300.046669 -343.540741) (xy 300.061096 -343.555087) (xy 300.068958 -343.573852)
			(xy 300.069504 -343.584022) (xy 300.069504 -344.320622) (xy 312.285888 -344.320622) (xy 312.285888 -343.584022)
			(xy 312.286283 -343.573846) (xy 312.29407 -343.555042) (xy 312.308466 -343.540655) (xy 312.327273 -343.532878)
			(xy 312.33745 -343.53246) (xy 312.580274 -343.53246) (xy 312.909966 -343.748614) (xy 312.921016 -343.754085)
			(xy 312.945634 -343.754763) (xy 312.956956 -343.749884) (xy 313.271916 -343.544652) (xy 313.278266 -343.540588)
			(xy 313.278774 -343.54008) (xy 313.290966 -343.53246) (xy 313.53379 -343.53246) (xy 313.543964 -343.532872)
			(xy 313.562762 -343.540658) (xy 313.577148 -343.555048) (xy 313.58493 -343.573848) (xy 313.585352 -343.584022)
			(xy 313.585352 -344.320622) (xy 315.394848 -344.320622) (xy 315.394848 -343.584022) (xy 315.395282 -343.573851)
			(xy 315.403062 -343.555055) (xy 315.417444 -343.540669) (xy 315.436239 -343.532885) (xy 315.44641 -343.53246)
			(xy 315.689234 -343.53246) (xy 316.018926 -343.748614) (xy 316.02996 -343.754125) (xy 316.054593 -343.754778)
			(xy 316.065916 -343.749884) (xy 316.380876 -343.544652) (xy 316.387226 -343.540588) (xy 316.387734 -343.54008)
			(xy 316.399926 -343.53246) (xy 316.64275 -343.53246) (xy 316.652921 -343.532905) (xy 316.671719 -343.540678)
			(xy 316.686106 -343.555058) (xy 316.693889 -343.573851) (xy 316.694312 -343.584022) (xy 316.694312 -344.320622)
			(xy 318.503808 -344.320622) (xy 318.503808 -343.584022) (xy 318.50435 -343.573869) (xy 318.512112 -343.555106)
			(xy 318.526463 -343.540741) (xy 318.545218 -343.532961) (xy 318.55537 -343.53246) (xy 318.798194 -343.53246)
			(xy 319.127886 -343.748614) (xy 319.138931 -343.754098) (xy 319.163554 -343.754768) (xy 319.174876 -343.749884)
			(xy 319.489836 -343.544652) (xy 319.496186 -343.540588) (xy 319.496694 -343.54008) (xy 319.508886 -343.53246)
			(xy 319.75171 -343.53246) (xy 319.761885 -343.532856) (xy 319.780684 -343.540649) (xy 319.795069 -343.555043)
			(xy 319.80285 -343.573847) (xy 319.803272 -343.584022) (xy 319.803272 -344.320622) (xy 321.612768 -344.320622)
			(xy 321.612768 -343.584022) (xy 321.613183 -343.573848) (xy 321.620966 -343.555048) (xy 321.635355 -343.540662)
			(xy 321.654156 -343.532881) (xy 321.66433 -343.53246) (xy 321.907154 -343.53246) (xy 322.236846 -343.748614)
			(xy 322.247901 -343.754072) (xy 322.272514 -343.754759) (xy 322.283836 -343.749884) (xy 322.598796 -343.544652)
			(xy 322.605146 -343.540588) (xy 322.605654 -343.54008) (xy 322.617846 -343.53246) (xy 322.86067 -343.53246)
			(xy 322.870842 -343.532889) (xy 322.889641 -343.540668) (xy 322.904027 -343.555053) (xy 322.911809 -343.57385)
			(xy 322.912232 -343.584022) (xy 322.912232 -344.320622) (xy 324.721728 -344.320622) (xy 324.721728 -343.584022)
			(xy 324.722182 -343.573853) (xy 324.729958 -343.555061) (xy 324.744334 -343.540676) (xy 324.763121 -343.532888)
			(xy 324.77329 -343.53246) (xy 325.016114 -343.53246) (xy 325.345806 -343.748614) (xy 325.356845 -343.754112)
			(xy 325.381473 -343.754773) (xy 325.392796 -343.749884) (xy 325.707756 -343.544652) (xy 325.714106 -343.540588)
			(xy 325.714614 -343.54008) (xy 325.726806 -343.53246) (xy 325.96963 -343.53246) (xy 325.979792 -343.532909)
			(xy 325.998567 -343.540698) (xy 326.012932 -343.555077) (xy 326.020701 -343.573859) (xy 326.021192 -343.584022)
			(xy 326.021192 -344.320622) (xy 327.830688 -344.320622) (xy 327.830688 -343.584022) (xy 327.831083 -343.573846)
			(xy 327.83887 -343.555042) (xy 327.853266 -343.540655) (xy 327.872073 -343.532878) (xy 327.88225 -343.53246)
			(xy 328.125074 -343.53246) (xy 328.454766 -343.748614) (xy 328.465816 -343.754085) (xy 328.490434 -343.754763)
			(xy 328.501756 -343.749884) (xy 328.816716 -343.544652) (xy 328.823066 -343.540588) (xy 328.823574 -343.54008)
			(xy 328.835766 -343.53246) (xy 329.07859 -343.53246) (xy 329.088764 -343.532872) (xy 329.107562 -343.540658)
			(xy 329.121948 -343.555048) (xy 329.12973 -343.573848) (xy 329.130152 -343.584022) (xy 329.130152 -344.320622)
			(xy 330.939648 -344.320622) (xy 330.939648 -343.584022) (xy 330.940082 -343.573851) (xy 330.947862 -343.555055)
			(xy 330.962244 -343.540669) (xy 330.981039 -343.532885) (xy 330.99121 -343.53246) (xy 331.234034 -343.53246)
			(xy 331.563726 -343.748614) (xy 331.57476 -343.754125) (xy 331.599393 -343.754778) (xy 331.610716 -343.749884)
			(xy 331.925676 -343.544652) (xy 331.932026 -343.540588) (xy 331.932534 -343.54008) (xy 331.944726 -343.53246)
			(xy 332.18755 -343.53246) (xy 332.197721 -343.532905) (xy 332.216519 -343.540678) (xy 332.230906 -343.555058)
			(xy 332.238689 -343.573851) (xy 332.239112 -343.584022) (xy 332.239112 -344.320622) (xy 334.048608 -344.320622)
			(xy 334.048608 -343.584022) (xy 334.04915 -343.573869) (xy 334.056912 -343.555106) (xy 334.071263 -343.540741)
			(xy 334.090018 -343.532961) (xy 334.10017 -343.53246) (xy 334.342994 -343.53246) (xy 334.672686 -343.748614)
			(xy 334.683731 -343.754098) (xy 334.708354 -343.754768) (xy 334.719676 -343.749884) (xy 335.034636 -343.544652)
			(xy 335.040986 -343.540588) (xy 335.041494 -343.54008) (xy 335.053686 -343.53246) (xy 335.29651 -343.53246)
			(xy 335.306685 -343.532856) (xy 335.325484 -343.540649) (xy 335.339869 -343.555043) (xy 335.34765 -343.573847)
			(xy 335.348072 -343.584022) (xy 335.348072 -344.320622) (xy 337.157568 -344.320622) (xy 337.157568 -343.584022)
			(xy 337.157983 -343.573848) (xy 337.165766 -343.555048) (xy 337.180155 -343.540662) (xy 337.198956 -343.532881)
			(xy 337.20913 -343.53246) (xy 337.451954 -343.53246) (xy 337.781646 -343.748614) (xy 337.792701 -343.754072)
			(xy 337.817314 -343.754759) (xy 337.828636 -343.749884) (xy 338.143596 -343.544652) (xy 338.149946 -343.540588)
			(xy 338.150454 -343.54008) (xy 338.162646 -343.53246) (xy 338.40547 -343.53246) (xy 338.415642 -343.532889)
			(xy 338.434441 -343.540668) (xy 338.448827 -343.555053) (xy 338.456609 -343.57385) (xy 338.457032 -343.584022)
			(xy 338.457032 -344.320622) (xy 340.266528 -344.320622) (xy 340.266528 -343.584022) (xy 340.266982 -343.573853)
			(xy 340.274758 -343.555061) (xy 340.289134 -343.540676) (xy 340.307921 -343.532888) (xy 340.31809 -343.53246)
			(xy 340.560914 -343.53246) (xy 340.890606 -343.748614) (xy 340.901645 -343.754112) (xy 340.926273 -343.754773)
			(xy 340.937596 -343.749884) (xy 341.252556 -343.544652) (xy 341.258906 -343.540588) (xy 341.259414 -343.54008)
			(xy 341.271606 -343.53246) (xy 341.51443 -343.53246) (xy 341.524592 -343.532909) (xy 341.543367 -343.540698)
			(xy 341.557732 -343.555077) (xy 341.565501 -343.573859) (xy 341.565992 -343.584022) (xy 341.565992 -344.320622)
			(xy 343.375488 -344.320622) (xy 343.375488 -343.584022) (xy 343.375883 -343.573846) (xy 343.38367 -343.555042)
			(xy 343.398066 -343.540655) (xy 343.416873 -343.532878) (xy 343.42705 -343.53246) (xy 343.669874 -343.53246)
			(xy 343.999566 -343.748614) (xy 344.010616 -343.754085) (xy 344.035234 -343.754763) (xy 344.046556 -343.749884)
			(xy 344.361516 -343.544652) (xy 344.367866 -343.540588) (xy 344.368374 -343.54008) (xy 344.380566 -343.53246)
			(xy 344.62339 -343.53246) (xy 344.633564 -343.532872) (xy 344.652362 -343.540658) (xy 344.666748 -343.555048)
			(xy 344.67453 -343.573848) (xy 344.674952 -343.584022) (xy 344.674952 -344.320622) (xy 370.971064 -344.320622)
			(xy 370.971064 -343.584022) (xy 370.971483 -343.573849) (xy 370.979265 -343.55505) (xy 370.993653 -343.540663)
			(xy 371.012453 -343.532882) (xy 371.022626 -343.53246) (xy 371.26545 -343.53246) (xy 371.595142 -343.748614)
			(xy 371.606172 -343.754136) (xy 371.630809 -343.754782) (xy 371.642132 -343.749884) (xy 371.957092 -343.544652)
			(xy 371.963442 -343.540588) (xy 371.96395 -343.54008) (xy 371.976142 -343.53246) (xy 372.218966 -343.53246)
			(xy 372.229138 -343.532892) (xy 372.247936 -343.54067) (xy 372.262323 -343.555054) (xy 372.270105 -343.57385)
			(xy 372.270528 -343.584022) (xy 372.270528 -344.320622) (xy 374.080024 -344.320622) (xy 374.080024 -343.584022)
			(xy 374.080482 -343.573854) (xy 374.088257 -343.555062) (xy 374.102632 -343.540677) (xy 374.121418 -343.532889)
			(xy 374.131586 -343.53246) (xy 374.37441 -343.53246) (xy 374.704102 -343.748614) (xy 374.715142 -343.75411)
			(xy 374.739769 -343.754772) (xy 374.751092 -343.749884) (xy 375.066052 -343.544652) (xy 375.072402 -343.540588)
			(xy 375.07291 -343.54008) (xy 375.085102 -343.53246) (xy 375.327926 -343.53246) (xy 375.338088 -343.532912)
			(xy 375.356862 -343.5407) (xy 375.371227 -343.555078) (xy 375.378997 -343.573859) (xy 375.379488 -343.584022)
			(xy 375.379488 -344.320622) (xy 377.188984 -344.320622) (xy 377.188984 -343.584022) (xy 377.189383 -343.573846)
			(xy 377.197169 -343.555043) (xy 377.211563 -343.540656) (xy 377.23037 -343.532878) (xy 377.240546 -343.53246)
			(xy 377.48337 -343.53246) (xy 377.813062 -343.748614) (xy 377.824113 -343.754083) (xy 377.84873 -343.754762)
			(xy 377.860052 -343.749884) (xy 378.175012 -343.544652) (xy 378.181362 -343.540588) (xy 378.18187 -343.54008)
			(xy 378.194062 -343.53246) (xy 378.436886 -343.53246) (xy 378.447059 -343.532876) (xy 378.465858 -343.54066)
			(xy 378.480244 -343.555049) (xy 378.488026 -343.573848) (xy 378.488448 -343.584022) (xy 378.488448 -344.320622)
			(xy 380.297944 -344.320622) (xy 380.297944 -343.584022) (xy 380.298382 -343.573851) (xy 380.306161 -343.555056)
			(xy 380.320542 -343.54067) (xy 380.339335 -343.532885) (xy 380.349506 -343.53246) (xy 380.59233 -343.53246)
			(xy 380.922022 -343.748614) (xy 380.933057 -343.754123) (xy 380.957689 -343.754777) (xy 380.969012 -343.749884)
			(xy 381.283972 -343.544652) (xy 381.290322 -343.540588) (xy 381.29083 -343.54008) (xy 381.303022 -343.53246)
			(xy 381.545846 -343.53246) (xy 381.556009 -343.532896) (xy 381.574784 -343.54069) (xy 381.589148 -343.555073)
			(xy 381.596917 -343.573858) (xy 381.597408 -343.584022) (xy 381.597408 -344.320622) (xy 383.406904 -344.320622)
			(xy 383.406904 -343.584022) (xy 383.40745 -343.57387) (xy 383.415211 -343.555108) (xy 383.429561 -343.540743)
			(xy 383.448314 -343.532961) (xy 383.458466 -343.53246) (xy 383.70129 -343.53246) (xy 384.030982 -343.748614)
			(xy 384.042028 -343.754096) (xy 384.06665 -343.754767) (xy 384.077972 -343.749884) (xy 384.392932 -343.544652)
			(xy 384.399282 -343.540588) (xy 384.39979 -343.54008) (xy 384.411982 -343.53246) (xy 384.654806 -343.53246)
			(xy 384.664981 -343.53286) (xy 384.68378 -343.540651) (xy 384.698165 -343.555044) (xy 384.705946 -343.573847)
			(xy 384.706368 -343.584022) (xy 384.706368 -344.320622) (xy 386.515864 -344.320622) (xy 386.515864 -343.584022)
			(xy 386.516283 -343.573849) (xy 386.524065 -343.55505) (xy 386.538453 -343.540663) (xy 386.557253 -343.532882)
			(xy 386.567426 -343.53246) (xy 386.81025 -343.53246) (xy 387.139942 -343.748614) (xy 387.150972 -343.754136)
			(xy 387.175609 -343.754782) (xy 387.186932 -343.749884) (xy 387.501892 -343.544652) (xy 387.508242 -343.540588)
			(xy 387.50875 -343.54008) (xy 387.520942 -343.53246) (xy 387.763766 -343.53246) (xy 387.773938 -343.532892)
			(xy 387.792736 -343.54067) (xy 387.807123 -343.555054) (xy 387.814905 -343.57385) (xy 387.815328 -343.584022)
			(xy 387.815328 -344.320622) (xy 389.624824 -344.320622) (xy 389.624824 -343.584022) (xy 389.625282 -343.573854)
			(xy 389.633057 -343.555062) (xy 389.647432 -343.540677) (xy 389.666218 -343.532889) (xy 389.676386 -343.53246)
			(xy 389.91921 -343.53246) (xy 390.248902 -343.748614) (xy 390.259942 -343.75411) (xy 390.284569 -343.754772)
			(xy 390.295892 -343.749884) (xy 390.610852 -343.544652) (xy 390.617202 -343.540588) (xy 390.61771 -343.54008)
			(xy 390.629902 -343.53246) (xy 390.872726 -343.53246) (xy 390.882888 -343.532912) (xy 390.901662 -343.5407)
			(xy 390.916027 -343.555078) (xy 390.923797 -343.573859) (xy 390.924288 -343.584022) (xy 390.924288 -344.320622)
			(xy 392.733784 -344.320622) (xy 392.733784 -343.584022) (xy 392.734183 -343.573846) (xy 392.741969 -343.555043)
			(xy 392.756363 -343.540656) (xy 392.77517 -343.532878) (xy 392.785346 -343.53246) (xy 393.02817 -343.53246)
			(xy 393.357862 -343.748614) (xy 393.368913 -343.754083) (xy 393.39353 -343.754762) (xy 393.404852 -343.749884)
			(xy 393.719812 -343.544652) (xy 393.726162 -343.540588) (xy 393.72667 -343.54008) (xy 393.738862 -343.53246)
			(xy 393.981686 -343.53246) (xy 393.991859 -343.532876) (xy 394.010658 -343.54066) (xy 394.025044 -343.555049)
			(xy 394.032826 -343.573848) (xy 394.033248 -343.584022) (xy 394.033248 -344.320622) (xy 395.842744 -344.320622)
			(xy 395.842744 -343.584022) (xy 395.843182 -343.573851) (xy 395.850961 -343.555056) (xy 395.865342 -343.54067)
			(xy 395.884135 -343.532885) (xy 395.894306 -343.53246) (xy 396.13713 -343.53246) (xy 396.466822 -343.748614)
			(xy 396.477857 -343.754123) (xy 396.502489 -343.754777) (xy 396.513812 -343.749884) (xy 396.828772 -343.544652)
			(xy 396.835122 -343.540588) (xy 396.83563 -343.54008) (xy 396.847822 -343.53246) (xy 397.090646 -343.53246)
			(xy 397.100809 -343.532896) (xy 397.119584 -343.54069) (xy 397.133948 -343.555073) (xy 397.141717 -343.573858)
			(xy 397.142208 -343.584022) (xy 397.142208 -344.320622) (xy 398.951704 -344.320622) (xy 398.951704 -343.584022)
			(xy 398.95225 -343.57387) (xy 398.960011 -343.555108) (xy 398.974361 -343.540743) (xy 398.993114 -343.532961)
			(xy 399.003266 -343.53246) (xy 399.24609 -343.53246) (xy 399.575782 -343.748614) (xy 399.586828 -343.754096)
			(xy 399.61145 -343.754767) (xy 399.622772 -343.749884) (xy 399.937732 -343.544652) (xy 399.944082 -343.540588)
			(xy 399.94459 -343.54008) (xy 399.956782 -343.53246) (xy 400.199606 -343.53246) (xy 400.209781 -343.53286)
			(xy 400.22858 -343.540651) (xy 400.242965 -343.555044) (xy 400.250746 -343.573847) (xy 400.251168 -343.584022)
			(xy 400.251168 -344.320622) (xy 402.060664 -344.320622) (xy 402.060664 -343.584022) (xy 402.061083 -343.573849)
			(xy 402.068865 -343.55505) (xy 402.083253 -343.540663) (xy 402.102053 -343.532882) (xy 402.112226 -343.53246)
			(xy 402.35505 -343.53246) (xy 402.684742 -343.748614) (xy 402.695772 -343.754136) (xy 402.720409 -343.754782)
			(xy 402.731732 -343.749884) (xy 403.046692 -343.544652) (xy 403.053042 -343.540588) (xy 403.05355 -343.54008)
			(xy 403.065742 -343.53246) (xy 403.308566 -343.53246) (xy 403.318738 -343.532892) (xy 403.337536 -343.54067)
			(xy 403.351923 -343.555054) (xy 403.359705 -343.57385) (xy 403.360128 -343.584022) (xy 403.360128 -344.320622)
			(xy 409.078176 -344.320622) (xy 409.078176 -343.584022) (xy 409.078583 -343.573847) (xy 409.086368 -343.555046)
			(xy 409.100759 -343.540659) (xy 409.119563 -343.53288) (xy 409.129738 -343.53246) (xy 409.372562 -343.53246)
			(xy 409.702254 -343.748614) (xy 409.713307 -343.754077) (xy 409.737922 -343.754761) (xy 409.749244 -343.749884)
			(xy 410.064204 -343.544652) (xy 410.070554 -343.540588) (xy 410.071062 -343.54008) (xy 410.083254 -343.53246)
			(xy 410.326078 -343.53246) (xy 410.336251 -343.532883) (xy 410.355049 -343.540664) (xy 410.369436 -343.555051)
			(xy 410.377217 -343.573849) (xy 410.37764 -343.584022) (xy 410.37764 -344.320622) (xy 412.187136 -344.320622)
			(xy 412.187136 -343.584022) (xy 412.187582 -343.573852) (xy 412.195359 -343.555058) (xy 412.209738 -343.540673)
			(xy 412.228528 -343.532887) (xy 412.238698 -343.53246) (xy 412.481522 -343.53246) (xy 412.811214 -343.748614)
			(xy 412.822251 -343.754118) (xy 412.846881 -343.754775) (xy 412.858204 -343.749884) (xy 413.173164 -343.544652)
			(xy 413.179514 -343.540588) (xy 413.180022 -343.54008) (xy 413.192214 -343.53246) (xy 413.435038 -343.53246)
			(xy 413.445201 -343.532903) (xy 413.463975 -343.540694) (xy 413.47834 -343.555075) (xy 413.486109 -343.573858)
			(xy 413.4866 -343.584022) (xy 413.4866 -344.320622) (xy 415.296096 -344.320622) (xy 415.296096 -343.584022)
			(xy 415.29665 -343.573871) (xy 415.30441 -343.55511) (xy 415.318756 -343.540746) (xy 415.337507 -343.532963)
			(xy 415.347658 -343.53246) (xy 415.590482 -343.53246) (xy 415.920174 -343.748614) (xy 415.931222 -343.754091)
			(xy 415.955842 -343.754765) (xy 415.967164 -343.749884) (xy 416.282124 -343.544652) (xy 416.288474 -343.540588)
			(xy 416.288982 -343.54008) (xy 416.301174 -343.53246) (xy 416.543998 -343.53246) (xy 416.554172 -343.532866)
			(xy 416.572971 -343.540654) (xy 416.587357 -343.555046) (xy 416.595138 -343.573848) (xy 416.59556 -343.584022)
			(xy 416.59556 -344.320622) (xy 418.405056 -344.320622) (xy 418.405056 -343.584022) (xy 418.405483 -343.57385)
			(xy 418.413264 -343.555052) (xy 418.427649 -343.540666) (xy 418.446446 -343.532883) (xy 418.456618 -343.53246)
			(xy 418.699442 -343.53246) (xy 419.029134 -343.748614) (xy 419.040166 -343.754131) (xy 419.064801 -343.75478)
			(xy 419.076124 -343.749884) (xy 419.391084 -343.544652) (xy 419.397434 -343.540588) (xy 419.397942 -343.54008)
			(xy 419.410134 -343.53246) (xy 419.652958 -343.53246) (xy 419.66313 -343.532899) (xy 419.681928 -343.540674)
			(xy 419.696315 -343.555056) (xy 419.704097 -343.573851) (xy 419.70452 -343.584022) (xy 419.70452 -344.320622)
			(xy 421.514016 -344.320622) (xy 421.514016 -343.584022) (xy 421.514551 -343.573868) (xy 421.522314 -343.555104)
			(xy 421.536667 -343.540739) (xy 421.555425 -343.532959) (xy 421.565578 -343.53246) (xy 421.808402 -343.53246)
			(xy 422.138094 -343.748614) (xy 422.149136 -343.754104) (xy 422.173762 -343.75477) (xy 422.185084 -343.749884)
			(xy 422.500044 -343.544652) (xy 422.506394 -343.540588) (xy 422.506902 -343.54008) (xy 422.519094 -343.53246)
			(xy 422.761918 -343.53246) (xy 422.772093 -343.53285) (xy 422.790893 -343.540645) (xy 422.805278 -343.555041)
			(xy 422.813058 -343.573846) (xy 422.81348 -343.584022) (xy 422.81348 -344.320622) (xy 424.622976 -344.320622)
			(xy 424.622976 -343.584022) (xy 424.623383 -343.573847) (xy 424.631168 -343.555046) (xy 424.645559 -343.540659)
			(xy 424.664363 -343.53288) (xy 424.674538 -343.53246) (xy 424.917362 -343.53246) (xy 425.247054 -343.748614)
			(xy 425.258107 -343.754077) (xy 425.282722 -343.754761) (xy 425.294044 -343.749884) (xy 425.609004 -343.544652)
			(xy 425.615354 -343.540588) (xy 425.615862 -343.54008) (xy 425.628054 -343.53246) (xy 425.870878 -343.53246)
			(xy 425.881051 -343.532883) (xy 425.899849 -343.540664) (xy 425.914236 -343.555051) (xy 425.922017 -343.573849)
			(xy 425.92244 -343.584022) (xy 425.92244 -344.320622) (xy 427.731936 -344.320622) (xy 427.731936 -343.584022)
			(xy 427.732382 -343.573852) (xy 427.740159 -343.555058) (xy 427.754538 -343.540673) (xy 427.773328 -343.532887)
			(xy 427.783498 -343.53246) (xy 428.026322 -343.53246) (xy 428.356014 -343.748614) (xy 428.367051 -343.754118)
			(xy 428.391681 -343.754775) (xy 428.403004 -343.749884) (xy 428.717964 -343.544652) (xy 428.724314 -343.540588)
			(xy 428.724822 -343.54008) (xy 428.737014 -343.53246) (xy 428.979838 -343.53246) (xy 428.990001 -343.532903)
			(xy 429.008775 -343.540694) (xy 429.02314 -343.555075) (xy 429.030909 -343.573858) (xy 429.0314 -343.584022)
			(xy 429.0314 -344.320622) (xy 430.840896 -344.320622) (xy 430.840896 -343.584022) (xy 430.84145 -343.573871)
			(xy 430.84921 -343.55511) (xy 430.863556 -343.540746) (xy 430.882307 -343.532963) (xy 430.892458 -343.53246)
			(xy 431.135282 -343.53246) (xy 431.464974 -343.748614) (xy 431.476022 -343.754091) (xy 431.500642 -343.754765)
			(xy 431.511964 -343.749884) (xy 431.826924 -343.544652) (xy 431.833274 -343.540588) (xy 431.833782 -343.54008)
			(xy 431.845974 -343.53246) (xy 432.088798 -343.53246) (xy 432.098972 -343.532866) (xy 432.117771 -343.540654)
			(xy 432.132157 -343.555046) (xy 432.139938 -343.573848) (xy 432.14036 -343.584022) (xy 432.14036 -344.320622)
			(xy 433.949856 -344.320622) (xy 433.949856 -343.584022) (xy 433.950283 -343.57385) (xy 433.958064 -343.555052)
			(xy 433.972449 -343.540666) (xy 433.991246 -343.532883) (xy 434.001418 -343.53246) (xy 434.244242 -343.53246)
			(xy 434.573934 -343.748614) (xy 434.584966 -343.754131) (xy 434.609601 -343.75478) (xy 434.620924 -343.749884)
			(xy 434.935884 -343.544652) (xy 434.942234 -343.540588) (xy 434.942742 -343.54008) (xy 434.954934 -343.53246)
			(xy 435.197758 -343.53246) (xy 435.20793 -343.532899) (xy 435.226728 -343.540674) (xy 435.241115 -343.555056)
			(xy 435.248897 -343.573851) (xy 435.24932 -343.584022) (xy 435.24932 -344.320622) (xy 437.058816 -344.320622)
			(xy 437.058816 -343.584022) (xy 437.059351 -343.573868) (xy 437.067114 -343.555104) (xy 437.081467 -343.540739)
			(xy 437.100225 -343.532959) (xy 437.110378 -343.53246) (xy 437.353202 -343.53246) (xy 437.682894 -343.748614)
			(xy 437.693936 -343.754104) (xy 437.718562 -343.75477) (xy 437.729884 -343.749884) (xy 438.044844 -343.544652)
			(xy 438.051194 -343.540588) (xy 438.051702 -343.54008) (xy 438.063894 -343.53246) (xy 438.306718 -343.53246)
			(xy 438.316893 -343.53285) (xy 438.335693 -343.540645) (xy 438.350078 -343.555041) (xy 438.357858 -343.573846)
			(xy 438.35828 -343.584022) (xy 438.35828 -344.320622) (xy 440.167776 -344.320622) (xy 440.167776 -343.584022)
			(xy 440.168183 -343.573847) (xy 440.175968 -343.555046) (xy 440.190359 -343.540659) (xy 440.209163 -343.53288)
			(xy 440.219338 -343.53246) (xy 440.462162 -343.53246) (xy 440.791854 -343.748614) (xy 440.802907 -343.754077)
			(xy 440.827522 -343.754761) (xy 440.838844 -343.749884) (xy 441.153804 -343.544652) (xy 441.160154 -343.540588)
			(xy 441.160662 -343.54008) (xy 441.172854 -343.53246) (xy 441.415678 -343.53246) (xy 441.425851 -343.532883)
			(xy 441.444649 -343.540664) (xy 441.459036 -343.555051) (xy 441.466817 -343.573849) (xy 441.46724 -343.584022)
			(xy 441.46724 -344.320622) (xy 441.466784 -344.330784) (xy 441.458998 -344.349558) (xy 441.444621 -344.363923)
			(xy 441.42584 -344.371693) (xy 441.415678 -344.372184) (xy 441.172854 -344.372184) (xy 440.84113 -344.155522)
			(xy 440.829991 -344.150484) (xy 440.805583 -344.150344) (xy 440.794394 -344.155268) (xy 440.463432 -344.372184)
			(xy 440.219338 -344.372184) (xy 440.209172 -344.371706) (xy 440.190382 -344.363937) (xy 440.175997 -344.349568)
			(xy 440.168206 -344.330788) (xy 440.167776 -344.320622) (xy 438.35828 -344.320622) (xy 438.357785 -344.330779)
			(xy 438.350007 -344.349545) (xy 438.335642 -344.363909) (xy 438.316875 -344.371686) (xy 438.306718 -344.372184)
			(xy 438.063894 -344.372184) (xy 437.73217 -344.155522) (xy 437.721045 -344.150444) (xy 437.696624 -344.15033)
			(xy 437.685434 -344.155268) (xy 437.354472 -344.372184) (xy 437.110378 -344.372184) (xy 437.100222 -344.371685)
			(xy 437.081456 -344.363908) (xy 437.067092 -344.349544) (xy 437.059315 -344.330778) (xy 437.058816 -344.320622)
			(xy 435.24932 -344.320622) (xy 435.248953 -344.3308) (xy 435.241153 -344.349603) (xy 435.22675 -344.363989)
			(xy 435.207937 -344.371766) (xy 435.197758 -344.372184) (xy 434.954934 -344.372184) (xy 434.62321 -344.155522)
			(xy 434.612076 -344.150471) (xy 434.587663 -344.15034) (xy 434.576474 -344.155268) (xy 434.245512 -344.372184)
			(xy 434.001418 -344.372184) (xy 433.991264 -344.371653) (xy 433.972499 -344.363888) (xy 433.958134 -344.349534)
			(xy 433.950355 -344.330776) (xy 433.949856 -344.320622) (xy 432.14036 -344.320622) (xy 432.139885 -344.330781)
			(xy 432.132103 -344.349552) (xy 432.117731 -344.363916) (xy 432.098958 -344.37169) (xy 432.088798 -344.372184)
			(xy 431.845974 -344.372184) (xy 431.51425 -344.155522) (xy 431.503106 -344.150497) (xy 431.478703 -344.150349)
			(xy 431.467514 -344.155268) (xy 431.136552 -344.372184) (xy 430.892458 -344.372184) (xy 430.8823 -344.371702)
			(xy 430.863534 -344.363917) (xy 430.849171 -344.349549) (xy 430.841395 -344.33078) (xy 430.840896 -344.320622)
			(xy 429.0314 -344.320622) (xy 429.030886 -344.330777) (xy 429.023111 -344.349539) (xy 429.008752 -344.363902)
			(xy 428.989992 -344.371683) (xy 428.979838 -344.372184) (xy 428.737014 -344.372184) (xy 428.40529 -344.155522)
			(xy 428.39416 -344.150457) (xy 428.369744 -344.150335) (xy 428.358554 -344.155268) (xy 428.027592 -344.372184)
			(xy 427.783498 -344.372184) (xy 427.773343 -344.371669) (xy 427.754578 -344.363898) (xy 427.740213 -344.349539)
			(xy 427.732435 -344.330777) (xy 427.731936 -344.320622) (xy 425.92244 -344.320622) (xy 425.921984 -344.330784)
			(xy 425.914198 -344.349558) (xy 425.899821 -344.363923) (xy 425.88104 -344.371693) (xy 425.870878 -344.372184)
			(xy 425.628054 -344.372184) (xy 425.29633 -344.155522) (xy 425.285191 -344.150484) (xy 425.260783 -344.150344)
			(xy 425.249594 -344.155268) (xy 424.918632 -344.372184) (xy 424.674538 -344.372184) (xy 424.664372 -344.371706)
			(xy 424.645582 -344.363937) (xy 424.631197 -344.349568) (xy 424.623406 -344.330788) (xy 424.622976 -344.320622)
			(xy 422.81348 -344.320622) (xy 422.812985 -344.330779) (xy 422.805207 -344.349545) (xy 422.790842 -344.363909)
			(xy 422.772075 -344.371686) (xy 422.761918 -344.372184) (xy 422.519094 -344.372184) (xy 422.18737 -344.155522)
			(xy 422.176245 -344.150444) (xy 422.151824 -344.15033) (xy 422.140634 -344.155268) (xy 421.809672 -344.372184)
			(xy 421.565578 -344.372184) (xy 421.555422 -344.371685) (xy 421.536656 -344.363908) (xy 421.522292 -344.349544)
			(xy 421.514515 -344.330778) (xy 421.514016 -344.320622) (xy 419.70452 -344.320622) (xy 419.704153 -344.3308)
			(xy 419.696353 -344.349603) (xy 419.68195 -344.363989) (xy 419.663137 -344.371766) (xy 419.652958 -344.372184)
			(xy 419.410134 -344.372184) (xy 419.07841 -344.155522) (xy 419.067276 -344.150471) (xy 419.042863 -344.15034)
			(xy 419.031674 -344.155268) (xy 418.700712 -344.372184) (xy 418.456618 -344.372184) (xy 418.446464 -344.371653)
			(xy 418.427699 -344.363888) (xy 418.413334 -344.349534) (xy 418.405555 -344.330776) (xy 418.405056 -344.320622)
			(xy 416.59556 -344.320622) (xy 416.595085 -344.330781) (xy 416.587303 -344.349552) (xy 416.572931 -344.363916)
			(xy 416.554158 -344.37169) (xy 416.543998 -344.372184) (xy 416.301174 -344.372184) (xy 415.96945 -344.155522)
			(xy 415.958306 -344.150497) (xy 415.933903 -344.150349) (xy 415.922714 -344.155268) (xy 415.591752 -344.372184)
			(xy 415.347658 -344.372184) (xy 415.3375 -344.371702) (xy 415.318734 -344.363917) (xy 415.304371 -344.349549)
			(xy 415.296595 -344.33078) (xy 415.296096 -344.320622) (xy 413.4866 -344.320622) (xy 413.486086 -344.330777)
			(xy 413.478311 -344.349539) (xy 413.463952 -344.363902) (xy 413.445192 -344.371683) (xy 413.435038 -344.372184)
			(xy 413.192214 -344.372184) (xy 412.86049 -344.155522) (xy 412.84936 -344.150457) (xy 412.824944 -344.150335)
			(xy 412.813754 -344.155268) (xy 412.482792 -344.372184) (xy 412.238698 -344.372184) (xy 412.228543 -344.371669)
			(xy 412.209778 -344.363898) (xy 412.195413 -344.349539) (xy 412.187635 -344.330777) (xy 412.187136 -344.320622)
			(xy 410.37764 -344.320622) (xy 410.377184 -344.330784) (xy 410.369398 -344.349558) (xy 410.355021 -344.363923)
			(xy 410.33624 -344.371693) (xy 410.326078 -344.372184) (xy 410.083254 -344.372184) (xy 409.75153 -344.155522)
			(xy 409.740391 -344.150484) (xy 409.715983 -344.150344) (xy 409.704794 -344.155268) (xy 409.373832 -344.372184)
			(xy 409.129738 -344.372184) (xy 409.119572 -344.371706) (xy 409.100782 -344.363937) (xy 409.086397 -344.349568)
			(xy 409.078606 -344.330788) (xy 409.078176 -344.320622) (xy 403.360128 -344.320622) (xy 403.359753 -344.330799)
			(xy 403.351955 -344.349601) (xy 403.337554 -344.363986) (xy 403.318744 -344.371764) (xy 403.308566 -344.372184)
			(xy 403.065742 -344.372184) (xy 402.734018 -344.155522) (xy 402.722882 -344.150476) (xy 402.698471 -344.150342)
			(xy 402.687282 -344.155268) (xy 402.35632 -344.372184) (xy 402.112226 -344.372184) (xy 402.102059 -344.371715)
			(xy 402.083269 -344.363943) (xy 402.068884 -344.349571) (xy 402.061094 -344.330789) (xy 402.060664 -344.320622)
			(xy 400.251168 -344.320622) (xy 400.250685 -344.33078) (xy 400.242904 -344.349549) (xy 400.228536 -344.363913)
			(xy 400.209765 -344.371688) (xy 400.199606 -344.372184) (xy 399.956782 -344.372184) (xy 399.625058 -344.155522)
			(xy 399.613912 -344.150503) (xy 399.589511 -344.150351) (xy 399.578322 -344.155268) (xy 399.24736 -344.372184)
			(xy 399.003266 -344.372184) (xy 398.993109 -344.371695) (xy 398.974343 -344.363914) (xy 398.95998 -344.349547)
			(xy 398.952203 -344.330779) (xy 398.951704 -344.320622) (xy 397.142208 -344.320622) (xy 397.141686 -344.330776)
			(xy 397.133913 -344.349536) (xy 397.119557 -344.363899) (xy 397.100799 -344.371681) (xy 397.090646 -344.372184)
			(xy 396.847822 -344.372184) (xy 396.516098 -344.155522) (xy 396.504967 -344.150463) (xy 396.480551 -344.150336)
			(xy 396.469362 -344.155268) (xy 396.1384 -344.372184) (xy 395.894306 -344.372184) (xy 395.884151 -344.371662)
			(xy 395.865387 -344.363894) (xy 395.851022 -344.349537) (xy 395.843243 -344.330776) (xy 395.842744 -344.320622)
			(xy 394.033248 -344.320622) (xy 394.032784 -344.330783) (xy 394.025 -344.349555) (xy 394.010625 -344.36392)
			(xy 393.991847 -344.371692) (xy 393.981686 -344.372184) (xy 393.738862 -344.372184) (xy 393.407138 -344.155522)
			(xy 393.395997 -344.150489) (xy 393.371591 -344.150346) (xy 393.360402 -344.155268) (xy 393.02944 -344.372184)
			(xy 392.785346 -344.372184) (xy 392.77518 -344.371699) (xy 392.756391 -344.363933) (xy 392.742005 -344.349567)
			(xy 392.734214 -344.330787) (xy 392.733784 -344.320622) (xy 390.924288 -344.320622) (xy 390.923785 -344.330778)
			(xy 390.916009 -344.349543) (xy 390.901646 -344.363906) (xy 390.882882 -344.371685) (xy 390.872726 -344.372184)
			(xy 390.629902 -344.372184) (xy 390.298178 -344.155522) (xy 390.287051 -344.150449) (xy 390.262632 -344.150332)
			(xy 390.251442 -344.155268) (xy 389.92048 -344.372184) (xy 389.676386 -344.372184) (xy 389.66623 -344.371678)
			(xy 389.647465 -344.363903) (xy 389.633101 -344.349542) (xy 389.625323 -344.330778) (xy 389.624824 -344.320622)
			(xy 387.815328 -344.320622) (xy 387.814953 -344.330799) (xy 387.807155 -344.349601) (xy 387.792754 -344.363986)
			(xy 387.773944 -344.371764) (xy 387.763766 -344.372184) (xy 387.520942 -344.372184) (xy 387.189218 -344.155522)
			(xy 387.178082 -344.150476) (xy 387.153671 -344.150342) (xy 387.142482 -344.155268) (xy 386.81152 -344.372184)
			(xy 386.567426 -344.372184) (xy 386.557259 -344.371715) (xy 386.538469 -344.363943) (xy 386.524084 -344.349571)
			(xy 386.516294 -344.330789) (xy 386.515864 -344.320622) (xy 384.706368 -344.320622) (xy 384.705885 -344.33078)
			(xy 384.698104 -344.349549) (xy 384.683736 -344.363913) (xy 384.664965 -344.371688) (xy 384.654806 -344.372184)
			(xy 384.411982 -344.372184) (xy 384.080258 -344.155522) (xy 384.069112 -344.150503) (xy 384.044711 -344.150351)
			(xy 384.033522 -344.155268) (xy 383.70256 -344.372184) (xy 383.458466 -344.372184) (xy 383.448309 -344.371695)
			(xy 383.429543 -344.363914) (xy 383.41518 -344.349547) (xy 383.407403 -344.330779) (xy 383.406904 -344.320622)
			(xy 381.597408 -344.320622) (xy 381.596886 -344.330776) (xy 381.589113 -344.349536) (xy 381.574757 -344.363899)
			(xy 381.555999 -344.371681) (xy 381.545846 -344.372184) (xy 381.303022 -344.372184) (xy 380.971298 -344.155522)
			(xy 380.960167 -344.150463) (xy 380.935751 -344.150336) (xy 380.924562 -344.155268) (xy 380.5936 -344.372184)
			(xy 380.349506 -344.372184) (xy 380.339351 -344.371662) (xy 380.320587 -344.363894) (xy 380.306222 -344.349537)
			(xy 380.298443 -344.330776) (xy 380.297944 -344.320622) (xy 378.488448 -344.320622) (xy 378.487984 -344.330783)
			(xy 378.4802 -344.349555) (xy 378.465825 -344.36392) (xy 378.447047 -344.371692) (xy 378.436886 -344.372184)
			(xy 378.194062 -344.372184) (xy 377.862338 -344.155522) (xy 377.851197 -344.150489) (xy 377.826791 -344.150346)
			(xy 377.815602 -344.155268) (xy 377.48464 -344.372184) (xy 377.240546 -344.372184) (xy 377.23038 -344.371699)
			(xy 377.211591 -344.363933) (xy 377.197205 -344.349567) (xy 377.189414 -344.330787) (xy 377.188984 -344.320622)
			(xy 375.379488 -344.320622) (xy 375.378985 -344.330778) (xy 375.371209 -344.349543) (xy 375.356846 -344.363906)
			(xy 375.338082 -344.371685) (xy 375.327926 -344.372184) (xy 375.085102 -344.372184) (xy 374.753378 -344.155522)
			(xy 374.742251 -344.150449) (xy 374.717832 -344.150332) (xy 374.706642 -344.155268) (xy 374.37568 -344.372184)
			(xy 374.131586 -344.372184) (xy 374.12143 -344.371678) (xy 374.102665 -344.363903) (xy 374.088301 -344.349542)
			(xy 374.080523 -344.330778) (xy 374.080024 -344.320622) (xy 372.270528 -344.320622) (xy 372.270153 -344.330799)
			(xy 372.262355 -344.349601) (xy 372.247954 -344.363986) (xy 372.229144 -344.371764) (xy 372.218966 -344.372184)
			(xy 371.976142 -344.372184) (xy 371.644418 -344.155522) (xy 371.633282 -344.150476) (xy 371.608871 -344.150342)
			(xy 371.597682 -344.155268) (xy 371.26672 -344.372184) (xy 371.022626 -344.372184) (xy 371.012459 -344.371715)
			(xy 370.993669 -344.363943) (xy 370.979284 -344.349571) (xy 370.971494 -344.330789) (xy 370.971064 -344.320622)
			(xy 344.674952 -344.320622) (xy 344.674485 -344.330782) (xy 344.666701 -344.349554) (xy 344.652327 -344.363919)
			(xy 344.633551 -344.371691) (xy 344.62339 -344.372184) (xy 344.380566 -344.372184) (xy 344.048842 -344.155522)
			(xy 344.0377 -344.150492) (xy 344.013295 -344.150347) (xy 344.002106 -344.155268) (xy 343.671144 -344.372184)
			(xy 343.42705 -344.372184) (xy 343.416884 -344.371696) (xy 343.398095 -344.363931) (xy 343.383709 -344.349566)
			(xy 343.375918 -344.330787) (xy 343.375488 -344.320622) (xy 341.565992 -344.320622) (xy 341.565486 -344.330778)
			(xy 341.557709 -344.349541) (xy 341.543348 -344.363905) (xy 341.524585 -344.371684) (xy 341.51443 -344.372184)
			(xy 341.271606 -344.372184) (xy 340.939882 -344.155522) (xy 340.928754 -344.150452) (xy 340.904336 -344.150333)
			(xy 340.893146 -344.155268) (xy 340.562184 -344.372184) (xy 340.31809 -344.372184) (xy 340.307934 -344.371675)
			(xy 340.289169 -344.363902) (xy 340.274805 -344.349541) (xy 340.267027 -344.330778) (xy 340.266528 -344.320622)
			(xy 338.457032 -344.320622) (xy 338.456653 -344.330799) (xy 338.448855 -344.3496) (xy 338.434456 -344.363985)
			(xy 338.415647 -344.371763) (xy 338.40547 -344.372184) (xy 338.162646 -344.372184) (xy 337.830922 -344.155522)
			(xy 337.819785 -344.150479) (xy 337.795375 -344.150342) (xy 337.784186 -344.155268) (xy 337.453224 -344.372184)
			(xy 337.20913 -344.372184) (xy 337.198963 -344.371712) (xy 337.180173 -344.363941) (xy 337.165788 -344.34957)
			(xy 337.157998 -344.330788) (xy 337.157568 -344.320622) (xy 335.348072 -344.320622) (xy 335.347585 -344.33078)
			(xy 335.339805 -344.349548) (xy 335.325438 -344.363912) (xy 335.306668 -344.371687) (xy 335.29651 -344.372184)
			(xy 335.053686 -344.372184) (xy 334.721962 -344.155522) (xy 334.710815 -344.150505) (xy 334.686415 -344.150352)
			(xy 334.675226 -344.155268) (xy 334.344264 -344.372184) (xy 334.10017 -344.372184) (xy 334.090013 -344.371692)
			(xy 334.071247 -344.363912) (xy 334.056884 -344.349546) (xy 334.049107 -344.330779) (xy 334.048608 -344.320622)
			(xy 332.239112 -344.320622) (xy 332.238753 -344.330801) (xy 332.230951 -344.349606) (xy 332.216545 -344.363992)
			(xy 332.19773 -344.371767) (xy 332.18755 -344.372184) (xy 331.944726 -344.372184) (xy 331.613002 -344.155522)
			(xy 331.60187 -344.150466) (xy 331.577456 -344.150338) (xy 331.566266 -344.155268) (xy 331.235304 -344.372184)
			(xy 330.99121 -344.372184) (xy 330.981056 -344.371659) (xy 330.962291 -344.363892) (xy 330.947926 -344.349536)
			(xy 330.940147 -344.330776) (xy 330.939648 -344.320622) (xy 329.130152 -344.320622) (xy 329.129685 -344.330782)
			(xy 329.121901 -344.349554) (xy 329.107527 -344.363919) (xy 329.088751 -344.371691) (xy 329.07859 -344.372184)
			(xy 328.835766 -344.372184) (xy 328.504042 -344.155522) (xy 328.4929 -344.150492) (xy 328.468495 -344.150347)
			(xy 328.457306 -344.155268) (xy 328.126344 -344.372184) (xy 327.88225 -344.372184) (xy 327.872084 -344.371696)
			(xy 327.853295 -344.363931) (xy 327.838909 -344.349566) (xy 327.831118 -344.330787) (xy 327.830688 -344.320622)
			(xy 326.021192 -344.320622) (xy 326.020686 -344.330778) (xy 326.012909 -344.349541) (xy 325.998548 -344.363905)
			(xy 325.979785 -344.371684) (xy 325.96963 -344.372184) (xy 325.726806 -344.372184) (xy 325.395082 -344.155522)
			(xy 325.383954 -344.150452) (xy 325.359536 -344.150333) (xy 325.348346 -344.155268) (xy 325.017384 -344.372184)
			(xy 324.77329 -344.372184) (xy 324.763134 -344.371675) (xy 324.744369 -344.363902) (xy 324.730005 -344.349541)
			(xy 324.722227 -344.330778) (xy 324.721728 -344.320622) (xy 322.912232 -344.320622) (xy 322.911853 -344.330799)
			(xy 322.904055 -344.3496) (xy 322.889656 -344.363985) (xy 322.870847 -344.371763) (xy 322.86067 -344.372184)
			(xy 322.617846 -344.372184) (xy 322.286122 -344.155522) (xy 322.274985 -344.150479) (xy 322.250575 -344.150342)
			(xy 322.239386 -344.155268) (xy 321.908424 -344.372184) (xy 321.66433 -344.372184) (xy 321.654163 -344.371712)
			(xy 321.635373 -344.363941) (xy 321.620988 -344.34957) (xy 321.613198 -344.330788) (xy 321.612768 -344.320622)
			(xy 319.803272 -344.320622) (xy 319.802785 -344.33078) (xy 319.795005 -344.349548) (xy 319.780638 -344.363912)
			(xy 319.761868 -344.371687) (xy 319.75171 -344.372184) (xy 319.508886 -344.372184) (xy 319.177162 -344.155522)
			(xy 319.166015 -344.150505) (xy 319.141615 -344.150352) (xy 319.130426 -344.155268) (xy 318.799464 -344.372184)
			(xy 318.55537 -344.372184) (xy 318.545213 -344.371692) (xy 318.526447 -344.363912) (xy 318.512084 -344.349546)
			(xy 318.504307 -344.330779) (xy 318.503808 -344.320622) (xy 316.694312 -344.320622) (xy 316.693953 -344.330801)
			(xy 316.686151 -344.349606) (xy 316.671745 -344.363992) (xy 316.65293 -344.371767) (xy 316.64275 -344.372184)
			(xy 316.399926 -344.372184) (xy 316.068202 -344.155522) (xy 316.05707 -344.150466) (xy 316.032656 -344.150338)
			(xy 316.021466 -344.155268) (xy 315.690504 -344.372184) (xy 315.44641 -344.372184) (xy 315.436256 -344.371659)
			(xy 315.417491 -344.363892) (xy 315.403126 -344.349536) (xy 315.395347 -344.330776) (xy 315.394848 -344.320622)
			(xy 313.585352 -344.320622) (xy 313.584885 -344.330782) (xy 313.577101 -344.349554) (xy 313.562727 -344.363919)
			(xy 313.543951 -344.371691) (xy 313.53379 -344.372184) (xy 313.290966 -344.372184) (xy 312.959242 -344.155522)
			(xy 312.9481 -344.150492) (xy 312.923695 -344.150347) (xy 312.912506 -344.155268) (xy 312.581544 -344.372184)
			(xy 312.33745 -344.372184) (xy 312.327284 -344.371696) (xy 312.308495 -344.363931) (xy 312.294109 -344.349566)
			(xy 312.286318 -344.330787) (xy 312.285888 -344.320622) (xy 300.069504 -344.320622) (xy 300.069049 -344.330821)
			(xy 300.061217 -344.349657) (xy 300.04676 -344.364049) (xy 300.027889 -344.371795) (xy 300.017688 -344.372184)
			(xy 299.774864 -344.372184) (xy 299.44314 -344.155522) (xy 299.431998 -344.150491) (xy 299.407593 -344.150347)
			(xy 299.396404 -344.155268) (xy 299.065442 -344.372184) (xy 298.821348 -344.372184) (xy 298.811171 -344.371685)
			(xy 298.792352 -344.363929) (xy 298.777923 -344.349574) (xy 298.770069 -344.330797) (xy 298.769532 -344.320622)
			(xy 296.960544 -344.320622) (xy 296.960148 -344.330829) (xy 296.952305 -344.349676) (xy 296.937829 -344.36407)
			(xy 296.918937 -344.371805) (xy 296.908728 -344.372184) (xy 296.665904 -344.372184) (xy 296.33418 -344.155522)
			(xy 296.323053 -344.150451) (xy 296.298634 -344.150332) (xy 296.287444 -344.155268) (xy 295.956482 -344.372184)
			(xy 295.712388 -344.372184) (xy 295.702207 -344.371734) (xy 295.683387 -344.363958) (xy 295.66896 -344.349589)
			(xy 295.661108 -344.330801) (xy 295.660572 -344.320622) (xy 293.851584 -344.320622) (xy 293.851149 -344.330824)
			(xy 293.843313 -344.349663) (xy 293.82885 -344.364056) (xy 293.809972 -344.371798) (xy 293.799768 -344.372184)
			(xy 293.556944 -344.372184) (xy 293.22522 -344.155522) (xy 293.214083 -344.150478) (xy 293.189673 -344.150342)
			(xy 293.178484 -344.155268) (xy 292.847522 -344.372184) (xy 292.603428 -344.372184) (xy 292.593249 -344.371701)
			(xy 292.574431 -344.363939) (xy 292.560001 -344.349579) (xy 292.552148 -344.330798) (xy 292.551612 -344.320622)
			(xy 290.742624 -344.320622) (xy 290.742248 -344.330831) (xy 290.734401 -344.349683) (xy 290.719918 -344.364077)
			(xy 290.70102 -344.371809) (xy 290.690808 -344.372184) (xy 290.447984 -344.372184) (xy 290.11626 -344.155522)
			(xy 290.105114 -344.150504) (xy 290.080713 -344.150351) (xy 290.069524 -344.155268) (xy 289.738562 -344.372184)
			(xy 289.494468 -344.372184) (xy 289.484285 -344.37175) (xy 289.465465 -344.363968) (xy 289.451038 -344.349594)
			(xy 289.443187 -344.330803) (xy 289.442652 -344.320622) (xy 287.633664 -344.320622) (xy 287.633248 -344.330826)
			(xy 287.625409 -344.34967) (xy 287.610939 -344.364063) (xy 287.592055 -344.371802) (xy 287.581848 -344.372184)
			(xy 287.339024 -344.372184) (xy 287.0073 -344.155522) (xy 286.996168 -344.150464) (xy 286.971754 -344.150337)
			(xy 286.960564 -344.155268) (xy 286.629602 -344.372184) (xy 286.385508 -344.372184) (xy 286.375328 -344.371718)
			(xy 286.356509 -344.363949) (xy 286.342081 -344.349584) (xy 286.334228 -344.3308) (xy 286.333692 -344.320622)
			(xy 284.524704 -344.320622) (xy 284.524249 -344.330821) (xy 284.516417 -344.349657) (xy 284.50196 -344.364049)
			(xy 284.483089 -344.371795) (xy 284.472888 -344.372184) (xy 284.230064 -344.372184) (xy 283.89834 -344.155522)
			(xy 283.887198 -344.150491) (xy 283.862793 -344.150347) (xy 283.851604 -344.155268) (xy 283.520642 -344.372184)
			(xy 283.276548 -344.372184) (xy 283.266371 -344.371685) (xy 283.247552 -344.363929) (xy 283.233123 -344.349574)
			(xy 283.225269 -344.330797) (xy 283.224732 -344.320622) (xy 281.415744 -344.320622) (xy 281.415348 -344.330829)
			(xy 281.407505 -344.349676) (xy 281.393029 -344.36407) (xy 281.374137 -344.371805) (xy 281.363928 -344.372184)
			(xy 281.121104 -344.372184) (xy 280.78938 -344.155522) (xy 280.778253 -344.150451) (xy 280.753834 -344.150332)
			(xy 280.742644 -344.155268) (xy 280.411682 -344.372184) (xy 280.167588 -344.372184) (xy 280.157407 -344.371734)
			(xy 280.138587 -344.363958) (xy 280.12416 -344.349589) (xy 280.116308 -344.330801) (xy 280.115772 -344.320622)
			(xy 278.306784 -344.320622) (xy 278.306349 -344.330824) (xy 278.298513 -344.349663) (xy 278.28405 -344.364056)
			(xy 278.265172 -344.371798) (xy 278.254968 -344.372184) (xy 278.012144 -344.372184) (xy 277.68042 -344.155522)
			(xy 277.669283 -344.150478) (xy 277.644873 -344.150342) (xy 277.633684 -344.155268) (xy 277.302722 -344.372184)
			(xy 277.058628 -344.372184) (xy 277.048449 -344.371701) (xy 277.029631 -344.363939) (xy 277.015201 -344.349579)
			(xy 277.007348 -344.330798) (xy 277.006812 -344.320622) (xy 275.197824 -344.320622) (xy 275.197448 -344.330831)
			(xy 275.189601 -344.349683) (xy 275.175118 -344.364077) (xy 275.15622 -344.371809) (xy 275.146008 -344.372184)
			(xy 274.903184 -344.372184) (xy 274.57146 -344.155522) (xy 274.560314 -344.150504) (xy 274.535913 -344.150351)
			(xy 274.524724 -344.155268) (xy 274.193762 -344.372184) (xy 273.949668 -344.372184) (xy 273.939485 -344.37175)
			(xy 273.920665 -344.363968) (xy 273.906238 -344.349594) (xy 273.898387 -344.330803) (xy 273.897852 -344.320622)
			(xy 272.088864 -344.320622) (xy 272.088448 -344.330826) (xy 272.080609 -344.34967) (xy 272.066139 -344.364063)
			(xy 272.047255 -344.371802) (xy 272.037048 -344.372184) (xy 271.794224 -344.372184) (xy 271.4625 -344.155522)
			(xy 271.451368 -344.150464) (xy 271.426954 -344.150337) (xy 271.415764 -344.155268) (xy 271.084802 -344.372184)
			(xy 270.840708 -344.372184) (xy 270.830528 -344.371718) (xy 270.811709 -344.363949) (xy 270.797281 -344.349584)
			(xy 270.789428 -344.3308) (xy 270.788892 -344.320622) (xy 268.979904 -344.320622) (xy 268.979449 -344.330821)
			(xy 268.971617 -344.349657) (xy 268.95716 -344.364049) (xy 268.938289 -344.371795) (xy 268.928088 -344.372184)
			(xy 268.685264 -344.372184) (xy 268.35354 -344.155522) (xy 268.342398 -344.150491) (xy 268.317993 -344.150347)
			(xy 268.306804 -344.155268) (xy 267.975842 -344.372184) (xy 267.731748 -344.372184) (xy 267.721571 -344.371685)
			(xy 267.702752 -344.363929) (xy 267.688323 -344.349574) (xy 267.680469 -344.330797) (xy 267.679932 -344.320622)
			(xy 197.46722 -344.320622) (xy 197.466853 -344.3308) (xy 197.459053 -344.349603) (xy 197.44465 -344.363989)
			(xy 197.425837 -344.371766) (xy 197.415658 -344.372184) (xy 197.172834 -344.372184) (xy 196.84111 -344.155522)
			(xy 196.829976 -344.150471) (xy 196.805563 -344.15034) (xy 196.794374 -344.155268) (xy 196.463412 -344.372184)
			(xy 196.219318 -344.372184) (xy 196.209164 -344.371653) (xy 196.190399 -344.363888) (xy 196.176034 -344.349534)
			(xy 196.168255 -344.330776) (xy 196.167756 -344.320622) (xy 194.35826 -344.320622) (xy 194.357785 -344.330781)
			(xy 194.350003 -344.349552) (xy 194.335631 -344.363916) (xy 194.316858 -344.37169) (xy 194.306698 -344.372184)
			(xy 194.063874 -344.372184) (xy 193.73215 -344.155522) (xy 193.721006 -344.150497) (xy 193.696603 -344.150349)
			(xy 193.685414 -344.155268) (xy 193.354452 -344.372184) (xy 193.110358 -344.372184) (xy 193.1002 -344.371702)
			(xy 193.081434 -344.363917) (xy 193.067071 -344.349549) (xy 193.059295 -344.33078) (xy 193.058796 -344.320622)
			(xy 191.2493 -344.320622) (xy 191.248786 -344.330777) (xy 191.241011 -344.349539) (xy 191.226652 -344.363902)
			(xy 191.207892 -344.371683) (xy 191.197738 -344.372184) (xy 190.954914 -344.372184) (xy 190.62319 -344.155522)
			(xy 190.61206 -344.150457) (xy 190.587644 -344.150335) (xy 190.576454 -344.155268) (xy 190.245492 -344.372184)
			(xy 190.001398 -344.372184) (xy 189.991243 -344.371669) (xy 189.972478 -344.363898) (xy 189.958113 -344.349539)
			(xy 189.950335 -344.330777) (xy 189.949836 -344.320622) (xy 188.14034 -344.320622) (xy 188.139884 -344.330784)
			(xy 188.132098 -344.349558) (xy 188.117721 -344.363923) (xy 188.09894 -344.371693) (xy 188.088778 -344.372184)
			(xy 187.845954 -344.372184) (xy 187.51423 -344.155522) (xy 187.503091 -344.150484) (xy 187.478683 -344.150344)
			(xy 187.467494 -344.155268) (xy 187.136532 -344.372184) (xy 186.892438 -344.372184) (xy 186.882272 -344.371706)
			(xy 186.863482 -344.363937) (xy 186.849097 -344.349568) (xy 186.841306 -344.330788) (xy 186.840876 -344.320622)
			(xy 185.03138 -344.320622) (xy 185.030885 -344.330779) (xy 185.023107 -344.349545) (xy 185.008742 -344.363909)
			(xy 184.989975 -344.371686) (xy 184.979818 -344.372184) (xy 184.736994 -344.372184) (xy 184.40527 -344.155522)
			(xy 184.394145 -344.150444) (xy 184.369724 -344.15033) (xy 184.358534 -344.155268) (xy 184.027572 -344.372184)
			(xy 183.783478 -344.372184) (xy 183.773322 -344.371685) (xy 183.754556 -344.363908) (xy 183.740192 -344.349544)
			(xy 183.732415 -344.330778) (xy 183.731916 -344.320622) (xy 181.92242 -344.320622) (xy 181.922053 -344.3308)
			(xy 181.914253 -344.349603) (xy 181.89985 -344.363989) (xy 181.881037 -344.371766) (xy 181.870858 -344.372184)
			(xy 181.628034 -344.372184) (xy 181.29631 -344.155522) (xy 181.285176 -344.150471) (xy 181.260763 -344.15034)
			(xy 181.249574 -344.155268) (xy 180.918612 -344.372184) (xy 180.674518 -344.372184) (xy 180.664364 -344.371653)
			(xy 180.645599 -344.363888) (xy 180.631234 -344.349534) (xy 180.623455 -344.330776) (xy 180.622956 -344.320622)
			(xy 178.81346 -344.320622) (xy 178.812985 -344.330781) (xy 178.805203 -344.349552) (xy 178.790831 -344.363916)
			(xy 178.772058 -344.37169) (xy 178.761898 -344.372184) (xy 178.519074 -344.372184) (xy 178.18735 -344.155522)
			(xy 178.176206 -344.150497) (xy 178.151803 -344.150349) (xy 178.140614 -344.155268) (xy 177.809652 -344.372184)
			(xy 177.565558 -344.372184) (xy 177.5554 -344.371702) (xy 177.536634 -344.363917) (xy 177.522271 -344.349549)
			(xy 177.514495 -344.33078) (xy 177.513996 -344.320622) (xy 175.7045 -344.320622) (xy 175.703986 -344.330777)
			(xy 175.696211 -344.349539) (xy 175.681852 -344.363902) (xy 175.663092 -344.371683) (xy 175.652938 -344.372184)
			(xy 175.410114 -344.372184) (xy 175.07839 -344.155522) (xy 175.06726 -344.150457) (xy 175.042844 -344.150335)
			(xy 175.031654 -344.155268) (xy 174.700692 -344.372184) (xy 174.456598 -344.372184) (xy 174.446443 -344.371669)
			(xy 174.427678 -344.363898) (xy 174.413313 -344.349539) (xy 174.405535 -344.330777) (xy 174.405036 -344.320622)
			(xy 172.59554 -344.320622) (xy 172.595084 -344.330784) (xy 172.587298 -344.349558) (xy 172.572921 -344.363923)
			(xy 172.55414 -344.371693) (xy 172.543978 -344.372184) (xy 172.301154 -344.372184) (xy 171.96943 -344.155522)
			(xy 171.958291 -344.150484) (xy 171.933883 -344.150344) (xy 171.922694 -344.155268) (xy 171.591732 -344.372184)
			(xy 171.347638 -344.372184) (xy 171.337472 -344.371706) (xy 171.318682 -344.363937) (xy 171.304297 -344.349568)
			(xy 171.296506 -344.330788) (xy 171.296076 -344.320622) (xy 169.48658 -344.320622) (xy 169.486085 -344.330779)
			(xy 169.478307 -344.349545) (xy 169.463942 -344.363909) (xy 169.445175 -344.371686) (xy 169.435018 -344.372184)
			(xy 169.192194 -344.372184) (xy 168.86047 -344.155522) (xy 168.849345 -344.150444) (xy 168.824924 -344.15033)
			(xy 168.813734 -344.155268) (xy 168.482772 -344.372184) (xy 168.238678 -344.372184) (xy 168.228522 -344.371685)
			(xy 168.209756 -344.363908) (xy 168.195392 -344.349544) (xy 168.187615 -344.330778) (xy 168.187116 -344.320622)
			(xy 166.37762 -344.320622) (xy 166.377253 -344.3308) (xy 166.369453 -344.349603) (xy 166.35505 -344.363989)
			(xy 166.336237 -344.371766) (xy 166.326058 -344.372184) (xy 166.083234 -344.372184) (xy 165.75151 -344.155522)
			(xy 165.740376 -344.150471) (xy 165.715963 -344.15034) (xy 165.704774 -344.155268) (xy 165.373812 -344.372184)
			(xy 165.129718 -344.372184) (xy 165.119564 -344.371653) (xy 165.100799 -344.363888) (xy 165.086434 -344.349534)
			(xy 165.078655 -344.330776) (xy 165.078156 -344.320622) (xy 144.034256 -344.320622) (xy 144.033785 -344.330782)
			(xy 144.026002 -344.349553) (xy 144.011629 -344.363918) (xy 143.992854 -344.37169) (xy 143.982694 -344.372184)
			(xy 143.73987 -344.372184) (xy 143.408146 -344.155522) (xy 143.397003 -344.150495) (xy 143.372599 -344.150348)
			(xy 143.36141 -344.155268) (xy 143.030448 -344.372184) (xy 142.786354 -344.372184) (xy 142.776196 -344.371705)
			(xy 142.75743 -344.363919) (xy 142.743067 -344.34955) (xy 142.735291 -344.33078) (xy 142.734792 -344.320622)
			(xy 140.925296 -344.320622) (xy 140.924786 -344.330777) (xy 140.91701 -344.34954) (xy 140.90265 -344.363904)
			(xy 140.883889 -344.371683) (xy 140.873734 -344.372184) (xy 140.63091 -344.372184) (xy 140.299186 -344.155522)
			(xy 140.288057 -344.150455) (xy 140.26364 -344.150334) (xy 140.25245 -344.155268) (xy 139.921488 -344.372184)
			(xy 139.677394 -344.372184) (xy 139.667239 -344.371672) (xy 139.648474 -344.3639) (xy 139.634109 -344.34954)
			(xy 139.626331 -344.330777) (xy 139.625832 -344.320622) (xy 137.816336 -344.320622) (xy 137.815953 -344.330798)
			(xy 137.808156 -344.349598) (xy 137.793758 -344.363983) (xy 137.774951 -344.371763) (xy 137.764774 -344.372184)
			(xy 137.52195 -344.372184) (xy 137.190226 -344.155522) (xy 137.179088 -344.150482) (xy 137.154679 -344.150343)
			(xy 137.14349 -344.155268) (xy 136.812528 -344.372184) (xy 136.568434 -344.372184) (xy 136.558267 -344.371709)
			(xy 136.539478 -344.363939) (xy 136.525092 -344.349569) (xy 136.517302 -344.330788) (xy 136.516872 -344.320622)
			(xy 134.707376 -344.320622) (xy 134.706885 -344.330779) (xy 134.699106 -344.349547) (xy 134.68474 -344.363911)
			(xy 134.665972 -344.371687) (xy 134.655814 -344.372184) (xy 134.41299 -344.372184) (xy 134.081266 -344.155522)
			(xy 134.070142 -344.150442) (xy 134.04572 -344.150329) (xy 134.03453 -344.155268) (xy 133.703568 -344.372184)
			(xy 133.459474 -344.372184) (xy 133.449317 -344.371689) (xy 133.430552 -344.36391) (xy 133.416188 -344.349545)
			(xy 133.408411 -344.330779) (xy 133.407912 -344.320622) (xy 131.598416 -344.320622) (xy 131.598053 -344.330801)
			(xy 131.590252 -344.349605) (xy 131.575847 -344.36399) (xy 131.557033 -344.371766) (xy 131.546854 -344.372184)
			(xy 131.30403 -344.372184) (xy 130.972306 -344.155522) (xy 130.961173 -344.150468) (xy 130.936759 -344.150339)
			(xy 130.92557 -344.155268) (xy 130.594608 -344.372184) (xy 130.350514 -344.372184) (xy 130.34036 -344.371656)
			(xy 130.321595 -344.36389) (xy 130.30723 -344.349535) (xy 130.299451 -344.330776) (xy 130.298952 -344.320622)
			(xy 128.489456 -344.320622) (xy 128.488985 -344.330782) (xy 128.481202 -344.349553) (xy 128.466829 -344.363918)
			(xy 128.448054 -344.37169) (xy 128.437894 -344.372184) (xy 128.19507 -344.372184) (xy 127.863346 -344.155522)
			(xy 127.852203 -344.150495) (xy 127.827799 -344.150348) (xy 127.81661 -344.155268) (xy 127.485648 -344.372184)
			(xy 127.241554 -344.372184) (xy 127.231396 -344.371705) (xy 127.21263 -344.363919) (xy 127.198267 -344.34955)
			(xy 127.190491 -344.33078) (xy 127.189992 -344.320622) (xy 125.380496 -344.320622) (xy 125.379986 -344.330777)
			(xy 125.37221 -344.34954) (xy 125.35785 -344.363904) (xy 125.339089 -344.371683) (xy 125.328934 -344.372184)
			(xy 125.08611 -344.372184) (xy 124.754386 -344.155522) (xy 124.743257 -344.150455) (xy 124.71884 -344.150334)
			(xy 124.70765 -344.155268) (xy 124.376688 -344.372184) (xy 124.132594 -344.372184) (xy 124.122439 -344.371672)
			(xy 124.103674 -344.3639) (xy 124.089309 -344.34954) (xy 124.081531 -344.330777) (xy 124.081032 -344.320622)
			(xy 122.271536 -344.320622) (xy 122.271153 -344.330798) (xy 122.263356 -344.349598) (xy 122.248958 -344.363983)
			(xy 122.230151 -344.371763) (xy 122.219974 -344.372184) (xy 121.97715 -344.372184) (xy 121.645426 -344.155522)
			(xy 121.634288 -344.150482) (xy 121.609879 -344.150343) (xy 121.59869 -344.155268) (xy 121.267728 -344.372184)
			(xy 121.023634 -344.372184) (xy 121.013467 -344.371709) (xy 120.994678 -344.363939) (xy 120.980292 -344.349569)
			(xy 120.972502 -344.330788) (xy 120.972072 -344.320622) (xy 119.162576 -344.320622) (xy 119.162085 -344.330779)
			(xy 119.154306 -344.349547) (xy 119.13994 -344.363911) (xy 119.121172 -344.371687) (xy 119.111014 -344.372184)
			(xy 118.86819 -344.372184) (xy 118.536466 -344.155522) (xy 118.525342 -344.150442) (xy 118.50092 -344.150329)
			(xy 118.48973 -344.155268) (xy 118.158768 -344.372184) (xy 117.914674 -344.372184) (xy 117.904517 -344.371689)
			(xy 117.885752 -344.36391) (xy 117.871388 -344.349545) (xy 117.863611 -344.330779) (xy 117.863112 -344.320622)
			(xy 116.053616 -344.320622) (xy 116.053253 -344.330801) (xy 116.045452 -344.349605) (xy 116.031047 -344.36399)
			(xy 116.012233 -344.371766) (xy 116.002054 -344.372184) (xy 115.75923 -344.372184) (xy 115.427506 -344.155522)
			(xy 115.416373 -344.150468) (xy 115.391959 -344.150339) (xy 115.38077 -344.155268) (xy 115.049808 -344.372184)
			(xy 114.805714 -344.372184) (xy 114.79556 -344.371656) (xy 114.776795 -344.36389) (xy 114.76243 -344.349535)
			(xy 114.754651 -344.330776) (xy 114.754152 -344.320622) (xy 112.944656 -344.320622) (xy 112.944185 -344.330782)
			(xy 112.936402 -344.349553) (xy 112.922029 -344.363918) (xy 112.903254 -344.37169) (xy 112.893094 -344.372184)
			(xy 112.65027 -344.372184) (xy 112.318546 -344.155522) (xy 112.307403 -344.150495) (xy 112.282999 -344.150348)
			(xy 112.27181 -344.155268) (xy 111.940848 -344.372184) (xy 111.696754 -344.372184) (xy 111.686596 -344.371705)
			(xy 111.66783 -344.363919) (xy 111.653467 -344.34955) (xy 111.645691 -344.33078) (xy 111.645192 -344.320622)
			(xy 93.544644 -344.320622) (xy 93.544248 -344.330829) (xy 93.536405 -344.349676) (xy 93.521929 -344.36407)
			(xy 93.503037 -344.371805) (xy 93.492828 -344.372184) (xy 93.250004 -344.372184) (xy 92.91828 -344.155522)
			(xy 92.907153 -344.150451) (xy 92.882734 -344.150332) (xy 92.871544 -344.155268) (xy 92.540582 -344.372184)
			(xy 92.296488 -344.372184) (xy 92.286307 -344.371734) (xy 92.267487 -344.363958) (xy 92.25306 -344.349589)
			(xy 92.245208 -344.330801) (xy 92.244672 -344.320622) (xy 90.435684 -344.320622) (xy 90.435249 -344.330824)
			(xy 90.427413 -344.349663) (xy 90.41295 -344.364056) (xy 90.394072 -344.371798) (xy 90.383868 -344.372184)
			(xy 90.141044 -344.372184) (xy 89.80932 -344.155522) (xy 89.798183 -344.150478) (xy 89.773773 -344.150342)
			(xy 89.762584 -344.155268) (xy 89.431622 -344.372184) (xy 89.187528 -344.372184) (xy 89.177349 -344.371701)
			(xy 89.158531 -344.363939) (xy 89.144101 -344.349579) (xy 89.136248 -344.330798) (xy 89.135712 -344.320622)
			(xy 87.326724 -344.320622) (xy 87.326348 -344.330831) (xy 87.318501 -344.349683) (xy 87.304018 -344.364077)
			(xy 87.28512 -344.371809) (xy 87.274908 -344.372184) (xy 87.032084 -344.372184) (xy 86.70036 -344.155522)
			(xy 86.689214 -344.150504) (xy 86.664813 -344.150351) (xy 86.653624 -344.155268) (xy 86.322662 -344.372184)
			(xy 86.078568 -344.372184) (xy 86.068385 -344.37175) (xy 86.049565 -344.363968) (xy 86.035138 -344.349594)
			(xy 86.027287 -344.330803) (xy 86.026752 -344.320622) (xy 84.217764 -344.320622) (xy 84.217348 -344.330826)
			(xy 84.209509 -344.34967) (xy 84.195039 -344.364063) (xy 84.176155 -344.371802) (xy 84.165948 -344.372184)
			(xy 83.923124 -344.372184) (xy 83.5914 -344.155522) (xy 83.580268 -344.150464) (xy 83.555854 -344.150337)
			(xy 83.544664 -344.155268) (xy 83.213702 -344.372184) (xy 82.969608 -344.372184) (xy 82.959428 -344.371718)
			(xy 82.940609 -344.363949) (xy 82.926181 -344.349584) (xy 82.918328 -344.3308) (xy 82.917792 -344.320622)
			(xy 81.108804 -344.320622) (xy 81.108349 -344.330821) (xy 81.100517 -344.349657) (xy 81.08606 -344.364049)
			(xy 81.067189 -344.371795) (xy 81.056988 -344.372184) (xy 80.814164 -344.372184) (xy 80.48244 -344.155522)
			(xy 80.471298 -344.150491) (xy 80.446893 -344.150347) (xy 80.435704 -344.155268) (xy 80.104742 -344.372184)
			(xy 79.860648 -344.372184) (xy 79.850471 -344.371685) (xy 79.831652 -344.363929) (xy 79.817223 -344.349574)
			(xy 79.809369 -344.330797) (xy 79.808832 -344.320622) (xy 77.999844 -344.320622) (xy 77.999448 -344.330829)
			(xy 77.991605 -344.349676) (xy 77.977129 -344.36407) (xy 77.958237 -344.371805) (xy 77.948028 -344.372184)
			(xy 77.705204 -344.372184) (xy 77.37348 -344.155522) (xy 77.362353 -344.150451) (xy 77.337934 -344.150332)
			(xy 77.326744 -344.155268) (xy 76.995782 -344.372184) (xy 76.751688 -344.372184) (xy 76.741507 -344.371734)
			(xy 76.722687 -344.363958) (xy 76.70826 -344.349589) (xy 76.700408 -344.330801) (xy 76.699872 -344.320622)
			(xy 74.890884 -344.320622) (xy 74.890449 -344.330824) (xy 74.882613 -344.349663) (xy 74.86815 -344.364056)
			(xy 74.849272 -344.371798) (xy 74.839068 -344.372184) (xy 74.596244 -344.372184) (xy 74.26452 -344.155522)
			(xy 74.253383 -344.150478) (xy 74.228973 -344.150342) (xy 74.217784 -344.155268) (xy 73.886822 -344.372184)
			(xy 73.642728 -344.372184) (xy 73.632549 -344.371701) (xy 73.613731 -344.363939) (xy 73.599301 -344.349579)
			(xy 73.591448 -344.330798) (xy 73.590912 -344.320622) (xy 71.781924 -344.320622) (xy 71.781548 -344.330831)
			(xy 71.773701 -344.349683) (xy 71.759218 -344.364077) (xy 71.74032 -344.371809) (xy 71.730108 -344.372184)
			(xy 71.487284 -344.372184) (xy 71.15556 -344.155522) (xy 71.144414 -344.150504) (xy 71.120013 -344.150351)
			(xy 71.108824 -344.155268) (xy 70.777862 -344.372184) (xy 70.533768 -344.372184) (xy 70.523585 -344.37175)
			(xy 70.504765 -344.363968) (xy 70.490338 -344.349594) (xy 70.482487 -344.330803) (xy 70.481952 -344.320622)
			(xy 68.672964 -344.320622) (xy 68.672548 -344.330826) (xy 68.664709 -344.34967) (xy 68.650239 -344.364063)
			(xy 68.631355 -344.371802) (xy 68.621148 -344.372184) (xy 68.378324 -344.372184) (xy 68.0466 -344.155522)
			(xy 68.035468 -344.150464) (xy 68.011054 -344.150337) (xy 67.999864 -344.155268) (xy 67.668902 -344.372184)
			(xy 67.424808 -344.372184) (xy 67.414628 -344.371718) (xy 67.395809 -344.363949) (xy 67.381381 -344.349584)
			(xy 67.373528 -344.3308) (xy 67.372992 -344.320622) (xy 65.564004 -344.320622) (xy 65.563549 -344.330821)
			(xy 65.555717 -344.349657) (xy 65.54126 -344.364049) (xy 65.522389 -344.371795) (xy 65.512188 -344.372184)
			(xy 65.269364 -344.372184) (xy 64.93764 -344.155522) (xy 64.926498 -344.150491) (xy 64.902093 -344.150347)
			(xy 64.890904 -344.155268) (xy 64.559942 -344.372184) (xy 64.315848 -344.372184) (xy 64.305671 -344.371685)
			(xy 64.286852 -344.363929) (xy 64.272423 -344.349574) (xy 64.264569 -344.330797) (xy 64.264032 -344.320622)
			(xy 62.455044 -344.320622) (xy 62.454648 -344.330829) (xy 62.446805 -344.349676) (xy 62.432329 -344.36407)
			(xy 62.413437 -344.371805) (xy 62.403228 -344.372184) (xy 62.160404 -344.372184) (xy 61.82868 -344.155522)
			(xy 61.817553 -344.150451) (xy 61.793134 -344.150332) (xy 61.781944 -344.155268) (xy 61.450982 -344.372184)
			(xy 61.206888 -344.372184) (xy 61.196707 -344.371734) (xy 61.177887 -344.363958) (xy 61.16346 -344.349589)
			(xy 61.155608 -344.330801) (xy 61.155072 -344.320622) (xy 51.504596 -344.320622) (xy 51.504086 -344.330777)
			(xy 51.49631 -344.34954) (xy 51.48195 -344.363904) (xy 51.463189 -344.371683) (xy 51.453034 -344.372184)
			(xy 51.21021 -344.372184) (xy 50.878486 -344.155522) (xy 50.867357 -344.150455) (xy 50.84294 -344.150334)
			(xy 50.83175 -344.155268) (xy 50.500788 -344.372184) (xy 50.256694 -344.372184) (xy 50.246539 -344.371672)
			(xy 50.227774 -344.3639) (xy 50.213409 -344.34954) (xy 50.205631 -344.330777) (xy 50.205132 -344.320622)
			(xy 48.395636 -344.320622) (xy 48.395253 -344.330798) (xy 48.387456 -344.349598) (xy 48.373058 -344.363983)
			(xy 48.354251 -344.371763) (xy 48.344074 -344.372184) (xy 48.10125 -344.372184) (xy 47.769526 -344.155522)
			(xy 47.758388 -344.150482) (xy 47.733979 -344.150343) (xy 47.72279 -344.155268) (xy 47.391828 -344.372184)
			(xy 47.147734 -344.372184) (xy 47.137567 -344.371709) (xy 47.118778 -344.363939) (xy 47.104392 -344.349569)
			(xy 47.096602 -344.330788) (xy 47.096172 -344.320622) (xy 45.286676 -344.320622) (xy 45.286185 -344.330779)
			(xy 45.278406 -344.349547) (xy 45.26404 -344.363911) (xy 45.245272 -344.371687) (xy 45.235114 -344.372184)
			(xy 44.99229 -344.372184) (xy 44.660566 -344.155522) (xy 44.649442 -344.150442) (xy 44.62502 -344.150329)
			(xy 44.61383 -344.155268) (xy 44.282868 -344.372184) (xy 44.038774 -344.372184) (xy 44.028617 -344.371689)
			(xy 44.009852 -344.36391) (xy 43.995488 -344.349545) (xy 43.987711 -344.330779) (xy 43.987212 -344.320622)
			(xy 42.177716 -344.320622) (xy 42.177353 -344.330801) (xy 42.169552 -344.349605) (xy 42.155147 -344.36399)
			(xy 42.136333 -344.371766) (xy 42.126154 -344.372184) (xy 41.88333 -344.372184) (xy 41.551606 -344.155522)
			(xy 41.540473 -344.150468) (xy 41.516059 -344.150339) (xy 41.50487 -344.155268) (xy 41.173908 -344.372184)
			(xy 40.929814 -344.372184) (xy 40.91966 -344.371656) (xy 40.900895 -344.36389) (xy 40.88653 -344.349535)
			(xy 40.878751 -344.330776) (xy 40.878252 -344.320622) (xy 39.068756 -344.320622) (xy 39.068285 -344.330782)
			(xy 39.060502 -344.349553) (xy 39.046129 -344.363918) (xy 39.027354 -344.37169) (xy 39.017194 -344.372184)
			(xy 38.77437 -344.372184) (xy 38.442646 -344.155522) (xy 38.431503 -344.150495) (xy 38.407099 -344.150348)
			(xy 38.39591 -344.155268) (xy 38.064948 -344.372184) (xy 37.820854 -344.372184) (xy 37.810696 -344.371705)
			(xy 37.79193 -344.363919) (xy 37.777567 -344.34955) (xy 37.769791 -344.33078) (xy 37.769292 -344.320622)
			(xy 35.959796 -344.320622) (xy 35.959286 -344.330777) (xy 35.95151 -344.34954) (xy 35.93715 -344.363904)
			(xy 35.918389 -344.371683) (xy 35.908234 -344.372184) (xy 35.66541 -344.372184) (xy 35.333686 -344.155522)
			(xy 35.322557 -344.150455) (xy 35.29814 -344.150334) (xy 35.28695 -344.155268) (xy 34.955988 -344.372184)
			(xy 34.711894 -344.372184) (xy 34.701739 -344.371672) (xy 34.682974 -344.3639) (xy 34.668609 -344.34954)
			(xy 34.660831 -344.330777) (xy 34.660332 -344.320622) (xy 32.850836 -344.320622) (xy 32.850453 -344.330798)
			(xy 32.842656 -344.349598) (xy 32.828258 -344.363983) (xy 32.809451 -344.371763) (xy 32.799274 -344.372184)
			(xy 32.55645 -344.372184) (xy 32.224726 -344.155522) (xy 32.213588 -344.150482) (xy 32.189179 -344.150343)
			(xy 32.17799 -344.155268) (xy 31.847028 -344.372184) (xy 31.602934 -344.372184) (xy 31.592767 -344.371709)
			(xy 31.573978 -344.363939) (xy 31.559592 -344.349569) (xy 31.551802 -344.330788) (xy 31.551372 -344.320622)
			(xy 29.741876 -344.320622) (xy 29.741385 -344.330779) (xy 29.733606 -344.349547) (xy 29.71924 -344.363911)
			(xy 29.700472 -344.371687) (xy 29.690314 -344.372184) (xy 29.44749 -344.372184) (xy 29.115766 -344.155522)
			(xy 29.104642 -344.150442) (xy 29.08022 -344.150329) (xy 29.06903 -344.155268) (xy 28.738068 -344.372184)
			(xy 28.493974 -344.372184) (xy 28.483817 -344.371689) (xy 28.465052 -344.36391) (xy 28.450688 -344.349545)
			(xy 28.442911 -344.330779) (xy 28.442412 -344.320622) (xy 26.632916 -344.320622) (xy 26.632553 -344.330801)
			(xy 26.624752 -344.349605) (xy 26.610347 -344.36399) (xy 26.591533 -344.371766) (xy 26.581354 -344.372184)
			(xy 26.33853 -344.372184) (xy 26.006806 -344.155522) (xy 25.995673 -344.150468) (xy 25.971259 -344.150339)
			(xy 25.96007 -344.155268) (xy 25.629108 -344.372184) (xy 25.385014 -344.372184) (xy 25.37486 -344.371656)
			(xy 25.356095 -344.36389) (xy 25.34173 -344.349535) (xy 25.333951 -344.330776) (xy 25.333452 -344.320622)
			(xy 23.523956 -344.320622) (xy 23.523485 -344.330782) (xy 23.515702 -344.349553) (xy 23.501329 -344.363918)
			(xy 23.482554 -344.37169) (xy 23.472394 -344.372184) (xy 23.22957 -344.372184) (xy 22.897846 -344.155522)
			(xy 22.886703 -344.150495) (xy 22.862299 -344.150348) (xy 22.85111 -344.155268) (xy 22.520148 -344.372184)
			(xy 22.276054 -344.372184) (xy 22.265896 -344.371705) (xy 22.24713 -344.363919) (xy 22.232767 -344.34955)
			(xy 22.224991 -344.33078) (xy 22.224492 -344.320622) (xy 20.414996 -344.320622) (xy 20.414486 -344.330777)
			(xy 20.40671 -344.34954) (xy 20.39235 -344.363904) (xy 20.373589 -344.371683) (xy 20.363434 -344.372184)
			(xy 20.12061 -344.372184) (xy 19.788886 -344.155522) (xy 19.777757 -344.150455) (xy 19.75334 -344.150334)
			(xy 19.74215 -344.155268) (xy 19.411188 -344.372184) (xy 19.167094 -344.372184) (xy 19.156939 -344.371672)
			(xy 19.138174 -344.3639) (xy 19.123809 -344.34954) (xy 19.116031 -344.330777) (xy 19.115532 -344.320622)
			(xy 0.509016 -344.320622) (xy 0.509016 -345.49242) (xy 18.95117 -345.49242) (xy 18.95117 -345.43788)
			(xy 18.958932 -345.383896) (xy 18.974298 -345.331567) (xy 18.996954 -345.281956) (xy 19.02644 -345.236075)
			(xy 19.062155 -345.194857) (xy 19.103373 -345.159141) (xy 19.149254 -345.129655) (xy 19.198865 -345.106998)
			(xy 19.251194 -345.091633) (xy 19.305178 -345.083871) (xy 19.332448 -345.083384) (xy 20.196048 -345.083384)
			(xy 20.223319 -345.083855) (xy 20.277305 -345.091617) (xy 20.329638 -345.106983) (xy 20.379251 -345.12964)
			(xy 20.425134 -345.159128) (xy 20.466354 -345.194845) (xy 20.502071 -345.236064) (xy 20.531559 -345.281948)
			(xy 20.554216 -345.33156) (xy 20.569582 -345.383893) (xy 20.577345 -345.437879) (xy 20.577345 -345.49242)
			(xy 22.06013 -345.49242) (xy 22.06013 -345.43788) (xy 22.067892 -345.383896) (xy 22.083258 -345.331567)
			(xy 22.105914 -345.281956) (xy 22.1354 -345.236075) (xy 22.171115 -345.194857) (xy 22.212333 -345.159141)
			(xy 22.258214 -345.129655) (xy 22.307825 -345.106998) (xy 22.360154 -345.091633) (xy 22.414138 -345.083871)
			(xy 22.441408 -345.083384) (xy 23.305008 -345.083384) (xy 23.332279 -345.083855) (xy 23.386265 -345.091617)
			(xy 23.438598 -345.106983) (xy 23.488211 -345.12964) (xy 23.534094 -345.159128) (xy 23.575314 -345.194845)
			(xy 23.611031 -345.236064) (xy 23.640519 -345.281948) (xy 23.663176 -345.33156) (xy 23.678542 -345.383893)
			(xy 23.686305 -345.437879) (xy 23.686305 -345.492365) (xy 25.16917 -345.492365) (xy 25.16917 -345.437835)
			(xy 25.17693 -345.383861) (xy 25.192292 -345.33154) (xy 25.214943 -345.281938) (xy 25.244422 -345.236064)
			(xy 25.28013 -345.194853) (xy 25.321339 -345.159142) (xy 25.36721 -345.129658) (xy 25.41681 -345.107003)
			(xy 25.46913 -345.091637) (xy 25.523103 -345.083872) (xy 25.550368 -345.083384) (xy 26.413968 -345.083384)
			(xy 26.441244 -345.083753) (xy 26.495241 -345.091513) (xy 26.547583 -345.106878) (xy 26.597207 -345.129537)
			(xy 26.6431 -345.159027) (xy 26.684329 -345.194749) (xy 26.720054 -345.235975) (xy 26.749548 -345.281865)
			(xy 26.772211 -345.331487) (xy 26.78758 -345.383828) (xy 26.795344 -345.437824) (xy 26.795344 -345.492369)
			(xy 28.278047 -345.492369) (xy 28.278047 -345.437831) (xy 28.285809 -345.383848) (xy 28.301175 -345.33152)
			(xy 28.323832 -345.281911) (xy 28.353319 -345.236031) (xy 28.389035 -345.194815) (xy 28.430253 -345.159102)
			(xy 28.476135 -345.129619) (xy 28.525746 -345.106965) (xy 28.578076 -345.091603) (xy 28.632059 -345.083845)
			(xy 28.659328 -345.083384) (xy 29.522928 -345.083384) (xy 29.550199 -345.08378) (xy 29.604186 -345.091546)
			(xy 29.656519 -345.106916) (xy 29.706132 -345.129576) (xy 29.752014 -345.159067) (xy 29.793234 -345.194786)
			(xy 29.82895 -345.236008) (xy 29.858437 -345.281893) (xy 29.881094 -345.331507) (xy 29.89646 -345.383841)
			(xy 29.904222 -345.437829) (xy 29.904222 -345.492366) (xy 31.38707 -345.492366) (xy 31.38707 -345.437834)
			(xy 31.394831 -345.383858) (xy 31.410194 -345.331536) (xy 31.432846 -345.281933) (xy 31.462327 -345.236058)
			(xy 31.498037 -345.194846) (xy 31.539248 -345.159135) (xy 31.585122 -345.129652) (xy 31.634725 -345.106998)
			(xy 31.687047 -345.091633) (xy 31.741022 -345.083871) (xy 31.768288 -345.083384) (xy 32.631888 -345.083384)
			(xy 32.659163 -345.083755) (xy 32.713157 -345.091516) (xy 32.765498 -345.106884) (xy 32.815119 -345.129543)
			(xy 32.861009 -345.159034) (xy 32.902236 -345.194756) (xy 32.937959 -345.235981) (xy 32.967451 -345.281871)
			(xy 32.990112 -345.331491) (xy 33.005481 -345.383831) (xy 33.013244 -345.437825) (xy 33.013244 -345.49237)
			(xy 34.495948 -345.49237) (xy 34.495948 -345.43783) (xy 34.50371 -345.383846) (xy 34.519077 -345.331515)
			(xy 34.541735 -345.281905) (xy 34.571224 -345.236024) (xy 34.606942 -345.194808) (xy 34.648163 -345.159095)
			(xy 34.694047 -345.129612) (xy 34.74366 -345.10696) (xy 34.795992 -345.0916) (xy 34.849978 -345.083844)
			(xy 34.877248 -345.083384) (xy 35.740848 -345.083384) (xy 35.768118 -345.083782) (xy 35.822103 -345.09155)
			(xy 35.874433 -345.106921) (xy 35.924044 -345.129583) (xy 35.969924 -345.159074) (xy 36.011141 -345.194793)
			(xy 36.046855 -345.236015) (xy 36.07634 -345.281899) (xy 36.098995 -345.331512) (xy 36.11436 -345.383844)
			(xy 36.122122 -345.43783) (xy 36.122122 -345.492368) (xy 37.604947 -345.492368) (xy 37.604947 -345.437832)
			(xy 37.612709 -345.383851) (xy 37.628074 -345.331524) (xy 37.650729 -345.281916) (xy 37.680214 -345.236038)
			(xy 37.715928 -345.194822) (xy 37.757144 -345.159109) (xy 37.803023 -345.129625) (xy 37.852631 -345.106971)
			(xy 37.904959 -345.091607) (xy 37.95894 -345.083847) (xy 37.986208 -345.083384) (xy 38.849808 -345.083384)
			(xy 38.87708 -345.083779) (xy 38.93107 -345.091543) (xy 38.983404 -345.106911) (xy 39.03302 -345.12957)
			(xy 39.078905 -345.15906) (xy 39.120127 -345.194779) (xy 39.155845 -345.236001) (xy 39.185334 -345.281888)
			(xy 39.207992 -345.331503) (xy 39.223359 -345.383838) (xy 39.231121 -345.437828) (xy 39.231121 -345.492365)
			(xy 40.71397 -345.492365) (xy 40.71397 -345.437835) (xy 40.72173 -345.383861) (xy 40.737092 -345.33154)
			(xy 40.759743 -345.281938) (xy 40.789222 -345.236064) (xy 40.82493 -345.194853) (xy 40.866139 -345.159142)
			(xy 40.91201 -345.129658) (xy 40.96161 -345.107003) (xy 41.01393 -345.091637) (xy 41.067903 -345.083872)
			(xy 41.095168 -345.083384) (xy 41.958768 -345.083384) (xy 41.986044 -345.083753) (xy 42.040041 -345.091513)
			(xy 42.092383 -345.106878) (xy 42.142007 -345.129537) (xy 42.1879 -345.159027) (xy 42.229129 -345.194749)
			(xy 42.264854 -345.235975) (xy 42.294348 -345.281865) (xy 42.317011 -345.331487) (xy 42.33238 -345.383828)
			(xy 42.340144 -345.437824) (xy 42.340144 -345.492369) (xy 43.822847 -345.492369) (xy 43.822847 -345.437831)
			(xy 43.830609 -345.383848) (xy 43.845975 -345.33152) (xy 43.868632 -345.281911) (xy 43.898119 -345.236031)
			(xy 43.933835 -345.194815) (xy 43.975053 -345.159102) (xy 44.020935 -345.129619) (xy 44.070546 -345.106965)
			(xy 44.122876 -345.091603) (xy 44.176859 -345.083845) (xy 44.204128 -345.083384) (xy 45.067728 -345.083384)
			(xy 45.094999 -345.08378) (xy 45.148986 -345.091546) (xy 45.201319 -345.106916) (xy 45.250932 -345.129576)
			(xy 45.296814 -345.159067) (xy 45.338034 -345.194786) (xy 45.37375 -345.236008) (xy 45.403237 -345.281893)
			(xy 45.425894 -345.331507) (xy 45.44126 -345.383841) (xy 45.449022 -345.437829) (xy 45.449022 -345.492366)
			(xy 46.93187 -345.492366) (xy 46.93187 -345.437834) (xy 46.939631 -345.383858) (xy 46.954994 -345.331536)
			(xy 46.977646 -345.281933) (xy 47.007127 -345.236058) (xy 47.042837 -345.194846) (xy 47.084048 -345.159135)
			(xy 47.129922 -345.129652) (xy 47.179525 -345.106998) (xy 47.231847 -345.091633) (xy 47.285822 -345.083871)
			(xy 47.313088 -345.083384) (xy 48.176688 -345.083384) (xy 48.203963 -345.083755) (xy 48.257957 -345.091516)
			(xy 48.310298 -345.106884) (xy 48.359919 -345.129543) (xy 48.405809 -345.159034) (xy 48.447036 -345.194756)
			(xy 48.482759 -345.235981) (xy 48.512251 -345.281871) (xy 48.534912 -345.331491) (xy 48.550281 -345.383831)
			(xy 48.558044 -345.437825) (xy 48.558044 -345.49237) (xy 50.040748 -345.49237) (xy 50.040748 -345.43783)
			(xy 50.04851 -345.383846) (xy 50.063877 -345.331515) (xy 50.086535 -345.281905) (xy 50.116024 -345.236024)
			(xy 50.151742 -345.194808) (xy 50.192963 -345.159095) (xy 50.238847 -345.129612) (xy 50.28846 -345.10696)
			(xy 50.340792 -345.0916) (xy 50.394778 -345.083844) (xy 50.422048 -345.083384) (xy 51.285648 -345.083384)
			(xy 51.312918 -345.083782) (xy 51.366903 -345.09155) (xy 51.419233 -345.106921) (xy 51.468844 -345.129583)
			(xy 51.514724 -345.159074) (xy 51.555941 -345.194793) (xy 51.591655 -345.236015) (xy 51.62114 -345.281899)
			(xy 51.643795 -345.331512) (xy 51.65916 -345.383844) (xy 51.666922 -345.43783) (xy 51.666922 -345.49237)
			(xy 60.990948 -345.49237) (xy 60.990948 -345.43783) (xy 60.99871 -345.383846) (xy 61.014076 -345.331517)
			(xy 61.036734 -345.281907) (xy 61.066222 -345.236026) (xy 61.10194 -345.19481) (xy 61.14316 -345.159097)
			(xy 61.189044 -345.129614) (xy 61.238656 -345.106962) (xy 61.290987 -345.091601) (xy 61.344972 -345.083845)
			(xy 61.372242 -345.083384) (xy 62.235842 -345.083384) (xy 62.263113 -345.083781) (xy 62.317098 -345.091549)
			(xy 62.369429 -345.10692) (xy 62.41904 -345.129581) (xy 62.464921 -345.159072) (xy 62.506139 -345.194791)
			(xy 62.541854 -345.236013) (xy 62.571339 -345.281897) (xy 62.593995 -345.33151) (xy 62.60936 -345.383843)
			(xy 62.617122 -345.437829) (xy 62.617122 -345.492368) (xy 64.099947 -345.492368) (xy 64.099947 -345.437832)
			(xy 64.107709 -345.383852) (xy 64.123073 -345.331525) (xy 64.145728 -345.281918) (xy 64.175212 -345.23604)
			(xy 64.210926 -345.194824) (xy 64.252141 -345.159111) (xy 64.29802 -345.129627) (xy 64.347627 -345.106972)
			(xy 64.399954 -345.091608) (xy 64.453934 -345.083847) (xy 64.481202 -345.083384) (xy 65.344802 -345.083384)
			(xy 65.372075 -345.083779) (xy 65.426064 -345.091542) (xy 65.4784 -345.106909) (xy 65.528016 -345.129568)
			(xy 65.573902 -345.159057) (xy 65.615124 -345.194777) (xy 65.650844 -345.236) (xy 65.680333 -345.281886)
			(xy 65.702992 -345.331502) (xy 65.718359 -345.383838) (xy 65.726121 -345.437827) (xy 65.726121 -345.492364)
			(xy 67.20897 -345.492364) (xy 67.20897 -345.437836) (xy 67.21673 -345.383862) (xy 67.232092 -345.331542)
			(xy 67.254742 -345.28194) (xy 67.284221 -345.236066) (xy 67.319928 -345.194855) (xy 67.361136 -345.159144)
			(xy 67.407007 -345.12966) (xy 67.456606 -345.107005) (xy 67.508925 -345.091638) (xy 67.562898 -345.083873)
			(xy 67.590162 -345.083384) (xy 68.453762 -345.083384) (xy 68.481038 -345.083753) (xy 68.535036 -345.091512)
			(xy 68.587379 -345.106877) (xy 68.637003 -345.129535) (xy 68.682897 -345.159025) (xy 68.724127 -345.194747)
			(xy 68.759852 -345.235973) (xy 68.789347 -345.281864) (xy 68.81201 -345.331485) (xy 68.82738 -345.383827)
			(xy 68.835144 -345.437824) (xy 68.835144 -345.492369) (xy 70.317847 -345.492369) (xy 70.317847 -345.437831)
			(xy 70.325609 -345.383849) (xy 70.340975 -345.331521) (xy 70.363631 -345.281912) (xy 70.393117 -345.236033)
			(xy 70.428833 -345.194817) (xy 70.470051 -345.159104) (xy 70.515932 -345.129621) (xy 70.565541 -345.106967)
			(xy 70.617871 -345.091605) (xy 70.671853 -345.083846) (xy 70.699122 -345.083384) (xy 71.562722 -345.083384)
			(xy 71.589994 -345.08378) (xy 71.643981 -345.091545) (xy 71.696315 -345.106914) (xy 71.745928 -345.129574)
			(xy 71.791812 -345.159064) (xy 71.833032 -345.194784) (xy 71.868749 -345.236006) (xy 71.898236 -345.281891)
			(xy 71.920893 -345.331506) (xy 71.936259 -345.38384) (xy 71.944022 -345.437828) (xy 71.944022 -345.492365)
			(xy 73.42687 -345.492365) (xy 73.42687 -345.437835) (xy 73.434631 -345.383859) (xy 73.449993 -345.331537)
			(xy 73.472645 -345.281934) (xy 73.502126 -345.23606) (xy 73.537835 -345.194848) (xy 73.579045 -345.159137)
			(xy 73.624919 -345.129654) (xy 73.674521 -345.106999) (xy 73.726842 -345.091634) (xy 73.780817 -345.083872)
			(xy 73.808082 -345.083384) (xy 74.671682 -345.083384) (xy 74.698957 -345.083754) (xy 74.752952 -345.091515)
			(xy 74.805294 -345.106882) (xy 74.854915 -345.129541) (xy 74.900806 -345.159032) (xy 74.942034 -345.194754)
			(xy 74.977757 -345.235979) (xy 75.00725 -345.281869) (xy 75.029912 -345.33149) (xy 75.045281 -345.38383)
			(xy 75.053044 -345.437825) (xy 75.053044 -345.49237) (xy 76.535748 -345.49237) (xy 76.535748 -345.43783)
			(xy 76.54351 -345.383846) (xy 76.558876 -345.331517) (xy 76.581534 -345.281907) (xy 76.611022 -345.236026)
			(xy 76.64674 -345.19481) (xy 76.68796 -345.159097) (xy 76.733844 -345.129614) (xy 76.783456 -345.106962)
			(xy 76.835787 -345.091601) (xy 76.889772 -345.083845) (xy 76.917042 -345.083384) (xy 77.780642 -345.083384)
			(xy 77.807913 -345.083781) (xy 77.861898 -345.091549) (xy 77.914229 -345.10692) (xy 77.96384 -345.129581)
			(xy 78.009721 -345.159072) (xy 78.050939 -345.194791) (xy 78.086654 -345.236013) (xy 78.116139 -345.281897)
			(xy 78.138795 -345.33151) (xy 78.15416 -345.383843) (xy 78.161922 -345.437829) (xy 78.161922 -345.492368)
			(xy 79.644747 -345.492368) (xy 79.644747 -345.437832) (xy 79.652509 -345.383852) (xy 79.667873 -345.331525)
			(xy 79.690528 -345.281918) (xy 79.720012 -345.23604) (xy 79.755726 -345.194824) (xy 79.796941 -345.159111)
			(xy 79.84282 -345.129627) (xy 79.892427 -345.106972) (xy 79.944754 -345.091608) (xy 79.998734 -345.083847)
			(xy 80.026002 -345.083384) (xy 80.889602 -345.083384) (xy 80.916875 -345.083779) (xy 80.970864 -345.091542)
			(xy 81.0232 -345.106909) (xy 81.072816 -345.129568) (xy 81.118702 -345.159057) (xy 81.159924 -345.194777)
			(xy 81.195644 -345.236) (xy 81.225133 -345.281886) (xy 81.247792 -345.331502) (xy 81.263159 -345.383838)
			(xy 81.270921 -345.437827) (xy 81.270921 -345.492364) (xy 82.75377 -345.492364) (xy 82.75377 -345.437836)
			(xy 82.76153 -345.383862) (xy 82.776892 -345.331542) (xy 82.799542 -345.28194) (xy 82.829021 -345.236066)
			(xy 82.864728 -345.194855) (xy 82.905936 -345.159144) (xy 82.951807 -345.12966) (xy 83.001406 -345.107005)
			(xy 83.053725 -345.091638) (xy 83.107698 -345.083873) (xy 83.134962 -345.083384) (xy 83.998562 -345.083384)
			(xy 84.025838 -345.083753) (xy 84.079836 -345.091512) (xy 84.132179 -345.106877) (xy 84.181803 -345.129535)
			(xy 84.227697 -345.159025) (xy 84.268927 -345.194747) (xy 84.304652 -345.235973) (xy 84.334147 -345.281864)
			(xy 84.35681 -345.331485) (xy 84.37218 -345.383827) (xy 84.379944 -345.437824) (xy 84.379944 -345.492369)
			(xy 85.862647 -345.492369) (xy 85.862647 -345.437831) (xy 85.870409 -345.383849) (xy 85.885775 -345.331521)
			(xy 85.908431 -345.281912) (xy 85.937917 -345.236033) (xy 85.973633 -345.194817) (xy 86.014851 -345.159104)
			(xy 86.060732 -345.129621) (xy 86.110341 -345.106967) (xy 86.162671 -345.091605) (xy 86.216653 -345.083846)
			(xy 86.243922 -345.083384) (xy 87.107522 -345.083384) (xy 87.134794 -345.08378) (xy 87.188781 -345.091545)
			(xy 87.241115 -345.106914) (xy 87.290728 -345.129574) (xy 87.336612 -345.159064) (xy 87.377832 -345.194784)
			(xy 87.413549 -345.236006) (xy 87.443036 -345.281891) (xy 87.465693 -345.331506) (xy 87.481059 -345.38384)
			(xy 87.488822 -345.437828) (xy 87.488822 -345.492365) (xy 88.97167 -345.492365) (xy 88.97167 -345.437835)
			(xy 88.979431 -345.383859) (xy 88.994793 -345.331537) (xy 89.017445 -345.281934) (xy 89.046926 -345.23606)
			(xy 89.082635 -345.194848) (xy 89.123845 -345.159137) (xy 89.169719 -345.129654) (xy 89.219321 -345.106999)
			(xy 89.271642 -345.091634) (xy 89.325617 -345.083872) (xy 89.352882 -345.083384) (xy 90.216482 -345.083384)
			(xy 90.243757 -345.083754) (xy 90.297752 -345.091515) (xy 90.350094 -345.106882) (xy 90.399715 -345.129541)
			(xy 90.445606 -345.159032) (xy 90.486834 -345.194754) (xy 90.522557 -345.235979) (xy 90.55205 -345.281869)
			(xy 90.574712 -345.33149) (xy 90.590081 -345.38383) (xy 90.597844 -345.437825) (xy 90.597844 -345.49237)
			(xy 92.080548 -345.49237) (xy 92.080548 -345.43783) (xy 92.08831 -345.383846) (xy 92.103676 -345.331517)
			(xy 92.126334 -345.281907) (xy 92.155822 -345.236026) (xy 92.19154 -345.19481) (xy 92.23276 -345.159097)
			(xy 92.278644 -345.129614) (xy 92.328256 -345.106962) (xy 92.380587 -345.091601) (xy 92.434572 -345.083845)
			(xy 92.461842 -345.083384) (xy 93.325442 -345.083384) (xy 93.352713 -345.083781) (xy 93.406698 -345.091549)
			(xy 93.459029 -345.10692) (xy 93.50864 -345.129581) (xy 93.554521 -345.159072) (xy 93.595739 -345.194791)
			(xy 93.631454 -345.236013) (xy 93.660939 -345.281897) (xy 93.683595 -345.33151) (xy 93.69896 -345.383843)
			(xy 93.706722 -345.437829) (xy 93.706722 -345.492368) (xy 111.480847 -345.492368) (xy 111.480847 -345.437832)
			(xy 111.488609 -345.383851) (xy 111.503974 -345.331524) (xy 111.526629 -345.281916) (xy 111.556114 -345.236038)
			(xy 111.591828 -345.194822) (xy 111.633044 -345.159109) (xy 111.678923 -345.129625) (xy 111.728531 -345.106971)
			(xy 111.780859 -345.091607) (xy 111.83484 -345.083847) (xy 111.862108 -345.083384) (xy 112.725708 -345.083384)
			(xy 112.75298 -345.083779) (xy 112.80697 -345.091543) (xy 112.859304 -345.106911) (xy 112.90892 -345.12957)
			(xy 112.954805 -345.15906) (xy 112.996027 -345.194779) (xy 113.031745 -345.236001) (xy 113.061234 -345.281888)
			(xy 113.083892 -345.331503) (xy 113.099259 -345.383838) (xy 113.107021 -345.437828) (xy 113.107021 -345.492365)
			(xy 114.58987 -345.492365) (xy 114.58987 -345.437835) (xy 114.59763 -345.383861) (xy 114.612992 -345.33154)
			(xy 114.635643 -345.281938) (xy 114.665122 -345.236064) (xy 114.70083 -345.194853) (xy 114.742039 -345.159142)
			(xy 114.78791 -345.129658) (xy 114.83751 -345.107003) (xy 114.88983 -345.091637) (xy 114.943803 -345.083872)
			(xy 114.971068 -345.083384) (xy 115.834668 -345.083384) (xy 115.861944 -345.083753) (xy 115.915941 -345.091513)
			(xy 115.968283 -345.106878) (xy 116.017907 -345.129537) (xy 116.0638 -345.159027) (xy 116.105029 -345.194749)
			(xy 116.140754 -345.235975) (xy 116.170248 -345.281865) (xy 116.192911 -345.331487) (xy 116.20828 -345.383828)
			(xy 116.216044 -345.437824) (xy 116.216044 -345.492369) (xy 117.698747 -345.492369) (xy 117.698747 -345.437831)
			(xy 117.706509 -345.383848) (xy 117.721875 -345.33152) (xy 117.744532 -345.281911) (xy 117.774019 -345.236031)
			(xy 117.809735 -345.194815) (xy 117.850953 -345.159102) (xy 117.896835 -345.129619) (xy 117.946446 -345.106965)
			(xy 117.998776 -345.091603) (xy 118.052759 -345.083845) (xy 118.080028 -345.083384) (xy 118.943628 -345.083384)
			(xy 118.970899 -345.08378) (xy 119.024886 -345.091546) (xy 119.077219 -345.106916) (xy 119.126832 -345.129576)
			(xy 119.172714 -345.159067) (xy 119.213934 -345.194786) (xy 119.24965 -345.236008) (xy 119.279137 -345.281893)
			(xy 119.301794 -345.331507) (xy 119.31716 -345.383841) (xy 119.324922 -345.437829) (xy 119.324922 -345.492366)
			(xy 120.80777 -345.492366) (xy 120.80777 -345.437834) (xy 120.815531 -345.383858) (xy 120.830894 -345.331536)
			(xy 120.853546 -345.281933) (xy 120.883027 -345.236058) (xy 120.918737 -345.194846) (xy 120.959948 -345.159135)
			(xy 121.005822 -345.129652) (xy 121.055425 -345.106998) (xy 121.107747 -345.091633) (xy 121.161722 -345.083871)
			(xy 121.188988 -345.083384) (xy 122.052588 -345.083384) (xy 122.079863 -345.083755) (xy 122.133857 -345.091516)
			(xy 122.186198 -345.106884) (xy 122.235819 -345.129543) (xy 122.281709 -345.159034) (xy 122.322936 -345.194756)
			(xy 122.358659 -345.235981) (xy 122.388151 -345.281871) (xy 122.410812 -345.331491) (xy 122.426181 -345.383831)
			(xy 122.433944 -345.437825) (xy 122.433944 -345.49237) (xy 123.916648 -345.49237) (xy 123.916648 -345.43783)
			(xy 123.92441 -345.383846) (xy 123.939777 -345.331515) (xy 123.962435 -345.281905) (xy 123.991924 -345.236024)
			(xy 124.027642 -345.194808) (xy 124.068863 -345.159095) (xy 124.114747 -345.129612) (xy 124.16436 -345.10696)
			(xy 124.216692 -345.0916) (xy 124.270678 -345.083844) (xy 124.297948 -345.083384) (xy 125.161548 -345.083384)
			(xy 125.188818 -345.083782) (xy 125.242803 -345.09155) (xy 125.295133 -345.106921) (xy 125.344744 -345.129583)
			(xy 125.390624 -345.159074) (xy 125.431841 -345.194793) (xy 125.467555 -345.236015) (xy 125.49704 -345.281899)
			(xy 125.519695 -345.331512) (xy 125.53506 -345.383844) (xy 125.542822 -345.43783) (xy 125.542822 -345.492368)
			(xy 127.025647 -345.492368) (xy 127.025647 -345.437832) (xy 127.033409 -345.383851) (xy 127.048774 -345.331524)
			(xy 127.071429 -345.281916) (xy 127.100914 -345.236038) (xy 127.136628 -345.194822) (xy 127.177844 -345.159109)
			(xy 127.223723 -345.129625) (xy 127.273331 -345.106971) (xy 127.325659 -345.091607) (xy 127.37964 -345.083847)
			(xy 127.406908 -345.083384) (xy 128.270508 -345.083384) (xy 128.29778 -345.083779) (xy 128.35177 -345.091543)
			(xy 128.404104 -345.106911) (xy 128.45372 -345.12957) (xy 128.499605 -345.15906) (xy 128.540827 -345.194779)
			(xy 128.576545 -345.236001) (xy 128.606034 -345.281888) (xy 128.628692 -345.331503) (xy 128.644059 -345.383838)
			(xy 128.651821 -345.437828) (xy 128.651821 -345.492365) (xy 130.13467 -345.492365) (xy 130.13467 -345.437835)
			(xy 130.14243 -345.383861) (xy 130.157792 -345.33154) (xy 130.180443 -345.281938) (xy 130.209922 -345.236064)
			(xy 130.24563 -345.194853) (xy 130.286839 -345.159142) (xy 130.33271 -345.129658) (xy 130.38231 -345.107003)
			(xy 130.43463 -345.091637) (xy 130.488603 -345.083872) (xy 130.515868 -345.083384) (xy 131.379468 -345.083384)
			(xy 131.406744 -345.083753) (xy 131.460741 -345.091513) (xy 131.513083 -345.106878) (xy 131.562707 -345.129537)
			(xy 131.6086 -345.159027) (xy 131.649829 -345.194749) (xy 131.685554 -345.235975) (xy 131.715048 -345.281865)
			(xy 131.737711 -345.331487) (xy 131.75308 -345.383828) (xy 131.760844 -345.437824) (xy 131.760844 -345.492369)
			(xy 133.243547 -345.492369) (xy 133.243547 -345.437831) (xy 133.251309 -345.383848) (xy 133.266675 -345.33152)
			(xy 133.289332 -345.281911) (xy 133.318819 -345.236031) (xy 133.354535 -345.194815) (xy 133.395753 -345.159102)
			(xy 133.441635 -345.129619) (xy 133.491246 -345.106965) (xy 133.543576 -345.091603) (xy 133.597559 -345.083845)
			(xy 133.624828 -345.083384) (xy 134.488428 -345.083384) (xy 134.515699 -345.08378) (xy 134.569686 -345.091546)
			(xy 134.622019 -345.106916) (xy 134.671632 -345.129576) (xy 134.717514 -345.159067) (xy 134.758734 -345.194786)
			(xy 134.79445 -345.236008) (xy 134.823937 -345.281893) (xy 134.846594 -345.331507) (xy 134.86196 -345.383841)
			(xy 134.869722 -345.437829) (xy 134.869722 -345.492366) (xy 136.35257 -345.492366) (xy 136.35257 -345.437834)
			(xy 136.360331 -345.383858) (xy 136.375694 -345.331536) (xy 136.398346 -345.281933) (xy 136.427827 -345.236058)
			(xy 136.463537 -345.194846) (xy 136.504748 -345.159135) (xy 136.550622 -345.129652) (xy 136.600225 -345.106998)
			(xy 136.652547 -345.091633) (xy 136.706522 -345.083871) (xy 136.733788 -345.083384) (xy 137.597388 -345.083384)
			(xy 137.624663 -345.083755) (xy 137.678657 -345.091516) (xy 137.730998 -345.106884) (xy 137.780619 -345.129543)
			(xy 137.826509 -345.159034) (xy 137.867736 -345.194756) (xy 137.903459 -345.235981) (xy 137.932951 -345.281871)
			(xy 137.955612 -345.331491) (xy 137.970981 -345.383831) (xy 137.978744 -345.437825) (xy 137.978744 -345.49237)
			(xy 139.461448 -345.49237) (xy 139.461448 -345.43783) (xy 139.46921 -345.383846) (xy 139.484577 -345.331515)
			(xy 139.507235 -345.281905) (xy 139.536724 -345.236024) (xy 139.572442 -345.194808) (xy 139.613663 -345.159095)
			(xy 139.659547 -345.129612) (xy 139.70916 -345.10696) (xy 139.761492 -345.0916) (xy 139.815478 -345.083844)
			(xy 139.842748 -345.083384) (xy 140.706348 -345.083384) (xy 140.733618 -345.083782) (xy 140.787603 -345.09155)
			(xy 140.839933 -345.106921) (xy 140.889544 -345.129583) (xy 140.935424 -345.159074) (xy 140.976641 -345.194793)
			(xy 141.012355 -345.236015) (xy 141.04184 -345.281899) (xy 141.064495 -345.331512) (xy 141.07986 -345.383844)
			(xy 141.087622 -345.43783) (xy 141.087622 -345.492368) (xy 142.570447 -345.492368) (xy 142.570447 -345.437832)
			(xy 142.578209 -345.383851) (xy 142.593574 -345.331524) (xy 142.616229 -345.281916) (xy 142.645714 -345.236038)
			(xy 142.681428 -345.194822) (xy 142.722644 -345.159109) (xy 142.768523 -345.129625) (xy 142.818131 -345.106971)
			(xy 142.870459 -345.091607) (xy 142.92444 -345.083847) (xy 142.951708 -345.083384) (xy 143.815308 -345.083384)
			(xy 143.84258 -345.083779) (xy 143.89657 -345.091543) (xy 143.948904 -345.106911) (xy 143.99852 -345.12957)
			(xy 144.044405 -345.15906) (xy 144.085627 -345.194779) (xy 144.121345 -345.236001) (xy 144.150834 -345.281888)
			(xy 144.173492 -345.331503) (xy 144.188859 -345.383838) (xy 144.196621 -345.437828) (xy 144.196621 -345.492365)
			(xy 164.91387 -345.492365) (xy 164.91387 -345.437835) (xy 164.92163 -345.383861) (xy 164.936992 -345.33154)
			(xy 164.959644 -345.281937) (xy 164.989123 -345.236063) (xy 165.024831 -345.194851) (xy 165.066041 -345.15914)
			(xy 165.111913 -345.129657) (xy 165.161513 -345.107002) (xy 165.213833 -345.091636) (xy 165.267807 -345.083872)
			(xy 165.295072 -345.083384) (xy 166.158672 -345.083384) (xy 166.185948 -345.083754) (xy 166.239944 -345.091514)
			(xy 166.292286 -345.106879) (xy 166.341909 -345.129538) (xy 166.387802 -345.159028) (xy 166.42903 -345.19475)
			(xy 166.464755 -345.235976) (xy 166.494249 -345.281866) (xy 166.516911 -345.331487) (xy 166.532281 -345.383829)
			(xy 166.540044 -345.437824) (xy 166.540044 -345.492369) (xy 168.022747 -345.492369) (xy 168.022747 -345.437831)
			(xy 168.03051 -345.383848) (xy 168.045876 -345.331519) (xy 168.068533 -345.281909) (xy 168.09802 -345.23603)
			(xy 168.133736 -345.194814) (xy 168.174955 -345.159101) (xy 168.220838 -345.129617) (xy 168.270449 -345.106964)
			(xy 168.322779 -345.091603) (xy 168.376763 -345.083845) (xy 168.404032 -345.083384) (xy 169.267632 -345.083384)
			(xy 169.294903 -345.083781) (xy 169.34889 -345.091547) (xy 169.401222 -345.106917) (xy 169.450834 -345.129578)
			(xy 169.496716 -345.159068) (xy 169.537935 -345.194788) (xy 169.573651 -345.236009) (xy 169.603138 -345.281894)
			(xy 169.625794 -345.331508) (xy 169.64116 -345.383842) (xy 169.648922 -345.437829) (xy 169.648922 -345.492366)
			(xy 171.13177 -345.492366) (xy 171.13177 -345.437834) (xy 171.139531 -345.383858) (xy 171.154894 -345.331535)
			(xy 171.177547 -345.281932) (xy 171.207028 -345.236057) (xy 171.242738 -345.194844) (xy 171.28395 -345.159133)
			(xy 171.329825 -345.129651) (xy 171.379428 -345.106997) (xy 171.43175 -345.091633) (xy 171.485726 -345.083871)
			(xy 171.512992 -345.083384) (xy 172.376592 -345.083384) (xy 172.403867 -345.083755) (xy 172.457861 -345.091517)
			(xy 172.510201 -345.106885) (xy 172.559821 -345.129544) (xy 172.605711 -345.159035) (xy 172.646937 -345.194757)
			(xy 172.68266 -345.235982) (xy 172.712152 -345.281872) (xy 172.734813 -345.331492) (xy 172.750181 -345.383831)
			(xy 172.757944 -345.437825) (xy 172.757944 -345.492364) (xy 174.24077 -345.492364) (xy 174.24077 -345.437836)
			(xy 174.24853 -345.383863) (xy 174.263891 -345.331544) (xy 174.286541 -345.281943) (xy 174.316019 -345.23607)
			(xy 174.351724 -345.194858) (xy 174.392931 -345.159147) (xy 174.438801 -345.129664) (xy 174.488399 -345.107008)
			(xy 174.540716 -345.09164) (xy 174.594688 -345.083874) (xy 174.621952 -345.083384) (xy 175.485552 -345.083384)
			(xy 175.512829 -345.083752) (xy 175.566827 -345.09151) (xy 175.619172 -345.106874) (xy 175.668797 -345.129531)
			(xy 175.714692 -345.159021) (xy 175.755923 -345.194743) (xy 175.79165 -345.235969) (xy 175.821146 -345.281861)
			(xy 175.843809 -345.331483) (xy 175.85918 -345.383826) (xy 175.866944 -345.437824) (xy 175.866944 -345.492368)
			(xy 177.349647 -345.492368) (xy 177.349647 -345.437832) (xy 177.357409 -345.38385) (xy 177.372774 -345.331523)
			(xy 177.39543 -345.281915) (xy 177.424915 -345.236036) (xy 177.460629 -345.194821) (xy 177.501846 -345.159108)
			(xy 177.547726 -345.129624) (xy 177.597334 -345.10697) (xy 177.649662 -345.091606) (xy 177.703644 -345.083847)
			(xy 177.730912 -345.083384) (xy 178.594512 -345.083384) (xy 178.621784 -345.083779) (xy 178.675773 -345.091543)
			(xy 178.728107 -345.106912) (xy 178.777722 -345.129571) (xy 178.823607 -345.159061) (xy 178.864828 -345.194781)
			(xy 178.900546 -345.236003) (xy 178.930035 -345.281889) (xy 178.952693 -345.331504) (xy 178.968059 -345.383839)
			(xy 178.975821 -345.437828) (xy 178.975821 -345.492365) (xy 180.45867 -345.492365) (xy 180.45867 -345.437835)
			(xy 180.46643 -345.383861) (xy 180.481792 -345.33154) (xy 180.504444 -345.281937) (xy 180.533923 -345.236063)
			(xy 180.569631 -345.194851) (xy 180.610841 -345.15914) (xy 180.656713 -345.129657) (xy 180.706313 -345.107002)
			(xy 180.758633 -345.091636) (xy 180.812607 -345.083872) (xy 180.839872 -345.083384) (xy 181.703472 -345.083384)
			(xy 181.730748 -345.083754) (xy 181.784744 -345.091514) (xy 181.837086 -345.106879) (xy 181.886709 -345.129538)
			(xy 181.932602 -345.159028) (xy 181.97383 -345.19475) (xy 182.009555 -345.235976) (xy 182.039049 -345.281866)
			(xy 182.061711 -345.331487) (xy 182.077081 -345.383829) (xy 182.084844 -345.437824) (xy 182.084844 -345.492369)
			(xy 183.567547 -345.492369) (xy 183.567547 -345.437831) (xy 183.57531 -345.383848) (xy 183.590676 -345.331519)
			(xy 183.613333 -345.281909) (xy 183.64282 -345.23603) (xy 183.678536 -345.194814) (xy 183.719755 -345.159101)
			(xy 183.765638 -345.129617) (xy 183.815249 -345.106964) (xy 183.867579 -345.091603) (xy 183.921563 -345.083845)
			(xy 183.948832 -345.083384) (xy 184.812432 -345.083384) (xy 184.839703 -345.083781) (xy 184.89369 -345.091547)
			(xy 184.946022 -345.106917) (xy 184.995634 -345.129578) (xy 185.041516 -345.159068) (xy 185.082735 -345.194788)
			(xy 185.118451 -345.236009) (xy 185.147938 -345.281894) (xy 185.170594 -345.331508) (xy 185.18596 -345.383842)
			(xy 185.193722 -345.437829) (xy 185.193722 -345.492366) (xy 186.67657 -345.492366) (xy 186.67657 -345.437834)
			(xy 186.684331 -345.383858) (xy 186.699694 -345.331535) (xy 186.722347 -345.281932) (xy 186.751828 -345.236057)
			(xy 186.787538 -345.194844) (xy 186.82875 -345.159133) (xy 186.874625 -345.129651) (xy 186.924228 -345.106997)
			(xy 186.97655 -345.091633) (xy 187.030526 -345.083871) (xy 187.057792 -345.083384) (xy 187.921392 -345.083384)
			(xy 187.948667 -345.083755) (xy 188.002661 -345.091517) (xy 188.055001 -345.106885) (xy 188.104621 -345.129544)
			(xy 188.150511 -345.159035) (xy 188.191737 -345.194757) (xy 188.22746 -345.235982) (xy 188.256952 -345.281872)
			(xy 188.279613 -345.331492) (xy 188.294981 -345.383831) (xy 188.302744 -345.437825) (xy 188.302744 -345.492364)
			(xy 189.78557 -345.492364) (xy 189.78557 -345.437836) (xy 189.79333 -345.383863) (xy 189.808691 -345.331544)
			(xy 189.831341 -345.281943) (xy 189.860819 -345.23607) (xy 189.896524 -345.194858) (xy 189.937731 -345.159147)
			(xy 189.983601 -345.129664) (xy 190.033199 -345.107008) (xy 190.085516 -345.09164) (xy 190.139488 -345.083874)
			(xy 190.166752 -345.083384) (xy 191.030352 -345.083384) (xy 191.057629 -345.083752) (xy 191.111627 -345.09151)
			(xy 191.163972 -345.106874) (xy 191.213597 -345.129531) (xy 191.259492 -345.159021) (xy 191.300723 -345.194743)
			(xy 191.33645 -345.235969) (xy 191.365946 -345.281861) (xy 191.388609 -345.331483) (xy 191.40398 -345.383826)
			(xy 191.411744 -345.437824) (xy 191.411744 -345.492368) (xy 192.894447 -345.492368) (xy 192.894447 -345.437832)
			(xy 192.902209 -345.38385) (xy 192.917574 -345.331523) (xy 192.94023 -345.281915) (xy 192.969715 -345.236036)
			(xy 193.005429 -345.194821) (xy 193.046646 -345.159108) (xy 193.092526 -345.129624) (xy 193.142134 -345.10697)
			(xy 193.194462 -345.091606) (xy 193.248444 -345.083847) (xy 193.275712 -345.083384) (xy 194.139312 -345.083384)
			(xy 194.166584 -345.083779) (xy 194.220573 -345.091543) (xy 194.272907 -345.106912) (xy 194.322522 -345.129571)
			(xy 194.368407 -345.159061) (xy 194.409628 -345.194781) (xy 194.445346 -345.236003) (xy 194.474835 -345.281889)
			(xy 194.497493 -345.331504) (xy 194.512859 -345.383839) (xy 194.520621 -345.437828) (xy 194.520621 -345.492365)
			(xy 196.00347 -345.492365) (xy 196.00347 -345.437835) (xy 196.01123 -345.383861) (xy 196.026592 -345.33154)
			(xy 196.049244 -345.281937) (xy 196.078723 -345.236063) (xy 196.114431 -345.194851) (xy 196.155641 -345.15914)
			(xy 196.201513 -345.129657) (xy 196.251113 -345.107002) (xy 196.303433 -345.091636) (xy 196.357407 -345.083872)
			(xy 196.384672 -345.083384) (xy 197.248272 -345.083384) (xy 197.275548 -345.083754) (xy 197.329544 -345.091514)
			(xy 197.381886 -345.106879) (xy 197.431509 -345.129538) (xy 197.477402 -345.159028) (xy 197.51863 -345.19475)
			(xy 197.554355 -345.235976) (xy 197.583849 -345.281866) (xy 197.606511 -345.331487) (xy 197.621881 -345.383829)
			(xy 197.629644 -345.437824) (xy 197.629644 -345.492368) (xy 267.515847 -345.492368) (xy 267.515847 -345.437832)
			(xy 267.523609 -345.383852) (xy 267.538973 -345.331525) (xy 267.561628 -345.281918) (xy 267.591112 -345.23604)
			(xy 267.626826 -345.194824) (xy 267.668041 -345.159111) (xy 267.71392 -345.129627) (xy 267.763527 -345.106972)
			(xy 267.815854 -345.091608) (xy 267.869834 -345.083847) (xy 267.897102 -345.083384) (xy 268.760702 -345.083384)
			(xy 268.787975 -345.083779) (xy 268.841964 -345.091542) (xy 268.8943 -345.106909) (xy 268.943916 -345.129568)
			(xy 268.989802 -345.159057) (xy 269.031024 -345.194777) (xy 269.066744 -345.236) (xy 269.096233 -345.281886)
			(xy 269.118892 -345.331502) (xy 269.134259 -345.383838) (xy 269.142021 -345.437827) (xy 269.142021 -345.492364)
			(xy 270.62487 -345.492364) (xy 270.62487 -345.437836) (xy 270.63263 -345.383862) (xy 270.647992 -345.331542)
			(xy 270.670642 -345.28194) (xy 270.700121 -345.236066) (xy 270.735828 -345.194855) (xy 270.777036 -345.159144)
			(xy 270.822907 -345.12966) (xy 270.872506 -345.107005) (xy 270.924825 -345.091638) (xy 270.978798 -345.083873)
			(xy 271.006062 -345.083384) (xy 271.869662 -345.083384) (xy 271.896938 -345.083753) (xy 271.950936 -345.091512)
			(xy 272.003279 -345.106877) (xy 272.052903 -345.129535) (xy 272.098797 -345.159025) (xy 272.140027 -345.194747)
			(xy 272.175752 -345.235973) (xy 272.205247 -345.281864) (xy 272.22791 -345.331485) (xy 272.24328 -345.383827)
			(xy 272.251044 -345.437824) (xy 272.251044 -345.492369) (xy 273.733747 -345.492369) (xy 273.733747 -345.437831)
			(xy 273.741509 -345.383849) (xy 273.756875 -345.331521) (xy 273.779531 -345.281912) (xy 273.809017 -345.236033)
			(xy 273.844733 -345.194817) (xy 273.885951 -345.159104) (xy 273.931832 -345.129621) (xy 273.981441 -345.106967)
			(xy 274.033771 -345.091605) (xy 274.087753 -345.083846) (xy 274.115022 -345.083384) (xy 274.978622 -345.083384)
			(xy 275.005894 -345.08378) (xy 275.059881 -345.091545) (xy 275.112215 -345.106914) (xy 275.161828 -345.129574)
			(xy 275.207712 -345.159064) (xy 275.248932 -345.194784) (xy 275.284649 -345.236006) (xy 275.314136 -345.281891)
			(xy 275.336793 -345.331506) (xy 275.352159 -345.38384) (xy 275.359922 -345.437828) (xy 275.359922 -345.492365)
			(xy 276.84277 -345.492365) (xy 276.84277 -345.437835) (xy 276.850531 -345.383859) (xy 276.865893 -345.331537)
			(xy 276.888545 -345.281934) (xy 276.918026 -345.23606) (xy 276.953735 -345.194848) (xy 276.994945 -345.159137)
			(xy 277.040819 -345.129654) (xy 277.090421 -345.106999) (xy 277.142742 -345.091634) (xy 277.196717 -345.083872)
			(xy 277.223982 -345.083384) (xy 278.087582 -345.083384) (xy 278.114857 -345.083754) (xy 278.168852 -345.091515)
			(xy 278.221194 -345.106882) (xy 278.270815 -345.129541) (xy 278.316706 -345.159032) (xy 278.357934 -345.194754)
			(xy 278.393657 -345.235979) (xy 278.42315 -345.281869) (xy 278.445812 -345.33149) (xy 278.461181 -345.38383)
			(xy 278.468944 -345.437825) (xy 278.468944 -345.49237) (xy 279.951648 -345.49237) (xy 279.951648 -345.43783)
			(xy 279.95941 -345.383846) (xy 279.974776 -345.331517) (xy 279.997434 -345.281907) (xy 280.026922 -345.236026)
			(xy 280.06264 -345.19481) (xy 280.10386 -345.159097) (xy 280.149744 -345.129614) (xy 280.199356 -345.106962)
			(xy 280.251687 -345.091601) (xy 280.305672 -345.083845) (xy 280.332942 -345.083384) (xy 281.196542 -345.083384)
			(xy 281.223813 -345.083781) (xy 281.277798 -345.091549) (xy 281.330129 -345.10692) (xy 281.37974 -345.129581)
			(xy 281.425621 -345.159072) (xy 281.466839 -345.194791) (xy 281.502554 -345.236013) (xy 281.532039 -345.281897)
			(xy 281.554695 -345.33151) (xy 281.57006 -345.383843) (xy 281.577822 -345.437829) (xy 281.577822 -345.492368)
			(xy 283.060647 -345.492368) (xy 283.060647 -345.437832) (xy 283.068409 -345.383852) (xy 283.083773 -345.331525)
			(xy 283.106428 -345.281918) (xy 283.135912 -345.23604) (xy 283.171626 -345.194824) (xy 283.212841 -345.159111)
			(xy 283.25872 -345.129627) (xy 283.308327 -345.106972) (xy 283.360654 -345.091608) (xy 283.414634 -345.083847)
			(xy 283.441902 -345.083384) (xy 284.305502 -345.083384) (xy 284.332775 -345.083779) (xy 284.386764 -345.091542)
			(xy 284.4391 -345.106909) (xy 284.488716 -345.129568) (xy 284.534602 -345.159057) (xy 284.575824 -345.194777)
			(xy 284.611544 -345.236) (xy 284.641033 -345.281886) (xy 284.663692 -345.331502) (xy 284.679059 -345.383838)
			(xy 284.686821 -345.437827) (xy 284.686821 -345.492364) (xy 286.16967 -345.492364) (xy 286.16967 -345.437836)
			(xy 286.17743 -345.383862) (xy 286.192792 -345.331542) (xy 286.215442 -345.28194) (xy 286.244921 -345.236066)
			(xy 286.280628 -345.194855) (xy 286.321836 -345.159144) (xy 286.367707 -345.12966) (xy 286.417306 -345.107005)
			(xy 286.469625 -345.091638) (xy 286.523598 -345.083873) (xy 286.550862 -345.083384) (xy 287.414462 -345.083384)
			(xy 287.441738 -345.083753) (xy 287.495736 -345.091512) (xy 287.548079 -345.106877) (xy 287.597703 -345.129535)
			(xy 287.643597 -345.159025) (xy 287.684827 -345.194747) (xy 287.720552 -345.235973) (xy 287.750047 -345.281864)
			(xy 287.77271 -345.331485) (xy 287.78808 -345.383827) (xy 287.795844 -345.437824) (xy 287.795844 -345.492369)
			(xy 289.278547 -345.492369) (xy 289.278547 -345.437831) (xy 289.286309 -345.383849) (xy 289.301675 -345.331521)
			(xy 289.324331 -345.281912) (xy 289.353817 -345.236033) (xy 289.389533 -345.194817) (xy 289.430751 -345.159104)
			(xy 289.476632 -345.129621) (xy 289.526241 -345.106967) (xy 289.578571 -345.091605) (xy 289.632553 -345.083846)
			(xy 289.659822 -345.083384) (xy 290.523422 -345.083384) (xy 290.550694 -345.08378) (xy 290.604681 -345.091545)
			(xy 290.657015 -345.106914) (xy 290.706628 -345.129574) (xy 290.752512 -345.159064) (xy 290.793732 -345.194784)
			(xy 290.829449 -345.236006) (xy 290.858936 -345.281891) (xy 290.881593 -345.331506) (xy 290.896959 -345.38384)
			(xy 290.904722 -345.437828) (xy 290.904722 -345.492365) (xy 292.38757 -345.492365) (xy 292.38757 -345.437835)
			(xy 292.395331 -345.383859) (xy 292.410693 -345.331537) (xy 292.433345 -345.281934) (xy 292.462826 -345.23606)
			(xy 292.498535 -345.194848) (xy 292.539745 -345.159137) (xy 292.585619 -345.129654) (xy 292.635221 -345.106999)
			(xy 292.687542 -345.091634) (xy 292.741517 -345.083872) (xy 292.768782 -345.083384) (xy 293.632382 -345.083384)
			(xy 293.659657 -345.083754) (xy 293.713652 -345.091515) (xy 293.765994 -345.106882) (xy 293.815615 -345.129541)
			(xy 293.861506 -345.159032) (xy 293.902734 -345.194754) (xy 293.938457 -345.235979) (xy 293.96795 -345.281869)
			(xy 293.990612 -345.33149) (xy 294.005981 -345.38383) (xy 294.013744 -345.437825) (xy 294.013744 -345.49237)
			(xy 295.496448 -345.49237) (xy 295.496448 -345.43783) (xy 295.50421 -345.383846) (xy 295.519576 -345.331517)
			(xy 295.542234 -345.281907) (xy 295.571722 -345.236026) (xy 295.60744 -345.19481) (xy 295.64866 -345.159097)
			(xy 295.694544 -345.129614) (xy 295.744156 -345.106962) (xy 295.796487 -345.091601) (xy 295.850472 -345.083845)
			(xy 295.877742 -345.083384) (xy 296.741342 -345.083384) (xy 296.768613 -345.083781) (xy 296.822598 -345.091549)
			(xy 296.874929 -345.10692) (xy 296.92454 -345.129581) (xy 296.970421 -345.159072) (xy 297.011639 -345.194791)
			(xy 297.047354 -345.236013) (xy 297.076839 -345.281897) (xy 297.099495 -345.33151) (xy 297.11486 -345.383843)
			(xy 297.122622 -345.437829) (xy 297.122622 -345.492368) (xy 298.605447 -345.492368) (xy 298.605447 -345.437832)
			(xy 298.613209 -345.383852) (xy 298.628573 -345.331525) (xy 298.651228 -345.281918) (xy 298.680712 -345.23604)
			(xy 298.716426 -345.194824) (xy 298.757641 -345.159111) (xy 298.80352 -345.129627) (xy 298.853127 -345.106972)
			(xy 298.905454 -345.091608) (xy 298.959434 -345.083847) (xy 298.986702 -345.083384) (xy 299.850302 -345.083384)
			(xy 299.877575 -345.083779) (xy 299.931564 -345.091542) (xy 299.9839 -345.106909) (xy 300.033516 -345.129568)
			(xy 300.079402 -345.159057) (xy 300.120624 -345.194777) (xy 300.156344 -345.236) (xy 300.185833 -345.281886)
			(xy 300.208492 -345.331502) (xy 300.223859 -345.383838) (xy 300.231621 -345.437827) (xy 300.231621 -345.492368)
			(xy 312.121547 -345.492368) (xy 312.121547 -345.437832) (xy 312.129309 -345.383851) (xy 312.144673 -345.331525)
			(xy 312.167328 -345.281917) (xy 312.196813 -345.236039) (xy 312.232526 -345.194824) (xy 312.273742 -345.159111)
			(xy 312.319621 -345.129627) (xy 312.369228 -345.106972) (xy 312.421555 -345.091608) (xy 312.475536 -345.083847)
			(xy 312.502804 -345.083384) (xy 313.366404 -345.083384) (xy 313.393676 -345.083779) (xy 313.447666 -345.091542)
			(xy 313.500001 -345.106909) (xy 313.549617 -345.129569) (xy 313.595503 -345.159058) (xy 313.636725 -345.194778)
			(xy 313.672444 -345.236) (xy 313.701933 -345.281886) (xy 313.724592 -345.331502) (xy 313.739959 -345.383838)
			(xy 313.747721 -345.437828) (xy 313.747721 -345.492364) (xy 315.23057 -345.492364) (xy 315.23057 -345.437836)
			(xy 315.23833 -345.383862) (xy 315.253692 -345.331541) (xy 315.276343 -345.281939) (xy 315.305821 -345.236066)
			(xy 315.341529 -345.194854) (xy 315.382737 -345.159143) (xy 315.428608 -345.12966) (xy 315.478207 -345.107004)
			(xy 315.530526 -345.091638) (xy 315.5845 -345.083873) (xy 315.611764 -345.083384) (xy 316.475364 -345.083384)
			(xy 316.50264 -345.083753) (xy 316.556637 -345.091512) (xy 316.608981 -345.106877) (xy 316.658604 -345.129535)
			(xy 316.704498 -345.159026) (xy 316.745727 -345.194747) (xy 316.781453 -345.235973) (xy 316.810947 -345.281864)
			(xy 316.83361 -345.331486) (xy 316.84898 -345.383828) (xy 316.856744 -345.437824) (xy 316.856744 -345.492369)
			(xy 318.339447 -345.492369) (xy 318.339447 -345.437831) (xy 318.347209 -345.383849) (xy 318.362575 -345.33152)
			(xy 318.385231 -345.281912) (xy 318.414718 -345.236032) (xy 318.450434 -345.194817) (xy 318.491652 -345.159103)
			(xy 318.537533 -345.12962) (xy 318.587143 -345.106966) (xy 318.639472 -345.091604) (xy 318.693455 -345.083846)
			(xy 318.720724 -345.083384) (xy 319.584324 -345.083384) (xy 319.611596 -345.08378) (xy 319.665583 -345.091546)
			(xy 319.717916 -345.106915) (xy 319.767529 -345.129575) (xy 319.813413 -345.159065) (xy 319.854632 -345.194785)
			(xy 319.890349 -345.236007) (xy 319.919836 -345.281892) (xy 319.942494 -345.331507) (xy 319.95786 -345.38384)
			(xy 319.965622 -345.437828) (xy 319.965622 -345.492365) (xy 321.44847 -345.492365) (xy 321.44847 -345.437835)
			(xy 321.456231 -345.383859) (xy 321.471593 -345.331537) (xy 321.494246 -345.281934) (xy 321.523726 -345.236059)
			(xy 321.559436 -345.194847) (xy 321.600646 -345.159136) (xy 321.64652 -345.129653) (xy 321.696122 -345.106999)
			(xy 321.748443 -345.091634) (xy 321.802419 -345.083871) (xy 321.829684 -345.083384) (xy 322.693284 -345.083384)
			(xy 322.720559 -345.083755) (xy 322.774554 -345.091516) (xy 322.826895 -345.106882) (xy 322.876516 -345.129542)
			(xy 322.922407 -345.159033) (xy 322.963634 -345.194754) (xy 322.999358 -345.23598) (xy 323.02885 -345.28187)
			(xy 323.051512 -345.33149) (xy 323.066881 -345.38383) (xy 323.074644 -345.437825) (xy 323.074644 -345.49237)
			(xy 324.557348 -345.49237) (xy 324.557348 -345.43783) (xy 324.56511 -345.383846) (xy 324.580476 -345.331516)
			(xy 324.603135 -345.281906) (xy 324.632623 -345.236026) (xy 324.668341 -345.194809) (xy 324.709561 -345.159096)
			(xy 324.755445 -345.129613) (xy 324.805057 -345.106961) (xy 324.857389 -345.0916) (xy 324.911374 -345.083844)
			(xy 324.938644 -345.083384) (xy 325.802244 -345.083384) (xy 325.829515 -345.083782) (xy 325.8835 -345.091549)
			(xy 325.93583 -345.10692) (xy 325.985441 -345.129582) (xy 326.031322 -345.159072) (xy 326.072539 -345.194792)
			(xy 326.108254 -345.236013) (xy 326.137739 -345.281898) (xy 326.160395 -345.331511) (xy 326.17576 -345.383843)
			(xy 326.183522 -345.437829) (xy 326.183522 -345.492368) (xy 327.666347 -345.492368) (xy 327.666347 -345.437832)
			(xy 327.674109 -345.383851) (xy 327.689473 -345.331525) (xy 327.712128 -345.281917) (xy 327.741613 -345.236039)
			(xy 327.777326 -345.194824) (xy 327.818542 -345.159111) (xy 327.864421 -345.129627) (xy 327.914028 -345.106972)
			(xy 327.966355 -345.091608) (xy 328.020336 -345.083847) (xy 328.047604 -345.083384) (xy 328.911204 -345.083384)
			(xy 328.938476 -345.083779) (xy 328.992466 -345.091542) (xy 329.044801 -345.106909) (xy 329.094417 -345.129569)
			(xy 329.140303 -345.159058) (xy 329.181525 -345.194778) (xy 329.217244 -345.236) (xy 329.246733 -345.281886)
			(xy 329.269392 -345.331502) (xy 329.284759 -345.383838) (xy 329.292521 -345.437828) (xy 329.292521 -345.492364)
			(xy 330.77537 -345.492364) (xy 330.77537 -345.437836) (xy 330.78313 -345.383862) (xy 330.798492 -345.331541)
			(xy 330.821143 -345.281939) (xy 330.850621 -345.236066) (xy 330.886329 -345.194854) (xy 330.927537 -345.159143)
			(xy 330.973408 -345.12966) (xy 331.023007 -345.107004) (xy 331.075326 -345.091638) (xy 331.1293 -345.083873)
			(xy 331.156564 -345.083384) (xy 332.020164 -345.083384) (xy 332.04744 -345.083753) (xy 332.101437 -345.091512)
			(xy 332.153781 -345.106877) (xy 332.203404 -345.129535) (xy 332.249298 -345.159026) (xy 332.290527 -345.194747)
			(xy 332.326253 -345.235973) (xy 332.355747 -345.281864) (xy 332.37841 -345.331486) (xy 332.39378 -345.383828)
			(xy 332.401544 -345.437824) (xy 332.401544 -345.492369) (xy 333.884247 -345.492369) (xy 333.884247 -345.437831)
			(xy 333.892009 -345.383849) (xy 333.907375 -345.33152) (xy 333.930031 -345.281912) (xy 333.959518 -345.236032)
			(xy 333.995234 -345.194817) (xy 334.036452 -345.159103) (xy 334.082333 -345.12962) (xy 334.131943 -345.106966)
			(xy 334.184272 -345.091604) (xy 334.238255 -345.083846) (xy 334.265524 -345.083384) (xy 335.129124 -345.083384)
			(xy 335.156396 -345.08378) (xy 335.210383 -345.091546) (xy 335.262716 -345.106915) (xy 335.312329 -345.129575)
			(xy 335.358213 -345.159065) (xy 335.399432 -345.194785) (xy 335.435149 -345.236007) (xy 335.464636 -345.281892)
			(xy 335.487294 -345.331507) (xy 335.50266 -345.38384) (xy 335.510422 -345.437828) (xy 335.510422 -345.492365)
			(xy 336.99327 -345.492365) (xy 336.99327 -345.437835) (xy 337.001031 -345.383859) (xy 337.016393 -345.331537)
			(xy 337.039046 -345.281934) (xy 337.068526 -345.236059) (xy 337.104236 -345.194847) (xy 337.145446 -345.159136)
			(xy 337.19132 -345.129653) (xy 337.240922 -345.106999) (xy 337.293243 -345.091634) (xy 337.347219 -345.083871)
			(xy 337.374484 -345.083384) (xy 338.238084 -345.083384) (xy 338.265359 -345.083755) (xy 338.319354 -345.091516)
			(xy 338.371695 -345.106882) (xy 338.421316 -345.129542) (xy 338.467207 -345.159033) (xy 338.508434 -345.194754)
			(xy 338.544158 -345.23598) (xy 338.57365 -345.28187) (xy 338.596312 -345.33149) (xy 338.611681 -345.38383)
			(xy 338.619444 -345.437825) (xy 338.619444 -345.49237) (xy 340.102148 -345.49237) (xy 340.102148 -345.43783)
			(xy 340.10991 -345.383846) (xy 340.125276 -345.331516) (xy 340.147935 -345.281906) (xy 340.177423 -345.236026)
			(xy 340.213141 -345.194809) (xy 340.254361 -345.159096) (xy 340.300245 -345.129613) (xy 340.349857 -345.106961)
			(xy 340.402189 -345.0916) (xy 340.456174 -345.083844) (xy 340.483444 -345.083384) (xy 341.347044 -345.083384)
			(xy 341.374315 -345.083782) (xy 341.4283 -345.091549) (xy 341.48063 -345.10692) (xy 341.530241 -345.129582)
			(xy 341.576122 -345.159072) (xy 341.617339 -345.194792) (xy 341.653054 -345.236013) (xy 341.682539 -345.281898)
			(xy 341.705195 -345.331511) (xy 341.72056 -345.383843) (xy 341.728322 -345.437829) (xy 341.728322 -345.492368)
			(xy 343.211147 -345.492368) (xy 343.211147 -345.437832) (xy 343.218909 -345.383851) (xy 343.234273 -345.331525)
			(xy 343.256928 -345.281917) (xy 343.286413 -345.236039) (xy 343.322126 -345.194824) (xy 343.363342 -345.159111)
			(xy 343.409221 -345.129627) (xy 343.458828 -345.106972) (xy 343.511155 -345.091608) (xy 343.565136 -345.083847)
			(xy 343.592404 -345.083384) (xy 344.456004 -345.083384) (xy 344.483276 -345.083779) (xy 344.537266 -345.091542)
			(xy 344.589601 -345.106909) (xy 344.639217 -345.129569) (xy 344.685103 -345.159058) (xy 344.726325 -345.194778)
			(xy 344.762044 -345.236) (xy 344.791533 -345.281886) (xy 344.814192 -345.331502) (xy 344.829559 -345.383838)
			(xy 344.837321 -345.437828) (xy 344.837321 -345.492365) (xy 370.80677 -345.492365) (xy 370.80677 -345.437835)
			(xy 370.81453 -345.383859) (xy 370.829893 -345.331538) (xy 370.852545 -345.281935) (xy 370.882025 -345.236061)
			(xy 370.917734 -345.194848) (xy 370.958945 -345.159137) (xy 371.004817 -345.129655) (xy 371.054419 -345.107)
			(xy 371.10674 -345.091635) (xy 371.160715 -345.083872) (xy 371.18798 -345.083384) (xy 372.05158 -345.083384)
			(xy 372.078855 -345.083754) (xy 372.132851 -345.091515) (xy 372.185192 -345.106881) (xy 372.234814 -345.129541)
			(xy 372.280705 -345.159031) (xy 372.321933 -345.194753) (xy 372.357657 -345.235978) (xy 372.38715 -345.281869)
			(xy 372.409812 -345.331489) (xy 372.425181 -345.38383) (xy 372.432944 -345.437825) (xy 372.432944 -345.49237)
			(xy 373.915647 -345.49237) (xy 373.915647 -345.43783) (xy 373.92341 -345.383847) (xy 373.938776 -345.331517)
			(xy 373.961434 -345.281907) (xy 373.990922 -345.236027) (xy 374.026639 -345.194811) (xy 374.067859 -345.159098)
			(xy 374.113742 -345.129615) (xy 374.163355 -345.106962) (xy 374.215686 -345.091601) (xy 374.26967 -345.083845)
			(xy 374.29694 -345.083384) (xy 375.16054 -345.083384) (xy 375.187811 -345.083781) (xy 375.241797 -345.091549)
			(xy 375.294128 -345.106919) (xy 375.343739 -345.12958) (xy 375.38962 -345.159071) (xy 375.430838 -345.19479)
			(xy 375.466553 -345.236012) (xy 375.496039 -345.281896) (xy 375.518695 -345.33151) (xy 375.53406 -345.383843)
			(xy 375.541822 -345.437829) (xy 375.541822 -345.492366) (xy 377.02467 -345.492366) (xy 377.02467 -345.437834)
			(xy 377.032431 -345.383857) (xy 377.047795 -345.331534) (xy 377.070448 -345.281929) (xy 377.09993 -345.236054)
			(xy 377.135641 -345.194841) (xy 377.176854 -345.15913) (xy 377.222729 -345.129648) (xy 377.272334 -345.106995)
			(xy 377.324657 -345.091631) (xy 377.378634 -345.08387) (xy 377.4059 -345.083384) (xy 378.2695 -345.083384)
			(xy 378.296773 -345.083779) (xy 378.350763 -345.091541) (xy 378.403099 -345.106908) (xy 378.452715 -345.129567)
			(xy 378.498601 -345.159057) (xy 378.539824 -345.194776) (xy 378.575543 -345.235999) (xy 378.605033 -345.281885)
			(xy 378.627692 -345.331501) (xy 378.643059 -345.383837) (xy 378.650821 -345.437827) (xy 378.650821 -345.492364)
			(xy 380.13367 -345.492364) (xy 380.13367 -345.437836) (xy 380.14143 -345.383862) (xy 380.156791 -345.331542)
			(xy 380.179442 -345.281941) (xy 380.208921 -345.236067) (xy 380.244627 -345.194855) (xy 380.285835 -345.159145)
			(xy 380.331705 -345.129661) (xy 380.381305 -345.107005) (xy 380.433623 -345.091638) (xy 380.487596 -345.083873)
			(xy 380.51486 -345.083384) (xy 381.37846 -345.083384) (xy 381.405736 -345.083753) (xy 381.459734 -345.091511)
			(xy 381.512078 -345.106876) (xy 381.561702 -345.129534) (xy 381.607596 -345.159024) (xy 381.648826 -345.194746)
			(xy 381.684552 -345.235972) (xy 381.714047 -345.281863) (xy 381.73671 -345.331485) (xy 381.75208 -345.383827)
			(xy 381.759844 -345.437824) (xy 381.759844 -345.492369) (xy 383.242547 -345.492369) (xy 383.242547 -345.437831)
			(xy 383.250309 -345.383849) (xy 383.265675 -345.331521) (xy 383.288331 -345.281913) (xy 383.317817 -345.236034)
			(xy 383.353532 -345.194818) (xy 383.39475 -345.159105) (xy 383.44063 -345.129621) (xy 383.49024 -345.106968)
			(xy 383.542569 -345.091605) (xy 383.596551 -345.083846) (xy 383.62382 -345.083384) (xy 384.48742 -345.083384)
			(xy 384.514692 -345.08378) (xy 384.56868 -345.091545) (xy 384.621013 -345.106914) (xy 384.670627 -345.129574)
			(xy 384.716511 -345.159064) (xy 384.757731 -345.194783) (xy 384.793448 -345.236005) (xy 384.822936 -345.281891)
			(xy 384.845593 -345.331506) (xy 384.860959 -345.38384) (xy 384.868722 -345.437828) (xy 384.868722 -345.492365)
			(xy 386.35157 -345.492365) (xy 386.35157 -345.437835) (xy 386.35933 -345.383859) (xy 386.374693 -345.331538)
			(xy 386.397345 -345.281935) (xy 386.426825 -345.236061) (xy 386.462534 -345.194848) (xy 386.503745 -345.159137)
			(xy 386.549617 -345.129655) (xy 386.599219 -345.107) (xy 386.65154 -345.091635) (xy 386.705515 -345.083872)
			(xy 386.73278 -345.083384) (xy 387.59638 -345.083384) (xy 387.623655 -345.083754) (xy 387.677651 -345.091515)
			(xy 387.729992 -345.106881) (xy 387.779614 -345.129541) (xy 387.825505 -345.159031) (xy 387.866733 -345.194753)
			(xy 387.902457 -345.235978) (xy 387.93195 -345.281869) (xy 387.954612 -345.331489) (xy 387.969981 -345.38383)
			(xy 387.977744 -345.437825) (xy 387.977744 -345.49237) (xy 389.460447 -345.49237) (xy 389.460447 -345.43783)
			(xy 389.46821 -345.383847) (xy 389.483576 -345.331517) (xy 389.506234 -345.281907) (xy 389.535722 -345.236027)
			(xy 389.571439 -345.194811) (xy 389.612659 -345.159098) (xy 389.658542 -345.129615) (xy 389.708155 -345.106962)
			(xy 389.760486 -345.091601) (xy 389.81447 -345.083845) (xy 389.84174 -345.083384) (xy 390.70534 -345.083384)
			(xy 390.732611 -345.083781) (xy 390.786597 -345.091549) (xy 390.838928 -345.106919) (xy 390.888539 -345.12958)
			(xy 390.93442 -345.159071) (xy 390.975638 -345.19479) (xy 391.011353 -345.236012) (xy 391.040839 -345.281896)
			(xy 391.063495 -345.33151) (xy 391.07886 -345.383843) (xy 391.086622 -345.437829) (xy 391.086622 -345.492366)
			(xy 392.56947 -345.492366) (xy 392.56947 -345.437834) (xy 392.577231 -345.383857) (xy 392.592595 -345.331534)
			(xy 392.615248 -345.281929) (xy 392.64473 -345.236054) (xy 392.680441 -345.194841) (xy 392.721654 -345.15913)
			(xy 392.767529 -345.129648) (xy 392.817134 -345.106995) (xy 392.869457 -345.091631) (xy 392.923434 -345.08387)
			(xy 392.9507 -345.083384) (xy 393.8143 -345.083384) (xy 393.841573 -345.083779) (xy 393.895563 -345.091541)
			(xy 393.947899 -345.106908) (xy 393.997515 -345.129567) (xy 394.043401 -345.159057) (xy 394.084624 -345.194776)
			(xy 394.120343 -345.235999) (xy 394.149833 -345.281885) (xy 394.172492 -345.331501) (xy 394.187859 -345.383837)
			(xy 394.195621 -345.437827) (xy 394.195621 -345.492364) (xy 395.67847 -345.492364) (xy 395.67847 -345.437836)
			(xy 395.68623 -345.383862) (xy 395.701591 -345.331542) (xy 395.724242 -345.281941) (xy 395.753721 -345.236067)
			(xy 395.789427 -345.194855) (xy 395.830635 -345.159145) (xy 395.876505 -345.129661) (xy 395.926105 -345.107005)
			(xy 395.978423 -345.091638) (xy 396.032396 -345.083873) (xy 396.05966 -345.083384) (xy 396.92326 -345.083384)
			(xy 396.950536 -345.083753) (xy 397.004534 -345.091511) (xy 397.056878 -345.106876) (xy 397.106502 -345.129534)
			(xy 397.152396 -345.159024) (xy 397.193626 -345.194746) (xy 397.229352 -345.235972) (xy 397.258847 -345.281863)
			(xy 397.28151 -345.331485) (xy 397.29688 -345.383827) (xy 397.304644 -345.437824) (xy 397.304644 -345.492369)
			(xy 398.787347 -345.492369) (xy 398.787347 -345.437831) (xy 398.795109 -345.383849) (xy 398.810475 -345.331521)
			(xy 398.833131 -345.281913) (xy 398.862617 -345.236034) (xy 398.898332 -345.194818) (xy 398.93955 -345.159105)
			(xy 398.98543 -345.129621) (xy 399.03504 -345.106968) (xy 399.087369 -345.091605) (xy 399.141351 -345.083846)
			(xy 399.16862 -345.083384) (xy 400.03222 -345.083384) (xy 400.059492 -345.08378) (xy 400.11348 -345.091545)
			(xy 400.165813 -345.106914) (xy 400.215427 -345.129574) (xy 400.261311 -345.159064) (xy 400.302531 -345.194783)
			(xy 400.338248 -345.236005) (xy 400.367736 -345.281891) (xy 400.390393 -345.331506) (xy 400.405759 -345.38384)
			(xy 400.413522 -345.437828) (xy 400.413522 -345.492365) (xy 401.89637 -345.492365) (xy 401.89637 -345.437835)
			(xy 401.90413 -345.383859) (xy 401.919493 -345.331538) (xy 401.942145 -345.281935) (xy 401.971625 -345.236061)
			(xy 402.007334 -345.194848) (xy 402.048545 -345.159137) (xy 402.094417 -345.129655) (xy 402.144019 -345.107)
			(xy 402.19634 -345.091635) (xy 402.250315 -345.083872) (xy 402.27758 -345.083384) (xy 403.14118 -345.083384)
			(xy 403.168455 -345.083754) (xy 403.222451 -345.091515) (xy 403.274792 -345.106881) (xy 403.324414 -345.129541)
			(xy 403.370305 -345.159031) (xy 403.411533 -345.194753) (xy 403.447257 -345.235978) (xy 403.47675 -345.281869)
			(xy 403.499412 -345.331489) (xy 403.514781 -345.38383) (xy 403.522544 -345.437825) (xy 403.522544 -345.492366)
			(xy 408.91387 -345.492366) (xy 408.91387 -345.437834) (xy 408.921631 -345.383858) (xy 408.936994 -345.331535)
			(xy 408.959647 -345.281932) (xy 408.989128 -345.236057) (xy 409.024838 -345.194844) (xy 409.06605 -345.159133)
			(xy 409.111925 -345.129651) (xy 409.161528 -345.106997) (xy 409.21385 -345.091633) (xy 409.267826 -345.083871)
			(xy 409.295092 -345.083384) (xy 410.158692 -345.083384) (xy 410.185967 -345.083755) (xy 410.239961 -345.091517)
			(xy 410.292301 -345.106885) (xy 410.341921 -345.129544) (xy 410.387811 -345.159035) (xy 410.429037 -345.194757)
			(xy 410.46476 -345.235982) (xy 410.494252 -345.281872) (xy 410.516913 -345.331492) (xy 410.532281 -345.383831)
			(xy 410.540044 -345.437825) (xy 410.540044 -345.492364) (xy 412.02287 -345.492364) (xy 412.02287 -345.437836)
			(xy 412.03063 -345.383863) (xy 412.045991 -345.331544) (xy 412.068641 -345.281943) (xy 412.098119 -345.23607)
			(xy 412.133824 -345.194858) (xy 412.175031 -345.159147) (xy 412.220901 -345.129664) (xy 412.270499 -345.107008)
			(xy 412.322816 -345.09164) (xy 412.376788 -345.083874) (xy 412.404052 -345.083384) (xy 413.267652 -345.083384)
			(xy 413.294929 -345.083752) (xy 413.348927 -345.09151) (xy 413.401272 -345.106874) (xy 413.450897 -345.129531)
			(xy 413.496792 -345.159021) (xy 413.538023 -345.194743) (xy 413.57375 -345.235969) (xy 413.603246 -345.281861)
			(xy 413.625909 -345.331483) (xy 413.64128 -345.383826) (xy 413.649044 -345.437824) (xy 413.649044 -345.492368)
			(xy 415.131747 -345.492368) (xy 415.131747 -345.437832) (xy 415.139509 -345.38385) (xy 415.154874 -345.331523)
			(xy 415.17753 -345.281915) (xy 415.207015 -345.236036) (xy 415.242729 -345.194821) (xy 415.283946 -345.159108)
			(xy 415.329826 -345.129624) (xy 415.379434 -345.10697) (xy 415.431762 -345.091606) (xy 415.485744 -345.083847)
			(xy 415.513012 -345.083384) (xy 416.376612 -345.083384) (xy 416.403884 -345.083779) (xy 416.457873 -345.091543)
			(xy 416.510207 -345.106912) (xy 416.559822 -345.129571) (xy 416.605707 -345.159061) (xy 416.646928 -345.194781)
			(xy 416.682646 -345.236003) (xy 416.712135 -345.281889) (xy 416.734793 -345.331504) (xy 416.750159 -345.383839)
			(xy 416.757921 -345.437828) (xy 416.757921 -345.492365) (xy 418.24077 -345.492365) (xy 418.24077 -345.437835)
			(xy 418.24853 -345.383861) (xy 418.263892 -345.33154) (xy 418.286544 -345.281937) (xy 418.316023 -345.236063)
			(xy 418.351731 -345.194851) (xy 418.392941 -345.15914) (xy 418.438813 -345.129657) (xy 418.488413 -345.107002)
			(xy 418.540733 -345.091636) (xy 418.594707 -345.083872) (xy 418.621972 -345.083384) (xy 419.485572 -345.083384)
			(xy 419.512848 -345.083754) (xy 419.566844 -345.091514) (xy 419.619186 -345.106879) (xy 419.668809 -345.129538)
			(xy 419.714702 -345.159028) (xy 419.75593 -345.19475) (xy 419.791655 -345.235976) (xy 419.821149 -345.281866)
			(xy 419.843811 -345.331487) (xy 419.859181 -345.383829) (xy 419.866944 -345.437824) (xy 419.866944 -345.492369)
			(xy 421.349647 -345.492369) (xy 421.349647 -345.437831) (xy 421.35741 -345.383848) (xy 421.372776 -345.331519)
			(xy 421.395433 -345.281909) (xy 421.42492 -345.23603) (xy 421.460636 -345.194814) (xy 421.501855 -345.159101)
			(xy 421.547738 -345.129617) (xy 421.597349 -345.106964) (xy 421.649679 -345.091603) (xy 421.703663 -345.083845)
			(xy 421.730932 -345.083384) (xy 422.594532 -345.083384) (xy 422.621803 -345.083781) (xy 422.67579 -345.091547)
			(xy 422.728122 -345.106917) (xy 422.777734 -345.129578) (xy 422.823616 -345.159068) (xy 422.864835 -345.194788)
			(xy 422.900551 -345.236009) (xy 422.930038 -345.281894) (xy 422.952694 -345.331508) (xy 422.96806 -345.383842)
			(xy 422.975822 -345.437829) (xy 422.975822 -345.492366) (xy 424.45867 -345.492366) (xy 424.45867 -345.437834)
			(xy 424.466431 -345.383858) (xy 424.481794 -345.331535) (xy 424.504447 -345.281932) (xy 424.533928 -345.236057)
			(xy 424.569638 -345.194844) (xy 424.61085 -345.159133) (xy 424.656725 -345.129651) (xy 424.706328 -345.106997)
			(xy 424.75865 -345.091633) (xy 424.812626 -345.083871) (xy 424.839892 -345.083384) (xy 425.703492 -345.083384)
			(xy 425.730767 -345.083755) (xy 425.784761 -345.091517) (xy 425.837101 -345.106885) (xy 425.886721 -345.129544)
			(xy 425.932611 -345.159035) (xy 425.973837 -345.194757) (xy 426.00956 -345.235982) (xy 426.039052 -345.281872)
			(xy 426.061713 -345.331492) (xy 426.077081 -345.383831) (xy 426.084844 -345.437825) (xy 426.084844 -345.492364)
			(xy 427.56767 -345.492364) (xy 427.56767 -345.437836) (xy 427.57543 -345.383863) (xy 427.590791 -345.331544)
			(xy 427.613441 -345.281943) (xy 427.642919 -345.23607) (xy 427.678624 -345.194858) (xy 427.719831 -345.159147)
			(xy 427.765701 -345.129664) (xy 427.815299 -345.107008) (xy 427.867616 -345.09164) (xy 427.921588 -345.083874)
			(xy 427.948852 -345.083384) (xy 428.812452 -345.083384) (xy 428.839729 -345.083752) (xy 428.893727 -345.09151)
			(xy 428.946072 -345.106874) (xy 428.995697 -345.129531) (xy 429.041592 -345.159021) (xy 429.082823 -345.194743)
			(xy 429.11855 -345.235969) (xy 429.148046 -345.281861) (xy 429.170709 -345.331483) (xy 429.18608 -345.383826)
			(xy 429.193844 -345.437824) (xy 429.193844 -345.492368) (xy 430.676547 -345.492368) (xy 430.676547 -345.437832)
			(xy 430.684309 -345.38385) (xy 430.699674 -345.331523) (xy 430.72233 -345.281915) (xy 430.751815 -345.236036)
			(xy 430.787529 -345.194821) (xy 430.828746 -345.159108) (xy 430.874626 -345.129624) (xy 430.924234 -345.10697)
			(xy 430.976562 -345.091606) (xy 431.030544 -345.083847) (xy 431.057812 -345.083384) (xy 431.921412 -345.083384)
			(xy 431.948684 -345.083779) (xy 432.002673 -345.091543) (xy 432.055007 -345.106912) (xy 432.104622 -345.129571)
			(xy 432.150507 -345.159061) (xy 432.191728 -345.194781) (xy 432.227446 -345.236003) (xy 432.256935 -345.281889)
			(xy 432.279593 -345.331504) (xy 432.294959 -345.383839) (xy 432.302721 -345.437828) (xy 432.302721 -345.492365)
			(xy 433.78557 -345.492365) (xy 433.78557 -345.437835) (xy 433.79333 -345.383861) (xy 433.808692 -345.33154)
			(xy 433.831344 -345.281937) (xy 433.860823 -345.236063) (xy 433.896531 -345.194851) (xy 433.937741 -345.15914)
			(xy 433.983613 -345.129657) (xy 434.033213 -345.107002) (xy 434.085533 -345.091636) (xy 434.139507 -345.083872)
			(xy 434.166772 -345.083384) (xy 435.030372 -345.083384) (xy 435.057648 -345.083754) (xy 435.111644 -345.091514)
			(xy 435.163986 -345.106879) (xy 435.213609 -345.129538) (xy 435.259502 -345.159028) (xy 435.30073 -345.19475)
			(xy 435.336455 -345.235976) (xy 435.365949 -345.281866) (xy 435.388611 -345.331487) (xy 435.403981 -345.383829)
			(xy 435.411744 -345.437824) (xy 435.411744 -345.492369) (xy 436.894447 -345.492369) (xy 436.894447 -345.437831)
			(xy 436.90221 -345.383848) (xy 436.917576 -345.331519) (xy 436.940233 -345.281909) (xy 436.96972 -345.23603)
			(xy 437.005436 -345.194814) (xy 437.046655 -345.159101) (xy 437.092538 -345.129617) (xy 437.142149 -345.106964)
			(xy 437.194479 -345.091603) (xy 437.248463 -345.083845) (xy 437.275732 -345.083384) (xy 438.139332 -345.083384)
			(xy 438.166603 -345.083781) (xy 438.22059 -345.091547) (xy 438.272922 -345.106917) (xy 438.322534 -345.129578)
			(xy 438.368416 -345.159068) (xy 438.409635 -345.194788) (xy 438.445351 -345.236009) (xy 438.474838 -345.281894)
			(xy 438.497494 -345.331508) (xy 438.51286 -345.383842) (xy 438.520622 -345.437829) (xy 438.520622 -345.492366)
			(xy 440.00347 -345.492366) (xy 440.00347 -345.437834) (xy 440.011231 -345.383858) (xy 440.026594 -345.331535)
			(xy 440.049247 -345.281932) (xy 440.078728 -345.236057) (xy 440.114438 -345.194844) (xy 440.15565 -345.159133)
			(xy 440.201525 -345.129651) (xy 440.251128 -345.106997) (xy 440.30345 -345.091633) (xy 440.357426 -345.083871)
			(xy 440.384692 -345.083384) (xy 441.248292 -345.083384) (xy 441.275567 -345.083755) (xy 441.329561 -345.091517)
			(xy 441.381901 -345.106885) (xy 441.431521 -345.129544) (xy 441.477411 -345.159035) (xy 441.518637 -345.194757)
			(xy 441.55436 -345.235982) (xy 441.583852 -345.281872) (xy 441.606513 -345.331492) (xy 441.621881 -345.383831)
			(xy 441.629644 -345.437825) (xy 441.629644 -345.492375) (xy 441.621881 -345.546369) (xy 441.606513 -345.598708)
			(xy 441.583852 -345.648328) (xy 441.55436 -345.694218) (xy 441.518637 -345.735443) (xy 441.477411 -345.771165)
			(xy 441.431521 -345.800656) (xy 441.381901 -345.823315) (xy 441.329561 -345.838683) (xy 441.275567 -345.846445)
			(xy 441.248292 -345.846908) (xy 440.384692 -345.846908) (xy 440.357426 -345.846329) (xy 440.30345 -345.838567)
			(xy 440.251128 -345.823203) (xy 440.201525 -345.800549) (xy 440.15565 -345.771067) (xy 440.114438 -345.735356)
			(xy 440.078728 -345.694143) (xy 440.049247 -345.648268) (xy 440.026594 -345.598665) (xy 440.011231 -345.546342)
			(xy 440.00347 -345.492366) (xy 438.520622 -345.492366) (xy 438.520622 -345.492371) (xy 438.51286 -345.546358)
			(xy 438.497494 -345.598692) (xy 438.474838 -345.648306) (xy 438.445351 -345.694191) (xy 438.409635 -345.735412)
			(xy 438.368416 -345.771132) (xy 438.322534 -345.800622) (xy 438.272922 -345.823283) (xy 438.22059 -345.838653)
			(xy 438.166603 -345.846419) (xy 438.139332 -345.846908) (xy 437.275732 -345.846908) (xy 437.248463 -345.846355)
			(xy 437.194479 -345.838597) (xy 437.142149 -345.823236) (xy 437.092538 -345.800583) (xy 437.046655 -345.771099)
			(xy 437.005436 -345.735386) (xy 436.96972 -345.69417) (xy 436.940233 -345.648291) (xy 436.917576 -345.598681)
			(xy 436.90221 -345.546352) (xy 436.894447 -345.492369) (xy 435.411744 -345.492369) (xy 435.411744 -345.492376)
			(xy 435.403981 -345.546371) (xy 435.388611 -345.598713) (xy 435.365949 -345.648334) (xy 435.336455 -345.694224)
			(xy 435.30073 -345.73545) (xy 435.259502 -345.771172) (xy 435.213609 -345.800662) (xy 435.163986 -345.823321)
			(xy 435.111644 -345.838686) (xy 435.057648 -345.846446) (xy 435.030372 -345.846908) (xy 434.166772 -345.846908)
			(xy 434.139507 -345.846328) (xy 434.085533 -345.838564) (xy 434.033213 -345.823198) (xy 433.983613 -345.800543)
			(xy 433.937741 -345.77106) (xy 433.896531 -345.735349) (xy 433.860823 -345.694137) (xy 433.831344 -345.648263)
			(xy 433.808692 -345.59866) (xy 433.79333 -345.546339) (xy 433.78557 -345.492365) (xy 432.302721 -345.492365)
			(xy 432.302721 -345.492372) (xy 432.294959 -345.546361) (xy 432.279593 -345.598696) (xy 432.256935 -345.648311)
			(xy 432.227446 -345.694197) (xy 432.191728 -345.735419) (xy 432.150507 -345.771139) (xy 432.104622 -345.800629)
			(xy 432.055007 -345.823288) (xy 432.002673 -345.838657) (xy 431.948684 -345.846421) (xy 431.921412 -345.846908)
			(xy 431.057812 -345.846908) (xy 431.030544 -345.846353) (xy 430.976562 -345.838594) (xy 430.924234 -345.82323)
			(xy 430.874626 -345.800576) (xy 430.828746 -345.771092) (xy 430.787529 -345.735379) (xy 430.751815 -345.694164)
			(xy 430.72233 -345.648285) (xy 430.699674 -345.598677) (xy 430.684309 -345.54635) (xy 430.676547 -345.492368)
			(xy 429.193844 -345.492368) (xy 429.193844 -345.492376) (xy 429.18608 -345.546374) (xy 429.170709 -345.598717)
			(xy 429.148046 -345.648339) (xy 429.11855 -345.694231) (xy 429.082823 -345.735457) (xy 429.041592 -345.771179)
			(xy 428.995697 -345.800669) (xy 428.946072 -345.823326) (xy 428.893727 -345.83869) (xy 428.839729 -345.846448)
			(xy 428.812452 -345.846908) (xy 427.948852 -345.846908) (xy 427.921588 -345.846326) (xy 427.867616 -345.83856)
			(xy 427.815299 -345.823192) (xy 427.765701 -345.800536) (xy 427.719831 -345.771053) (xy 427.678624 -345.735342)
			(xy 427.642919 -345.69413) (xy 427.613441 -345.648257) (xy 427.590791 -345.598656) (xy 427.57543 -345.546337)
			(xy 427.56767 -345.492364) (xy 426.084844 -345.492364) (xy 426.084844 -345.492375) (xy 426.077081 -345.546369)
			(xy 426.061713 -345.598708) (xy 426.039052 -345.648328) (xy 426.00956 -345.694218) (xy 425.973837 -345.735443)
			(xy 425.932611 -345.771165) (xy 425.886721 -345.800656) (xy 425.837101 -345.823315) (xy 425.784761 -345.838683)
			(xy 425.730767 -345.846445) (xy 425.703492 -345.846908) (xy 424.839892 -345.846908) (xy 424.812626 -345.846329)
			(xy 424.75865 -345.838567) (xy 424.706328 -345.823203) (xy 424.656725 -345.800549) (xy 424.61085 -345.771067)
			(xy 424.569638 -345.735356) (xy 424.533928 -345.694143) (xy 424.504447 -345.648268) (xy 424.481794 -345.598665)
			(xy 424.466431 -345.546342) (xy 424.45867 -345.492366) (xy 422.975822 -345.492366) (xy 422.975822 -345.492371)
			(xy 422.96806 -345.546358) (xy 422.952694 -345.598692) (xy 422.930038 -345.648306) (xy 422.900551 -345.694191)
			(xy 422.864835 -345.735412) (xy 422.823616 -345.771132) (xy 422.777734 -345.800622) (xy 422.728122 -345.823283)
			(xy 422.67579 -345.838653) (xy 422.621803 -345.846419) (xy 422.594532 -345.846908) (xy 421.730932 -345.846908)
			(xy 421.703663 -345.846355) (xy 421.649679 -345.838597) (xy 421.597349 -345.823236) (xy 421.547738 -345.800583)
			(xy 421.501855 -345.771099) (xy 421.460636 -345.735386) (xy 421.42492 -345.69417) (xy 421.395433 -345.648291)
			(xy 421.372776 -345.598681) (xy 421.35741 -345.546352) (xy 421.349647 -345.492369) (xy 419.866944 -345.492369)
			(xy 419.866944 -345.492376) (xy 419.859181 -345.546371) (xy 419.843811 -345.598713) (xy 419.821149 -345.648334)
			(xy 419.791655 -345.694224) (xy 419.75593 -345.73545) (xy 419.714702 -345.771172) (xy 419.668809 -345.800662)
			(xy 419.619186 -345.823321) (xy 419.566844 -345.838686) (xy 419.512848 -345.846446) (xy 419.485572 -345.846908)
			(xy 418.621972 -345.846908) (xy 418.594707 -345.846328) (xy 418.540733 -345.838564) (xy 418.488413 -345.823198)
			(xy 418.438813 -345.800543) (xy 418.392941 -345.77106) (xy 418.351731 -345.735349) (xy 418.316023 -345.694137)
			(xy 418.286544 -345.648263) (xy 418.263892 -345.59866) (xy 418.24853 -345.546339) (xy 418.24077 -345.492365)
			(xy 416.757921 -345.492365) (xy 416.757921 -345.492372) (xy 416.750159 -345.546361) (xy 416.734793 -345.598696)
			(xy 416.712135 -345.648311) (xy 416.682646 -345.694197) (xy 416.646928 -345.735419) (xy 416.605707 -345.771139)
			(xy 416.559822 -345.800629) (xy 416.510207 -345.823288) (xy 416.457873 -345.838657) (xy 416.403884 -345.846421)
			(xy 416.376612 -345.846908) (xy 415.513012 -345.846908) (xy 415.485744 -345.846353) (xy 415.431762 -345.838594)
			(xy 415.379434 -345.82323) (xy 415.329826 -345.800576) (xy 415.283946 -345.771092) (xy 415.242729 -345.735379)
			(xy 415.207015 -345.694164) (xy 415.17753 -345.648285) (xy 415.154874 -345.598677) (xy 415.139509 -345.54635)
			(xy 415.131747 -345.492368) (xy 413.649044 -345.492368) (xy 413.649044 -345.492376) (xy 413.64128 -345.546374)
			(xy 413.625909 -345.598717) (xy 413.603246 -345.648339) (xy 413.57375 -345.694231) (xy 413.538023 -345.735457)
			(xy 413.496792 -345.771179) (xy 413.450897 -345.800669) (xy 413.401272 -345.823326) (xy 413.348927 -345.83869)
			(xy 413.294929 -345.846448) (xy 413.267652 -345.846908) (xy 412.404052 -345.846908) (xy 412.376788 -345.846326)
			(xy 412.322816 -345.83856) (xy 412.270499 -345.823192) (xy 412.220901 -345.800536) (xy 412.175031 -345.771053)
			(xy 412.133824 -345.735342) (xy 412.098119 -345.69413) (xy 412.068641 -345.648257) (xy 412.045991 -345.598656)
			(xy 412.03063 -345.546337) (xy 412.02287 -345.492364) (xy 410.540044 -345.492364) (xy 410.540044 -345.492375)
			(xy 410.532281 -345.546369) (xy 410.516913 -345.598708) (xy 410.494252 -345.648328) (xy 410.46476 -345.694218)
			(xy 410.429037 -345.735443) (xy 410.387811 -345.771165) (xy 410.341921 -345.800656) (xy 410.292301 -345.823315)
			(xy 410.239961 -345.838683) (xy 410.185967 -345.846445) (xy 410.158692 -345.846908) (xy 409.295092 -345.846908)
			(xy 409.267826 -345.846329) (xy 409.21385 -345.838567) (xy 409.161528 -345.823203) (xy 409.111925 -345.800549)
			(xy 409.06605 -345.771067) (xy 409.024838 -345.735356) (xy 408.989128 -345.694143) (xy 408.959647 -345.648268)
			(xy 408.936994 -345.598665) (xy 408.921631 -345.546342) (xy 408.91387 -345.492366) (xy 403.522544 -345.492366)
			(xy 403.522544 -345.492375) (xy 403.514781 -345.54637) (xy 403.499412 -345.598711) (xy 403.47675 -345.648331)
			(xy 403.447257 -345.694221) (xy 403.411533 -345.735447) (xy 403.370305 -345.771169) (xy 403.324414 -345.800659)
			(xy 403.274792 -345.823319) (xy 403.222451 -345.838685) (xy 403.168455 -345.846446) (xy 403.14118 -345.846908)
			(xy 402.27758 -345.846908) (xy 402.250315 -345.846328) (xy 402.19634 -345.838565) (xy 402.144019 -345.8232)
			(xy 402.094417 -345.800545) (xy 402.048545 -345.771063) (xy 402.007334 -345.735352) (xy 401.971625 -345.694139)
			(xy 401.942145 -345.648265) (xy 401.919493 -345.598662) (xy 401.90413 -345.546341) (xy 401.89637 -345.492365)
			(xy 400.413522 -345.492365) (xy 400.413522 -345.492372) (xy 400.405759 -345.54636) (xy 400.390393 -345.598694)
			(xy 400.367736 -345.648309) (xy 400.338248 -345.694195) (xy 400.302531 -345.735417) (xy 400.261311 -345.771136)
			(xy 400.215427 -345.800626) (xy 400.165813 -345.823286) (xy 400.11348 -345.838655) (xy 400.059492 -345.84642)
			(xy 400.03222 -345.846908) (xy 399.16862 -345.846908) (xy 399.141351 -345.846354) (xy 399.087369 -345.838595)
			(xy 399.03504 -345.823232) (xy 398.98543 -345.800579) (xy 398.93955 -345.771095) (xy 398.898332 -345.735382)
			(xy 398.862617 -345.694166) (xy 398.833131 -345.648287) (xy 398.810475 -345.598679) (xy 398.795109 -345.546351)
			(xy 398.787347 -345.492369) (xy 397.304644 -345.492369) (xy 397.304644 -345.492376) (xy 397.29688 -345.546373)
			(xy 397.28151 -345.598715) (xy 397.258847 -345.648337) (xy 397.229352 -345.694228) (xy 397.193626 -345.735454)
			(xy 397.152396 -345.771176) (xy 397.106502 -345.800666) (xy 397.056878 -345.823324) (xy 397.004534 -345.838689)
			(xy 396.950536 -345.846447) (xy 396.92326 -345.846908) (xy 396.05966 -345.846908) (xy 396.032396 -345.846327)
			(xy 395.978423 -345.838562) (xy 395.926105 -345.823195) (xy 395.876505 -345.800539) (xy 395.830635 -345.771055)
			(xy 395.789427 -345.735345) (xy 395.753721 -345.694133) (xy 395.724242 -345.648259) (xy 395.701591 -345.598658)
			(xy 395.68623 -345.546338) (xy 395.67847 -345.492364) (xy 394.195621 -345.492364) (xy 394.195621 -345.492373)
			(xy 394.187859 -345.546363) (xy 394.172492 -345.598699) (xy 394.149833 -345.648315) (xy 394.120343 -345.694201)
			(xy 394.084624 -345.735424) (xy 394.043401 -345.771143) (xy 393.997515 -345.800633) (xy 393.947899 -345.823292)
			(xy 393.895563 -345.838659) (xy 393.841573 -345.846421) (xy 393.8143 -345.846908) (xy 392.9507 -345.846908)
			(xy 392.923434 -345.84633) (xy 392.869457 -345.838569) (xy 392.817134 -345.823205) (xy 392.767529 -345.800552)
			(xy 392.721654 -345.77107) (xy 392.680441 -345.735359) (xy 392.64473 -345.694146) (xy 392.615248 -345.648271)
			(xy 392.592595 -345.598666) (xy 392.577231 -345.546343) (xy 392.56947 -345.492366) (xy 391.086622 -345.492366)
			(xy 391.086622 -345.492371) (xy 391.07886 -345.546357) (xy 391.063495 -345.59869) (xy 391.040839 -345.648304)
			(xy 391.011353 -345.694188) (xy 390.975638 -345.73541) (xy 390.93442 -345.771129) (xy 390.888539 -345.80062)
			(xy 390.838928 -345.823281) (xy 390.786597 -345.838651) (xy 390.732611 -345.846419) (xy 390.70534 -345.846908)
			(xy 389.84174 -345.846908) (xy 389.81447 -345.846355) (xy 389.760486 -345.838599) (xy 389.708155 -345.823238)
			(xy 389.658542 -345.800585) (xy 389.612659 -345.771102) (xy 389.571439 -345.735389) (xy 389.535722 -345.694173)
			(xy 389.506234 -345.648293) (xy 389.483576 -345.598683) (xy 389.46821 -345.546353) (xy 389.460447 -345.49237)
			(xy 387.977744 -345.49237) (xy 387.977744 -345.492375) (xy 387.969981 -345.54637) (xy 387.954612 -345.598711)
			(xy 387.93195 -345.648331) (xy 387.902457 -345.694221) (xy 387.866733 -345.735447) (xy 387.825505 -345.771169)
			(xy 387.779614 -345.800659) (xy 387.729992 -345.823319) (xy 387.677651 -345.838685) (xy 387.623655 -345.846446)
			(xy 387.59638 -345.846908) (xy 386.73278 -345.846908) (xy 386.705515 -345.846328) (xy 386.65154 -345.838565)
			(xy 386.599219 -345.8232) (xy 386.549617 -345.800545) (xy 386.503745 -345.771063) (xy 386.462534 -345.735352)
			(xy 386.426825 -345.694139) (xy 386.397345 -345.648265) (xy 386.374693 -345.598662) (xy 386.35933 -345.546341)
			(xy 386.35157 -345.492365) (xy 384.868722 -345.492365) (xy 384.868722 -345.492372) (xy 384.860959 -345.54636)
			(xy 384.845593 -345.598694) (xy 384.822936 -345.648309) (xy 384.793448 -345.694195) (xy 384.757731 -345.735417)
			(xy 384.716511 -345.771136) (xy 384.670627 -345.800626) (xy 384.621013 -345.823286) (xy 384.56868 -345.838655)
			(xy 384.514692 -345.84642) (xy 384.48742 -345.846908) (xy 383.62382 -345.846908) (xy 383.596551 -345.846354)
			(xy 383.542569 -345.838595) (xy 383.49024 -345.823232) (xy 383.44063 -345.800579) (xy 383.39475 -345.771095)
			(xy 383.353532 -345.735382) (xy 383.317817 -345.694166) (xy 383.288331 -345.648287) (xy 383.265675 -345.598679)
			(xy 383.250309 -345.546351) (xy 383.242547 -345.492369) (xy 381.759844 -345.492369) (xy 381.759844 -345.492376)
			(xy 381.75208 -345.546373) (xy 381.73671 -345.598715) (xy 381.714047 -345.648337) (xy 381.684552 -345.694228)
			(xy 381.648826 -345.735454) (xy 381.607596 -345.771176) (xy 381.561702 -345.800666) (xy 381.512078 -345.823324)
			(xy 381.459734 -345.838689) (xy 381.405736 -345.846447) (xy 381.37846 -345.846908) (xy 380.51486 -345.846908)
			(xy 380.487596 -345.846327) (xy 380.433623 -345.838562) (xy 380.381305 -345.823195) (xy 380.331705 -345.800539)
			(xy 380.285835 -345.771055) (xy 380.244627 -345.735345) (xy 380.208921 -345.694133) (xy 380.179442 -345.648259)
			(xy 380.156791 -345.598658) (xy 380.14143 -345.546338) (xy 380.13367 -345.492364) (xy 378.650821 -345.492364)
			(xy 378.650821 -345.492373) (xy 378.643059 -345.546363) (xy 378.627692 -345.598699) (xy 378.605033 -345.648315)
			(xy 378.575543 -345.694201) (xy 378.539824 -345.735424) (xy 378.498601 -345.771143) (xy 378.452715 -345.800633)
			(xy 378.403099 -345.823292) (xy 378.350763 -345.838659) (xy 378.296773 -345.846421) (xy 378.2695 -345.846908)
			(xy 377.4059 -345.846908) (xy 377.378634 -345.84633) (xy 377.324657 -345.838569) (xy 377.272334 -345.823205)
			(xy 377.222729 -345.800552) (xy 377.176854 -345.77107) (xy 377.135641 -345.735359) (xy 377.09993 -345.694146)
			(xy 377.070448 -345.648271) (xy 377.047795 -345.598666) (xy 377.032431 -345.546343) (xy 377.02467 -345.492366)
			(xy 375.541822 -345.492366) (xy 375.541822 -345.492371) (xy 375.53406 -345.546357) (xy 375.518695 -345.59869)
			(xy 375.496039 -345.648304) (xy 375.466553 -345.694188) (xy 375.430838 -345.73541) (xy 375.38962 -345.771129)
			(xy 375.343739 -345.80062) (xy 375.294128 -345.823281) (xy 375.241797 -345.838651) (xy 375.187811 -345.846419)
			(xy 375.16054 -345.846908) (xy 374.29694 -345.846908) (xy 374.26967 -345.846355) (xy 374.215686 -345.838599)
			(xy 374.163355 -345.823238) (xy 374.113742 -345.800585) (xy 374.067859 -345.771102) (xy 374.026639 -345.735389)
			(xy 373.990922 -345.694173) (xy 373.961434 -345.648293) (xy 373.938776 -345.598683) (xy 373.92341 -345.546353)
			(xy 373.915647 -345.49237) (xy 372.432944 -345.49237) (xy 372.432944 -345.492375) (xy 372.425181 -345.54637)
			(xy 372.409812 -345.598711) (xy 372.38715 -345.648331) (xy 372.357657 -345.694221) (xy 372.321933 -345.735447)
			(xy 372.280705 -345.771169) (xy 372.234814 -345.800659) (xy 372.185192 -345.823319) (xy 372.132851 -345.838685)
			(xy 372.078855 -345.846446) (xy 372.05158 -345.846908) (xy 371.18798 -345.846908) (xy 371.160715 -345.846328)
			(xy 371.10674 -345.838565) (xy 371.054419 -345.8232) (xy 371.004817 -345.800545) (xy 370.958945 -345.771063)
			(xy 370.917734 -345.735352) (xy 370.882025 -345.694139) (xy 370.852545 -345.648265) (xy 370.829893 -345.598662)
			(xy 370.81453 -345.546341) (xy 370.80677 -345.492365) (xy 344.837321 -345.492365) (xy 344.837321 -345.492372)
			(xy 344.829559 -345.546362) (xy 344.814192 -345.598698) (xy 344.791533 -345.648314) (xy 344.762044 -345.6942)
			(xy 344.726325 -345.735422) (xy 344.685103 -345.771142) (xy 344.639217 -345.800631) (xy 344.589601 -345.823291)
			(xy 344.537266 -345.838658) (xy 344.483276 -345.846421) (xy 344.456004 -345.846908) (xy 343.592404 -345.846908)
			(xy 343.565136 -345.846353) (xy 343.511155 -345.838592) (xy 343.458828 -345.823228) (xy 343.409221 -345.800573)
			(xy 343.363342 -345.771089) (xy 343.322126 -345.735376) (xy 343.286413 -345.694161) (xy 343.256928 -345.648283)
			(xy 343.234273 -345.598675) (xy 343.218909 -345.546349) (xy 343.211147 -345.492368) (xy 341.728322 -345.492368)
			(xy 341.728322 -345.492371) (xy 341.72056 -345.546357) (xy 341.705195 -345.598689) (xy 341.682539 -345.648302)
			(xy 341.653054 -345.694187) (xy 341.617339 -345.735408) (xy 341.576122 -345.771128) (xy 341.530241 -345.800618)
			(xy 341.48063 -345.82328) (xy 341.4283 -345.838651) (xy 341.374315 -345.846418) (xy 341.347044 -345.846908)
			(xy 340.483444 -345.846908) (xy 340.456174 -345.846356) (xy 340.402189 -345.8386) (xy 340.349857 -345.823239)
			(xy 340.300245 -345.800587) (xy 340.254361 -345.771104) (xy 340.213141 -345.735391) (xy 340.177423 -345.694174)
			(xy 340.147935 -345.648294) (xy 340.125276 -345.598684) (xy 340.10991 -345.546354) (xy 340.102148 -345.49237)
			(xy 338.619444 -345.49237) (xy 338.619444 -345.492375) (xy 338.611681 -345.54637) (xy 338.596312 -345.59871)
			(xy 338.57365 -345.64833) (xy 338.544158 -345.69422) (xy 338.508434 -345.735446) (xy 338.467207 -345.771167)
			(xy 338.421316 -345.800658) (xy 338.371695 -345.823318) (xy 338.319354 -345.838684) (xy 338.265359 -345.846445)
			(xy 338.238084 -345.846908) (xy 337.374484 -345.846908) (xy 337.347219 -345.846329) (xy 337.293243 -345.838566)
			(xy 337.240922 -345.823201) (xy 337.19132 -345.800547) (xy 337.145446 -345.771064) (xy 337.104236 -345.735353)
			(xy 337.068526 -345.694141) (xy 337.039046 -345.648266) (xy 337.016393 -345.598663) (xy 337.001031 -345.546341)
			(xy 336.99327 -345.492365) (xy 335.510422 -345.492365) (xy 335.510422 -345.492372) (xy 335.50266 -345.54636)
			(xy 335.487294 -345.598693) (xy 335.464636 -345.648308) (xy 335.435149 -345.694193) (xy 335.399432 -345.735415)
			(xy 335.358213 -345.771135) (xy 335.312329 -345.800625) (xy 335.262716 -345.823285) (xy 335.210383 -345.838654)
			(xy 335.156396 -345.84642) (xy 335.129124 -345.846908) (xy 334.265524 -345.846908) (xy 334.238255 -345.846354)
			(xy 334.184272 -345.838596) (xy 334.131943 -345.823234) (xy 334.082333 -345.80058) (xy 334.036452 -345.771097)
			(xy 333.995234 -345.735383) (xy 333.959518 -345.694168) (xy 333.930031 -345.648288) (xy 333.907375 -345.59868)
			(xy 333.892009 -345.546351) (xy 333.884247 -345.492369) (xy 332.401544 -345.492369) (xy 332.401544 -345.492376)
			(xy 332.39378 -345.546372) (xy 332.37841 -345.598714) (xy 332.355747 -345.648336) (xy 332.326253 -345.694227)
			(xy 332.290527 -345.735453) (xy 332.249298 -345.771174) (xy 332.203404 -345.800665) (xy 332.153781 -345.823323)
			(xy 332.101437 -345.838688) (xy 332.04744 -345.846447) (xy 332.020164 -345.846908) (xy 331.156564 -345.846908)
			(xy 331.1293 -345.846327) (xy 331.075326 -345.838562) (xy 331.023007 -345.823196) (xy 330.973408 -345.80054)
			(xy 330.927537 -345.771057) (xy 330.886329 -345.735346) (xy 330.850622 -345.694134) (xy 330.821143 -345.648261)
			(xy 330.798492 -345.598659) (xy 330.78313 -345.546338) (xy 330.77537 -345.492364) (xy 329.292521 -345.492364)
			(xy 329.292521 -345.492372) (xy 329.284759 -345.546362) (xy 329.269392 -345.598698) (xy 329.246733 -345.648314)
			(xy 329.217244 -345.6942) (xy 329.181525 -345.735422) (xy 329.140303 -345.771142) (xy 329.094417 -345.800631)
			(xy 329.044801 -345.823291) (xy 328.992466 -345.838658) (xy 328.938476 -345.846421) (xy 328.911204 -345.846908)
			(xy 328.047604 -345.846908) (xy 328.020336 -345.846353) (xy 327.966355 -345.838592) (xy 327.914028 -345.823228)
			(xy 327.864421 -345.800573) (xy 327.818542 -345.771089) (xy 327.777326 -345.735376) (xy 327.741613 -345.694161)
			(xy 327.712128 -345.648283) (xy 327.689473 -345.598675) (xy 327.674109 -345.546349) (xy 327.666347 -345.492368)
			(xy 326.183522 -345.492368) (xy 326.183522 -345.492371) (xy 326.17576 -345.546357) (xy 326.160395 -345.598689)
			(xy 326.137739 -345.648302) (xy 326.108254 -345.694187) (xy 326.072539 -345.735408) (xy 326.031322 -345.771128)
			(xy 325.985441 -345.800618) (xy 325.93583 -345.82328) (xy 325.8835 -345.838651) (xy 325.829515 -345.846418)
			(xy 325.802244 -345.846908) (xy 324.938644 -345.846908) (xy 324.911374 -345.846356) (xy 324.857389 -345.8386)
			(xy 324.805057 -345.823239) (xy 324.755445 -345.800587) (xy 324.709561 -345.771104) (xy 324.668341 -345.735391)
			(xy 324.632623 -345.694174) (xy 324.603135 -345.648294) (xy 324.580476 -345.598684) (xy 324.56511 -345.546354)
			(xy 324.557348 -345.49237) (xy 323.074644 -345.49237) (xy 323.074644 -345.492375) (xy 323.066881 -345.54637)
			(xy 323.051512 -345.59871) (xy 323.02885 -345.64833) (xy 322.999358 -345.69422) (xy 322.963634 -345.735446)
			(xy 322.922407 -345.771167) (xy 322.876516 -345.800658) (xy 322.826895 -345.823318) (xy 322.774554 -345.838684)
			(xy 322.720559 -345.846445) (xy 322.693284 -345.846908) (xy 321.829684 -345.846908) (xy 321.802419 -345.846329)
			(xy 321.748443 -345.838566) (xy 321.696122 -345.823201) (xy 321.64652 -345.800547) (xy 321.600646 -345.771064)
			(xy 321.559436 -345.735353) (xy 321.523726 -345.694141) (xy 321.494246 -345.648266) (xy 321.471593 -345.598663)
			(xy 321.456231 -345.546341) (xy 321.44847 -345.492365) (xy 319.965622 -345.492365) (xy 319.965622 -345.492372)
			(xy 319.95786 -345.54636) (xy 319.942494 -345.598693) (xy 319.919836 -345.648308) (xy 319.890349 -345.694193)
			(xy 319.854632 -345.735415) (xy 319.813413 -345.771135) (xy 319.767529 -345.800625) (xy 319.717916 -345.823285)
			(xy 319.665583 -345.838654) (xy 319.611596 -345.84642) (xy 319.584324 -345.846908) (xy 318.720724 -345.846908)
			(xy 318.693455 -345.846354) (xy 318.639472 -345.838596) (xy 318.587143 -345.823234) (xy 318.537533 -345.80058)
			(xy 318.491652 -345.771097) (xy 318.450434 -345.735383) (xy 318.414718 -345.694168) (xy 318.385231 -345.648288)
			(xy 318.362575 -345.59868) (xy 318.347209 -345.546351) (xy 318.339447 -345.492369) (xy 316.856744 -345.492369)
			(xy 316.856744 -345.492376) (xy 316.84898 -345.546372) (xy 316.83361 -345.598714) (xy 316.810947 -345.648336)
			(xy 316.781453 -345.694227) (xy 316.745727 -345.735453) (xy 316.704498 -345.771174) (xy 316.658604 -345.800665)
			(xy 316.608981 -345.823323) (xy 316.556637 -345.838688) (xy 316.50264 -345.846447) (xy 316.475364 -345.846908)
			(xy 315.611764 -345.846908) (xy 315.5845 -345.846327) (xy 315.530526 -345.838562) (xy 315.478207 -345.823196)
			(xy 315.428608 -345.80054) (xy 315.382737 -345.771057) (xy 315.341529 -345.735346) (xy 315.305822 -345.694134)
			(xy 315.276343 -345.648261) (xy 315.253692 -345.598659) (xy 315.23833 -345.546338) (xy 315.23057 -345.492364)
			(xy 313.747721 -345.492364) (xy 313.747721 -345.492372) (xy 313.739959 -345.546362) (xy 313.724592 -345.598698)
			(xy 313.701933 -345.648314) (xy 313.672444 -345.6942) (xy 313.636725 -345.735422) (xy 313.595503 -345.771142)
			(xy 313.549617 -345.800631) (xy 313.500001 -345.823291) (xy 313.447666 -345.838658) (xy 313.393676 -345.846421)
			(xy 313.366404 -345.846908) (xy 312.502804 -345.846908) (xy 312.475536 -345.846353) (xy 312.421555 -345.838592)
			(xy 312.369228 -345.823228) (xy 312.319621 -345.800573) (xy 312.273742 -345.771089) (xy 312.232526 -345.735376)
			(xy 312.196813 -345.694161) (xy 312.167328 -345.648283) (xy 312.144673 -345.598675) (xy 312.129309 -345.546349)
			(xy 312.121547 -345.492368) (xy 300.231621 -345.492368) (xy 300.231621 -345.492373) (xy 300.223859 -345.546362)
			(xy 300.208492 -345.598698) (xy 300.185833 -345.648314) (xy 300.156344 -345.6942) (xy 300.120624 -345.735423)
			(xy 300.079402 -345.771143) (xy 300.033516 -345.800632) (xy 299.9839 -345.823291) (xy 299.931564 -345.838658)
			(xy 299.877575 -345.846421) (xy 299.850302 -345.846908) (xy 298.986702 -345.846908) (xy 298.959434 -345.846353)
			(xy 298.905454 -345.838592) (xy 298.853127 -345.823228) (xy 298.80352 -345.800573) (xy 298.757641 -345.771089)
			(xy 298.716426 -345.735376) (xy 298.680712 -345.69416) (xy 298.651228 -345.648282) (xy 298.628573 -345.598675)
			(xy 298.613209 -345.546348) (xy 298.605447 -345.492368) (xy 297.122622 -345.492368) (xy 297.122622 -345.492371)
			(xy 297.11486 -345.546357) (xy 297.099495 -345.59869) (xy 297.076839 -345.648303) (xy 297.047354 -345.694187)
			(xy 297.011639 -345.735409) (xy 296.970421 -345.771128) (xy 296.92454 -345.800619) (xy 296.874929 -345.82328)
			(xy 296.822598 -345.838651) (xy 296.768613 -345.846419) (xy 296.741342 -345.846908) (xy 295.877742 -345.846908)
			(xy 295.850472 -345.846355) (xy 295.796487 -345.838599) (xy 295.744156 -345.823238) (xy 295.694543 -345.800586)
			(xy 295.64866 -345.771103) (xy 295.60744 -345.73539) (xy 295.571722 -345.694174) (xy 295.542234 -345.648293)
			(xy 295.519576 -345.598683) (xy 295.50421 -345.546354) (xy 295.496448 -345.49237) (xy 294.013744 -345.49237)
			(xy 294.013744 -345.492375) (xy 294.005981 -345.54637) (xy 293.990612 -345.59871) (xy 293.96795 -345.648331)
			(xy 293.938457 -345.694221) (xy 293.902734 -345.735446) (xy 293.861506 -345.771168) (xy 293.815615 -345.800659)
			(xy 293.765994 -345.823318) (xy 293.713652 -345.838685) (xy 293.659657 -345.846446) (xy 293.632382 -345.846908)
			(xy 292.768782 -345.846908) (xy 292.741517 -345.846328) (xy 292.687542 -345.838566) (xy 292.635221 -345.823201)
			(xy 292.585619 -345.800546) (xy 292.539745 -345.771063) (xy 292.498535 -345.735352) (xy 292.462826 -345.69414)
			(xy 292.433345 -345.648266) (xy 292.410693 -345.598663) (xy 292.395331 -345.546341) (xy 292.38757 -345.492365)
			(xy 290.904722 -345.492365) (xy 290.904722 -345.492372) (xy 290.896959 -345.54636) (xy 290.881593 -345.598694)
			(xy 290.858936 -345.648309) (xy 290.829449 -345.694194) (xy 290.793732 -345.735416) (xy 290.752512 -345.771136)
			(xy 290.706628 -345.800626) (xy 290.657015 -345.823286) (xy 290.604681 -345.838655) (xy 290.550694 -345.84642)
			(xy 290.523422 -345.846908) (xy 289.659822 -345.846908) (xy 289.632553 -345.846354) (xy 289.57857 -345.838595)
			(xy 289.526241 -345.823233) (xy 289.476632 -345.800579) (xy 289.430751 -345.771096) (xy 289.389533 -345.735383)
			(xy 289.353817 -345.694167) (xy 289.324331 -345.648288) (xy 289.301675 -345.598679) (xy 289.286309 -345.546351)
			(xy 289.278547 -345.492369) (xy 287.795844 -345.492369) (xy 287.795844 -345.492376) (xy 287.78808 -345.546373)
			(xy 287.77271 -345.598715) (xy 287.750047 -345.648336) (xy 287.720552 -345.694227) (xy 287.684827 -345.735453)
			(xy 287.643597 -345.771175) (xy 287.597703 -345.800665) (xy 287.548079 -345.823323) (xy 287.495736 -345.838688)
			(xy 287.441738 -345.846447) (xy 287.414462 -345.846908) (xy 286.550862 -345.846908) (xy 286.523598 -345.846327)
			(xy 286.469625 -345.838562) (xy 286.417306 -345.823195) (xy 286.367707 -345.80054) (xy 286.321836 -345.771056)
			(xy 286.280628 -345.735345) (xy 286.244921 -345.694134) (xy 286.215442 -345.64826) (xy 286.192792 -345.598658)
			(xy 286.17743 -345.546338) (xy 286.16967 -345.492364) (xy 284.686821 -345.492364) (xy 284.686821 -345.492373)
			(xy 284.679059 -345.546362) (xy 284.663692 -345.598698) (xy 284.641033 -345.648314) (xy 284.611544 -345.6942)
			(xy 284.575824 -345.735423) (xy 284.534602 -345.771143) (xy 284.488716 -345.800632) (xy 284.4391 -345.823291)
			(xy 284.386764 -345.838658) (xy 284.332775 -345.846421) (xy 284.305502 -345.846908) (xy 283.441902 -345.846908)
			(xy 283.414634 -345.846353) (xy 283.360654 -345.838592) (xy 283.308327 -345.823228) (xy 283.25872 -345.800573)
			(xy 283.212841 -345.771089) (xy 283.171626 -345.735376) (xy 283.135912 -345.69416) (xy 283.106428 -345.648282)
			(xy 283.083773 -345.598675) (xy 283.068409 -345.546348) (xy 283.060647 -345.492368) (xy 281.577822 -345.492368)
			(xy 281.577822 -345.492371) (xy 281.57006 -345.546357) (xy 281.554695 -345.59869) (xy 281.532039 -345.648303)
			(xy 281.502554 -345.694187) (xy 281.466839 -345.735409) (xy 281.425621 -345.771128) (xy 281.37974 -345.800619)
			(xy 281.330129 -345.82328) (xy 281.277798 -345.838651) (xy 281.223813 -345.846419) (xy 281.196542 -345.846908)
			(xy 280.332942 -345.846908) (xy 280.305672 -345.846355) (xy 280.251687 -345.838599) (xy 280.199356 -345.823238)
			(xy 280.149743 -345.800586) (xy 280.10386 -345.771103) (xy 280.06264 -345.73539) (xy 280.026922 -345.694174)
			(xy 279.997434 -345.648293) (xy 279.974776 -345.598683) (xy 279.95941 -345.546354) (xy 279.951648 -345.49237)
			(xy 278.468944 -345.49237) (xy 278.468944 -345.492375) (xy 278.461181 -345.54637) (xy 278.445812 -345.59871)
			(xy 278.42315 -345.648331) (xy 278.393657 -345.694221) (xy 278.357934 -345.735446) (xy 278.316706 -345.771168)
			(xy 278.270815 -345.800659) (xy 278.221194 -345.823318) (xy 278.168852 -345.838685) (xy 278.114857 -345.846446)
			(xy 278.087582 -345.846908) (xy 277.223982 -345.846908) (xy 277.196717 -345.846328) (xy 277.142742 -345.838566)
			(xy 277.090421 -345.823201) (xy 277.040819 -345.800546) (xy 276.994945 -345.771063) (xy 276.953735 -345.735352)
			(xy 276.918026 -345.69414) (xy 276.888545 -345.648266) (xy 276.865893 -345.598663) (xy 276.850531 -345.546341)
			(xy 276.84277 -345.492365) (xy 275.359922 -345.492365) (xy 275.359922 -345.492372) (xy 275.352159 -345.54636)
			(xy 275.336793 -345.598694) (xy 275.314136 -345.648309) (xy 275.284649 -345.694194) (xy 275.248932 -345.735416)
			(xy 275.207712 -345.771136) (xy 275.161828 -345.800626) (xy 275.112215 -345.823286) (xy 275.059881 -345.838655)
			(xy 275.005894 -345.84642) (xy 274.978622 -345.846908) (xy 274.115022 -345.846908) (xy 274.087753 -345.846354)
			(xy 274.03377 -345.838595) (xy 273.981441 -345.823233) (xy 273.931832 -345.800579) (xy 273.885951 -345.771096)
			(xy 273.844733 -345.735383) (xy 273.809017 -345.694167) (xy 273.779531 -345.648288) (xy 273.756875 -345.598679)
			(xy 273.741509 -345.546351) (xy 273.733747 -345.492369) (xy 272.251044 -345.492369) (xy 272.251044 -345.492376)
			(xy 272.24328 -345.546373) (xy 272.22791 -345.598715) (xy 272.205247 -345.648336) (xy 272.175752 -345.694227)
			(xy 272.140027 -345.735453) (xy 272.098797 -345.771175) (xy 272.052903 -345.800665) (xy 272.003279 -345.823323)
			(xy 271.950936 -345.838688) (xy 271.896938 -345.846447) (xy 271.869662 -345.846908) (xy 271.006062 -345.846908)
			(xy 270.978798 -345.846327) (xy 270.924825 -345.838562) (xy 270.872506 -345.823195) (xy 270.822907 -345.80054)
			(xy 270.777036 -345.771056) (xy 270.735828 -345.735345) (xy 270.700121 -345.694134) (xy 270.670642 -345.64826)
			(xy 270.647992 -345.598658) (xy 270.63263 -345.546338) (xy 270.62487 -345.492364) (xy 269.142021 -345.492364)
			(xy 269.142021 -345.492373) (xy 269.134259 -345.546362) (xy 269.118892 -345.598698) (xy 269.096233 -345.648314)
			(xy 269.066744 -345.6942) (xy 269.031024 -345.735423) (xy 268.989802 -345.771143) (xy 268.943916 -345.800632)
			(xy 268.8943 -345.823291) (xy 268.841964 -345.838658) (xy 268.787975 -345.846421) (xy 268.760702 -345.846908)
			(xy 267.897102 -345.846908) (xy 267.869834 -345.846353) (xy 267.815854 -345.838592) (xy 267.763527 -345.823228)
			(xy 267.71392 -345.800573) (xy 267.668041 -345.771089) (xy 267.626826 -345.735376) (xy 267.591112 -345.69416)
			(xy 267.561628 -345.648282) (xy 267.538973 -345.598675) (xy 267.523609 -345.546348) (xy 267.515847 -345.492368)
			(xy 197.629644 -345.492368) (xy 197.629644 -345.492376) (xy 197.621881 -345.546371) (xy 197.606511 -345.598713)
			(xy 197.583849 -345.648334) (xy 197.554355 -345.694224) (xy 197.51863 -345.73545) (xy 197.477402 -345.771172)
			(xy 197.431509 -345.800662) (xy 197.381886 -345.823321) (xy 197.329544 -345.838686) (xy 197.275548 -345.846446)
			(xy 197.248272 -345.846908) (xy 196.384672 -345.846908) (xy 196.357407 -345.846328) (xy 196.303433 -345.838564)
			(xy 196.251113 -345.823198) (xy 196.201513 -345.800543) (xy 196.155641 -345.77106) (xy 196.114431 -345.735349)
			(xy 196.078723 -345.694137) (xy 196.049244 -345.648263) (xy 196.026592 -345.59866) (xy 196.01123 -345.546339)
			(xy 196.00347 -345.492365) (xy 194.520621 -345.492365) (xy 194.520621 -345.492372) (xy 194.512859 -345.546361)
			(xy 194.497493 -345.598696) (xy 194.474835 -345.648311) (xy 194.445346 -345.694197) (xy 194.409628 -345.735419)
			(xy 194.368407 -345.771139) (xy 194.322522 -345.800629) (xy 194.272907 -345.823288) (xy 194.220573 -345.838657)
			(xy 194.166584 -345.846421) (xy 194.139312 -345.846908) (xy 193.275712 -345.846908) (xy 193.248444 -345.846353)
			(xy 193.194462 -345.838594) (xy 193.142134 -345.82323) (xy 193.092526 -345.800576) (xy 193.046646 -345.771092)
			(xy 193.005429 -345.735379) (xy 192.969715 -345.694164) (xy 192.94023 -345.648285) (xy 192.917574 -345.598677)
			(xy 192.902209 -345.54635) (xy 192.894447 -345.492368) (xy 191.411744 -345.492368) (xy 191.411744 -345.492376)
			(xy 191.40398 -345.546374) (xy 191.388609 -345.598717) (xy 191.365946 -345.648339) (xy 191.33645 -345.694231)
			(xy 191.300723 -345.735457) (xy 191.259492 -345.771179) (xy 191.213597 -345.800669) (xy 191.163972 -345.823326)
			(xy 191.111627 -345.83869) (xy 191.057629 -345.846448) (xy 191.030352 -345.846908) (xy 190.166752 -345.846908)
			(xy 190.139488 -345.846326) (xy 190.085516 -345.83856) (xy 190.033199 -345.823192) (xy 189.983601 -345.800536)
			(xy 189.937731 -345.771053) (xy 189.896524 -345.735342) (xy 189.860819 -345.69413) (xy 189.831341 -345.648257)
			(xy 189.808691 -345.598656) (xy 189.79333 -345.546337) (xy 189.78557 -345.492364) (xy 188.302744 -345.492364)
			(xy 188.302744 -345.492375) (xy 188.294981 -345.546369) (xy 188.279613 -345.598708) (xy 188.256952 -345.648328)
			(xy 188.22746 -345.694218) (xy 188.191737 -345.735443) (xy 188.150511 -345.771165) (xy 188.104621 -345.800656)
			(xy 188.055001 -345.823315) (xy 188.002661 -345.838683) (xy 187.948667 -345.846445) (xy 187.921392 -345.846908)
			(xy 187.057792 -345.846908) (xy 187.030526 -345.846329) (xy 186.97655 -345.838567) (xy 186.924228 -345.823203)
			(xy 186.874625 -345.800549) (xy 186.82875 -345.771067) (xy 186.787538 -345.735356) (xy 186.751828 -345.694143)
			(xy 186.722347 -345.648268) (xy 186.699694 -345.598665) (xy 186.684331 -345.546342) (xy 186.67657 -345.492366)
			(xy 185.193722 -345.492366) (xy 185.193722 -345.492371) (xy 185.18596 -345.546358) (xy 185.170594 -345.598692)
			(xy 185.147938 -345.648306) (xy 185.118451 -345.694191) (xy 185.082735 -345.735412) (xy 185.041516 -345.771132)
			(xy 184.995634 -345.800622) (xy 184.946022 -345.823283) (xy 184.89369 -345.838653) (xy 184.839703 -345.846419)
			(xy 184.812432 -345.846908) (xy 183.948832 -345.846908) (xy 183.921563 -345.846355) (xy 183.867579 -345.838597)
			(xy 183.815249 -345.823236) (xy 183.765638 -345.800583) (xy 183.719755 -345.771099) (xy 183.678536 -345.735386)
			(xy 183.64282 -345.69417) (xy 183.613333 -345.648291) (xy 183.590676 -345.598681) (xy 183.57531 -345.546352)
			(xy 183.567547 -345.492369) (xy 182.084844 -345.492369) (xy 182.084844 -345.492376) (xy 182.077081 -345.546371)
			(xy 182.061711 -345.598713) (xy 182.039049 -345.648334) (xy 182.009555 -345.694224) (xy 181.97383 -345.73545)
			(xy 181.932602 -345.771172) (xy 181.886709 -345.800662) (xy 181.837086 -345.823321) (xy 181.784744 -345.838686)
			(xy 181.730748 -345.846446) (xy 181.703472 -345.846908) (xy 180.839872 -345.846908) (xy 180.812607 -345.846328)
			(xy 180.758633 -345.838564) (xy 180.706313 -345.823198) (xy 180.656713 -345.800543) (xy 180.610841 -345.77106)
			(xy 180.569631 -345.735349) (xy 180.533923 -345.694137) (xy 180.504444 -345.648263) (xy 180.481792 -345.59866)
			(xy 180.46643 -345.546339) (xy 180.45867 -345.492365) (xy 178.975821 -345.492365) (xy 178.975821 -345.492372)
			(xy 178.968059 -345.546361) (xy 178.952693 -345.598696) (xy 178.930035 -345.648311) (xy 178.900546 -345.694197)
			(xy 178.864828 -345.735419) (xy 178.823607 -345.771139) (xy 178.777722 -345.800629) (xy 178.728107 -345.823288)
			(xy 178.675773 -345.838657) (xy 178.621784 -345.846421) (xy 178.594512 -345.846908) (xy 177.730912 -345.846908)
			(xy 177.703644 -345.846353) (xy 177.649662 -345.838594) (xy 177.597334 -345.82323) (xy 177.547726 -345.800576)
			(xy 177.501846 -345.771092) (xy 177.460629 -345.735379) (xy 177.424915 -345.694164) (xy 177.39543 -345.648285)
			(xy 177.372774 -345.598677) (xy 177.357409 -345.54635) (xy 177.349647 -345.492368) (xy 175.866944 -345.492368)
			(xy 175.866944 -345.492376) (xy 175.85918 -345.546374) (xy 175.843809 -345.598717) (xy 175.821146 -345.648339)
			(xy 175.79165 -345.694231) (xy 175.755923 -345.735457) (xy 175.714692 -345.771179) (xy 175.668797 -345.800669)
			(xy 175.619172 -345.823326) (xy 175.566827 -345.83869) (xy 175.512829 -345.846448) (xy 175.485552 -345.846908)
			(xy 174.621952 -345.846908) (xy 174.594688 -345.846326) (xy 174.540716 -345.83856) (xy 174.488399 -345.823192)
			(xy 174.438801 -345.800536) (xy 174.392931 -345.771053) (xy 174.351724 -345.735342) (xy 174.316019 -345.69413)
			(xy 174.286541 -345.648257) (xy 174.263891 -345.598656) (xy 174.24853 -345.546337) (xy 174.24077 -345.492364)
			(xy 172.757944 -345.492364) (xy 172.757944 -345.492375) (xy 172.750181 -345.546369) (xy 172.734813 -345.598708)
			(xy 172.712152 -345.648328) (xy 172.68266 -345.694218) (xy 172.646937 -345.735443) (xy 172.605711 -345.771165)
			(xy 172.559821 -345.800656) (xy 172.510201 -345.823315) (xy 172.457861 -345.838683) (xy 172.403867 -345.846445)
			(xy 172.376592 -345.846908) (xy 171.512992 -345.846908) (xy 171.485726 -345.846329) (xy 171.43175 -345.838567)
			(xy 171.379428 -345.823203) (xy 171.329825 -345.800549) (xy 171.28395 -345.771067) (xy 171.242738 -345.735356)
			(xy 171.207028 -345.694143) (xy 171.177547 -345.648268) (xy 171.154894 -345.598665) (xy 171.139531 -345.546342)
			(xy 171.13177 -345.492366) (xy 169.648922 -345.492366) (xy 169.648922 -345.492371) (xy 169.64116 -345.546358)
			(xy 169.625794 -345.598692) (xy 169.603138 -345.648306) (xy 169.573651 -345.694191) (xy 169.537935 -345.735412)
			(xy 169.496716 -345.771132) (xy 169.450834 -345.800622) (xy 169.401222 -345.823283) (xy 169.34889 -345.838653)
			(xy 169.294903 -345.846419) (xy 169.267632 -345.846908) (xy 168.404032 -345.846908) (xy 168.376763 -345.846355)
			(xy 168.322779 -345.838597) (xy 168.270449 -345.823236) (xy 168.220838 -345.800583) (xy 168.174955 -345.771099)
			(xy 168.133736 -345.735386) (xy 168.09802 -345.69417) (xy 168.068533 -345.648291) (xy 168.045876 -345.598681)
			(xy 168.03051 -345.546352) (xy 168.022747 -345.492369) (xy 166.540044 -345.492369) (xy 166.540044 -345.492376)
			(xy 166.532281 -345.546371) (xy 166.516911 -345.598713) (xy 166.494249 -345.648334) (xy 166.464755 -345.694224)
			(xy 166.42903 -345.73545) (xy 166.387802 -345.771172) (xy 166.341909 -345.800662) (xy 166.292286 -345.823321)
			(xy 166.239944 -345.838686) (xy 166.185948 -345.846446) (xy 166.158672 -345.846908) (xy 165.295072 -345.846908)
			(xy 165.267807 -345.846328) (xy 165.213833 -345.838564) (xy 165.161513 -345.823198) (xy 165.111913 -345.800543)
			(xy 165.066041 -345.77106) (xy 165.024831 -345.735349) (xy 164.989123 -345.694137) (xy 164.959644 -345.648263)
			(xy 164.936992 -345.59866) (xy 164.92163 -345.546339) (xy 164.91387 -345.492365) (xy 144.196621 -345.492365)
			(xy 144.196621 -345.492372) (xy 144.188859 -345.546362) (xy 144.173492 -345.598697) (xy 144.150834 -345.648312)
			(xy 144.121345 -345.694199) (xy 144.085627 -345.735421) (xy 144.044405 -345.77114) (xy 143.99852 -345.80063)
			(xy 143.948904 -345.82329) (xy 143.89657 -345.838657) (xy 143.84258 -345.846421) (xy 143.815308 -345.846908)
			(xy 142.951708 -345.846908) (xy 142.92444 -345.846353) (xy 142.870459 -345.838593) (xy 142.818131 -345.823229)
			(xy 142.768523 -345.800575) (xy 142.722644 -345.771091) (xy 142.681428 -345.735378) (xy 142.645714 -345.694162)
			(xy 142.616229 -345.648284) (xy 142.593574 -345.598676) (xy 142.578209 -345.546349) (xy 142.570447 -345.492368)
			(xy 141.087622 -345.492368) (xy 141.087622 -345.49237) (xy 141.07986 -345.546356) (xy 141.064495 -345.598688)
			(xy 141.04184 -345.648301) (xy 141.012355 -345.694185) (xy 140.976641 -345.735407) (xy 140.935424 -345.771126)
			(xy 140.889543 -345.800617) (xy 140.839933 -345.823279) (xy 140.787603 -345.83865) (xy 140.733618 -345.846418)
			(xy 140.706348 -345.846908) (xy 139.842748 -345.846908) (xy 139.815478 -345.846356) (xy 139.761492 -345.8386)
			(xy 139.70916 -345.82324) (xy 139.659547 -345.800588) (xy 139.613663 -345.771105) (xy 139.572442 -345.735392)
			(xy 139.536724 -345.694176) (xy 139.507235 -345.648295) (xy 139.484577 -345.598685) (xy 139.46921 -345.546354)
			(xy 139.461448 -345.49237) (xy 137.978744 -345.49237) (xy 137.978744 -345.492375) (xy 137.970981 -345.546369)
			(xy 137.955612 -345.598709) (xy 137.932951 -345.648329) (xy 137.903459 -345.694219) (xy 137.867736 -345.735444)
			(xy 137.826509 -345.771166) (xy 137.780619 -345.800657) (xy 137.730998 -345.823316) (xy 137.678658 -345.838684)
			(xy 137.624663 -345.846445) (xy 137.597388 -345.846908) (xy 136.733788 -345.846908) (xy 136.706522 -345.846329)
			(xy 136.652547 -345.838567) (xy 136.600225 -345.823202) (xy 136.550622 -345.800548) (xy 136.504748 -345.771065)
			(xy 136.463537 -345.735354) (xy 136.427827 -345.694142) (xy 136.398346 -345.648267) (xy 136.375694 -345.598664)
			(xy 136.360331 -345.546342) (xy 136.35257 -345.492366) (xy 134.869722 -345.492366) (xy 134.869722 -345.492371)
			(xy 134.86196 -345.546359) (xy 134.846594 -345.598693) (xy 134.823937 -345.648307) (xy 134.79445 -345.694192)
			(xy 134.758734 -345.735414) (xy 134.717514 -345.771133) (xy 134.671632 -345.800624) (xy 134.622019 -345.823284)
			(xy 134.569686 -345.838654) (xy 134.515699 -345.84642) (xy 134.488428 -345.846908) (xy 133.624828 -345.846908)
			(xy 133.597559 -345.846355) (xy 133.543576 -345.838597) (xy 133.491246 -345.823235) (xy 133.441635 -345.800581)
			(xy 133.395753 -345.771098) (xy 133.354535 -345.735385) (xy 133.318819 -345.694169) (xy 133.289332 -345.648289)
			(xy 133.266675 -345.59868) (xy 133.251309 -345.546352) (xy 133.243547 -345.492369) (xy 131.760844 -345.492369)
			(xy 131.760844 -345.492376) (xy 131.75308 -345.546372) (xy 131.737711 -345.598713) (xy 131.715048 -345.648335)
			(xy 131.685554 -345.694225) (xy 131.649829 -345.735451) (xy 131.6086 -345.771173) (xy 131.562707 -345.800663)
			(xy 131.513083 -345.823322) (xy 131.460741 -345.838687) (xy 131.406744 -345.846447) (xy 131.379468 -345.846908)
			(xy 130.515868 -345.846908) (xy 130.488603 -345.846328) (xy 130.43463 -345.838563) (xy 130.38231 -345.823197)
			(xy 130.33271 -345.800542) (xy 130.286839 -345.771058) (xy 130.24563 -345.735347) (xy 130.209922 -345.694136)
			(xy 130.180443 -345.648262) (xy 130.157792 -345.59866) (xy 130.14243 -345.546339) (xy 130.13467 -345.492365)
			(xy 128.651821 -345.492365) (xy 128.651821 -345.492372) (xy 128.644059 -345.546362) (xy 128.628692 -345.598697)
			(xy 128.606034 -345.648312) (xy 128.576545 -345.694199) (xy 128.540827 -345.735421) (xy 128.499605 -345.77114)
			(xy 128.45372 -345.80063) (xy 128.404104 -345.82329) (xy 128.35177 -345.838657) (xy 128.29778 -345.846421)
			(xy 128.270508 -345.846908) (xy 127.406908 -345.846908) (xy 127.37964 -345.846353) (xy 127.325659 -345.838593)
			(xy 127.273331 -345.823229) (xy 127.223723 -345.800575) (xy 127.177844 -345.771091) (xy 127.136628 -345.735378)
			(xy 127.100914 -345.694162) (xy 127.071429 -345.648284) (xy 127.048774 -345.598676) (xy 127.033409 -345.546349)
			(xy 127.025647 -345.492368) (xy 125.542822 -345.492368) (xy 125.542822 -345.49237) (xy 125.53506 -345.546356)
			(xy 125.519695 -345.598688) (xy 125.49704 -345.648301) (xy 125.467555 -345.694185) (xy 125.431841 -345.735407)
			(xy 125.390624 -345.771126) (xy 125.344743 -345.800617) (xy 125.295133 -345.823279) (xy 125.242803 -345.83865)
			(xy 125.188818 -345.846418) (xy 125.161548 -345.846908) (xy 124.297948 -345.846908) (xy 124.270678 -345.846356)
			(xy 124.216692 -345.8386) (xy 124.16436 -345.82324) (xy 124.114747 -345.800588) (xy 124.068863 -345.771105)
			(xy 124.027642 -345.735392) (xy 123.991924 -345.694176) (xy 123.962435 -345.648295) (xy 123.939777 -345.598685)
			(xy 123.92441 -345.546354) (xy 123.916648 -345.49237) (xy 122.433944 -345.49237) (xy 122.433944 -345.492375)
			(xy 122.426181 -345.546369) (xy 122.410812 -345.598709) (xy 122.388151 -345.648329) (xy 122.358659 -345.694219)
			(xy 122.322936 -345.735444) (xy 122.281709 -345.771166) (xy 122.235819 -345.800657) (xy 122.186198 -345.823316)
			(xy 122.133858 -345.838684) (xy 122.079863 -345.846445) (xy 122.052588 -345.846908) (xy 121.188988 -345.846908)
			(xy 121.161722 -345.846329) (xy 121.107747 -345.838567) (xy 121.055425 -345.823202) (xy 121.005822 -345.800548)
			(xy 120.959948 -345.771065) (xy 120.918737 -345.735354) (xy 120.883027 -345.694142) (xy 120.853546 -345.648267)
			(xy 120.830894 -345.598664) (xy 120.815531 -345.546342) (xy 120.80777 -345.492366) (xy 119.324922 -345.492366)
			(xy 119.324922 -345.492371) (xy 119.31716 -345.546359) (xy 119.301794 -345.598693) (xy 119.279137 -345.648307)
			(xy 119.24965 -345.694192) (xy 119.213934 -345.735414) (xy 119.172714 -345.771133) (xy 119.126832 -345.800624)
			(xy 119.077219 -345.823284) (xy 119.024886 -345.838654) (xy 118.970899 -345.84642) (xy 118.943628 -345.846908)
			(xy 118.080028 -345.846908) (xy 118.052759 -345.846355) (xy 117.998776 -345.838597) (xy 117.946446 -345.823235)
			(xy 117.896835 -345.800581) (xy 117.850953 -345.771098) (xy 117.809735 -345.735385) (xy 117.774019 -345.694169)
			(xy 117.744532 -345.648289) (xy 117.721875 -345.59868) (xy 117.706509 -345.546352) (xy 117.698747 -345.492369)
			(xy 116.216044 -345.492369) (xy 116.216044 -345.492376) (xy 116.20828 -345.546372) (xy 116.192911 -345.598713)
			(xy 116.170248 -345.648335) (xy 116.140754 -345.694225) (xy 116.105029 -345.735451) (xy 116.0638 -345.771173)
			(xy 116.017907 -345.800663) (xy 115.968283 -345.823322) (xy 115.915941 -345.838687) (xy 115.861944 -345.846447)
			(xy 115.834668 -345.846908) (xy 114.971068 -345.846908) (xy 114.943803 -345.846328) (xy 114.88983 -345.838563)
			(xy 114.83751 -345.823197) (xy 114.78791 -345.800542) (xy 114.742039 -345.771058) (xy 114.70083 -345.735347)
			(xy 114.665122 -345.694136) (xy 114.635643 -345.648262) (xy 114.612992 -345.59866) (xy 114.59763 -345.546339)
			(xy 114.58987 -345.492365) (xy 113.107021 -345.492365) (xy 113.107021 -345.492372) (xy 113.099259 -345.546362)
			(xy 113.083892 -345.598697) (xy 113.061234 -345.648312) (xy 113.031745 -345.694199) (xy 112.996027 -345.735421)
			(xy 112.954805 -345.77114) (xy 112.90892 -345.80063) (xy 112.859304 -345.82329) (xy 112.80697 -345.838657)
			(xy 112.75298 -345.846421) (xy 112.725708 -345.846908) (xy 111.862108 -345.846908) (xy 111.83484 -345.846353)
			(xy 111.780859 -345.838593) (xy 111.728531 -345.823229) (xy 111.678923 -345.800575) (xy 111.633044 -345.771091)
			(xy 111.591828 -345.735378) (xy 111.556114 -345.694162) (xy 111.526629 -345.648284) (xy 111.503974 -345.598676)
			(xy 111.488609 -345.546349) (xy 111.480847 -345.492368) (xy 93.706722 -345.492368) (xy 93.706722 -345.492371)
			(xy 93.69896 -345.546357) (xy 93.683595 -345.59869) (xy 93.660939 -345.648303) (xy 93.631454 -345.694187)
			(xy 93.595739 -345.735409) (xy 93.554521 -345.771128) (xy 93.50864 -345.800619) (xy 93.459029 -345.82328)
			(xy 93.406698 -345.838651) (xy 93.352713 -345.846419) (xy 93.325442 -345.846908) (xy 92.461842 -345.846908)
			(xy 92.434572 -345.846355) (xy 92.380587 -345.838599) (xy 92.328256 -345.823238) (xy 92.278643 -345.800586)
			(xy 92.23276 -345.771103) (xy 92.19154 -345.73539) (xy 92.155822 -345.694174) (xy 92.126334 -345.648293)
			(xy 92.103676 -345.598683) (xy 92.08831 -345.546354) (xy 92.080548 -345.49237) (xy 90.597844 -345.49237)
			(xy 90.597844 -345.492375) (xy 90.590081 -345.54637) (xy 90.574712 -345.59871) (xy 90.55205 -345.648331)
			(xy 90.522557 -345.694221) (xy 90.486834 -345.735446) (xy 90.445606 -345.771168) (xy 90.399715 -345.800659)
			(xy 90.350094 -345.823318) (xy 90.297752 -345.838685) (xy 90.243757 -345.846446) (xy 90.216482 -345.846908)
			(xy 89.352882 -345.846908) (xy 89.325617 -345.846328) (xy 89.271642 -345.838566) (xy 89.219321 -345.823201)
			(xy 89.169719 -345.800546) (xy 89.123845 -345.771063) (xy 89.082635 -345.735352) (xy 89.046926 -345.69414)
			(xy 89.017445 -345.648266) (xy 88.994793 -345.598663) (xy 88.979431 -345.546341) (xy 88.97167 -345.492365)
			(xy 87.488822 -345.492365) (xy 87.488822 -345.492372) (xy 87.481059 -345.54636) (xy 87.465693 -345.598694)
			(xy 87.443036 -345.648309) (xy 87.413549 -345.694194) (xy 87.377832 -345.735416) (xy 87.336612 -345.771136)
			(xy 87.290728 -345.800626) (xy 87.241115 -345.823286) (xy 87.188781 -345.838655) (xy 87.134794 -345.84642)
			(xy 87.107522 -345.846908) (xy 86.243922 -345.846908) (xy 86.216653 -345.846354) (xy 86.16267 -345.838595)
			(xy 86.110341 -345.823233) (xy 86.060732 -345.800579) (xy 86.014851 -345.771096) (xy 85.973633 -345.735383)
			(xy 85.937917 -345.694167) (xy 85.908431 -345.648288) (xy 85.885775 -345.598679) (xy 85.870409 -345.546351)
			(xy 85.862647 -345.492369) (xy 84.379944 -345.492369) (xy 84.379944 -345.492376) (xy 84.37218 -345.546373)
			(xy 84.35681 -345.598715) (xy 84.334147 -345.648336) (xy 84.304652 -345.694227) (xy 84.268927 -345.735453)
			(xy 84.227697 -345.771175) (xy 84.181803 -345.800665) (xy 84.132179 -345.823323) (xy 84.079836 -345.838688)
			(xy 84.025838 -345.846447) (xy 83.998562 -345.846908) (xy 83.134962 -345.846908) (xy 83.107698 -345.846327)
			(xy 83.053725 -345.838562) (xy 83.001406 -345.823195) (xy 82.951807 -345.80054) (xy 82.905936 -345.771056)
			(xy 82.864728 -345.735345) (xy 82.829021 -345.694134) (xy 82.799542 -345.64826) (xy 82.776892 -345.598658)
			(xy 82.76153 -345.546338) (xy 82.75377 -345.492364) (xy 81.270921 -345.492364) (xy 81.270921 -345.492373)
			(xy 81.263159 -345.546362) (xy 81.247792 -345.598698) (xy 81.225133 -345.648314) (xy 81.195644 -345.6942)
			(xy 81.159924 -345.735423) (xy 81.118702 -345.771143) (xy 81.072816 -345.800632) (xy 81.0232 -345.823291)
			(xy 80.970864 -345.838658) (xy 80.916875 -345.846421) (xy 80.889602 -345.846908) (xy 80.026002 -345.846908)
			(xy 79.998734 -345.846353) (xy 79.944754 -345.838592) (xy 79.892427 -345.823228) (xy 79.84282 -345.800573)
			(xy 79.796941 -345.771089) (xy 79.755726 -345.735376) (xy 79.720012 -345.69416) (xy 79.690528 -345.648282)
			(xy 79.667873 -345.598675) (xy 79.652509 -345.546348) (xy 79.644747 -345.492368) (xy 78.161922 -345.492368)
			(xy 78.161922 -345.492371) (xy 78.15416 -345.546357) (xy 78.138795 -345.59869) (xy 78.116139 -345.648303)
			(xy 78.086654 -345.694187) (xy 78.050939 -345.735409) (xy 78.009721 -345.771128) (xy 77.96384 -345.800619)
			(xy 77.914229 -345.82328) (xy 77.861898 -345.838651) (xy 77.807913 -345.846419) (xy 77.780642 -345.846908)
			(xy 76.917042 -345.846908) (xy 76.889772 -345.846355) (xy 76.835787 -345.838599) (xy 76.783456 -345.823238)
			(xy 76.733843 -345.800586) (xy 76.68796 -345.771103) (xy 76.64674 -345.73539) (xy 76.611022 -345.694174)
			(xy 76.581534 -345.648293) (xy 76.558876 -345.598683) (xy 76.54351 -345.546354) (xy 76.535748 -345.49237)
			(xy 75.053044 -345.49237) (xy 75.053044 -345.492375) (xy 75.045281 -345.54637) (xy 75.029912 -345.59871)
			(xy 75.00725 -345.648331) (xy 74.977757 -345.694221) (xy 74.942034 -345.735446) (xy 74.900806 -345.771168)
			(xy 74.854915 -345.800659) (xy 74.805294 -345.823318) (xy 74.752952 -345.838685) (xy 74.698957 -345.846446)
			(xy 74.671682 -345.846908) (xy 73.808082 -345.846908) (xy 73.780817 -345.846328) (xy 73.726842 -345.838566)
			(xy 73.674521 -345.823201) (xy 73.624919 -345.800546) (xy 73.579045 -345.771063) (xy 73.537835 -345.735352)
			(xy 73.502126 -345.69414) (xy 73.472645 -345.648266) (xy 73.449993 -345.598663) (xy 73.434631 -345.546341)
			(xy 73.42687 -345.492365) (xy 71.944022 -345.492365) (xy 71.944022 -345.492372) (xy 71.936259 -345.54636)
			(xy 71.920893 -345.598694) (xy 71.898236 -345.648309) (xy 71.868749 -345.694194) (xy 71.833032 -345.735416)
			(xy 71.791812 -345.771136) (xy 71.745928 -345.800626) (xy 71.696315 -345.823286) (xy 71.643981 -345.838655)
			(xy 71.589994 -345.84642) (xy 71.562722 -345.846908) (xy 70.699122 -345.846908) (xy 70.671853 -345.846354)
			(xy 70.61787 -345.838595) (xy 70.565541 -345.823233) (xy 70.515932 -345.800579) (xy 70.470051 -345.771096)
			(xy 70.428833 -345.735383) (xy 70.393117 -345.694167) (xy 70.363631 -345.648288) (xy 70.340975 -345.598679)
			(xy 70.325609 -345.546351) (xy 70.317847 -345.492369) (xy 68.835144 -345.492369) (xy 68.835144 -345.492376)
			(xy 68.82738 -345.546373) (xy 68.81201 -345.598715) (xy 68.789347 -345.648336) (xy 68.759852 -345.694227)
			(xy 68.724127 -345.735453) (xy 68.682897 -345.771175) (xy 68.637003 -345.800665) (xy 68.587379 -345.823323)
			(xy 68.535036 -345.838688) (xy 68.481038 -345.846447) (xy 68.453762 -345.846908) (xy 67.590162 -345.846908)
			(xy 67.562898 -345.846327) (xy 67.508925 -345.838562) (xy 67.456606 -345.823195) (xy 67.407007 -345.80054)
			(xy 67.361136 -345.771056) (xy 67.319928 -345.735345) (xy 67.284221 -345.694134) (xy 67.254742 -345.64826)
			(xy 67.232092 -345.598658) (xy 67.21673 -345.546338) (xy 67.20897 -345.492364) (xy 65.726121 -345.492364)
			(xy 65.726121 -345.492373) (xy 65.718359 -345.546362) (xy 65.702992 -345.598698) (xy 65.680333 -345.648314)
			(xy 65.650844 -345.6942) (xy 65.615124 -345.735423) (xy 65.573902 -345.771143) (xy 65.528016 -345.800632)
			(xy 65.4784 -345.823291) (xy 65.426064 -345.838658) (xy 65.372075 -345.846421) (xy 65.344802 -345.846908)
			(xy 64.481202 -345.846908) (xy 64.453934 -345.846353) (xy 64.399954 -345.838592) (xy 64.347627 -345.823228)
			(xy 64.29802 -345.800573) (xy 64.252141 -345.771089) (xy 64.210926 -345.735376) (xy 64.175212 -345.69416)
			(xy 64.145728 -345.648282) (xy 64.123073 -345.598675) (xy 64.107709 -345.546348) (xy 64.099947 -345.492368)
			(xy 62.617122 -345.492368) (xy 62.617122 -345.492371) (xy 62.60936 -345.546357) (xy 62.593995 -345.59869)
			(xy 62.571339 -345.648303) (xy 62.541854 -345.694187) (xy 62.506139 -345.735409) (xy 62.464921 -345.771128)
			(xy 62.41904 -345.800619) (xy 62.369429 -345.82328) (xy 62.317098 -345.838651) (xy 62.263113 -345.846419)
			(xy 62.235842 -345.846908) (xy 61.372242 -345.846908) (xy 61.344972 -345.846355) (xy 61.290987 -345.838599)
			(xy 61.238656 -345.823238) (xy 61.189043 -345.800586) (xy 61.14316 -345.771103) (xy 61.10194 -345.73539)
			(xy 61.066222 -345.694174) (xy 61.036734 -345.648293) (xy 61.014076 -345.598683) (xy 60.99871 -345.546354)
			(xy 60.990948 -345.49237) (xy 51.666922 -345.49237) (xy 51.65916 -345.546356) (xy 51.643795 -345.598688)
			(xy 51.62114 -345.648301) (xy 51.591655 -345.694185) (xy 51.555941 -345.735407) (xy 51.514724 -345.771126)
			(xy 51.468843 -345.800617) (xy 51.419233 -345.823279) (xy 51.366903 -345.83865) (xy 51.312918 -345.846418)
			(xy 51.285648 -345.846908) (xy 50.422048 -345.846908) (xy 50.394778 -345.846356) (xy 50.340792 -345.8386)
			(xy 50.28846 -345.82324) (xy 50.238847 -345.800588) (xy 50.192963 -345.771105) (xy 50.151742 -345.735392)
			(xy 50.116024 -345.694176) (xy 50.086535 -345.648295) (xy 50.063877 -345.598685) (xy 50.04851 -345.546354)
			(xy 50.040748 -345.49237) (xy 48.558044 -345.49237) (xy 48.558044 -345.492375) (xy 48.550281 -345.546369)
			(xy 48.534912 -345.598709) (xy 48.512251 -345.648329) (xy 48.482759 -345.694219) (xy 48.447036 -345.735444)
			(xy 48.405809 -345.771166) (xy 48.359919 -345.800657) (xy 48.310298 -345.823316) (xy 48.257958 -345.838684)
			(xy 48.203963 -345.846445) (xy 48.176688 -345.846908) (xy 47.313088 -345.846908) (xy 47.285822 -345.846329)
			(xy 47.231847 -345.838567) (xy 47.179525 -345.823202) (xy 47.129922 -345.800548) (xy 47.084048 -345.771065)
			(xy 47.042837 -345.735354) (xy 47.007127 -345.694142) (xy 46.977646 -345.648267) (xy 46.954994 -345.598664)
			(xy 46.939631 -345.546342) (xy 46.93187 -345.492366) (xy 45.449022 -345.492366) (xy 45.449022 -345.492371)
			(xy 45.44126 -345.546359) (xy 45.425894 -345.598693) (xy 45.403237 -345.648307) (xy 45.37375 -345.694192)
			(xy 45.338034 -345.735414) (xy 45.296814 -345.771133) (xy 45.250932 -345.800624) (xy 45.201319 -345.823284)
			(xy 45.148986 -345.838654) (xy 45.094999 -345.84642) (xy 45.067728 -345.846908) (xy 44.204128 -345.846908)
			(xy 44.176859 -345.846355) (xy 44.122876 -345.838597) (xy 44.070546 -345.823235) (xy 44.020935 -345.800581)
			(xy 43.975053 -345.771098) (xy 43.933835 -345.735385) (xy 43.898119 -345.694169) (xy 43.868632 -345.648289)
			(xy 43.845975 -345.59868) (xy 43.830609 -345.546352) (xy 43.822847 -345.492369) (xy 42.340144 -345.492369)
			(xy 42.340144 -345.492376) (xy 42.33238 -345.546372) (xy 42.317011 -345.598713) (xy 42.294348 -345.648335)
			(xy 42.264854 -345.694225) (xy 42.229129 -345.735451) (xy 42.1879 -345.771173) (xy 42.142007 -345.800663)
			(xy 42.092383 -345.823322) (xy 42.040041 -345.838687) (xy 41.986044 -345.846447) (xy 41.958768 -345.846908)
			(xy 41.095168 -345.846908) (xy 41.067903 -345.846328) (xy 41.01393 -345.838563) (xy 40.96161 -345.823197)
			(xy 40.91201 -345.800542) (xy 40.866139 -345.771058) (xy 40.82493 -345.735347) (xy 40.789222 -345.694136)
			(xy 40.759743 -345.648262) (xy 40.737092 -345.59866) (xy 40.72173 -345.546339) (xy 40.71397 -345.492365)
			(xy 39.231121 -345.492365) (xy 39.231121 -345.492372) (xy 39.223359 -345.546362) (xy 39.207992 -345.598697)
			(xy 39.185334 -345.648312) (xy 39.155845 -345.694199) (xy 39.120127 -345.735421) (xy 39.078905 -345.77114)
			(xy 39.03302 -345.80063) (xy 38.983404 -345.82329) (xy 38.93107 -345.838657) (xy 38.87708 -345.846421)
			(xy 38.849808 -345.846908) (xy 37.986208 -345.846908) (xy 37.95894 -345.846353) (xy 37.904959 -345.838593)
			(xy 37.852631 -345.823229) (xy 37.803023 -345.800575) (xy 37.757144 -345.771091) (xy 37.715928 -345.735378)
			(xy 37.680214 -345.694162) (xy 37.650729 -345.648284) (xy 37.628074 -345.598676) (xy 37.612709 -345.546349)
			(xy 37.604947 -345.492368) (xy 36.122122 -345.492368) (xy 36.122122 -345.49237) (xy 36.11436 -345.546356)
			(xy 36.098995 -345.598688) (xy 36.07634 -345.648301) (xy 36.046855 -345.694185) (xy 36.011141 -345.735407)
			(xy 35.969924 -345.771126) (xy 35.924043 -345.800617) (xy 35.874433 -345.823279) (xy 35.822103 -345.83865)
			(xy 35.768118 -345.846418) (xy 35.740848 -345.846908) (xy 34.877248 -345.846908) (xy 34.849978 -345.846356)
			(xy 34.795992 -345.8386) (xy 34.74366 -345.82324) (xy 34.694047 -345.800588) (xy 34.648163 -345.771105)
			(xy 34.606942 -345.735392) (xy 34.571224 -345.694176) (xy 34.541735 -345.648295) (xy 34.519077 -345.598685)
			(xy 34.50371 -345.546354) (xy 34.495948 -345.49237) (xy 33.013244 -345.49237) (xy 33.013244 -345.492375)
			(xy 33.005481 -345.546369) (xy 32.990112 -345.598709) (xy 32.967451 -345.648329) (xy 32.937959 -345.694219)
			(xy 32.902236 -345.735444) (xy 32.861009 -345.771166) (xy 32.815119 -345.800657) (xy 32.765498 -345.823316)
			(xy 32.713158 -345.838684) (xy 32.659163 -345.846445) (xy 32.631888 -345.846908) (xy 31.768288 -345.846908)
			(xy 31.741022 -345.846329) (xy 31.687047 -345.838567) (xy 31.634725 -345.823202) (xy 31.585122 -345.800548)
			(xy 31.539248 -345.771065) (xy 31.498037 -345.735354) (xy 31.462327 -345.694142) (xy 31.432846 -345.648267)
			(xy 31.410194 -345.598664) (xy 31.394831 -345.546342) (xy 31.38707 -345.492366) (xy 29.904222 -345.492366)
			(xy 29.904222 -345.492371) (xy 29.89646 -345.546359) (xy 29.881094 -345.598693) (xy 29.858437 -345.648307)
			(xy 29.82895 -345.694192) (xy 29.793234 -345.735414) (xy 29.752014 -345.771133) (xy 29.706132 -345.800624)
			(xy 29.656519 -345.823284) (xy 29.604186 -345.838654) (xy 29.550199 -345.84642) (xy 29.522928 -345.846908)
			(xy 28.659328 -345.846908) (xy 28.632059 -345.846355) (xy 28.578076 -345.838597) (xy 28.525746 -345.823235)
			(xy 28.476135 -345.800581) (xy 28.430253 -345.771098) (xy 28.389035 -345.735385) (xy 28.353319 -345.694169)
			(xy 28.323832 -345.648289) (xy 28.301175 -345.59868) (xy 28.285809 -345.546352) (xy 28.278047 -345.492369)
			(xy 26.795344 -345.492369) (xy 26.795344 -345.492376) (xy 26.78758 -345.546372) (xy 26.772211 -345.598713)
			(xy 26.749548 -345.648335) (xy 26.720054 -345.694225) (xy 26.684329 -345.735451) (xy 26.6431 -345.771173)
			(xy 26.597207 -345.800663) (xy 26.547583 -345.823322) (xy 26.495241 -345.838687) (xy 26.441244 -345.846447)
			(xy 26.413968 -345.846908) (xy 25.550368 -345.846908) (xy 25.523103 -345.846328) (xy 25.46913 -345.838563)
			(xy 25.41681 -345.823197) (xy 25.36721 -345.800542) (xy 25.321339 -345.771058) (xy 25.28013 -345.735347)
			(xy 25.244422 -345.694136) (xy 25.214943 -345.648262) (xy 25.192292 -345.59866) (xy 25.17693 -345.546339)
			(xy 25.16917 -345.492365) (xy 23.686305 -345.492365) (xy 23.686305 -345.492421) (xy 23.678542 -345.546407)
			(xy 23.663176 -345.59874) (xy 23.640519 -345.648352) (xy 23.611031 -345.694236) (xy 23.575314 -345.735455)
			(xy 23.534094 -345.771172) (xy 23.488211 -345.80066) (xy 23.438598 -345.823317) (xy 23.386265 -345.838683)
			(xy 23.332279 -345.846445) (xy 23.305008 -345.846908) (xy 22.441408 -345.846908) (xy 22.414138 -345.846429)
			(xy 22.360154 -345.838667) (xy 22.307825 -345.823302) (xy 22.258214 -345.800645) (xy 22.212333 -345.771159)
			(xy 22.171115 -345.735443) (xy 22.1354 -345.694225) (xy 22.105914 -345.648344) (xy 22.083258 -345.598733)
			(xy 22.067892 -345.546404) (xy 22.06013 -345.49242) (xy 20.577345 -345.49242) (xy 20.577345 -345.492421)
			(xy 20.569582 -345.546407) (xy 20.554216 -345.59874) (xy 20.531559 -345.648352) (xy 20.502071 -345.694236)
			(xy 20.466354 -345.735455) (xy 20.425134 -345.771172) (xy 20.379251 -345.80066) (xy 20.329638 -345.823317)
			(xy 20.277305 -345.838683) (xy 20.223319 -345.846445) (xy 20.196048 -345.846908) (xy 19.332448 -345.846908)
			(xy 19.305178 -345.846429) (xy 19.251194 -345.838667) (xy 19.198865 -345.823302) (xy 19.149254 -345.800645)
			(xy 19.103373 -345.771159) (xy 19.062155 -345.735443) (xy 19.02644 -345.694225) (xy 18.996954 -345.648344)
			(xy 18.974298 -345.598733) (xy 18.958932 -345.546404) (xy 18.95117 -345.49242) (xy 0.509016 -345.49242)
			(xy 0.509016 -348.976496) (xy 4.708641 -348.976496) (xy 4.708641 -348.847356) (xy 4.716591 -348.718461)
			(xy 4.732461 -348.590301) (xy 4.75619 -348.46336) (xy 4.787689 -348.338121) (xy 4.826838 -348.215058)
			(xy 4.873489 -348.094639) (xy 4.927464 -347.97732) (xy 4.988559 -347.863546) (xy 5.056542 -347.753749)
			(xy 5.131156 -347.648346) (xy 5.212117 -347.547736) (xy 5.299117 -347.452301) (xy 5.391828 -347.362402)
			(xy 5.489898 -347.278381) (xy 5.592953 -347.200557) (xy 5.700604 -347.129225) (xy 5.812443 -347.064655)
			(xy 5.928044 -347.007093) (xy 6.046969 -346.956756) (xy 6.168768 -346.913836) (xy 6.292978 -346.878495)
			(xy 6.419127 -346.850868) (xy 6.546739 -346.831059) (xy 6.675328 -346.819143) (xy 6.804406 -346.815167)
			(xy 6.933484 -346.819143) (xy 7.062073 -346.831059) (xy 7.189685 -346.850868) (xy 7.315834 -346.878495)
			(xy 7.440044 -346.913836) (xy 7.451736 -346.917956) (xy 245.50903 -346.917956) (xy 245.50903 -346.83326)
			(xy 245.517081 -346.748946) (xy 245.53311 -346.66578) (xy 245.556971 -346.584513) (xy 245.58845 -346.505883)
			(xy 245.627261 -346.430602) (xy 245.673051 -346.35935) (xy 245.725407 -346.292774) (xy 245.783855 -346.231476)
			(xy 245.847865 -346.176011) (xy 245.916857 -346.126882) (xy 245.990207 -346.084533) (xy 246.06725 -346.049349)
			(xy 246.147289 -346.021647) (xy 246.229598 -346.001679) (xy 246.313433 -345.989626) (xy 246.398034 -345.985596)
			(xy 246.482635 -345.989626) (xy 246.56647 -346.001679) (xy 246.648779 -346.021647) (xy 246.728818 -346.049349)
			(xy 246.805861 -346.084533) (xy 246.879211 -346.126882) (xy 246.948203 -346.176011) (xy 247.012213 -346.231476)
			(xy 247.070661 -346.292774) (xy 247.123017 -346.35935) (xy 247.168807 -346.430602) (xy 247.207618 -346.505883)
			(xy 247.239097 -346.584513) (xy 247.262958 -346.66578) (xy 247.278987 -346.748946) (xy 247.287038 -346.83326)
			(xy 247.287542 -346.875608) (xy 247.287038 -346.917956) (xy 247.278987 -347.00227) (xy 247.262958 -347.085436)
			(xy 247.239097 -347.166703) (xy 247.207618 -347.245333) (xy 247.168807 -347.320614) (xy 247.123017 -347.391866)
			(xy 247.070661 -347.458442) (xy 247.012213 -347.51974) (xy 246.948203 -347.575205) (xy 246.879211 -347.624334)
			(xy 246.805861 -347.666683) (xy 246.728818 -347.701867) (xy 246.648779 -347.729569) (xy 246.56647 -347.749537)
			(xy 246.482635 -347.76159) (xy 246.398034 -347.765621) (xy 246.313433 -347.76159) (xy 246.229598 -347.749537)
			(xy 246.147289 -347.729569) (xy 246.06725 -347.701867) (xy 245.990207 -347.666683) (xy 245.916857 -347.624334)
			(xy 245.847865 -347.575205) (xy 245.783855 -347.51974) (xy 245.725407 -347.458442) (xy 245.673051 -347.391866)
			(xy 245.627261 -347.320614) (xy 245.58845 -347.245333) (xy 245.556971 -347.166703) (xy 245.53311 -347.085436)
			(xy 245.517081 -347.00227) (xy 245.50903 -346.917956) (xy 7.451736 -346.917956) (xy 7.561843 -346.956756)
			(xy 7.680768 -347.007093) (xy 7.796369 -347.064655) (xy 7.908208 -347.129225) (xy 8.015859 -347.200557)
			(xy 8.118914 -347.278381) (xy 8.216984 -347.362402) (xy 8.309695 -347.452301) (xy 8.396695 -347.547736)
			(xy 8.477656 -347.648346) (xy 8.55227 -347.753749) (xy 8.620253 -347.863546) (xy 8.681348 -347.97732)
			(xy 8.735323 -348.094639) (xy 8.781974 -348.215058) (xy 8.821123 -348.338121) (xy 8.852622 -348.46336)
			(xy 8.876351 -348.590301) (xy 8.879169 -348.613059) (xy 18.951174 -348.613059) (xy 18.951174 -348.558521)
			(xy 18.958936 -348.504537) (xy 18.974301 -348.452208) (xy 18.996957 -348.402598) (xy 19.026443 -348.356717)
			(xy 19.062158 -348.315499) (xy 19.103375 -348.279784) (xy 19.149256 -348.250298) (xy 19.198866 -348.227642)
			(xy 19.251195 -348.212276) (xy 19.305179 -348.204515) (xy 19.332448 -348.204028) (xy 20.196048 -348.204028)
			(xy 20.223319 -348.204491) (xy 20.277306 -348.212253) (xy 20.329639 -348.227619) (xy 20.379253 -348.250277)
			(xy 20.425136 -348.279764) (xy 20.466357 -348.315482) (xy 20.502074 -348.356702) (xy 20.531562 -348.402586)
			(xy 20.55422 -348.452199) (xy 20.569586 -348.504532) (xy 20.577349 -348.558519) (xy 20.577349 -348.613061)
			(xy 20.577347 -348.613072) (xy 22.060092 -348.613072) (xy 22.060092 -348.558528) (xy 22.067854 -348.504539)
			(xy 22.083221 -348.452204) (xy 22.10588 -348.402589) (xy 22.135369 -348.356704) (xy 22.171088 -348.315483)
			(xy 22.21231 -348.279764) (xy 22.258196 -348.250276) (xy 22.307812 -348.227618) (xy 22.360147 -348.212252)
			(xy 22.414136 -348.204491) (xy 22.441408 -348.204028) (xy 23.305008 -348.204028) (xy 23.332276 -348.204535)
			(xy 23.386258 -348.212297) (xy 23.438585 -348.227663) (xy 23.488193 -348.250319) (xy 23.534071 -348.279804)
			(xy 23.575287 -348.315519) (xy 23.611 -348.356735) (xy 23.640485 -348.402614) (xy 23.66314 -348.452223)
			(xy 23.678504 -348.50455) (xy 23.686266 -348.558532) (xy 23.686266 -348.613068) (xy 23.686266 -348.613069)
			(xy 25.169114 -348.613069) (xy 25.169114 -348.558531) (xy 25.176875 -348.504549) (xy 25.19224 -348.452221)
			(xy 25.214894 -348.402611) (xy 25.244378 -348.356731) (xy 25.28009 -348.315513) (xy 25.321305 -348.279797)
			(xy 25.367183 -348.250309) (xy 25.416791 -348.227651) (xy 25.469118 -348.212282) (xy 25.523099 -348.204517)
			(xy 25.550368 -348.204028) (xy 26.413968 -348.204028) (xy 26.44124 -348.204509) (xy 26.495229 -348.212268)
			(xy 26.547564 -348.227631) (xy 26.59718 -348.250286) (xy 26.643066 -348.279772) (xy 26.684289 -348.315488)
			(xy 26.720009 -348.356708) (xy 26.749499 -348.402592) (xy 26.772158 -348.452206) (xy 26.787526 -348.50454)
			(xy 26.795288 -348.558528) (xy 26.795288 -348.613072) (xy 26.795288 -348.613073) (xy 28.277992 -348.613073)
			(xy 28.277992 -348.558527) (xy 28.285755 -348.504536) (xy 28.301123 -348.4522) (xy 28.323783 -348.402584)
			(xy 28.353274 -348.356697) (xy 28.388995 -348.315476) (xy 28.43022 -348.279757) (xy 28.476108 -348.25027)
			(xy 28.525726 -348.227613) (xy 28.578064 -348.212249) (xy 28.632055 -348.20449) (xy 28.659328 -348.204028)
			(xy 29.522928 -348.204028) (xy 29.550195 -348.204536) (xy 29.604175 -348.212301) (xy 29.656499 -348.227668)
			(xy 29.706105 -348.250326) (xy 29.751981 -348.279811) (xy 29.793194 -348.315526) (xy 29.828905 -348.356742)
			(xy 29.858388 -348.40262) (xy 29.881041 -348.452227) (xy 29.896405 -348.504553) (xy 29.904166 -348.558533)
			(xy 29.904166 -348.613067) (xy 29.904166 -348.61307) (xy 31.387014 -348.61307) (xy 31.387014 -348.55853)
			(xy 31.394776 -348.504546) (xy 31.410141 -348.452217) (xy 31.432797 -348.402606) (xy 31.462283 -348.356724)
			(xy 31.497997 -348.315506) (xy 31.539215 -348.27979) (xy 31.585095 -348.250303) (xy 31.634705 -348.227645)
			(xy 31.687035 -348.212279) (xy 31.741018 -348.204515) (xy 31.768288 -348.204028) (xy 32.631888 -348.204028)
			(xy 32.659159 -348.204511) (xy 32.713146 -348.212271) (xy 32.765478 -348.227636) (xy 32.815092 -348.250292)
			(xy 32.860976 -348.279779) (xy 32.902196 -348.315495) (xy 32.937914 -348.356715) (xy 32.967402 -348.402598)
			(xy 32.99006 -348.45221) (xy 33.005426 -348.504543) (xy 33.013189 -348.558529) (xy 33.013189 -348.613071)
			(xy 33.013189 -348.613074) (xy 34.495892 -348.613074) (xy 34.495892 -348.558526) (xy 34.503655 -348.504534)
			(xy 34.519024 -348.452196) (xy 34.541686 -348.402578) (xy 34.571179 -348.356691) (xy 34.606902 -348.315468)
			(xy 34.648129 -348.27975) (xy 34.69402 -348.250263) (xy 34.743641 -348.227608) (xy 34.795981 -348.212245)
			(xy 34.849974 -348.204488) (xy 34.877248 -348.204028) (xy 35.740848 -348.204028) (xy 35.768114 -348.204538)
			(xy 35.822091 -348.212305) (xy 35.874414 -348.227674) (xy 35.924017 -348.250332) (xy 35.96989 -348.279819)
			(xy 36.011101 -348.315533) (xy 36.04681 -348.356748) (xy 36.076291 -348.402626) (xy 36.098943 -348.452231)
			(xy 36.114306 -348.504556) (xy 36.122066 -348.558534) (xy 36.122066 -348.613066) (xy 36.122065 -348.613072)
			(xy 37.604892 -348.613072) (xy 37.604892 -348.558528) (xy 37.612654 -348.504539) (xy 37.628021 -348.452204)
			(xy 37.65068 -348.402589) (xy 37.680169 -348.356704) (xy 37.715888 -348.315483) (xy 37.75711 -348.279764)
			(xy 37.802996 -348.250276) (xy 37.852612 -348.227618) (xy 37.904947 -348.212252) (xy 37.958936 -348.204491)
			(xy 37.986208 -348.204028) (xy 38.849808 -348.204028) (xy 38.877076 -348.204535) (xy 38.931058 -348.212297)
			(xy 38.983385 -348.227663) (xy 39.032993 -348.250319) (xy 39.078871 -348.279804) (xy 39.120087 -348.315519)
			(xy 39.1558 -348.356735) (xy 39.185285 -348.402614) (xy 39.20794 -348.452223) (xy 39.223304 -348.50455)
			(xy 39.231066 -348.558532) (xy 39.231066 -348.613068) (xy 39.231066 -348.613069) (xy 40.713914 -348.613069)
			(xy 40.713914 -348.558531) (xy 40.721675 -348.504549) (xy 40.73704 -348.452221) (xy 40.759694 -348.402611)
			(xy 40.789178 -348.356731) (xy 40.82489 -348.315513) (xy 40.866105 -348.279797) (xy 40.911983 -348.250309)
			(xy 40.961591 -348.227651) (xy 41.013918 -348.212282) (xy 41.067899 -348.204517) (xy 41.095168 -348.204028)
			(xy 41.958768 -348.204028) (xy 41.98604 -348.204509) (xy 42.040029 -348.212268) (xy 42.092364 -348.227631)
			(xy 42.14198 -348.250286) (xy 42.187866 -348.279772) (xy 42.229089 -348.315488) (xy 42.264809 -348.356708)
			(xy 42.294299 -348.402592) (xy 42.316958 -348.452206) (xy 42.332326 -348.50454) (xy 42.340088 -348.558528)
			(xy 42.340088 -348.613072) (xy 42.340088 -348.613073) (xy 43.822792 -348.613073) (xy 43.822792 -348.558527)
			(xy 43.830555 -348.504536) (xy 43.845923 -348.4522) (xy 43.868583 -348.402584) (xy 43.898074 -348.356697)
			(xy 43.933795 -348.315476) (xy 43.97502 -348.279757) (xy 44.020908 -348.25027) (xy 44.070526 -348.227613)
			(xy 44.122864 -348.212249) (xy 44.176855 -348.20449) (xy 44.204128 -348.204028) (xy 45.067728 -348.204028)
			(xy 45.094995 -348.204536) (xy 45.148975 -348.212301) (xy 45.201299 -348.227668) (xy 45.250905 -348.250326)
			(xy 45.296781 -348.279811) (xy 45.337994 -348.315526) (xy 45.373705 -348.356742) (xy 45.403188 -348.40262)
			(xy 45.425841 -348.452227) (xy 45.441205 -348.504553) (xy 45.448966 -348.558533) (xy 45.448966 -348.613067)
			(xy 45.448966 -348.61307) (xy 46.931814 -348.61307) (xy 46.931814 -348.55853) (xy 46.939576 -348.504546)
			(xy 46.954941 -348.452217) (xy 46.977597 -348.402606) (xy 47.007083 -348.356724) (xy 47.042797 -348.315506)
			(xy 47.084015 -348.27979) (xy 47.129895 -348.250303) (xy 47.179505 -348.227645) (xy 47.231835 -348.212279)
			(xy 47.285818 -348.204515) (xy 47.313088 -348.204028) (xy 48.176688 -348.204028) (xy 48.203959 -348.204511)
			(xy 48.257946 -348.212271) (xy 48.310278 -348.227636) (xy 48.359892 -348.250292) (xy 48.405776 -348.279779)
			(xy 48.446996 -348.315495) (xy 48.482714 -348.356715) (xy 48.512202 -348.402598) (xy 48.53486 -348.45221)
			(xy 48.550226 -348.504543) (xy 48.557989 -348.558529) (xy 48.557989 -348.613071) (xy 48.557989 -348.613074)
			(xy 50.040692 -348.613074) (xy 50.040692 -348.558526) (xy 50.048455 -348.504534) (xy 50.063824 -348.452196)
			(xy 50.086486 -348.402578) (xy 50.115979 -348.356691) (xy 50.151702 -348.315468) (xy 50.192929 -348.27975)
			(xy 50.23882 -348.250263) (xy 50.288441 -348.227608) (xy 50.340781 -348.212245) (xy 50.394774 -348.204488)
			(xy 50.422048 -348.204028) (xy 51.285648 -348.204028) (xy 51.312914 -348.204538) (xy 51.366891 -348.212305)
			(xy 51.419214 -348.227674) (xy 51.468817 -348.250332) (xy 51.51469 -348.279819) (xy 51.555901 -348.315533)
			(xy 51.59161 -348.356748) (xy 51.621091 -348.402626) (xy 51.643743 -348.452231) (xy 51.659106 -348.504556)
			(xy 51.666866 -348.558534) (xy 51.666866 -348.613066) (xy 51.666865 -348.613074) (xy 60.990892 -348.613074)
			(xy 60.990892 -348.558526) (xy 60.998655 -348.504534) (xy 61.014024 -348.452197) (xy 61.036685 -348.40258)
			(xy 61.066177 -348.356693) (xy 61.1019 -348.315471) (xy 61.143127 -348.279752) (xy 61.189017 -348.250265)
			(xy 61.238636 -348.227609) (xy 61.290976 -348.212246) (xy 61.344968 -348.204489) (xy 61.372242 -348.204028)
			(xy 62.235842 -348.204028) (xy 62.263109 -348.204537) (xy 62.317086 -348.212304) (xy 62.369409 -348.227672)
			(xy 62.419013 -348.25033) (xy 62.464887 -348.279816) (xy 62.506099 -348.315531) (xy 62.541809 -348.356746)
			(xy 62.57129 -348.402624) (xy 62.593943 -348.45223) (xy 62.609305 -348.504555) (xy 62.617066 -348.558533)
			(xy 62.617066 -348.613067) (xy 62.617065 -348.613072) (xy 64.099892 -348.613072) (xy 64.099892 -348.558528)
			(xy 64.107654 -348.50454) (xy 64.123021 -348.452206) (xy 64.145679 -348.402591) (xy 64.175168 -348.356706)
			(xy 64.210886 -348.315485) (xy 64.252108 -348.279766) (xy 64.297993 -348.250278) (xy 64.347607 -348.22762)
			(xy 64.399942 -348.212253) (xy 64.45393 -348.204491) (xy 64.481202 -348.204028) (xy 65.344802 -348.204028)
			(xy 65.372071 -348.204535) (xy 65.426053 -348.212296) (xy 65.47838 -348.227661) (xy 65.527989 -348.250317)
			(xy 65.573869 -348.279802) (xy 65.615085 -348.315517) (xy 65.650799 -348.356733) (xy 65.680284 -348.402613)
			(xy 65.702939 -348.452221) (xy 65.718304 -348.504549) (xy 65.726066 -348.558531) (xy 65.726066 -348.613068)
			(xy 67.208914 -348.613068) (xy 67.208914 -348.558532) (xy 67.216675 -348.50455) (xy 67.232039 -348.452222)
			(xy 67.254693 -348.402613) (xy 67.284176 -348.356733) (xy 67.319888 -348.315515) (xy 67.361102 -348.279799)
			(xy 67.40698 -348.250311) (xy 67.456586 -348.227652) (xy 67.508913 -348.212283) (xy 67.562894 -348.204517)
			(xy 67.590162 -348.204028) (xy 68.453762 -348.204028) (xy 68.481034 -348.204509) (xy 68.535024 -348.212266)
			(xy 68.58736 -348.227629) (xy 68.636976 -348.250284) (xy 68.682863 -348.27977) (xy 68.724087 -348.315486)
			(xy 68.759808 -348.356706) (xy 68.789298 -348.40259) (xy 68.811958 -348.452205) (xy 68.827326 -348.504539)
			(xy 68.835088 -348.558528) (xy 68.835088 -348.613072) (xy 68.835088 -348.613073) (xy 70.317792 -348.613073)
			(xy 70.317792 -348.558527) (xy 70.325554 -348.504537) (xy 70.340922 -348.452201) (xy 70.363582 -348.402585)
			(xy 70.393072 -348.356699) (xy 70.428793 -348.315478) (xy 70.470017 -348.279759) (xy 70.515905 -348.250271)
			(xy 70.565522 -348.227615) (xy 70.617859 -348.21225) (xy 70.671849 -348.20449) (xy 70.699122 -348.204028)
			(xy 71.562722 -348.204028) (xy 71.58999 -348.204536) (xy 71.643969 -348.2123) (xy 71.696295 -348.227667)
			(xy 71.745901 -348.250324) (xy 71.791778 -348.279809) (xy 71.832992 -348.315524) (xy 71.868704 -348.35674)
			(xy 71.898187 -348.402618) (xy 71.920841 -348.452226) (xy 71.936205 -348.504552) (xy 71.943966 -348.558532)
			(xy 71.943966 -348.613068) (xy 71.943966 -348.613069) (xy 73.426814 -348.613069) (xy 73.426814 -348.558531)
			(xy 73.434576 -348.504547) (xy 73.449941 -348.452218) (xy 73.472596 -348.402608) (xy 73.502081 -348.356726)
			(xy 73.537795 -348.315508) (xy 73.579012 -348.279792) (xy 73.624892 -348.250305) (xy 73.674501 -348.227647)
			(xy 73.72683 -348.21228) (xy 73.780813 -348.204516) (xy 73.808082 -348.204028) (xy 74.671682 -348.204028)
			(xy 74.698953 -348.20451) (xy 74.752941 -348.21227) (xy 74.805274 -348.227634) (xy 74.854888 -348.25029)
			(xy 74.900773 -348.279777) (xy 74.941994 -348.315493) (xy 74.977712 -348.356713) (xy 75.007201 -348.402596)
			(xy 75.029859 -348.452209) (xy 75.045226 -348.504542) (xy 75.052988 -348.558529) (xy 75.052988 -348.613071)
			(xy 75.052988 -348.613074) (xy 76.535692 -348.613074) (xy 76.535692 -348.558526) (xy 76.543455 -348.504534)
			(xy 76.558824 -348.452197) (xy 76.581485 -348.40258) (xy 76.610977 -348.356693) (xy 76.6467 -348.315471)
			(xy 76.687927 -348.279752) (xy 76.733817 -348.250265) (xy 76.783436 -348.227609) (xy 76.835776 -348.212246)
			(xy 76.889768 -348.204489) (xy 76.917042 -348.204028) (xy 77.780642 -348.204028) (xy 77.807909 -348.204537)
			(xy 77.861886 -348.212304) (xy 77.914209 -348.227672) (xy 77.963813 -348.25033) (xy 78.009687 -348.279816)
			(xy 78.050899 -348.315531) (xy 78.086609 -348.356746) (xy 78.11609 -348.402624) (xy 78.138743 -348.45223)
			(xy 78.154105 -348.504555) (xy 78.161866 -348.558533) (xy 78.161866 -348.613067) (xy 78.161865 -348.613072)
			(xy 79.644692 -348.613072) (xy 79.644692 -348.558528) (xy 79.652454 -348.50454) (xy 79.667821 -348.452206)
			(xy 79.690479 -348.402591) (xy 79.719968 -348.356706) (xy 79.755686 -348.315485) (xy 79.796908 -348.279766)
			(xy 79.842793 -348.250278) (xy 79.892407 -348.22762) (xy 79.944742 -348.212253) (xy 79.99873 -348.204491)
			(xy 80.026002 -348.204028) (xy 80.889602 -348.204028) (xy 80.916871 -348.204535) (xy 80.970853 -348.212296)
			(xy 81.02318 -348.227661) (xy 81.072789 -348.250317) (xy 81.118669 -348.279802) (xy 81.159885 -348.315517)
			(xy 81.195599 -348.356733) (xy 81.225084 -348.402613) (xy 81.247739 -348.452221) (xy 81.263104 -348.504549)
			(xy 81.270866 -348.558531) (xy 81.270866 -348.613068) (xy 82.753714 -348.613068) (xy 82.753714 -348.558532)
			(xy 82.761475 -348.50455) (xy 82.776839 -348.452222) (xy 82.799493 -348.402613) (xy 82.828976 -348.356733)
			(xy 82.864688 -348.315515) (xy 82.905902 -348.279799) (xy 82.95178 -348.250311) (xy 83.001386 -348.227652)
			(xy 83.053713 -348.212283) (xy 83.107694 -348.204517) (xy 83.134962 -348.204028) (xy 83.998562 -348.204028)
			(xy 84.025834 -348.204509) (xy 84.079824 -348.212266) (xy 84.13216 -348.227629) (xy 84.181776 -348.250284)
			(xy 84.227663 -348.27977) (xy 84.268887 -348.315486) (xy 84.304608 -348.356706) (xy 84.334098 -348.40259)
			(xy 84.356758 -348.452205) (xy 84.372126 -348.504539) (xy 84.379888 -348.558528) (xy 84.379888 -348.613072)
			(xy 84.379888 -348.613073) (xy 85.862592 -348.613073) (xy 85.862592 -348.558527) (xy 85.870354 -348.504537)
			(xy 85.885722 -348.452201) (xy 85.908382 -348.402585) (xy 85.937872 -348.356699) (xy 85.973593 -348.315478)
			(xy 86.014817 -348.279759) (xy 86.060705 -348.250271) (xy 86.110322 -348.227615) (xy 86.162659 -348.21225)
			(xy 86.216649 -348.20449) (xy 86.243922 -348.204028) (xy 87.107522 -348.204028) (xy 87.13479 -348.204536)
			(xy 87.188769 -348.2123) (xy 87.241095 -348.227667) (xy 87.290701 -348.250324) (xy 87.336578 -348.279809)
			(xy 87.377792 -348.315524) (xy 87.413504 -348.35674) (xy 87.442987 -348.402618) (xy 87.465641 -348.452226)
			(xy 87.481005 -348.504552) (xy 87.488766 -348.558532) (xy 87.488766 -348.613068) (xy 87.488766 -348.613069)
			(xy 88.971614 -348.613069) (xy 88.971614 -348.558531) (xy 88.979376 -348.504547) (xy 88.994741 -348.452218)
			(xy 89.017396 -348.402608) (xy 89.046881 -348.356726) (xy 89.082595 -348.315508) (xy 89.123812 -348.279792)
			(xy 89.169692 -348.250305) (xy 89.219301 -348.227647) (xy 89.27163 -348.21228) (xy 89.325613 -348.204516)
			(xy 89.352882 -348.204028) (xy 90.216482 -348.204028) (xy 90.243753 -348.20451) (xy 90.297741 -348.21227)
			(xy 90.350074 -348.227634) (xy 90.399688 -348.25029) (xy 90.445573 -348.279777) (xy 90.486794 -348.315493)
			(xy 90.522512 -348.356713) (xy 90.552001 -348.402596) (xy 90.574659 -348.452209) (xy 90.590026 -348.504542)
			(xy 90.597788 -348.558529) (xy 90.597788 -348.613071) (xy 90.597788 -348.613074) (xy 92.080492 -348.613074)
			(xy 92.080492 -348.558526) (xy 92.088255 -348.504534) (xy 92.103624 -348.452197) (xy 92.126285 -348.40258)
			(xy 92.155777 -348.356693) (xy 92.1915 -348.315471) (xy 92.232727 -348.279752) (xy 92.278617 -348.250265)
			(xy 92.328236 -348.227609) (xy 92.380576 -348.212246) (xy 92.434568 -348.204489) (xy 92.461842 -348.204028)
			(xy 93.325442 -348.204028) (xy 93.352709 -348.204537) (xy 93.406686 -348.212304) (xy 93.459009 -348.227672)
			(xy 93.508613 -348.25033) (xy 93.554487 -348.279816) (xy 93.595699 -348.315531) (xy 93.631409 -348.356746)
			(xy 93.66089 -348.402624) (xy 93.683543 -348.45223) (xy 93.698905 -348.504555) (xy 93.706666 -348.558533)
			(xy 93.706666 -348.613067) (xy 93.706665 -348.613072) (xy 111.480792 -348.613072) (xy 111.480792 -348.558528)
			(xy 111.488554 -348.504539) (xy 111.503921 -348.452204) (xy 111.52658 -348.402589) (xy 111.556069 -348.356704)
			(xy 111.591788 -348.315483) (xy 111.63301 -348.279764) (xy 111.678896 -348.250276) (xy 111.728512 -348.227618)
			(xy 111.780847 -348.212252) (xy 111.834836 -348.204491) (xy 111.862108 -348.204028) (xy 112.725708 -348.204028)
			(xy 112.752976 -348.204535) (xy 112.806958 -348.212297) (xy 112.859285 -348.227663) (xy 112.908893 -348.250319)
			(xy 112.954771 -348.279804) (xy 112.995987 -348.315519) (xy 113.0317 -348.356735) (xy 113.061185 -348.402614)
			(xy 113.08384 -348.452223) (xy 113.099204 -348.50455) (xy 113.106966 -348.558532) (xy 113.106966 -348.613068)
			(xy 113.106966 -348.613069) (xy 114.589814 -348.613069) (xy 114.589814 -348.558531) (xy 114.597575 -348.504549)
			(xy 114.61294 -348.452221) (xy 114.635594 -348.402611) (xy 114.665078 -348.356731) (xy 114.70079 -348.315513)
			(xy 114.742005 -348.279797) (xy 114.787883 -348.250309) (xy 114.837491 -348.227651) (xy 114.889818 -348.212282)
			(xy 114.943799 -348.204517) (xy 114.971068 -348.204028) (xy 115.834668 -348.204028) (xy 115.86194 -348.204509)
			(xy 115.915929 -348.212268) (xy 115.968264 -348.227631) (xy 116.01788 -348.250286) (xy 116.063766 -348.279772)
			(xy 116.104989 -348.315488) (xy 116.140709 -348.356708) (xy 116.170199 -348.402592) (xy 116.192858 -348.452206)
			(xy 116.208226 -348.50454) (xy 116.215988 -348.558528) (xy 116.215988 -348.613072) (xy 116.215988 -348.613073)
			(xy 117.698692 -348.613073) (xy 117.698692 -348.558527) (xy 117.706455 -348.504536) (xy 117.721823 -348.4522)
			(xy 117.744483 -348.402584) (xy 117.773974 -348.356697) (xy 117.809695 -348.315476) (xy 117.85092 -348.279757)
			(xy 117.896808 -348.25027) (xy 117.946426 -348.227613) (xy 117.998764 -348.212249) (xy 118.052755 -348.20449)
			(xy 118.080028 -348.204028) (xy 118.943628 -348.204028) (xy 118.970895 -348.204536) (xy 119.024875 -348.212301)
			(xy 119.077199 -348.227668) (xy 119.126805 -348.250326) (xy 119.172681 -348.279811) (xy 119.213894 -348.315526)
			(xy 119.249605 -348.356742) (xy 119.279088 -348.40262) (xy 119.301741 -348.452227) (xy 119.317105 -348.504553)
			(xy 119.324866 -348.558533) (xy 119.324866 -348.613067) (xy 119.324866 -348.61307) (xy 120.807714 -348.61307)
			(xy 120.807714 -348.55853) (xy 120.815476 -348.504546) (xy 120.830841 -348.452217) (xy 120.853497 -348.402606)
			(xy 120.882983 -348.356724) (xy 120.918697 -348.315506) (xy 120.959915 -348.27979) (xy 121.005795 -348.250303)
			(xy 121.055405 -348.227645) (xy 121.107735 -348.212279) (xy 121.161718 -348.204515) (xy 121.188988 -348.204028)
			(xy 122.052588 -348.204028) (xy 122.079859 -348.204511) (xy 122.133846 -348.212271) (xy 122.186178 -348.227636)
			(xy 122.235792 -348.250292) (xy 122.281676 -348.279779) (xy 122.322896 -348.315495) (xy 122.358614 -348.356715)
			(xy 122.388102 -348.402598) (xy 122.41076 -348.45221) (xy 122.426126 -348.504543) (xy 122.433889 -348.558529)
			(xy 122.433889 -348.613071) (xy 122.433889 -348.613074) (xy 123.916592 -348.613074) (xy 123.916592 -348.558526)
			(xy 123.924355 -348.504534) (xy 123.939724 -348.452196) (xy 123.962386 -348.402578) (xy 123.991879 -348.356691)
			(xy 124.027602 -348.315468) (xy 124.068829 -348.27975) (xy 124.11472 -348.250263) (xy 124.164341 -348.227608)
			(xy 124.216681 -348.212245) (xy 124.270674 -348.204488) (xy 124.297948 -348.204028) (xy 125.161548 -348.204028)
			(xy 125.188814 -348.204538) (xy 125.242791 -348.212305) (xy 125.295114 -348.227674) (xy 125.344717 -348.250332)
			(xy 125.39059 -348.279819) (xy 125.431801 -348.315533) (xy 125.46751 -348.356748) (xy 125.496991 -348.402626)
			(xy 125.519643 -348.452231) (xy 125.535006 -348.504556) (xy 125.542766 -348.558534) (xy 125.542766 -348.613066)
			(xy 125.542765 -348.613072) (xy 127.025592 -348.613072) (xy 127.025592 -348.558528) (xy 127.033354 -348.504539)
			(xy 127.048721 -348.452204) (xy 127.07138 -348.402589) (xy 127.100869 -348.356704) (xy 127.136588 -348.315483)
			(xy 127.17781 -348.279764) (xy 127.223696 -348.250276) (xy 127.273312 -348.227618) (xy 127.325647 -348.212252)
			(xy 127.379636 -348.204491) (xy 127.406908 -348.204028) (xy 128.270508 -348.204028) (xy 128.297776 -348.204535)
			(xy 128.351758 -348.212297) (xy 128.404085 -348.227663) (xy 128.453693 -348.250319) (xy 128.499571 -348.279804)
			(xy 128.540787 -348.315519) (xy 128.5765 -348.356735) (xy 128.605985 -348.402614) (xy 128.62864 -348.452223)
			(xy 128.644004 -348.50455) (xy 128.651766 -348.558532) (xy 128.651766 -348.613068) (xy 128.651766 -348.613069)
			(xy 130.134614 -348.613069) (xy 130.134614 -348.558531) (xy 130.142375 -348.504549) (xy 130.15774 -348.452221)
			(xy 130.180394 -348.402611) (xy 130.209878 -348.356731) (xy 130.24559 -348.315513) (xy 130.286805 -348.279797)
			(xy 130.332683 -348.250309) (xy 130.382291 -348.227651) (xy 130.434618 -348.212282) (xy 130.488599 -348.204517)
			(xy 130.515868 -348.204028) (xy 131.379468 -348.204028) (xy 131.40674 -348.204509) (xy 131.460729 -348.212268)
			(xy 131.513064 -348.227631) (xy 131.56268 -348.250286) (xy 131.608566 -348.279772) (xy 131.649789 -348.315488)
			(xy 131.685509 -348.356708) (xy 131.714999 -348.402592) (xy 131.737658 -348.452206) (xy 131.753026 -348.50454)
			(xy 131.760788 -348.558528) (xy 131.760788 -348.613072) (xy 131.760788 -348.613073) (xy 133.243492 -348.613073)
			(xy 133.243492 -348.558527) (xy 133.251255 -348.504536) (xy 133.266623 -348.4522) (xy 133.289283 -348.402584)
			(xy 133.318774 -348.356697) (xy 133.354495 -348.315476) (xy 133.39572 -348.279757) (xy 133.441608 -348.25027)
			(xy 133.491226 -348.227613) (xy 133.543564 -348.212249) (xy 133.597555 -348.20449) (xy 133.624828 -348.204028)
			(xy 134.488428 -348.204028) (xy 134.515695 -348.204536) (xy 134.569675 -348.212301) (xy 134.621999 -348.227668)
			(xy 134.671605 -348.250326) (xy 134.717481 -348.279811) (xy 134.758694 -348.315526) (xy 134.794405 -348.356742)
			(xy 134.823888 -348.40262) (xy 134.846541 -348.452227) (xy 134.861905 -348.504553) (xy 134.869666 -348.558533)
			(xy 134.869666 -348.613067) (xy 134.869666 -348.61307) (xy 136.352514 -348.61307) (xy 136.352514 -348.55853)
			(xy 136.360276 -348.504546) (xy 136.375641 -348.452217) (xy 136.398297 -348.402606) (xy 136.427783 -348.356724)
			(xy 136.463497 -348.315506) (xy 136.504715 -348.27979) (xy 136.550595 -348.250303) (xy 136.600205 -348.227645)
			(xy 136.652535 -348.212279) (xy 136.706518 -348.204515) (xy 136.733788 -348.204028) (xy 137.597388 -348.204028)
			(xy 137.624659 -348.204511) (xy 137.678646 -348.212271) (xy 137.730978 -348.227636) (xy 137.780592 -348.250292)
			(xy 137.826476 -348.279779) (xy 137.867696 -348.315495) (xy 137.903414 -348.356715) (xy 137.932902 -348.402598)
			(xy 137.95556 -348.45221) (xy 137.970926 -348.504543) (xy 137.978689 -348.558529) (xy 137.978689 -348.613071)
			(xy 137.978689 -348.613074) (xy 139.461392 -348.613074) (xy 139.461392 -348.558526) (xy 139.469155 -348.504534)
			(xy 139.484524 -348.452196) (xy 139.507186 -348.402578) (xy 139.536679 -348.356691) (xy 139.572402 -348.315468)
			(xy 139.613629 -348.27975) (xy 139.65952 -348.250263) (xy 139.709141 -348.227608) (xy 139.761481 -348.212245)
			(xy 139.815474 -348.204488) (xy 139.842748 -348.204028) (xy 140.706348 -348.204028) (xy 140.733614 -348.204538)
			(xy 140.787591 -348.212305) (xy 140.839914 -348.227674) (xy 140.889517 -348.250332) (xy 140.93539 -348.279819)
			(xy 140.976601 -348.315533) (xy 141.01231 -348.356748) (xy 141.041791 -348.402626) (xy 141.064443 -348.452231)
			(xy 141.079806 -348.504556) (xy 141.087566 -348.558534) (xy 141.087566 -348.613066) (xy 141.087565 -348.613072)
			(xy 142.570392 -348.613072) (xy 142.570392 -348.558528) (xy 142.578154 -348.504539) (xy 142.593521 -348.452204)
			(xy 142.61618 -348.402589) (xy 142.645669 -348.356704) (xy 142.681388 -348.315483) (xy 142.72261 -348.279764)
			(xy 142.768496 -348.250276) (xy 142.818112 -348.227618) (xy 142.870447 -348.212252) (xy 142.924436 -348.204491)
			(xy 142.951708 -348.204028) (xy 143.815308 -348.204028) (xy 143.842576 -348.204535) (xy 143.896558 -348.212297)
			(xy 143.948885 -348.227663) (xy 143.998493 -348.250319) (xy 144.044371 -348.279804) (xy 144.085587 -348.315519)
			(xy 144.1213 -348.356735) (xy 144.150785 -348.402614) (xy 144.17344 -348.452223) (xy 144.188804 -348.50455)
			(xy 144.196566 -348.558532) (xy 144.196566 -348.613068) (xy 144.196565 -348.613072) (xy 161.804792 -348.613072)
			(xy 161.804792 -348.558528) (xy 161.812554 -348.504538) (xy 161.827921 -348.452203) (xy 161.850581 -348.402588)
			(xy 161.88007 -348.356703) (xy 161.91579 -348.315481) (xy 161.957012 -348.279763) (xy 162.002899 -348.250275)
			(xy 162.052515 -348.227617) (xy 162.10485 -348.212252) (xy 162.15884 -348.204491) (xy 162.186112 -348.204028)
			(xy 163.049712 -348.204028) (xy 163.07698 -348.204535) (xy 163.130961 -348.212298) (xy 163.183288 -348.227664)
			(xy 163.232895 -348.25032) (xy 163.278773 -348.279806) (xy 163.319988 -348.31552) (xy 163.355701 -348.356736)
			(xy 163.385185 -348.402615) (xy 163.40784 -348.452224) (xy 163.423204 -348.504551) (xy 163.430966 -348.558532)
			(xy 163.430966 -348.613068) (xy 163.430966 -348.613069) (xy 164.913814 -348.613069) (xy 164.913814 -348.558531)
			(xy 164.921576 -348.504549) (xy 164.93694 -348.45222) (xy 164.959595 -348.40261) (xy 164.989079 -348.35673)
			(xy 165.024792 -348.315512) (xy 165.066007 -348.279795) (xy 165.111886 -348.250308) (xy 165.161494 -348.22765)
			(xy 165.213821 -348.212281) (xy 165.267803 -348.204516) (xy 165.295072 -348.204028) (xy 166.158672 -348.204028)
			(xy 166.185944 -348.20451) (xy 166.239932 -348.212268) (xy 166.292267 -348.227632) (xy 166.341882 -348.250287)
			(xy 166.387768 -348.279773) (xy 166.42899 -348.31549) (xy 166.46471 -348.356709) (xy 166.494199 -348.402593)
			(xy 166.516859 -348.452207) (xy 166.532226 -348.504541) (xy 166.539988 -348.558528) (xy 166.539988 -348.613072)
			(xy 166.539988 -348.613073) (xy 168.022692 -348.613073) (xy 168.022692 -348.558527) (xy 168.030455 -348.504536)
			(xy 168.045823 -348.452199) (xy 168.068484 -348.402583) (xy 168.097975 -348.356696) (xy 168.133697 -348.315474)
			(xy 168.174922 -348.279756) (xy 168.220811 -348.250268) (xy 168.270429 -348.227612) (xy 168.322767 -348.212248)
			(xy 168.376759 -348.204489) (xy 168.404032 -348.204028) (xy 169.267632 -348.204028) (xy 169.294899 -348.204537)
			(xy 169.348878 -348.212302) (xy 169.401202 -348.227669) (xy 169.450807 -348.250327) (xy 169.496683 -348.279813)
			(xy 169.537895 -348.315527) (xy 169.573606 -348.356743) (xy 169.603088 -348.402621) (xy 169.625742 -348.452228)
			(xy 169.641105 -348.504553) (xy 169.648866 -348.558533) (xy 169.648866 -348.613067) (xy 169.648866 -348.61307)
			(xy 171.131714 -348.61307) (xy 171.131714 -348.55853) (xy 171.139476 -348.504546) (xy 171.154841 -348.452216)
			(xy 171.177498 -348.402605) (xy 171.206984 -348.356723) (xy 171.242699 -348.315505) (xy 171.283917 -348.279788)
			(xy 171.329798 -348.250301) (xy 171.379408 -348.227644) (xy 171.431738 -348.212278) (xy 171.485722 -348.204515)
			(xy 171.512992 -348.204028) (xy 172.376592 -348.204028) (xy 172.403863 -348.204511) (xy 172.457849 -348.212272)
			(xy 172.510181 -348.227637) (xy 172.559794 -348.250294) (xy 172.605678 -348.27978) (xy 172.646898 -348.315497)
			(xy 172.682615 -348.356716) (xy 172.712103 -348.402599) (xy 172.73476 -348.452211) (xy 172.750126 -348.504543)
			(xy 172.757889 -348.558529) (xy 172.757889 -348.613068) (xy 174.240714 -348.613068) (xy 174.240714 -348.558532)
			(xy 174.248475 -348.504551) (xy 174.263838 -348.452224) (xy 174.286492 -348.402616) (xy 174.315974 -348.356736)
			(xy 174.351685 -348.315519) (xy 174.392898 -348.279803) (xy 174.438774 -348.250315) (xy 174.488379 -348.227655)
			(xy 174.540704 -348.212285) (xy 174.594684 -348.204518) (xy 174.621952 -348.204028) (xy 175.485552 -348.204028)
			(xy 175.512825 -348.204508) (xy 175.566815 -348.212265) (xy 175.619152 -348.227626) (xy 175.66877 -348.250281)
			(xy 175.714659 -348.279766) (xy 175.755883 -348.315483) (xy 175.791605 -348.356703) (xy 175.821096 -348.402588)
			(xy 175.843757 -348.452203) (xy 175.859125 -348.504538) (xy 175.866888 -348.558528) (xy 175.866888 -348.613072)
			(xy 177.349592 -348.613072) (xy 177.349592 -348.558528) (xy 177.357354 -348.504538) (xy 177.372721 -348.452203)
			(xy 177.395381 -348.402588) (xy 177.42487 -348.356703) (xy 177.46059 -348.315481) (xy 177.501812 -348.279763)
			(xy 177.547699 -348.250275) (xy 177.597315 -348.227617) (xy 177.64965 -348.212252) (xy 177.70364 -348.204491)
			(xy 177.730912 -348.204028) (xy 178.594512 -348.204028) (xy 178.62178 -348.204535) (xy 178.675761 -348.212298)
			(xy 178.728088 -348.227664) (xy 178.777695 -348.25032) (xy 178.823573 -348.279806) (xy 178.864788 -348.31552)
			(xy 178.900501 -348.356736) (xy 178.929985 -348.402615) (xy 178.95264 -348.452224) (xy 178.968004 -348.504551)
			(xy 178.975766 -348.558532) (xy 178.975766 -348.613068) (xy 178.975766 -348.613069) (xy 180.458614 -348.613069)
			(xy 180.458614 -348.558531) (xy 180.466376 -348.504549) (xy 180.48174 -348.45222) (xy 180.504395 -348.40261)
			(xy 180.533879 -348.35673) (xy 180.569592 -348.315512) (xy 180.610807 -348.279795) (xy 180.656686 -348.250308)
			(xy 180.706294 -348.22765) (xy 180.758621 -348.212281) (xy 180.812603 -348.204516) (xy 180.839872 -348.204028)
			(xy 181.703472 -348.204028) (xy 181.730744 -348.20451) (xy 181.784732 -348.212268) (xy 181.837067 -348.227632)
			(xy 181.886682 -348.250287) (xy 181.932568 -348.279773) (xy 181.97379 -348.31549) (xy 182.00951 -348.356709)
			(xy 182.038999 -348.402593) (xy 182.061659 -348.452207) (xy 182.077026 -348.504541) (xy 182.084788 -348.558528)
			(xy 182.084788 -348.613072) (xy 182.084788 -348.613073) (xy 183.567492 -348.613073) (xy 183.567492 -348.558527)
			(xy 183.575255 -348.504536) (xy 183.590623 -348.452199) (xy 183.613284 -348.402583) (xy 183.642775 -348.356696)
			(xy 183.678497 -348.315474) (xy 183.719722 -348.279756) (xy 183.765611 -348.250268) (xy 183.815229 -348.227612)
			(xy 183.867567 -348.212248) (xy 183.921559 -348.204489) (xy 183.948832 -348.204028) (xy 184.812432 -348.204028)
			(xy 184.839699 -348.204537) (xy 184.893678 -348.212302) (xy 184.946002 -348.227669) (xy 184.995607 -348.250327)
			(xy 185.041483 -348.279813) (xy 185.082695 -348.315527) (xy 185.118406 -348.356743) (xy 185.147888 -348.402621)
			(xy 185.170542 -348.452228) (xy 185.185905 -348.504553) (xy 185.193666 -348.558533) (xy 185.193666 -348.613067)
			(xy 185.193666 -348.61307) (xy 186.676514 -348.61307) (xy 186.676514 -348.55853) (xy 186.684276 -348.504546)
			(xy 186.699641 -348.452216) (xy 186.722298 -348.402605) (xy 186.751784 -348.356723) (xy 186.787499 -348.315505)
			(xy 186.828717 -348.279788) (xy 186.874598 -348.250301) (xy 186.924208 -348.227644) (xy 186.976538 -348.212278)
			(xy 187.030522 -348.204515) (xy 187.057792 -348.204028) (xy 187.921392 -348.204028) (xy 187.948663 -348.204511)
			(xy 188.002649 -348.212272) (xy 188.054981 -348.227637) (xy 188.104594 -348.250294) (xy 188.150478 -348.27978)
			(xy 188.191698 -348.315497) (xy 188.227415 -348.356716) (xy 188.256903 -348.402599) (xy 188.27956 -348.452211)
			(xy 188.294926 -348.504543) (xy 188.302689 -348.558529) (xy 188.302689 -348.613068) (xy 189.785514 -348.613068)
			(xy 189.785514 -348.558532) (xy 189.793275 -348.504551) (xy 189.808638 -348.452224) (xy 189.831292 -348.402616)
			(xy 189.860774 -348.356736) (xy 189.896485 -348.315519) (xy 189.937698 -348.279803) (xy 189.983574 -348.250315)
			(xy 190.033179 -348.227655) (xy 190.085504 -348.212285) (xy 190.139484 -348.204518) (xy 190.166752 -348.204028)
			(xy 191.030352 -348.204028) (xy 191.057625 -348.204508) (xy 191.111615 -348.212265) (xy 191.163952 -348.227626)
			(xy 191.21357 -348.250281) (xy 191.259459 -348.279766) (xy 191.300683 -348.315483) (xy 191.336405 -348.356703)
			(xy 191.365896 -348.402588) (xy 191.388557 -348.452203) (xy 191.403925 -348.504538) (xy 191.411688 -348.558528)
			(xy 191.411688 -348.613072) (xy 192.894392 -348.613072) (xy 192.894392 -348.558528) (xy 192.902154 -348.504538)
			(xy 192.917521 -348.452203) (xy 192.940181 -348.402588) (xy 192.96967 -348.356703) (xy 193.00539 -348.315481)
			(xy 193.046612 -348.279763) (xy 193.092499 -348.250275) (xy 193.142115 -348.227617) (xy 193.19445 -348.212252)
			(xy 193.24844 -348.204491) (xy 193.275712 -348.204028) (xy 194.139312 -348.204028) (xy 194.16658 -348.204535)
			(xy 194.220561 -348.212298) (xy 194.272888 -348.227664) (xy 194.322495 -348.25032) (xy 194.368373 -348.279806)
			(xy 194.409588 -348.31552) (xy 194.445301 -348.356736) (xy 194.474785 -348.402615) (xy 194.49744 -348.452224)
			(xy 194.512804 -348.504551) (xy 194.520566 -348.558532) (xy 194.520566 -348.613068) (xy 194.520565 -348.613072)
			(xy 267.515792 -348.613072) (xy 267.515792 -348.558528) (xy 267.523554 -348.50454) (xy 267.538921 -348.452206)
			(xy 267.561579 -348.402591) (xy 267.591068 -348.356706) (xy 267.626786 -348.315485) (xy 267.668008 -348.279766)
			(xy 267.713893 -348.250278) (xy 267.763507 -348.22762) (xy 267.815842 -348.212253) (xy 267.86983 -348.204491)
			(xy 267.897102 -348.204028) (xy 268.760702 -348.204028) (xy 268.787971 -348.204535) (xy 268.841953 -348.212296)
			(xy 268.89428 -348.227661) (xy 268.943889 -348.250317) (xy 268.989769 -348.279802) (xy 269.030985 -348.315517)
			(xy 269.066699 -348.356733) (xy 269.096184 -348.402613) (xy 269.118839 -348.452221) (xy 269.134204 -348.504549)
			(xy 269.141966 -348.558531) (xy 269.141966 -348.613068) (xy 270.624814 -348.613068) (xy 270.624814 -348.558532)
			(xy 270.632575 -348.50455) (xy 270.647939 -348.452222) (xy 270.670593 -348.402613) (xy 270.700076 -348.356733)
			(xy 270.735788 -348.315515) (xy 270.777002 -348.279799) (xy 270.82288 -348.250311) (xy 270.872486 -348.227652)
			(xy 270.924813 -348.212283) (xy 270.978794 -348.204517) (xy 271.006062 -348.204028) (xy 271.869662 -348.204028)
			(xy 271.896934 -348.204509) (xy 271.950924 -348.212266) (xy 272.00326 -348.227629) (xy 272.052876 -348.250284)
			(xy 272.098763 -348.27977) (xy 272.139987 -348.315486) (xy 272.175708 -348.356706) (xy 272.205198 -348.40259)
			(xy 272.227858 -348.452205) (xy 272.243226 -348.504539) (xy 272.250988 -348.558528) (xy 272.250988 -348.613072)
			(xy 272.250988 -348.613073) (xy 273.733692 -348.613073) (xy 273.733692 -348.558527) (xy 273.741454 -348.504537)
			(xy 273.756822 -348.452201) (xy 273.779482 -348.402585) (xy 273.808972 -348.356699) (xy 273.844693 -348.315478)
			(xy 273.885917 -348.279759) (xy 273.931805 -348.250271) (xy 273.981422 -348.227615) (xy 274.033759 -348.21225)
			(xy 274.087749 -348.20449) (xy 274.115022 -348.204028) (xy 274.978622 -348.204028) (xy 275.00589 -348.204536)
			(xy 275.059869 -348.2123) (xy 275.112195 -348.227667) (xy 275.161801 -348.250324) (xy 275.207678 -348.279809)
			(xy 275.248892 -348.315524) (xy 275.284604 -348.35674) (xy 275.314087 -348.402618) (xy 275.336741 -348.452226)
			(xy 275.352105 -348.504552) (xy 275.359866 -348.558532) (xy 275.359866 -348.613068) (xy 275.359866 -348.613069)
			(xy 276.842714 -348.613069) (xy 276.842714 -348.558531) (xy 276.850476 -348.504547) (xy 276.865841 -348.452218)
			(xy 276.888496 -348.402608) (xy 276.917981 -348.356726) (xy 276.953695 -348.315508) (xy 276.994912 -348.279792)
			(xy 277.040792 -348.250305) (xy 277.090401 -348.227647) (xy 277.14273 -348.21228) (xy 277.196713 -348.204516)
			(xy 277.223982 -348.204028) (xy 278.087582 -348.204028) (xy 278.114853 -348.20451) (xy 278.168841 -348.21227)
			(xy 278.221174 -348.227634) (xy 278.270788 -348.25029) (xy 278.316673 -348.279777) (xy 278.357894 -348.315493)
			(xy 278.393612 -348.356713) (xy 278.423101 -348.402596) (xy 278.445759 -348.452209) (xy 278.461126 -348.504542)
			(xy 278.468888 -348.558529) (xy 278.468888 -348.613071) (xy 278.468888 -348.613074) (xy 279.951592 -348.613074)
			(xy 279.951592 -348.558526) (xy 279.959355 -348.504534) (xy 279.974724 -348.452197) (xy 279.997385 -348.40258)
			(xy 280.026877 -348.356693) (xy 280.0626 -348.315471) (xy 280.103827 -348.279752) (xy 280.149717 -348.250265)
			(xy 280.199336 -348.227609) (xy 280.251676 -348.212246) (xy 280.305668 -348.204489) (xy 280.332942 -348.204028)
			(xy 281.196542 -348.204028) (xy 281.223809 -348.204537) (xy 281.277786 -348.212304) (xy 281.330109 -348.227672)
			(xy 281.379713 -348.25033) (xy 281.425587 -348.279816) (xy 281.466799 -348.315531) (xy 281.502509 -348.356746)
			(xy 281.53199 -348.402624) (xy 281.554643 -348.45223) (xy 281.570005 -348.504555) (xy 281.577766 -348.558533)
			(xy 281.577766 -348.613067) (xy 281.577765 -348.613072) (xy 283.060592 -348.613072) (xy 283.060592 -348.558528)
			(xy 283.068354 -348.50454) (xy 283.083721 -348.452206) (xy 283.106379 -348.402591) (xy 283.135868 -348.356706)
			(xy 283.171586 -348.315485) (xy 283.212808 -348.279766) (xy 283.258693 -348.250278) (xy 283.308307 -348.22762)
			(xy 283.360642 -348.212253) (xy 283.41463 -348.204491) (xy 283.441902 -348.204028) (xy 284.305502 -348.204028)
			(xy 284.332771 -348.204535) (xy 284.386753 -348.212296) (xy 284.43908 -348.227661) (xy 284.488689 -348.250317)
			(xy 284.534569 -348.279802) (xy 284.575785 -348.315517) (xy 284.611499 -348.356733) (xy 284.640984 -348.402613)
			(xy 284.663639 -348.452221) (xy 284.679004 -348.504549) (xy 284.686766 -348.558531) (xy 284.686766 -348.613068)
			(xy 286.169614 -348.613068) (xy 286.169614 -348.558532) (xy 286.177375 -348.50455) (xy 286.192739 -348.452222)
			(xy 286.215393 -348.402613) (xy 286.244876 -348.356733) (xy 286.280588 -348.315515) (xy 286.321802 -348.279799)
			(xy 286.36768 -348.250311) (xy 286.417286 -348.227652) (xy 286.469613 -348.212283) (xy 286.523594 -348.204517)
			(xy 286.550862 -348.204028) (xy 287.414462 -348.204028) (xy 287.441734 -348.204509) (xy 287.495724 -348.212266)
			(xy 287.54806 -348.227629) (xy 287.597676 -348.250284) (xy 287.643563 -348.27977) (xy 287.684787 -348.315486)
			(xy 287.720508 -348.356706) (xy 287.749998 -348.40259) (xy 287.772658 -348.452205) (xy 287.788026 -348.504539)
			(xy 287.795788 -348.558528) (xy 287.795788 -348.613072) (xy 287.795788 -348.613073) (xy 289.278492 -348.613073)
			(xy 289.278492 -348.558527) (xy 289.286254 -348.504537) (xy 289.301622 -348.452201) (xy 289.324282 -348.402585)
			(xy 289.353772 -348.356699) (xy 289.389493 -348.315478) (xy 289.430717 -348.279759) (xy 289.476605 -348.250271)
			(xy 289.526222 -348.227615) (xy 289.578559 -348.21225) (xy 289.632549 -348.20449) (xy 289.659822 -348.204028)
			(xy 290.523422 -348.204028) (xy 290.55069 -348.204536) (xy 290.604669 -348.2123) (xy 290.656995 -348.227667)
			(xy 290.706601 -348.250324) (xy 290.752478 -348.279809) (xy 290.793692 -348.315524) (xy 290.829404 -348.35674)
			(xy 290.858887 -348.402618) (xy 290.881541 -348.452226) (xy 290.896905 -348.504552) (xy 290.904666 -348.558532)
			(xy 290.904666 -348.613068) (xy 290.904666 -348.613069) (xy 292.387514 -348.613069) (xy 292.387514 -348.558531)
			(xy 292.395276 -348.504547) (xy 292.410641 -348.452218) (xy 292.433296 -348.402608) (xy 292.462781 -348.356726)
			(xy 292.498495 -348.315508) (xy 292.539712 -348.279792) (xy 292.585592 -348.250305) (xy 292.635201 -348.227647)
			(xy 292.68753 -348.21228) (xy 292.741513 -348.204516) (xy 292.768782 -348.204028) (xy 293.632382 -348.204028)
			(xy 293.659653 -348.20451) (xy 293.713641 -348.21227) (xy 293.765974 -348.227634) (xy 293.815588 -348.25029)
			(xy 293.861473 -348.279777) (xy 293.902694 -348.315493) (xy 293.938412 -348.356713) (xy 293.967901 -348.402596)
			(xy 293.990559 -348.452209) (xy 294.005926 -348.504542) (xy 294.013688 -348.558529) (xy 294.013688 -348.613071)
			(xy 294.013688 -348.613074) (xy 295.496392 -348.613074) (xy 295.496392 -348.558526) (xy 295.504155 -348.504534)
			(xy 295.519524 -348.452197) (xy 295.542185 -348.40258) (xy 295.571677 -348.356693) (xy 295.6074 -348.315471)
			(xy 295.648627 -348.279752) (xy 295.694517 -348.250265) (xy 295.744136 -348.227609) (xy 295.796476 -348.212246)
			(xy 295.850468 -348.204489) (xy 295.877742 -348.204028) (xy 296.741342 -348.204028) (xy 296.768609 -348.204537)
			(xy 296.822586 -348.212304) (xy 296.874909 -348.227672) (xy 296.924513 -348.25033) (xy 296.970387 -348.279816)
			(xy 297.011599 -348.315531) (xy 297.047309 -348.356746) (xy 297.07679 -348.402624) (xy 297.099443 -348.45223)
			(xy 297.114805 -348.504555) (xy 297.122566 -348.558533) (xy 297.122566 -348.613067) (xy 297.122565 -348.613072)
			(xy 298.605392 -348.613072) (xy 298.605392 -348.558528) (xy 298.613154 -348.50454) (xy 298.628521 -348.452206)
			(xy 298.651179 -348.402591) (xy 298.680668 -348.356706) (xy 298.716386 -348.315485) (xy 298.757608 -348.279766)
			(xy 298.803493 -348.250278) (xy 298.853107 -348.22762) (xy 298.905442 -348.212253) (xy 298.95943 -348.204491)
			(xy 298.986702 -348.204028) (xy 299.850302 -348.204028) (xy 299.877571 -348.204535) (xy 299.931553 -348.212296)
			(xy 299.98388 -348.227661) (xy 300.033489 -348.250317) (xy 300.079369 -348.279802) (xy 300.120585 -348.315517)
			(xy 300.156299 -348.356733) (xy 300.185784 -348.402613) (xy 300.208439 -348.452221) (xy 300.223804 -348.504549)
			(xy 300.231566 -348.558531) (xy 300.231566 -348.613069) (xy 300.231566 -348.613072) (xy 312.121492 -348.613072)
			(xy 312.121492 -348.558528) (xy 312.129254 -348.504539) (xy 312.144621 -348.452205) (xy 312.167279 -348.40259)
			(xy 312.196768 -348.356705) (xy 312.232487 -348.315484) (xy 312.273709 -348.279766) (xy 312.319594 -348.250277)
			(xy 312.369209 -348.227619) (xy 312.421543 -348.212253) (xy 312.475532 -348.204491) (xy 312.502804 -348.204028)
			(xy 313.366404 -348.204028) (xy 313.393672 -348.204535) (xy 313.447654 -348.212297) (xy 313.499982 -348.227662)
			(xy 313.54959 -348.250318) (xy 313.595469 -348.279803) (xy 313.636686 -348.315517) (xy 313.672399 -348.356734)
			(xy 313.701884 -348.402613) (xy 313.72454 -348.452222) (xy 313.739904 -348.50455) (xy 313.747666 -348.558532)
			(xy 313.747666 -348.613068) (xy 315.230514 -348.613068) (xy 315.230514 -348.558532) (xy 315.238275 -348.50455)
			(xy 315.253639 -348.452222) (xy 315.276293 -348.402613) (xy 315.305777 -348.356732) (xy 315.341489 -348.315514)
			(xy 315.382703 -348.279798) (xy 315.428581 -348.250311) (xy 315.478188 -348.227652) (xy 315.530514 -348.212283)
			(xy 315.584496 -348.204517) (xy 315.611764 -348.204028) (xy 316.475364 -348.204028) (xy 316.502636 -348.204509)
			(xy 316.556625 -348.212267) (xy 316.608961 -348.22763) (xy 316.658577 -348.250284) (xy 316.704464 -348.27977)
			(xy 316.745688 -348.315487) (xy 316.781408 -348.356707) (xy 316.810898 -348.402591) (xy 316.833558 -348.452205)
			(xy 316.848926 -348.504539) (xy 316.856688 -348.558528) (xy 316.856688 -348.613072) (xy 316.856688 -348.613073)
			(xy 318.339392 -348.613073) (xy 318.339392 -348.558527) (xy 318.347155 -348.504537) (xy 318.362522 -348.452201)
			(xy 318.385182 -348.402585) (xy 318.414673 -348.356699) (xy 318.450394 -348.315477) (xy 318.491618 -348.279759)
			(xy 318.537506 -348.250271) (xy 318.587123 -348.227614) (xy 318.63946 -348.212249) (xy 318.693451 -348.20449)
			(xy 318.720724 -348.204028) (xy 319.584324 -348.204028) (xy 319.611592 -348.204536) (xy 319.665571 -348.2123)
			(xy 319.717896 -348.227667) (xy 319.767502 -348.250324) (xy 319.813379 -348.27981) (xy 319.854593 -348.315524)
			(xy 319.890304 -348.35674) (xy 319.919787 -348.402619) (xy 319.942441 -348.452226) (xy 319.957805 -348.504552)
			(xy 319.965566 -348.558532) (xy 319.965566 -348.613068) (xy 319.965566 -348.613069) (xy 321.448414 -348.613069)
			(xy 321.448414 -348.558531) (xy 321.456176 -348.504547) (xy 321.471541 -348.452217) (xy 321.494196 -348.402607)
			(xy 321.523682 -348.356726) (xy 321.559396 -348.315507) (xy 321.600613 -348.279791) (xy 321.646493 -348.250304)
			(xy 321.696102 -348.227646) (xy 321.748431 -348.212279) (xy 321.802415 -348.204516) (xy 321.829684 -348.204028)
			(xy 322.693284 -348.204028) (xy 322.720555 -348.20451) (xy 322.774542 -348.21227) (xy 322.826875 -348.227635)
			(xy 322.876489 -348.250291) (xy 322.922374 -348.279777) (xy 322.963595 -348.315494) (xy 322.999313 -348.356713)
			(xy 323.028801 -348.402597) (xy 323.051459 -348.45221) (xy 323.066826 -348.504542) (xy 323.074588 -348.558529)
			(xy 323.074588 -348.613071) (xy 323.074588 -348.613074) (xy 324.557292 -348.613074) (xy 324.557292 -348.558526)
			(xy 324.565055 -348.504534) (xy 324.580424 -348.452197) (xy 324.603085 -348.402579) (xy 324.632578 -348.356692)
			(xy 324.668301 -348.31547) (xy 324.709527 -348.279751) (xy 324.755418 -348.250264) (xy 324.805038 -348.227609)
			(xy 324.857377 -348.212246) (xy 324.91137 -348.204489) (xy 324.938644 -348.204028) (xy 325.802244 -348.204028)
			(xy 325.829511 -348.204537) (xy 325.883488 -348.212304) (xy 325.935811 -348.227673) (xy 325.985414 -348.250331)
			(xy 326.031288 -348.279817) (xy 326.0725 -348.315531) (xy 326.108209 -348.356747) (xy 326.13769 -348.402624)
			(xy 326.160343 -348.45223) (xy 326.175705 -348.504555) (xy 326.183466 -348.558533) (xy 326.183466 -348.613067)
			(xy 326.183465 -348.613072) (xy 327.666292 -348.613072) (xy 327.666292 -348.558528) (xy 327.674054 -348.504539)
			(xy 327.689421 -348.452205) (xy 327.712079 -348.40259) (xy 327.741568 -348.356705) (xy 327.777287 -348.315484)
			(xy 327.818509 -348.279766) (xy 327.864394 -348.250277) (xy 327.914009 -348.227619) (xy 327.966343 -348.212253)
			(xy 328.020332 -348.204491) (xy 328.047604 -348.204028) (xy 328.911204 -348.204028) (xy 328.938472 -348.204535)
			(xy 328.992454 -348.212297) (xy 329.044782 -348.227662) (xy 329.09439 -348.250318) (xy 329.140269 -348.279803)
			(xy 329.181486 -348.315517) (xy 329.217199 -348.356734) (xy 329.246684 -348.402613) (xy 329.26934 -348.452222)
			(xy 329.284704 -348.50455) (xy 329.292466 -348.558532) (xy 329.292466 -348.613068) (xy 330.775314 -348.613068)
			(xy 330.775314 -348.558532) (xy 330.783075 -348.50455) (xy 330.798439 -348.452222) (xy 330.821093 -348.402613)
			(xy 330.850577 -348.356732) (xy 330.886289 -348.315514) (xy 330.927503 -348.279798) (xy 330.973381 -348.250311)
			(xy 331.022988 -348.227652) (xy 331.075314 -348.212283) (xy 331.129296 -348.204517) (xy 331.156564 -348.204028)
			(xy 332.020164 -348.204028) (xy 332.047436 -348.204509) (xy 332.101425 -348.212267) (xy 332.153761 -348.22763)
			(xy 332.203377 -348.250284) (xy 332.249264 -348.27977) (xy 332.290488 -348.315487) (xy 332.326208 -348.356707)
			(xy 332.355698 -348.402591) (xy 332.378358 -348.452205) (xy 332.393726 -348.504539) (xy 332.401488 -348.558528)
			(xy 332.401488 -348.613072) (xy 332.401488 -348.613073) (xy 333.884192 -348.613073) (xy 333.884192 -348.558527)
			(xy 333.891955 -348.504537) (xy 333.907322 -348.452201) (xy 333.929982 -348.402585) (xy 333.959473 -348.356699)
			(xy 333.995194 -348.315477) (xy 334.036418 -348.279759) (xy 334.082306 -348.250271) (xy 334.131923 -348.227614)
			(xy 334.18426 -348.212249) (xy 334.238251 -348.20449) (xy 334.265524 -348.204028) (xy 335.129124 -348.204028)
			(xy 335.156392 -348.204536) (xy 335.210371 -348.2123) (xy 335.262696 -348.227667) (xy 335.312302 -348.250324)
			(xy 335.358179 -348.27981) (xy 335.399393 -348.315524) (xy 335.435104 -348.35674) (xy 335.464587 -348.402619)
			(xy 335.487241 -348.452226) (xy 335.502605 -348.504552) (xy 335.510366 -348.558532) (xy 335.510366 -348.613068)
			(xy 335.510366 -348.613069) (xy 336.993214 -348.613069) (xy 336.993214 -348.558531) (xy 337.000976 -348.504547)
			(xy 337.016341 -348.452217) (xy 337.038996 -348.402607) (xy 337.068482 -348.356726) (xy 337.104196 -348.315507)
			(xy 337.145413 -348.279791) (xy 337.191293 -348.250304) (xy 337.240902 -348.227646) (xy 337.293231 -348.212279)
			(xy 337.347215 -348.204516) (xy 337.374484 -348.204028) (xy 338.238084 -348.204028) (xy 338.265355 -348.20451)
			(xy 338.319342 -348.21227) (xy 338.371675 -348.227635) (xy 338.421289 -348.250291) (xy 338.467174 -348.279777)
			(xy 338.508395 -348.315494) (xy 338.544113 -348.356713) (xy 338.573601 -348.402597) (xy 338.596259 -348.45221)
			(xy 338.611626 -348.504542) (xy 338.619388 -348.558529) (xy 338.619388 -348.613071) (xy 338.619388 -348.613074)
			(xy 340.102092 -348.613074) (xy 340.102092 -348.558526) (xy 340.109855 -348.504534) (xy 340.125224 -348.452197)
			(xy 340.147885 -348.402579) (xy 340.177378 -348.356692) (xy 340.213101 -348.31547) (xy 340.254327 -348.279751)
			(xy 340.300218 -348.250264) (xy 340.349838 -348.227609) (xy 340.402177 -348.212246) (xy 340.45617 -348.204489)
			(xy 340.483444 -348.204028) (xy 341.347044 -348.204028) (xy 341.374311 -348.204537) (xy 341.428288 -348.212304)
			(xy 341.480611 -348.227673) (xy 341.530214 -348.250331) (xy 341.576088 -348.279817) (xy 341.6173 -348.315531)
			(xy 341.653009 -348.356747) (xy 341.68249 -348.402624) (xy 341.705143 -348.45223) (xy 341.720505 -348.504555)
			(xy 341.728266 -348.558533) (xy 341.728266 -348.613067) (xy 341.728265 -348.613072) (xy 343.211092 -348.613072)
			(xy 343.211092 -348.558528) (xy 343.218854 -348.504539) (xy 343.234221 -348.452205) (xy 343.256879 -348.40259)
			(xy 343.286368 -348.356705) (xy 343.322087 -348.315484) (xy 343.363309 -348.279766) (xy 343.409194 -348.250277)
			(xy 343.458809 -348.227619) (xy 343.511143 -348.212253) (xy 343.565132 -348.204491) (xy 343.592404 -348.204028)
			(xy 344.456004 -348.204028) (xy 344.483272 -348.204535) (xy 344.537254 -348.212297) (xy 344.589582 -348.227662)
			(xy 344.63919 -348.250318) (xy 344.685069 -348.279803) (xy 344.726286 -348.315517) (xy 344.761999 -348.356734)
			(xy 344.791484 -348.402613) (xy 344.81414 -348.452222) (xy 344.829504 -348.50455) (xy 344.837266 -348.558532)
			(xy 344.837266 -348.613068) (xy 344.837266 -348.613069) (xy 370.806714 -348.613069) (xy 370.806714 -348.558531)
			(xy 370.814476 -348.504548) (xy 370.82984 -348.452218) (xy 370.852496 -348.402608) (xy 370.881981 -348.356727)
			(xy 370.917695 -348.315509) (xy 370.958911 -348.279793) (xy 371.004791 -348.250305) (xy 371.054399 -348.227647)
			(xy 371.106728 -348.21228) (xy 371.160711 -348.204516) (xy 371.18798 -348.204028) (xy 372.05158 -348.204028)
			(xy 372.078851 -348.20451) (xy 372.132839 -348.21227) (xy 372.185173 -348.227634) (xy 372.234787 -348.25029)
			(xy 372.280672 -348.279776) (xy 372.321893 -348.315493) (xy 372.357612 -348.356712) (xy 372.387101 -348.402595)
			(xy 372.409759 -348.452209) (xy 372.425126 -348.504542) (xy 372.432888 -348.558529) (xy 372.432888 -348.613071)
			(xy 372.432888 -348.613074) (xy 373.915592 -348.613074) (xy 373.915592 -348.558526) (xy 373.923355 -348.504535)
			(xy 373.938724 -348.452197) (xy 373.961385 -348.40258) (xy 373.990877 -348.356694) (xy 374.0266 -348.315471)
			(xy 374.067826 -348.279753) (xy 374.113715 -348.250266) (xy 374.163335 -348.22761) (xy 374.215674 -348.212246)
			(xy 374.269666 -348.204489) (xy 374.29694 -348.204028) (xy 375.16054 -348.204028) (xy 375.187807 -348.204537)
			(xy 375.241785 -348.212303) (xy 375.294108 -348.227672) (xy 375.343712 -348.25033) (xy 375.389587 -348.279816)
			(xy 375.430798 -348.31553) (xy 375.466508 -348.356746) (xy 375.49599 -348.402623) (xy 375.518642 -348.45223)
			(xy 375.534005 -348.504554) (xy 375.541766 -348.558533) (xy 375.541766 -348.613067) (xy 375.541766 -348.61307)
			(xy 377.024614 -348.61307) (xy 377.024614 -348.55853) (xy 377.032376 -348.504545) (xy 377.047742 -348.452214)
			(xy 377.070399 -348.402603) (xy 377.099886 -348.35672) (xy 377.135602 -348.315502) (xy 377.17682 -348.279786)
			(xy 377.222703 -348.250299) (xy 377.272314 -348.227642) (xy 377.324645 -348.212276) (xy 377.37863 -348.204514)
			(xy 377.4059 -348.204028) (xy 378.2695 -348.204028) (xy 378.296769 -348.204534) (xy 378.350751 -348.212296)
			(xy 378.403079 -348.227661) (xy 378.452688 -348.250316) (xy 378.498568 -348.279802) (xy 378.539784 -348.315516)
			(xy 378.575498 -348.356732) (xy 378.604984 -348.402612) (xy 378.627639 -348.452221) (xy 378.643004 -348.504549)
			(xy 378.650766 -348.558531) (xy 378.650766 -348.613068) (xy 380.133614 -348.613068) (xy 380.133614 -348.558532)
			(xy 380.141375 -348.50455) (xy 380.156739 -348.452223) (xy 380.179393 -348.402614) (xy 380.208876 -348.356734)
			(xy 380.244588 -348.315516) (xy 380.285801 -348.2798) (xy 380.331679 -348.250312) (xy 380.381285 -348.227653)
			(xy 380.433611 -348.212284) (xy 380.487592 -348.204517) (xy 380.51486 -348.204028) (xy 381.37846 -348.204028)
			(xy 381.405732 -348.204509) (xy 381.459722 -348.212266) (xy 381.512058 -348.227628) (xy 381.561675 -348.250283)
			(xy 381.607562 -348.279769) (xy 381.648786 -348.315485) (xy 381.684507 -348.356706) (xy 381.713998 -348.40259)
			(xy 381.736658 -348.452204) (xy 381.752025 -348.504539) (xy 381.759788 -348.558528) (xy 381.759788 -348.613072)
			(xy 381.759788 -348.613073) (xy 383.242492 -348.613073) (xy 383.242492 -348.558527) (xy 383.250254 -348.504537)
			(xy 383.265622 -348.452202) (xy 383.288282 -348.402586) (xy 383.317772 -348.3567) (xy 383.353493 -348.315478)
			(xy 383.394716 -348.27976) (xy 383.440603 -348.250272) (xy 383.49022 -348.227615) (xy 383.542557 -348.21225)
			(xy 383.596547 -348.20449) (xy 383.62382 -348.204028) (xy 384.48742 -348.204028) (xy 384.514688 -348.204536)
			(xy 384.568668 -348.2123) (xy 384.620994 -348.227666) (xy 384.6706 -348.250323) (xy 384.716477 -348.279809)
			(xy 384.757691 -348.315523) (xy 384.793403 -348.356739) (xy 384.822887 -348.402618) (xy 384.845541 -348.452225)
			(xy 384.860905 -348.504552) (xy 384.868666 -348.558532) (xy 384.868666 -348.613068) (xy 384.868666 -348.613069)
			(xy 386.351514 -348.613069) (xy 386.351514 -348.558531) (xy 386.359276 -348.504548) (xy 386.37464 -348.452218)
			(xy 386.397296 -348.402608) (xy 386.426781 -348.356727) (xy 386.462495 -348.315509) (xy 386.503711 -348.279793)
			(xy 386.549591 -348.250305) (xy 386.599199 -348.227647) (xy 386.651528 -348.21228) (xy 386.705511 -348.204516)
			(xy 386.73278 -348.204028) (xy 387.59638 -348.204028) (xy 387.623651 -348.20451) (xy 387.677639 -348.21227)
			(xy 387.729973 -348.227634) (xy 387.779587 -348.25029) (xy 387.825472 -348.279776) (xy 387.866693 -348.315493)
			(xy 387.902412 -348.356712) (xy 387.931901 -348.402595) (xy 387.954559 -348.452209) (xy 387.969926 -348.504542)
			(xy 387.977688 -348.558529) (xy 387.977688 -348.613071) (xy 387.977688 -348.613074) (xy 389.460392 -348.613074)
			(xy 389.460392 -348.558526) (xy 389.468155 -348.504535) (xy 389.483524 -348.452197) (xy 389.506185 -348.40258)
			(xy 389.535677 -348.356694) (xy 389.5714 -348.315471) (xy 389.612626 -348.279753) (xy 389.658515 -348.250266)
			(xy 389.708135 -348.22761) (xy 389.760474 -348.212246) (xy 389.814466 -348.204489) (xy 389.84174 -348.204028)
			(xy 390.70534 -348.204028) (xy 390.732607 -348.204537) (xy 390.786585 -348.212303) (xy 390.838908 -348.227672)
			(xy 390.888512 -348.25033) (xy 390.934387 -348.279816) (xy 390.975598 -348.31553) (xy 391.011308 -348.356746)
			(xy 391.04079 -348.402623) (xy 391.063442 -348.45223) (xy 391.078805 -348.504554) (xy 391.086566 -348.558533)
			(xy 391.086566 -348.613067) (xy 391.086566 -348.61307) (xy 392.569414 -348.61307) (xy 392.569414 -348.55853)
			(xy 392.577176 -348.504545) (xy 392.592542 -348.452214) (xy 392.615199 -348.402603) (xy 392.644686 -348.35672)
			(xy 392.680402 -348.315502) (xy 392.72162 -348.279786) (xy 392.767503 -348.250299) (xy 392.817114 -348.227642)
			(xy 392.869445 -348.212276) (xy 392.92343 -348.204514) (xy 392.9507 -348.204028) (xy 393.8143 -348.204028)
			(xy 393.841569 -348.204534) (xy 393.895551 -348.212296) (xy 393.947879 -348.227661) (xy 393.997488 -348.250316)
			(xy 394.043368 -348.279802) (xy 394.084584 -348.315516) (xy 394.120298 -348.356732) (xy 394.149784 -348.402612)
			(xy 394.172439 -348.452221) (xy 394.187804 -348.504549) (xy 394.195566 -348.558531) (xy 394.195566 -348.613068)
			(xy 395.678414 -348.613068) (xy 395.678414 -348.558532) (xy 395.686175 -348.50455) (xy 395.701539 -348.452223)
			(xy 395.724193 -348.402614) (xy 395.753676 -348.356734) (xy 395.789388 -348.315516) (xy 395.830601 -348.2798)
			(xy 395.876479 -348.250312) (xy 395.926085 -348.227653) (xy 395.978411 -348.212284) (xy 396.032392 -348.204517)
			(xy 396.05966 -348.204028) (xy 396.92326 -348.204028) (xy 396.950532 -348.204509) (xy 397.004522 -348.212266)
			(xy 397.056858 -348.227628) (xy 397.106475 -348.250283) (xy 397.152362 -348.279769) (xy 397.193586 -348.315485)
			(xy 397.229307 -348.356706) (xy 397.258798 -348.40259) (xy 397.281458 -348.452204) (xy 397.296825 -348.504539)
			(xy 397.304588 -348.558528) (xy 397.304588 -348.613072) (xy 397.304588 -348.613073) (xy 398.787292 -348.613073)
			(xy 398.787292 -348.558527) (xy 398.795054 -348.504537) (xy 398.810422 -348.452202) (xy 398.833082 -348.402586)
			(xy 398.862572 -348.3567) (xy 398.898293 -348.315478) (xy 398.939516 -348.27976) (xy 398.985403 -348.250272)
			(xy 399.03502 -348.227615) (xy 399.087357 -348.21225) (xy 399.141347 -348.20449) (xy 399.16862 -348.204028)
			(xy 400.03222 -348.204028) (xy 400.059488 -348.204536) (xy 400.113468 -348.2123) (xy 400.165794 -348.227666)
			(xy 400.2154 -348.250323) (xy 400.261277 -348.279809) (xy 400.302491 -348.315523) (xy 400.338203 -348.356739)
			(xy 400.367687 -348.402618) (xy 400.390341 -348.452225) (xy 400.405705 -348.504552) (xy 400.413466 -348.558532)
			(xy 400.413466 -348.613068) (xy 400.413466 -348.613069) (xy 401.896314 -348.613069) (xy 401.896314 -348.558531)
			(xy 401.904076 -348.504548) (xy 401.91944 -348.452218) (xy 401.942096 -348.402608) (xy 401.971581 -348.356727)
			(xy 402.007295 -348.315509) (xy 402.048511 -348.279793) (xy 402.094391 -348.250305) (xy 402.143999 -348.227647)
			(xy 402.196328 -348.21228) (xy 402.250311 -348.204516) (xy 402.27758 -348.204028) (xy 403.14118 -348.204028)
			(xy 403.168451 -348.20451) (xy 403.222439 -348.21227) (xy 403.274773 -348.227634) (xy 403.324387 -348.25029)
			(xy 403.370272 -348.279776) (xy 403.411493 -348.315493) (xy 403.447212 -348.356712) (xy 403.476701 -348.402595)
			(xy 403.499359 -348.452209) (xy 403.514726 -348.504542) (xy 403.522488 -348.558529) (xy 403.522488 -348.61307)
			(xy 408.913814 -348.61307) (xy 408.913814 -348.55853) (xy 408.921576 -348.504546) (xy 408.936941 -348.452216)
			(xy 408.959598 -348.402605) (xy 408.989084 -348.356723) (xy 409.024799 -348.315505) (xy 409.066017 -348.279788)
			(xy 409.111898 -348.250301) (xy 409.161508 -348.227644) (xy 409.213838 -348.212278) (xy 409.267822 -348.204515)
			(xy 409.295092 -348.204028) (xy 410.158692 -348.204028) (xy 410.185963 -348.204511) (xy 410.239949 -348.212272)
			(xy 410.292281 -348.227637) (xy 410.341894 -348.250294) (xy 410.387778 -348.27978) (xy 410.428998 -348.315497)
			(xy 410.464715 -348.356716) (xy 410.494203 -348.402599) (xy 410.51686 -348.452211) (xy 410.532226 -348.504543)
			(xy 410.539989 -348.558529) (xy 410.539989 -348.613068) (xy 412.022814 -348.613068) (xy 412.022814 -348.558532)
			(xy 412.030575 -348.504551) (xy 412.045938 -348.452224) (xy 412.068592 -348.402616) (xy 412.098074 -348.356736)
			(xy 412.133785 -348.315519) (xy 412.174998 -348.279803) (xy 412.220874 -348.250315) (xy 412.270479 -348.227655)
			(xy 412.322804 -348.212285) (xy 412.376784 -348.204518) (xy 412.404052 -348.204028) (xy 413.267652 -348.204028)
			(xy 413.294925 -348.204508) (xy 413.348915 -348.212265) (xy 413.401252 -348.227626) (xy 413.45087 -348.250281)
			(xy 413.496759 -348.279766) (xy 413.537983 -348.315483) (xy 413.573705 -348.356703) (xy 413.603196 -348.402588)
			(xy 413.625857 -348.452203) (xy 413.641225 -348.504538) (xy 413.648988 -348.558528) (xy 413.648988 -348.613072)
			(xy 415.131692 -348.613072) (xy 415.131692 -348.558528) (xy 415.139454 -348.504538) (xy 415.154821 -348.452203)
			(xy 415.177481 -348.402588) (xy 415.20697 -348.356703) (xy 415.24269 -348.315481) (xy 415.283912 -348.279763)
			(xy 415.329799 -348.250275) (xy 415.379415 -348.227617) (xy 415.43175 -348.212252) (xy 415.48574 -348.204491)
			(xy 415.513012 -348.204028) (xy 416.376612 -348.204028) (xy 416.40388 -348.204535) (xy 416.457861 -348.212298)
			(xy 416.510188 -348.227664) (xy 416.559795 -348.25032) (xy 416.605673 -348.279806) (xy 416.646888 -348.31552)
			(xy 416.682601 -348.356736) (xy 416.712085 -348.402615) (xy 416.73474 -348.452224) (xy 416.750104 -348.504551)
			(xy 416.757866 -348.558532) (xy 416.757866 -348.613068) (xy 416.757866 -348.613069) (xy 418.240714 -348.613069)
			(xy 418.240714 -348.558531) (xy 418.248476 -348.504549) (xy 418.26384 -348.45222) (xy 418.286495 -348.40261)
			(xy 418.315979 -348.35673) (xy 418.351692 -348.315512) (xy 418.392907 -348.279795) (xy 418.438786 -348.250308)
			(xy 418.488394 -348.22765) (xy 418.540721 -348.212281) (xy 418.594703 -348.204516) (xy 418.621972 -348.204028)
			(xy 419.485572 -348.204028) (xy 419.512844 -348.20451) (xy 419.566832 -348.212268) (xy 419.619167 -348.227632)
			(xy 419.668782 -348.250287) (xy 419.714668 -348.279773) (xy 419.75589 -348.31549) (xy 419.79161 -348.356709)
			(xy 419.821099 -348.402593) (xy 419.843759 -348.452207) (xy 419.859126 -348.504541) (xy 419.866888 -348.558528)
			(xy 419.866888 -348.613072) (xy 419.866888 -348.613073) (xy 421.349592 -348.613073) (xy 421.349592 -348.558527)
			(xy 421.357355 -348.504536) (xy 421.372723 -348.452199) (xy 421.395384 -348.402583) (xy 421.424875 -348.356696)
			(xy 421.460597 -348.315474) (xy 421.501822 -348.279756) (xy 421.547711 -348.250268) (xy 421.597329 -348.227612)
			(xy 421.649667 -348.212248) (xy 421.703659 -348.204489) (xy 421.730932 -348.204028) (xy 422.594532 -348.204028)
			(xy 422.621799 -348.204537) (xy 422.675778 -348.212302) (xy 422.728102 -348.227669) (xy 422.777707 -348.250327)
			(xy 422.823583 -348.279813) (xy 422.864795 -348.315527) (xy 422.900506 -348.356743) (xy 422.929988 -348.402621)
			(xy 422.952642 -348.452228) (xy 422.968005 -348.504553) (xy 422.975766 -348.558533) (xy 422.975766 -348.613067)
			(xy 422.975766 -348.61307) (xy 424.458614 -348.61307) (xy 424.458614 -348.55853) (xy 424.466376 -348.504546)
			(xy 424.481741 -348.452216) (xy 424.504398 -348.402605) (xy 424.533884 -348.356723) (xy 424.569599 -348.315505)
			(xy 424.610817 -348.279788) (xy 424.656698 -348.250301) (xy 424.706308 -348.227644) (xy 424.758638 -348.212278)
			(xy 424.812622 -348.204515) (xy 424.839892 -348.204028) (xy 425.703492 -348.204028) (xy 425.730763 -348.204511)
			(xy 425.784749 -348.212272) (xy 425.837081 -348.227637) (xy 425.886694 -348.250294) (xy 425.932578 -348.27978)
			(xy 425.973798 -348.315497) (xy 426.009515 -348.356716) (xy 426.039003 -348.402599) (xy 426.06166 -348.452211)
			(xy 426.077026 -348.504543) (xy 426.084789 -348.558529) (xy 426.084789 -348.613068) (xy 427.567614 -348.613068)
			(xy 427.567614 -348.558532) (xy 427.575375 -348.504551) (xy 427.590738 -348.452224) (xy 427.613392 -348.402616)
			(xy 427.642874 -348.356736) (xy 427.678585 -348.315519) (xy 427.719798 -348.279803) (xy 427.765674 -348.250315)
			(xy 427.815279 -348.227655) (xy 427.867604 -348.212285) (xy 427.921584 -348.204518) (xy 427.948852 -348.204028)
			(xy 428.812452 -348.204028) (xy 428.839725 -348.204508) (xy 428.893715 -348.212265) (xy 428.946052 -348.227626)
			(xy 428.99567 -348.250281) (xy 429.041559 -348.279766) (xy 429.082783 -348.315483) (xy 429.118505 -348.356703)
			(xy 429.147996 -348.402588) (xy 429.170657 -348.452203) (xy 429.186025 -348.504538) (xy 429.193788 -348.558528)
			(xy 429.193788 -348.613072) (xy 430.676492 -348.613072) (xy 430.676492 -348.558528) (xy 430.684254 -348.504538)
			(xy 430.699621 -348.452203) (xy 430.722281 -348.402588) (xy 430.75177 -348.356703) (xy 430.78749 -348.315481)
			(xy 430.828712 -348.279763) (xy 430.874599 -348.250275) (xy 430.924215 -348.227617) (xy 430.97655 -348.212252)
			(xy 431.03054 -348.204491) (xy 431.057812 -348.204028) (xy 431.921412 -348.204028) (xy 431.94868 -348.204535)
			(xy 432.002661 -348.212298) (xy 432.054988 -348.227664) (xy 432.104595 -348.25032) (xy 432.150473 -348.279806)
			(xy 432.191688 -348.31552) (xy 432.227401 -348.356736) (xy 432.256885 -348.402615) (xy 432.27954 -348.452224)
			(xy 432.294904 -348.504551) (xy 432.302666 -348.558532) (xy 432.302666 -348.613068) (xy 432.302666 -348.613069)
			(xy 433.785514 -348.613069) (xy 433.785514 -348.558531) (xy 433.793276 -348.504549) (xy 433.80864 -348.45222)
			(xy 433.831295 -348.40261) (xy 433.860779 -348.35673) (xy 433.896492 -348.315512) (xy 433.937707 -348.279795)
			(xy 433.983586 -348.250308) (xy 434.033194 -348.22765) (xy 434.085521 -348.212281) (xy 434.139503 -348.204516)
			(xy 434.166772 -348.204028) (xy 435.030372 -348.204028) (xy 435.057644 -348.20451) (xy 435.111632 -348.212268)
			(xy 435.163967 -348.227632) (xy 435.213582 -348.250287) (xy 435.259468 -348.279773) (xy 435.30069 -348.31549)
			(xy 435.33641 -348.356709) (xy 435.365899 -348.402593) (xy 435.388559 -348.452207) (xy 435.403926 -348.504541)
			(xy 435.411688 -348.558528) (xy 435.411688 -348.613072) (xy 435.411688 -348.613073) (xy 436.894392 -348.613073)
			(xy 436.894392 -348.558527) (xy 436.902155 -348.504536) (xy 436.917523 -348.452199) (xy 436.940184 -348.402583)
			(xy 436.969675 -348.356696) (xy 437.005397 -348.315474) (xy 437.046622 -348.279756) (xy 437.092511 -348.250268)
			(xy 437.142129 -348.227612) (xy 437.194467 -348.212248) (xy 437.248459 -348.204489) (xy 437.275732 -348.204028)
			(xy 438.139332 -348.204028) (xy 438.166599 -348.204537) (xy 438.220578 -348.212302) (xy 438.272902 -348.227669)
			(xy 438.322507 -348.250327) (xy 438.368383 -348.279813) (xy 438.409595 -348.315527) (xy 438.445306 -348.356743)
			(xy 438.474788 -348.402621) (xy 438.497442 -348.452228) (xy 438.512805 -348.504553) (xy 438.520566 -348.558533)
			(xy 438.520566 -348.613067) (xy 438.520566 -348.61307) (xy 440.003414 -348.61307) (xy 440.003414 -348.55853)
			(xy 440.011176 -348.504546) (xy 440.026541 -348.452216) (xy 440.049198 -348.402605) (xy 440.078684 -348.356723)
			(xy 440.114399 -348.315505) (xy 440.155617 -348.279788) (xy 440.201498 -348.250301) (xy 440.251108 -348.227644)
			(xy 440.303438 -348.212278) (xy 440.357422 -348.204515) (xy 440.384692 -348.204028) (xy 441.248292 -348.204028)
			(xy 441.275563 -348.204511) (xy 441.329549 -348.212272) (xy 441.381881 -348.227637) (xy 441.431494 -348.250294)
			(xy 441.477378 -348.27978) (xy 441.518598 -348.315497) (xy 441.554315 -348.356716) (xy 441.583803 -348.402599)
			(xy 441.60646 -348.452211) (xy 441.621826 -348.504543) (xy 441.629589 -348.558529) (xy 441.629589 -348.613071)
			(xy 441.621826 -348.667057) (xy 441.60646 -348.719389) (xy 441.583803 -348.769001) (xy 441.554315 -348.814884)
			(xy 441.518598 -348.856103) (xy 441.477378 -348.89182) (xy 441.431494 -348.921306) (xy 441.381881 -348.943963)
			(xy 441.329549 -348.959328) (xy 441.275563 -348.967089) (xy 441.248292 -348.967552) (xy 440.384692 -348.967552)
			(xy 440.357422 -348.967085) (xy 440.303438 -348.959322) (xy 440.251108 -348.943956) (xy 440.201498 -348.921299)
			(xy 440.155617 -348.891812) (xy 440.114399 -348.856095) (xy 440.078684 -348.814877) (xy 440.049198 -348.768995)
			(xy 440.026541 -348.719384) (xy 440.011176 -348.667054) (xy 440.003414 -348.61307) (xy 438.520566 -348.61307)
			(xy 438.512805 -348.667047) (xy 438.497442 -348.719372) (xy 438.474788 -348.768979) (xy 438.445306 -348.814857)
			(xy 438.409595 -348.856073) (xy 438.368383 -348.891787) (xy 438.322507 -348.921273) (xy 438.272902 -348.943931)
			(xy 438.220578 -348.959298) (xy 438.166599 -348.967063) (xy 438.139332 -348.967552) (xy 437.275732 -348.967552)
			(xy 437.248459 -348.967111) (xy 437.194467 -348.959352) (xy 437.142129 -348.943988) (xy 437.092511 -348.921332)
			(xy 437.046622 -348.891844) (xy 437.005397 -348.856126) (xy 436.969675 -348.814904) (xy 436.940184 -348.769017)
			(xy 436.917523 -348.719401) (xy 436.902155 -348.667064) (xy 436.894392 -348.613073) (xy 435.411688 -348.613073)
			(xy 435.403926 -348.667059) (xy 435.388559 -348.719393) (xy 435.365899 -348.769007) (xy 435.33641 -348.814891)
			(xy 435.30069 -348.85611) (xy 435.259468 -348.891827) (xy 435.213582 -348.921313) (xy 435.163967 -348.943968)
			(xy 435.111632 -348.959332) (xy 435.057644 -348.96709) (xy 435.030372 -348.967552) (xy 434.166772 -348.967552)
			(xy 434.139503 -348.967084) (xy 434.085521 -348.959319) (xy 434.033194 -348.94395) (xy 433.983586 -348.921292)
			(xy 433.937707 -348.891805) (xy 433.896492 -348.856088) (xy 433.860779 -348.81487) (xy 433.831295 -348.76899)
			(xy 433.80864 -348.71938) (xy 433.793276 -348.667051) (xy 433.785514 -348.613069) (xy 432.302666 -348.613069)
			(xy 432.294904 -348.667049) (xy 432.27954 -348.719376) (xy 432.256885 -348.768985) (xy 432.227401 -348.814864)
			(xy 432.191688 -348.85608) (xy 432.150473 -348.891794) (xy 432.104595 -348.92128) (xy 432.054988 -348.943936)
			(xy 432.002661 -348.959302) (xy 431.94868 -348.967065) (xy 431.921412 -348.967552) (xy 431.057812 -348.967552)
			(xy 431.03054 -348.967109) (xy 430.97655 -348.959348) (xy 430.924215 -348.943983) (xy 430.874599 -348.921325)
			(xy 430.828712 -348.891837) (xy 430.78749 -348.856119) (xy 430.75177 -348.814897) (xy 430.722281 -348.769012)
			(xy 430.699621 -348.719397) (xy 430.684254 -348.667062) (xy 430.676492 -348.613072) (xy 429.193788 -348.613072)
			(xy 429.186025 -348.667062) (xy 429.170657 -348.719397) (xy 429.147996 -348.769012) (xy 429.118505 -348.814897)
			(xy 429.082783 -348.856117) (xy 429.041559 -348.891834) (xy 428.99567 -348.921319) (xy 428.946052 -348.943974)
			(xy 428.893715 -348.959335) (xy 428.839725 -348.967092) (xy 428.812452 -348.967552) (xy 427.948852 -348.967552)
			(xy 427.921584 -348.967082) (xy 427.867604 -348.959315) (xy 427.815279 -348.943945) (xy 427.765674 -348.921285)
			(xy 427.719798 -348.891797) (xy 427.678585 -348.856081) (xy 427.642874 -348.814864) (xy 427.613392 -348.768984)
			(xy 427.590738 -348.719376) (xy 427.575375 -348.667049) (xy 427.567614 -348.613068) (xy 426.084789 -348.613068)
			(xy 426.084789 -348.613071) (xy 426.077026 -348.667057) (xy 426.06166 -348.719389) (xy 426.039003 -348.769001)
			(xy 426.009515 -348.814884) (xy 425.973798 -348.856103) (xy 425.932578 -348.89182) (xy 425.886694 -348.921306)
			(xy 425.837081 -348.943963) (xy 425.784749 -348.959328) (xy 425.730763 -348.967089) (xy 425.703492 -348.967552)
			(xy 424.839892 -348.967552) (xy 424.812622 -348.967085) (xy 424.758638 -348.959322) (xy 424.706308 -348.943956)
			(xy 424.656698 -348.921299) (xy 424.610817 -348.891812) (xy 424.569599 -348.856095) (xy 424.533884 -348.814877)
			(xy 424.504398 -348.768995) (xy 424.481741 -348.719384) (xy 424.466376 -348.667054) (xy 424.458614 -348.61307)
			(xy 422.975766 -348.61307) (xy 422.968005 -348.667047) (xy 422.952642 -348.719372) (xy 422.929988 -348.768979)
			(xy 422.900506 -348.814857) (xy 422.864795 -348.856073) (xy 422.823583 -348.891787) (xy 422.777707 -348.921273)
			(xy 422.728102 -348.943931) (xy 422.675778 -348.959298) (xy 422.621799 -348.967063) (xy 422.594532 -348.967552)
			(xy 421.730932 -348.967552) (xy 421.703659 -348.967111) (xy 421.649667 -348.959352) (xy 421.597329 -348.943988)
			(xy 421.547711 -348.921332) (xy 421.501822 -348.891844) (xy 421.460597 -348.856126) (xy 421.424875 -348.814904)
			(xy 421.395384 -348.769017) (xy 421.372723 -348.719401) (xy 421.357355 -348.667064) (xy 421.349592 -348.613073)
			(xy 419.866888 -348.613073) (xy 419.859126 -348.667059) (xy 419.843759 -348.719393) (xy 419.821099 -348.769007)
			(xy 419.79161 -348.814891) (xy 419.75589 -348.85611) (xy 419.714668 -348.891827) (xy 419.668782 -348.921313)
			(xy 419.619167 -348.943968) (xy 419.566832 -348.959332) (xy 419.512844 -348.96709) (xy 419.485572 -348.967552)
			(xy 418.621972 -348.967552) (xy 418.594703 -348.967084) (xy 418.540721 -348.959319) (xy 418.488394 -348.94395)
			(xy 418.438786 -348.921292) (xy 418.392907 -348.891805) (xy 418.351692 -348.856088) (xy 418.315979 -348.81487)
			(xy 418.286495 -348.76899) (xy 418.26384 -348.71938) (xy 418.248476 -348.667051) (xy 418.240714 -348.613069)
			(xy 416.757866 -348.613069) (xy 416.750104 -348.667049) (xy 416.73474 -348.719376) (xy 416.712085 -348.768985)
			(xy 416.682601 -348.814864) (xy 416.646888 -348.85608) (xy 416.605673 -348.891794) (xy 416.559795 -348.92128)
			(xy 416.510188 -348.943936) (xy 416.457861 -348.959302) (xy 416.40388 -348.967065) (xy 416.376612 -348.967552)
			(xy 415.513012 -348.967552) (xy 415.48574 -348.967109) (xy 415.43175 -348.959348) (xy 415.379415 -348.943983)
			(xy 415.329799 -348.921325) (xy 415.283912 -348.891837) (xy 415.24269 -348.856119) (xy 415.20697 -348.814897)
			(xy 415.177481 -348.769012) (xy 415.154821 -348.719397) (xy 415.139454 -348.667062) (xy 415.131692 -348.613072)
			(xy 413.648988 -348.613072) (xy 413.641225 -348.667062) (xy 413.625857 -348.719397) (xy 413.603196 -348.769012)
			(xy 413.573705 -348.814897) (xy 413.537983 -348.856117) (xy 413.496759 -348.891834) (xy 413.45087 -348.921319)
			(xy 413.401252 -348.943974) (xy 413.348915 -348.959335) (xy 413.294925 -348.967092) (xy 413.267652 -348.967552)
			(xy 412.404052 -348.967552) (xy 412.376784 -348.967082) (xy 412.322804 -348.959315) (xy 412.270479 -348.943945)
			(xy 412.220874 -348.921285) (xy 412.174998 -348.891797) (xy 412.133785 -348.856081) (xy 412.098074 -348.814864)
			(xy 412.068592 -348.768984) (xy 412.045938 -348.719376) (xy 412.030575 -348.667049) (xy 412.022814 -348.613068)
			(xy 410.539989 -348.613068) (xy 410.539989 -348.613071) (xy 410.532226 -348.667057) (xy 410.51686 -348.719389)
			(xy 410.494203 -348.769001) (xy 410.464715 -348.814884) (xy 410.428998 -348.856103) (xy 410.387778 -348.89182)
			(xy 410.341894 -348.921306) (xy 410.292281 -348.943963) (xy 410.239949 -348.959328) (xy 410.185963 -348.967089)
			(xy 410.158692 -348.967552) (xy 409.295092 -348.967552) (xy 409.267822 -348.967085) (xy 409.213838 -348.959322)
			(xy 409.161508 -348.943956) (xy 409.111898 -348.921299) (xy 409.066017 -348.891812) (xy 409.024799 -348.856095)
			(xy 408.989084 -348.814877) (xy 408.959598 -348.768995) (xy 408.936941 -348.719384) (xy 408.921576 -348.667054)
			(xy 408.913814 -348.61307) (xy 403.522488 -348.61307) (xy 403.522488 -348.613071) (xy 403.514726 -348.667058)
			(xy 403.499359 -348.719391) (xy 403.476701 -348.769005) (xy 403.447212 -348.814888) (xy 403.411493 -348.856107)
			(xy 403.370272 -348.891824) (xy 403.324387 -348.92131) (xy 403.274773 -348.943966) (xy 403.222439 -348.95933)
			(xy 403.168451 -348.96709) (xy 403.14118 -348.967552) (xy 402.27758 -348.967552) (xy 402.250311 -348.967084)
			(xy 402.196328 -348.95932) (xy 402.143999 -348.943953) (xy 402.094391 -348.921295) (xy 402.048511 -348.891807)
			(xy 402.007295 -348.856091) (xy 401.971581 -348.814873) (xy 401.942096 -348.768992) (xy 401.91944 -348.719382)
			(xy 401.904076 -348.667052) (xy 401.896314 -348.613069) (xy 400.413466 -348.613069) (xy 400.405705 -348.667048)
			(xy 400.390341 -348.719375) (xy 400.367687 -348.768982) (xy 400.338203 -348.814861) (xy 400.302491 -348.856077)
			(xy 400.261277 -348.891791) (xy 400.2154 -348.921277) (xy 400.165794 -348.943934) (xy 400.113468 -348.9593)
			(xy 400.059488 -348.967064) (xy 400.03222 -348.967552) (xy 399.16862 -348.967552) (xy 399.141347 -348.96711)
			(xy 399.087357 -348.95935) (xy 399.03502 -348.943985) (xy 398.985403 -348.921328) (xy 398.939516 -348.89184)
			(xy 398.898293 -348.856122) (xy 398.862572 -348.8149) (xy 398.833082 -348.769014) (xy 398.810422 -348.719398)
			(xy 398.795054 -348.667063) (xy 398.787292 -348.613073) (xy 397.304588 -348.613073) (xy 397.296825 -348.667061)
			(xy 397.281458 -348.719396) (xy 397.258798 -348.76901) (xy 397.229307 -348.814894) (xy 397.193586 -348.856115)
			(xy 397.152362 -348.891831) (xy 397.106475 -348.921317) (xy 397.056858 -348.943972) (xy 397.004522 -348.959334)
			(xy 396.950532 -348.967091) (xy 396.92326 -348.967552) (xy 396.05966 -348.967552) (xy 396.032392 -348.967083)
			(xy 395.978411 -348.959316) (xy 395.926085 -348.943947) (xy 395.876479 -348.921288) (xy 395.830601 -348.8918)
			(xy 395.789388 -348.856084) (xy 395.753676 -348.814866) (xy 395.724193 -348.768986) (xy 395.701539 -348.719377)
			(xy 395.686175 -348.66705) (xy 395.678414 -348.613068) (xy 394.195566 -348.613068) (xy 394.195566 -348.613069)
			(xy 394.187804 -348.667051) (xy 394.172439 -348.719379) (xy 394.149784 -348.768988) (xy 394.120298 -348.814868)
			(xy 394.084584 -348.856084) (xy 394.043368 -348.891798) (xy 393.997488 -348.921284) (xy 393.947879 -348.943939)
			(xy 393.895551 -348.959304) (xy 393.841569 -348.967066) (xy 393.8143 -348.967552) (xy 392.9507 -348.967552)
			(xy 392.92343 -348.967086) (xy 392.869445 -348.959324) (xy 392.817114 -348.943958) (xy 392.767503 -348.921301)
			(xy 392.72162 -348.891814) (xy 392.680402 -348.856098) (xy 392.644686 -348.81488) (xy 392.615199 -348.768997)
			(xy 392.592542 -348.719386) (xy 392.577176 -348.667055) (xy 392.569414 -348.61307) (xy 391.086566 -348.61307)
			(xy 391.078805 -348.667046) (xy 391.063442 -348.71937) (xy 391.04079 -348.768977) (xy 391.011308 -348.814854)
			(xy 390.975598 -348.85607) (xy 390.934387 -348.891784) (xy 390.888512 -348.92127) (xy 390.838908 -348.943928)
			(xy 390.786585 -348.959297) (xy 390.732607 -348.967063) (xy 390.70534 -348.967552) (xy 389.84174 -348.967552)
			(xy 389.814466 -348.967111) (xy 389.760474 -348.959354) (xy 389.708135 -348.94399) (xy 389.658515 -348.921334)
			(xy 389.612626 -348.891847) (xy 389.5714 -348.856129) (xy 389.535677 -348.814906) (xy 389.506185 -348.76902)
			(xy 389.483524 -348.719403) (xy 389.468155 -348.667065) (xy 389.460392 -348.613074) (xy 387.977688 -348.613074)
			(xy 387.969926 -348.667058) (xy 387.954559 -348.719391) (xy 387.931901 -348.769005) (xy 387.902412 -348.814888)
			(xy 387.866693 -348.856107) (xy 387.825472 -348.891824) (xy 387.779587 -348.92131) (xy 387.729973 -348.943966)
			(xy 387.677639 -348.95933) (xy 387.623651 -348.96709) (xy 387.59638 -348.967552) (xy 386.73278 -348.967552)
			(xy 386.705511 -348.967084) (xy 386.651528 -348.95932) (xy 386.599199 -348.943953) (xy 386.549591 -348.921295)
			(xy 386.503711 -348.891807) (xy 386.462495 -348.856091) (xy 386.426781 -348.814873) (xy 386.397296 -348.768992)
			(xy 386.37464 -348.719382) (xy 386.359276 -348.667052) (xy 386.351514 -348.613069) (xy 384.868666 -348.613069)
			(xy 384.860905 -348.667048) (xy 384.845541 -348.719375) (xy 384.822887 -348.768982) (xy 384.793403 -348.814861)
			(xy 384.757691 -348.856077) (xy 384.716477 -348.891791) (xy 384.6706 -348.921277) (xy 384.620994 -348.943934)
			(xy 384.568668 -348.9593) (xy 384.514688 -348.967064) (xy 384.48742 -348.967552) (xy 383.62382 -348.967552)
			(xy 383.596547 -348.96711) (xy 383.542557 -348.95935) (xy 383.49022 -348.943985) (xy 383.440603 -348.921328)
			(xy 383.394716 -348.89184) (xy 383.353493 -348.856122) (xy 383.317772 -348.8149) (xy 383.288282 -348.769014)
			(xy 383.265622 -348.719398) (xy 383.250254 -348.667063) (xy 383.242492 -348.613073) (xy 381.759788 -348.613073)
			(xy 381.752025 -348.667061) (xy 381.736658 -348.719396) (xy 381.713998 -348.76901) (xy 381.684507 -348.814894)
			(xy 381.648786 -348.856115) (xy 381.607562 -348.891831) (xy 381.561675 -348.921317) (xy 381.512058 -348.943972)
			(xy 381.459722 -348.959334) (xy 381.405732 -348.967091) (xy 381.37846 -348.967552) (xy 380.51486 -348.967552)
			(xy 380.487592 -348.967083) (xy 380.433611 -348.959316) (xy 380.381285 -348.943947) (xy 380.331679 -348.921288)
			(xy 380.285801 -348.8918) (xy 380.244588 -348.856084) (xy 380.208876 -348.814866) (xy 380.179393 -348.768986)
			(xy 380.156739 -348.719377) (xy 380.141375 -348.66705) (xy 380.133614 -348.613068) (xy 378.650766 -348.613068)
			(xy 378.650766 -348.613069) (xy 378.643004 -348.667051) (xy 378.627639 -348.719379) (xy 378.604984 -348.768988)
			(xy 378.575498 -348.814868) (xy 378.539784 -348.856084) (xy 378.498568 -348.891798) (xy 378.452688 -348.921284)
			(xy 378.403079 -348.943939) (xy 378.350751 -348.959304) (xy 378.296769 -348.967066) (xy 378.2695 -348.967552)
			(xy 377.4059 -348.967552) (xy 377.37863 -348.967086) (xy 377.324645 -348.959324) (xy 377.272314 -348.943958)
			(xy 377.222703 -348.921301) (xy 377.17682 -348.891814) (xy 377.135602 -348.856098) (xy 377.099886 -348.81488)
			(xy 377.070399 -348.768997) (xy 377.047742 -348.719386) (xy 377.032376 -348.667055) (xy 377.024614 -348.61307)
			(xy 375.541766 -348.61307) (xy 375.534005 -348.667046) (xy 375.518642 -348.71937) (xy 375.49599 -348.768977)
			(xy 375.466508 -348.814854) (xy 375.430798 -348.85607) (xy 375.389587 -348.891784) (xy 375.343712 -348.92127)
			(xy 375.294108 -348.943928) (xy 375.241785 -348.959297) (xy 375.187807 -348.967063) (xy 375.16054 -348.967552)
			(xy 374.29694 -348.967552) (xy 374.269666 -348.967111) (xy 374.215674 -348.959354) (xy 374.163335 -348.94399)
			(xy 374.113715 -348.921334) (xy 374.067826 -348.891847) (xy 374.0266 -348.856129) (xy 373.990877 -348.814906)
			(xy 373.961385 -348.76902) (xy 373.938724 -348.719403) (xy 373.923355 -348.667065) (xy 373.915592 -348.613074)
			(xy 372.432888 -348.613074) (xy 372.425126 -348.667058) (xy 372.409759 -348.719391) (xy 372.387101 -348.769005)
			(xy 372.357612 -348.814888) (xy 372.321893 -348.856107) (xy 372.280672 -348.891824) (xy 372.234787 -348.92131)
			(xy 372.185173 -348.943966) (xy 372.132839 -348.95933) (xy 372.078851 -348.96709) (xy 372.05158 -348.967552)
			(xy 371.18798 -348.967552) (xy 371.160711 -348.967084) (xy 371.106728 -348.95932) (xy 371.054399 -348.943953)
			(xy 371.004791 -348.921295) (xy 370.958911 -348.891807) (xy 370.917695 -348.856091) (xy 370.881981 -348.814873)
			(xy 370.852496 -348.768992) (xy 370.82984 -348.719382) (xy 370.814476 -348.667052) (xy 370.806714 -348.613069)
			(xy 344.837266 -348.613069) (xy 344.829504 -348.66705) (xy 344.81414 -348.719378) (xy 344.791484 -348.768987)
			(xy 344.761999 -348.814866) (xy 344.726286 -348.856083) (xy 344.685069 -348.891797) (xy 344.63919 -348.921282)
			(xy 344.589582 -348.943938) (xy 344.537254 -348.959303) (xy 344.483272 -348.967065) (xy 344.456004 -348.967552)
			(xy 343.592404 -348.967552) (xy 343.565132 -348.967109) (xy 343.511143 -348.959347) (xy 343.458809 -348.943981)
			(xy 343.409194 -348.921323) (xy 343.363309 -348.891834) (xy 343.322087 -348.856116) (xy 343.286368 -348.814895)
			(xy 343.256879 -348.76901) (xy 343.234221 -348.719395) (xy 343.218854 -348.667061) (xy 343.211092 -348.613072)
			(xy 341.728265 -348.613072) (xy 341.720505 -348.667045) (xy 341.705143 -348.71937) (xy 341.68249 -348.768976)
			(xy 341.653009 -348.814853) (xy 341.6173 -348.856069) (xy 341.576088 -348.891783) (xy 341.530214 -348.921269)
			(xy 341.480611 -348.943927) (xy 341.428288 -348.959296) (xy 341.374311 -348.967063) (xy 341.347044 -348.967552)
			(xy 340.483444 -348.967552) (xy 340.45617 -348.967111) (xy 340.402177 -348.959354) (xy 340.349838 -348.943991)
			(xy 340.300218 -348.921336) (xy 340.254327 -348.891849) (xy 340.213101 -348.85613) (xy 340.177378 -348.814908)
			(xy 340.147885 -348.769021) (xy 340.125224 -348.719403) (xy 340.109855 -348.667066) (xy 340.102092 -348.613074)
			(xy 338.619388 -348.613074) (xy 338.611626 -348.667058) (xy 338.596259 -348.71939) (xy 338.573601 -348.769003)
			(xy 338.544113 -348.814887) (xy 338.508395 -348.856106) (xy 338.467174 -348.891823) (xy 338.421289 -348.921309)
			(xy 338.371675 -348.943965) (xy 338.319342 -348.95933) (xy 338.265355 -348.96709) (xy 338.238084 -348.967552)
			(xy 337.374484 -348.967552) (xy 337.347215 -348.967084) (xy 337.293231 -348.959321) (xy 337.240902 -348.943954)
			(xy 337.191293 -348.921296) (xy 337.145413 -348.891809) (xy 337.104196 -348.856093) (xy 337.068482 -348.814874)
			(xy 337.038996 -348.768993) (xy 337.016341 -348.719383) (xy 337.000976 -348.667053) (xy 336.993214 -348.613069)
			(xy 335.510366 -348.613069) (xy 335.502605 -348.667048) (xy 335.487241 -348.719374) (xy 335.464587 -348.768981)
			(xy 335.435104 -348.81486) (xy 335.399393 -348.856076) (xy 335.358179 -348.89179) (xy 335.312302 -348.921276)
			(xy 335.262696 -348.943933) (xy 335.210371 -348.9593) (xy 335.156392 -348.967064) (xy 335.129124 -348.967552)
			(xy 334.265524 -348.967552) (xy 334.238251 -348.96711) (xy 334.18426 -348.959351) (xy 334.131923 -348.943986)
			(xy 334.082306 -348.921329) (xy 334.036418 -348.891841) (xy 333.995194 -348.856123) (xy 333.959473 -348.814901)
			(xy 333.929982 -348.769015) (xy 333.907322 -348.719399) (xy 333.891955 -348.667063) (xy 333.884192 -348.613073)
			(xy 332.401488 -348.613073) (xy 332.393726 -348.667061) (xy 332.378358 -348.719395) (xy 332.355698 -348.769009)
			(xy 332.326208 -348.814893) (xy 332.290488 -348.856113) (xy 332.249264 -348.89183) (xy 332.203377 -348.921316)
			(xy 332.153761 -348.94397) (xy 332.101425 -348.959333) (xy 332.047436 -348.967091) (xy 332.020164 -348.967552)
			(xy 331.156564 -348.967552) (xy 331.129296 -348.967083) (xy 331.075314 -348.959317) (xy 331.022988 -348.943948)
			(xy 330.973381 -348.921289) (xy 330.927503 -348.891802) (xy 330.886289 -348.856086) (xy 330.850577 -348.814868)
			(xy 330.821093 -348.768987) (xy 330.798439 -348.719378) (xy 330.783075 -348.66705) (xy 330.775314 -348.613068)
			(xy 329.292466 -348.613068) (xy 329.284704 -348.66705) (xy 329.26934 -348.719378) (xy 329.246684 -348.768987)
			(xy 329.217199 -348.814866) (xy 329.181486 -348.856083) (xy 329.140269 -348.891797) (xy 329.09439 -348.921282)
			(xy 329.044782 -348.943938) (xy 328.992454 -348.959303) (xy 328.938472 -348.967065) (xy 328.911204 -348.967552)
			(xy 328.047604 -348.967552) (xy 328.020332 -348.967109) (xy 327.966343 -348.959347) (xy 327.914009 -348.943981)
			(xy 327.864394 -348.921323) (xy 327.818509 -348.891834) (xy 327.777287 -348.856116) (xy 327.741568 -348.814895)
			(xy 327.712079 -348.76901) (xy 327.689421 -348.719395) (xy 327.674054 -348.667061) (xy 327.666292 -348.613072)
			(xy 326.183465 -348.613072) (xy 326.175705 -348.667045) (xy 326.160343 -348.71937) (xy 326.13769 -348.768976)
			(xy 326.108209 -348.814853) (xy 326.0725 -348.856069) (xy 326.031288 -348.891783) (xy 325.985414 -348.921269)
			(xy 325.935811 -348.943927) (xy 325.883488 -348.959296) (xy 325.829511 -348.967063) (xy 325.802244 -348.967552)
			(xy 324.938644 -348.967552) (xy 324.91137 -348.967111) (xy 324.857377 -348.959354) (xy 324.805038 -348.943991)
			(xy 324.755418 -348.921336) (xy 324.709527 -348.891849) (xy 324.668301 -348.85613) (xy 324.632578 -348.814908)
			(xy 324.603085 -348.769021) (xy 324.580424 -348.719403) (xy 324.565055 -348.667066) (xy 324.557292 -348.613074)
			(xy 323.074588 -348.613074) (xy 323.066826 -348.667058) (xy 323.051459 -348.71939) (xy 323.028801 -348.769003)
			(xy 322.999313 -348.814887) (xy 322.963595 -348.856106) (xy 322.922374 -348.891823) (xy 322.876489 -348.921309)
			(xy 322.826875 -348.943965) (xy 322.774542 -348.95933) (xy 322.720555 -348.96709) (xy 322.693284 -348.967552)
			(xy 321.829684 -348.967552) (xy 321.802415 -348.967084) (xy 321.748431 -348.959321) (xy 321.696102 -348.943954)
			(xy 321.646493 -348.921296) (xy 321.600613 -348.891809) (xy 321.559396 -348.856093) (xy 321.523682 -348.814874)
			(xy 321.494196 -348.768993) (xy 321.471541 -348.719383) (xy 321.456176 -348.667053) (xy 321.448414 -348.613069)
			(xy 319.965566 -348.613069) (xy 319.957805 -348.667048) (xy 319.942441 -348.719374) (xy 319.919787 -348.768981)
			(xy 319.890304 -348.81486) (xy 319.854593 -348.856076) (xy 319.813379 -348.89179) (xy 319.767502 -348.921276)
			(xy 319.717896 -348.943933) (xy 319.665571 -348.9593) (xy 319.611592 -348.967064) (xy 319.584324 -348.967552)
			(xy 318.720724 -348.967552) (xy 318.693451 -348.96711) (xy 318.63946 -348.959351) (xy 318.587123 -348.943986)
			(xy 318.537506 -348.921329) (xy 318.491618 -348.891841) (xy 318.450394 -348.856123) (xy 318.414673 -348.814901)
			(xy 318.385182 -348.769015) (xy 318.362522 -348.719399) (xy 318.347155 -348.667063) (xy 318.339392 -348.613073)
			(xy 316.856688 -348.613073) (xy 316.848926 -348.667061) (xy 316.833558 -348.719395) (xy 316.810898 -348.769009)
			(xy 316.781408 -348.814893) (xy 316.745688 -348.856113) (xy 316.704464 -348.89183) (xy 316.658577 -348.921316)
			(xy 316.608961 -348.94397) (xy 316.556625 -348.959333) (xy 316.502636 -348.967091) (xy 316.475364 -348.967552)
			(xy 315.611764 -348.967552) (xy 315.584496 -348.967083) (xy 315.530514 -348.959317) (xy 315.478188 -348.943948)
			(xy 315.428581 -348.921289) (xy 315.382703 -348.891802) (xy 315.341489 -348.856086) (xy 315.305777 -348.814868)
			(xy 315.276293 -348.768987) (xy 315.253639 -348.719378) (xy 315.238275 -348.66705) (xy 315.230514 -348.613068)
			(xy 313.747666 -348.613068) (xy 313.739904 -348.66705) (xy 313.72454 -348.719378) (xy 313.701884 -348.768987)
			(xy 313.672399 -348.814866) (xy 313.636686 -348.856083) (xy 313.595469 -348.891797) (xy 313.54959 -348.921282)
			(xy 313.499982 -348.943938) (xy 313.447654 -348.959303) (xy 313.393672 -348.967065) (xy 313.366404 -348.967552)
			(xy 312.502804 -348.967552) (xy 312.475532 -348.967109) (xy 312.421543 -348.959347) (xy 312.369209 -348.943981)
			(xy 312.319594 -348.921323) (xy 312.273709 -348.891834) (xy 312.232487 -348.856116) (xy 312.196768 -348.814895)
			(xy 312.167279 -348.76901) (xy 312.144621 -348.719395) (xy 312.129254 -348.667061) (xy 312.121492 -348.613072)
			(xy 300.231566 -348.613072) (xy 300.223804 -348.667051) (xy 300.208439 -348.719379) (xy 300.185784 -348.768987)
			(xy 300.156299 -348.814867) (xy 300.120585 -348.856083) (xy 300.079369 -348.891798) (xy 300.033489 -348.921283)
			(xy 299.98388 -348.943939) (xy 299.931553 -348.959304) (xy 299.877571 -348.967065) (xy 299.850302 -348.967552)
			(xy 298.986702 -348.967552) (xy 298.95943 -348.967109) (xy 298.905442 -348.959347) (xy 298.853107 -348.94398)
			(xy 298.803493 -348.921322) (xy 298.757608 -348.891834) (xy 298.716386 -348.856115) (xy 298.680668 -348.814894)
			(xy 298.651179 -348.769009) (xy 298.628521 -348.719394) (xy 298.613154 -348.66706) (xy 298.605392 -348.613072)
			(xy 297.122565 -348.613072) (xy 297.114805 -348.667045) (xy 297.099443 -348.71937) (xy 297.07679 -348.768976)
			(xy 297.047309 -348.814854) (xy 297.011599 -348.856069) (xy 296.970387 -348.891784) (xy 296.924513 -348.92127)
			(xy 296.874909 -348.943928) (xy 296.822586 -348.959296) (xy 296.768609 -348.967063) (xy 296.741342 -348.967552)
			(xy 295.877742 -348.967552) (xy 295.850468 -348.967111) (xy 295.796476 -348.959354) (xy 295.744136 -348.943991)
			(xy 295.694517 -348.921335) (xy 295.648627 -348.891848) (xy 295.6074 -348.856129) (xy 295.571677 -348.814907)
			(xy 295.542185 -348.76902) (xy 295.519524 -348.719403) (xy 295.504155 -348.667066) (xy 295.496392 -348.613074)
			(xy 294.013688 -348.613074) (xy 294.005926 -348.667058) (xy 293.990559 -348.719391) (xy 293.967901 -348.769004)
			(xy 293.938412 -348.814887) (xy 293.902694 -348.856107) (xy 293.861473 -348.891823) (xy 293.815588 -348.92131)
			(xy 293.765974 -348.943966) (xy 293.713641 -348.95933) (xy 293.659653 -348.96709) (xy 293.632382 -348.967552)
			(xy 292.768782 -348.967552) (xy 292.741513 -348.967084) (xy 292.68753 -348.95932) (xy 292.635201 -348.943953)
			(xy 292.585592 -348.921295) (xy 292.539712 -348.891808) (xy 292.498495 -348.856092) (xy 292.462781 -348.814874)
			(xy 292.433296 -348.768992) (xy 292.410641 -348.719382) (xy 292.395276 -348.667053) (xy 292.387514 -348.613069)
			(xy 290.904666 -348.613069) (xy 290.896905 -348.667048) (xy 290.881541 -348.719374) (xy 290.858887 -348.768982)
			(xy 290.829404 -348.81486) (xy 290.793692 -348.856076) (xy 290.752478 -348.891791) (xy 290.706601 -348.921276)
			(xy 290.656995 -348.943933) (xy 290.604669 -348.9593) (xy 290.55069 -348.967064) (xy 290.523422 -348.967552)
			(xy 289.659822 -348.967552) (xy 289.632549 -348.96711) (xy 289.578559 -348.95935) (xy 289.526222 -348.943985)
			(xy 289.476605 -348.921329) (xy 289.430717 -348.891841) (xy 289.389493 -348.856122) (xy 289.353772 -348.814901)
			(xy 289.324282 -348.769015) (xy 289.301622 -348.719399) (xy 289.286254 -348.667063) (xy 289.278492 -348.613073)
			(xy 287.795788 -348.613073) (xy 287.788026 -348.667061) (xy 287.772658 -348.719395) (xy 287.749998 -348.76901)
			(xy 287.720508 -348.814894) (xy 287.684787 -348.856114) (xy 287.643563 -348.89183) (xy 287.597676 -348.921316)
			(xy 287.54806 -348.943971) (xy 287.495724 -348.959334) (xy 287.441734 -348.967091) (xy 287.414462 -348.967552)
			(xy 286.550862 -348.967552) (xy 286.523594 -348.967083) (xy 286.469613 -348.959317) (xy 286.417286 -348.943948)
			(xy 286.36768 -348.921289) (xy 286.321802 -348.891801) (xy 286.280588 -348.856085) (xy 286.244876 -348.814867)
			(xy 286.215393 -348.768987) (xy 286.192739 -348.719378) (xy 286.177375 -348.66705) (xy 286.169614 -348.613068)
			(xy 284.686766 -348.613068) (xy 284.686766 -348.613069) (xy 284.679004 -348.667051) (xy 284.663639 -348.719379)
			(xy 284.640984 -348.768987) (xy 284.611499 -348.814867) (xy 284.575785 -348.856083) (xy 284.534569 -348.891798)
			(xy 284.488689 -348.921283) (xy 284.43908 -348.943939) (xy 284.386753 -348.959304) (xy 284.332771 -348.967065)
			(xy 284.305502 -348.967552) (xy 283.441902 -348.967552) (xy 283.41463 -348.967109) (xy 283.360642 -348.959347)
			(xy 283.308307 -348.94398) (xy 283.258693 -348.921322) (xy 283.212808 -348.891834) (xy 283.171586 -348.856115)
			(xy 283.135868 -348.814894) (xy 283.106379 -348.769009) (xy 283.083721 -348.719394) (xy 283.068354 -348.66706)
			(xy 283.060592 -348.613072) (xy 281.577765 -348.613072) (xy 281.570005 -348.667045) (xy 281.554643 -348.71937)
			(xy 281.53199 -348.768976) (xy 281.502509 -348.814854) (xy 281.466799 -348.856069) (xy 281.425587 -348.891784)
			(xy 281.379713 -348.92127) (xy 281.330109 -348.943928) (xy 281.277786 -348.959296) (xy 281.223809 -348.967063)
			(xy 281.196542 -348.967552) (xy 280.332942 -348.967552) (xy 280.305668 -348.967111) (xy 280.251676 -348.959354)
			(xy 280.199336 -348.943991) (xy 280.149717 -348.921335) (xy 280.103827 -348.891848) (xy 280.0626 -348.856129)
			(xy 280.026877 -348.814907) (xy 279.997385 -348.76902) (xy 279.974724 -348.719403) (xy 279.959355 -348.667066)
			(xy 279.951592 -348.613074) (xy 278.468888 -348.613074) (xy 278.461126 -348.667058) (xy 278.445759 -348.719391)
			(xy 278.423101 -348.769004) (xy 278.393612 -348.814887) (xy 278.357894 -348.856107) (xy 278.316673 -348.891823)
			(xy 278.270788 -348.92131) (xy 278.221174 -348.943966) (xy 278.168841 -348.95933) (xy 278.114853 -348.96709)
			(xy 278.087582 -348.967552) (xy 277.223982 -348.967552) (xy 277.196713 -348.967084) (xy 277.14273 -348.95932)
			(xy 277.090401 -348.943953) (xy 277.040792 -348.921295) (xy 276.994912 -348.891808) (xy 276.953695 -348.856092)
			(xy 276.917981 -348.814874) (xy 276.888496 -348.768992) (xy 276.865841 -348.719382) (xy 276.850476 -348.667053)
			(xy 276.842714 -348.613069) (xy 275.359866 -348.613069) (xy 275.352105 -348.667048) (xy 275.336741 -348.719374)
			(xy 275.314087 -348.768982) (xy 275.284604 -348.81486) (xy 275.248892 -348.856076) (xy 275.207678 -348.891791)
			(xy 275.161801 -348.921276) (xy 275.112195 -348.943933) (xy 275.059869 -348.9593) (xy 275.00589 -348.967064)
			(xy 274.978622 -348.967552) (xy 274.115022 -348.967552) (xy 274.087749 -348.96711) (xy 274.033759 -348.95935)
			(xy 273.981422 -348.943985) (xy 273.931805 -348.921329) (xy 273.885917 -348.891841) (xy 273.844693 -348.856122)
			(xy 273.808972 -348.814901) (xy 273.779482 -348.769015) (xy 273.756822 -348.719399) (xy 273.741454 -348.667063)
			(xy 273.733692 -348.613073) (xy 272.250988 -348.613073) (xy 272.243226 -348.667061) (xy 272.227858 -348.719395)
			(xy 272.205198 -348.76901) (xy 272.175708 -348.814894) (xy 272.139987 -348.856114) (xy 272.098763 -348.89183)
			(xy 272.052876 -348.921316) (xy 272.00326 -348.943971) (xy 271.950924 -348.959334) (xy 271.896934 -348.967091)
			(xy 271.869662 -348.967552) (xy 271.006062 -348.967552) (xy 270.978794 -348.967083) (xy 270.924813 -348.959317)
			(xy 270.872486 -348.943948) (xy 270.82288 -348.921289) (xy 270.777002 -348.891801) (xy 270.735788 -348.856085)
			(xy 270.700076 -348.814867) (xy 270.670593 -348.768987) (xy 270.647939 -348.719378) (xy 270.632575 -348.66705)
			(xy 270.624814 -348.613068) (xy 269.141966 -348.613068) (xy 269.141966 -348.613069) (xy 269.134204 -348.667051)
			(xy 269.118839 -348.719379) (xy 269.096184 -348.768987) (xy 269.066699 -348.814867) (xy 269.030985 -348.856083)
			(xy 268.989769 -348.891798) (xy 268.943889 -348.921283) (xy 268.89428 -348.943939) (xy 268.841953 -348.959304)
			(xy 268.787971 -348.967065) (xy 268.760702 -348.967552) (xy 267.897102 -348.967552) (xy 267.86983 -348.967109)
			(xy 267.815842 -348.959347) (xy 267.763507 -348.94398) (xy 267.713893 -348.921322) (xy 267.668008 -348.891834)
			(xy 267.626786 -348.856115) (xy 267.591068 -348.814894) (xy 267.561579 -348.769009) (xy 267.538921 -348.719394)
			(xy 267.523554 -348.66706) (xy 267.515792 -348.613072) (xy 194.520565 -348.613072) (xy 194.512804 -348.667049)
			(xy 194.49744 -348.719376) (xy 194.474785 -348.768985) (xy 194.445301 -348.814864) (xy 194.409588 -348.85608)
			(xy 194.368373 -348.891794) (xy 194.322495 -348.92128) (xy 194.272888 -348.943936) (xy 194.220561 -348.959302)
			(xy 194.16658 -348.967065) (xy 194.139312 -348.967552) (xy 193.275712 -348.967552) (xy 193.24844 -348.967109)
			(xy 193.19445 -348.959348) (xy 193.142115 -348.943983) (xy 193.092499 -348.921325) (xy 193.046612 -348.891837)
			(xy 193.00539 -348.856119) (xy 192.96967 -348.814897) (xy 192.940181 -348.769012) (xy 192.917521 -348.719397)
			(xy 192.902154 -348.667062) (xy 192.894392 -348.613072) (xy 191.411688 -348.613072) (xy 191.403925 -348.667062)
			(xy 191.388557 -348.719397) (xy 191.365896 -348.769012) (xy 191.336405 -348.814897) (xy 191.300683 -348.856117)
			(xy 191.259459 -348.891834) (xy 191.21357 -348.921319) (xy 191.163952 -348.943974) (xy 191.111615 -348.959335)
			(xy 191.057625 -348.967092) (xy 191.030352 -348.967552) (xy 190.166752 -348.967552) (xy 190.139484 -348.967082)
			(xy 190.085504 -348.959315) (xy 190.033179 -348.943945) (xy 189.983574 -348.921285) (xy 189.937698 -348.891797)
			(xy 189.896485 -348.856081) (xy 189.860774 -348.814864) (xy 189.831292 -348.768984) (xy 189.808638 -348.719376)
			(xy 189.793275 -348.667049) (xy 189.785514 -348.613068) (xy 188.302689 -348.613068) (xy 188.302689 -348.613071)
			(xy 188.294926 -348.667057) (xy 188.27956 -348.719389) (xy 188.256903 -348.769001) (xy 188.227415 -348.814884)
			(xy 188.191698 -348.856103) (xy 188.150478 -348.89182) (xy 188.104594 -348.921306) (xy 188.054981 -348.943963)
			(xy 188.002649 -348.959328) (xy 187.948663 -348.967089) (xy 187.921392 -348.967552) (xy 187.057792 -348.967552)
			(xy 187.030522 -348.967085) (xy 186.976538 -348.959322) (xy 186.924208 -348.943956) (xy 186.874598 -348.921299)
			(xy 186.828717 -348.891812) (xy 186.787499 -348.856095) (xy 186.751784 -348.814877) (xy 186.722298 -348.768995)
			(xy 186.699641 -348.719384) (xy 186.684276 -348.667054) (xy 186.676514 -348.61307) (xy 185.193666 -348.61307)
			(xy 185.185905 -348.667047) (xy 185.170542 -348.719372) (xy 185.147888 -348.768979) (xy 185.118406 -348.814857)
			(xy 185.082695 -348.856073) (xy 185.041483 -348.891787) (xy 184.995607 -348.921273) (xy 184.946002 -348.943931)
			(xy 184.893678 -348.959298) (xy 184.839699 -348.967063) (xy 184.812432 -348.967552) (xy 183.948832 -348.967552)
			(xy 183.921559 -348.967111) (xy 183.867567 -348.959352) (xy 183.815229 -348.943988) (xy 183.765611 -348.921332)
			(xy 183.719722 -348.891844) (xy 183.678497 -348.856126) (xy 183.642775 -348.814904) (xy 183.613284 -348.769017)
			(xy 183.590623 -348.719401) (xy 183.575255 -348.667064) (xy 183.567492 -348.613073) (xy 182.084788 -348.613073)
			(xy 182.077026 -348.667059) (xy 182.061659 -348.719393) (xy 182.038999 -348.769007) (xy 182.00951 -348.814891)
			(xy 181.97379 -348.85611) (xy 181.932568 -348.891827) (xy 181.886682 -348.921313) (xy 181.837067 -348.943968)
			(xy 181.784732 -348.959332) (xy 181.730744 -348.96709) (xy 181.703472 -348.967552) (xy 180.839872 -348.967552)
			(xy 180.812603 -348.967084) (xy 180.758621 -348.959319) (xy 180.706294 -348.94395) (xy 180.656686 -348.921292)
			(xy 180.610807 -348.891805) (xy 180.569592 -348.856088) (xy 180.533879 -348.81487) (xy 180.504395 -348.76899)
			(xy 180.48174 -348.71938) (xy 180.466376 -348.667051) (xy 180.458614 -348.613069) (xy 178.975766 -348.613069)
			(xy 178.968004 -348.667049) (xy 178.95264 -348.719376) (xy 178.929985 -348.768985) (xy 178.900501 -348.814864)
			(xy 178.864788 -348.85608) (xy 178.823573 -348.891794) (xy 178.777695 -348.92128) (xy 178.728088 -348.943936)
			(xy 178.675761 -348.959302) (xy 178.62178 -348.967065) (xy 178.594512 -348.967552) (xy 177.730912 -348.967552)
			(xy 177.70364 -348.967109) (xy 177.64965 -348.959348) (xy 177.597315 -348.943983) (xy 177.547699 -348.921325)
			(xy 177.501812 -348.891837) (xy 177.46059 -348.856119) (xy 177.42487 -348.814897) (xy 177.395381 -348.769012)
			(xy 177.372721 -348.719397) (xy 177.357354 -348.667062) (xy 177.349592 -348.613072) (xy 175.866888 -348.613072)
			(xy 175.859125 -348.667062) (xy 175.843757 -348.719397) (xy 175.821096 -348.769012) (xy 175.791605 -348.814897)
			(xy 175.755883 -348.856117) (xy 175.714659 -348.891834) (xy 175.66877 -348.921319) (xy 175.619152 -348.943974)
			(xy 175.566815 -348.959335) (xy 175.512825 -348.967092) (xy 175.485552 -348.967552) (xy 174.621952 -348.967552)
			(xy 174.594684 -348.967082) (xy 174.540704 -348.959315) (xy 174.488379 -348.943945) (xy 174.438774 -348.921285)
			(xy 174.392898 -348.891797) (xy 174.351685 -348.856081) (xy 174.315974 -348.814864) (xy 174.286492 -348.768984)
			(xy 174.263838 -348.719376) (xy 174.248475 -348.667049) (xy 174.240714 -348.613068) (xy 172.757889 -348.613068)
			(xy 172.757889 -348.613071) (xy 172.750126 -348.667057) (xy 172.73476 -348.719389) (xy 172.712103 -348.769001)
			(xy 172.682615 -348.814884) (xy 172.646898 -348.856103) (xy 172.605678 -348.89182) (xy 172.559794 -348.921306)
			(xy 172.510181 -348.943963) (xy 172.457849 -348.959328) (xy 172.403863 -348.967089) (xy 172.376592 -348.967552)
			(xy 171.512992 -348.967552) (xy 171.485722 -348.967085) (xy 171.431738 -348.959322) (xy 171.379408 -348.943956)
			(xy 171.329798 -348.921299) (xy 171.283917 -348.891812) (xy 171.242699 -348.856095) (xy 171.206984 -348.814877)
			(xy 171.177498 -348.768995) (xy 171.154841 -348.719384) (xy 171.139476 -348.667054) (xy 171.131714 -348.61307)
			(xy 169.648866 -348.61307) (xy 169.641105 -348.667047) (xy 169.625742 -348.719372) (xy 169.603088 -348.768979)
			(xy 169.573606 -348.814857) (xy 169.537895 -348.856073) (xy 169.496683 -348.891787) (xy 169.450807 -348.921273)
			(xy 169.401202 -348.943931) (xy 169.348878 -348.959298) (xy 169.294899 -348.967063) (xy 169.267632 -348.967552)
			(xy 168.404032 -348.967552) (xy 168.376759 -348.967111) (xy 168.322767 -348.959352) (xy 168.270429 -348.943988)
			(xy 168.220811 -348.921332) (xy 168.174922 -348.891844) (xy 168.133697 -348.856126) (xy 168.097975 -348.814904)
			(xy 168.068484 -348.769017) (xy 168.045823 -348.719401) (xy 168.030455 -348.667064) (xy 168.022692 -348.613073)
			(xy 166.539988 -348.613073) (xy 166.532226 -348.667059) (xy 166.516859 -348.719393) (xy 166.494199 -348.769007)
			(xy 166.46471 -348.814891) (xy 166.42899 -348.85611) (xy 166.387768 -348.891827) (xy 166.341882 -348.921313)
			(xy 166.292267 -348.943968) (xy 166.239932 -348.959332) (xy 166.185944 -348.96709) (xy 166.158672 -348.967552)
			(xy 165.295072 -348.967552) (xy 165.267803 -348.967084) (xy 165.213821 -348.959319) (xy 165.161494 -348.94395)
			(xy 165.111886 -348.921292) (xy 165.066007 -348.891805) (xy 165.024792 -348.856088) (xy 164.989079 -348.81487)
			(xy 164.959595 -348.76899) (xy 164.93694 -348.71938) (xy 164.921576 -348.667051) (xy 164.913814 -348.613069)
			(xy 163.430966 -348.613069) (xy 163.423204 -348.667049) (xy 163.40784 -348.719376) (xy 163.385185 -348.768985)
			(xy 163.355701 -348.814864) (xy 163.319988 -348.85608) (xy 163.278773 -348.891794) (xy 163.232895 -348.92128)
			(xy 163.183288 -348.943936) (xy 163.130961 -348.959302) (xy 163.07698 -348.967065) (xy 163.049712 -348.967552)
			(xy 162.186112 -348.967552) (xy 162.15884 -348.967109) (xy 162.10485 -348.959348) (xy 162.052515 -348.943983)
			(xy 162.002899 -348.921325) (xy 161.957012 -348.891837) (xy 161.91579 -348.856119) (xy 161.88007 -348.814897)
			(xy 161.850581 -348.769012) (xy 161.827921 -348.719397) (xy 161.812554 -348.667062) (xy 161.804792 -348.613072)
			(xy 144.196565 -348.613072) (xy 144.188804 -348.66705) (xy 144.17344 -348.719377) (xy 144.150785 -348.768986)
			(xy 144.1213 -348.814865) (xy 144.085587 -348.856081) (xy 144.044371 -348.891796) (xy 143.998493 -348.921281)
			(xy 143.948885 -348.943937) (xy 143.896558 -348.959303) (xy 143.842576 -348.967065) (xy 143.815308 -348.967552)
			(xy 142.951708 -348.967552) (xy 142.924436 -348.967109) (xy 142.870447 -348.959348) (xy 142.818112 -348.943982)
			(xy 142.768496 -348.921324) (xy 142.72261 -348.891836) (xy 142.681388 -348.856117) (xy 142.645669 -348.814896)
			(xy 142.61618 -348.769011) (xy 142.593521 -348.719396) (xy 142.578154 -348.667061) (xy 142.570392 -348.613072)
			(xy 141.087565 -348.613072) (xy 141.079806 -348.667044) (xy 141.064443 -348.719369) (xy 141.041791 -348.768974)
			(xy 141.01231 -348.814852) (xy 140.976601 -348.856067) (xy 140.93539 -348.891781) (xy 140.889517 -348.921268)
			(xy 140.839914 -348.943926) (xy 140.787591 -348.959295) (xy 140.733614 -348.967062) (xy 140.706348 -348.967552)
			(xy 139.842748 -348.967552) (xy 139.815474 -348.967112) (xy 139.761481 -348.959355) (xy 139.709141 -348.943992)
			(xy 139.65952 -348.921337) (xy 139.613629 -348.89185) (xy 139.572402 -348.856132) (xy 139.536679 -348.814909)
			(xy 139.507186 -348.769022) (xy 139.484524 -348.719404) (xy 139.469155 -348.667066) (xy 139.461392 -348.613074)
			(xy 137.978689 -348.613074) (xy 137.970926 -348.667057) (xy 137.95556 -348.71939) (xy 137.932902 -348.769002)
			(xy 137.903414 -348.814885) (xy 137.867696 -348.856105) (xy 137.826476 -348.891821) (xy 137.780592 -348.921308)
			(xy 137.730978 -348.943964) (xy 137.678646 -348.959329) (xy 137.624659 -348.967089) (xy 137.597388 -348.967552)
			(xy 136.733788 -348.967552) (xy 136.706518 -348.967085) (xy 136.652535 -348.959321) (xy 136.600205 -348.943955)
			(xy 136.550595 -348.921297) (xy 136.504715 -348.89181) (xy 136.463497 -348.856094) (xy 136.427783 -348.814876)
			(xy 136.398297 -348.768994) (xy 136.375641 -348.719383) (xy 136.360276 -348.667053) (xy 136.352514 -348.61307)
			(xy 134.869666 -348.61307) (xy 134.861905 -348.667047) (xy 134.846541 -348.719373) (xy 134.823888 -348.76898)
			(xy 134.794405 -348.814858) (xy 134.758694 -348.856074) (xy 134.717481 -348.891789) (xy 134.671605 -348.921274)
			(xy 134.621999 -348.943932) (xy 134.569675 -348.959299) (xy 134.515695 -348.967064) (xy 134.488428 -348.967552)
			(xy 133.624828 -348.967552) (xy 133.597555 -348.96711) (xy 133.543564 -348.959351) (xy 133.491226 -348.943987)
			(xy 133.441608 -348.92133) (xy 133.39572 -348.891843) (xy 133.354495 -348.856124) (xy 133.318774 -348.814903)
			(xy 133.289283 -348.769016) (xy 133.266623 -348.7194) (xy 133.251255 -348.667064) (xy 133.243492 -348.613073)
			(xy 131.760788 -348.613073) (xy 131.753026 -348.66706) (xy 131.737658 -348.719394) (xy 131.714999 -348.769008)
			(xy 131.685509 -348.814892) (xy 131.649789 -348.856112) (xy 131.608566 -348.891828) (xy 131.56268 -348.921314)
			(xy 131.513064 -348.943969) (xy 131.460729 -348.959332) (xy 131.40674 -348.967091) (xy 131.379468 -348.967552)
			(xy 130.515868 -348.967552) (xy 130.488599 -348.967083) (xy 130.434618 -348.959318) (xy 130.382291 -348.943949)
			(xy 130.332683 -348.921291) (xy 130.286805 -348.891803) (xy 130.24559 -348.856087) (xy 130.209878 -348.814869)
			(xy 130.180394 -348.768989) (xy 130.15774 -348.719379) (xy 130.142375 -348.667051) (xy 130.134614 -348.613069)
			(xy 128.651766 -348.613069) (xy 128.644004 -348.66705) (xy 128.62864 -348.719377) (xy 128.605985 -348.768986)
			(xy 128.5765 -348.814865) (xy 128.540787 -348.856081) (xy 128.499571 -348.891796) (xy 128.453693 -348.921281)
			(xy 128.404085 -348.943937) (xy 128.351758 -348.959303) (xy 128.297776 -348.967065) (xy 128.270508 -348.967552)
			(xy 127.406908 -348.967552) (xy 127.379636 -348.967109) (xy 127.325647 -348.959348) (xy 127.273312 -348.943982)
			(xy 127.223696 -348.921324) (xy 127.17781 -348.891836) (xy 127.136588 -348.856117) (xy 127.100869 -348.814896)
			(xy 127.07138 -348.769011) (xy 127.048721 -348.719396) (xy 127.033354 -348.667061) (xy 127.025592 -348.613072)
			(xy 125.542765 -348.613072) (xy 125.535006 -348.667044) (xy 125.519643 -348.719369) (xy 125.496991 -348.768974)
			(xy 125.46751 -348.814852) (xy 125.431801 -348.856067) (xy 125.39059 -348.891781) (xy 125.344717 -348.921268)
			(xy 125.295114 -348.943926) (xy 125.242791 -348.959295) (xy 125.188814 -348.967062) (xy 125.161548 -348.967552)
			(xy 124.297948 -348.967552) (xy 124.270674 -348.967112) (xy 124.216681 -348.959355) (xy 124.164341 -348.943992)
			(xy 124.11472 -348.921337) (xy 124.068829 -348.89185) (xy 124.027602 -348.856132) (xy 123.991879 -348.814909)
			(xy 123.962386 -348.769022) (xy 123.939724 -348.719404) (xy 123.924355 -348.667066) (xy 123.916592 -348.613074)
			(xy 122.433889 -348.613074) (xy 122.426126 -348.667057) (xy 122.41076 -348.71939) (xy 122.388102 -348.769002)
			(xy 122.358614 -348.814885) (xy 122.322896 -348.856105) (xy 122.281676 -348.891821) (xy 122.235792 -348.921308)
			(xy 122.186178 -348.943964) (xy 122.133846 -348.959329) (xy 122.079859 -348.967089) (xy 122.052588 -348.967552)
			(xy 121.188988 -348.967552) (xy 121.161718 -348.967085) (xy 121.107735 -348.959321) (xy 121.055405 -348.943955)
			(xy 121.005795 -348.921297) (xy 120.959915 -348.89181) (xy 120.918697 -348.856094) (xy 120.882983 -348.814876)
			(xy 120.853497 -348.768994) (xy 120.830841 -348.719383) (xy 120.815476 -348.667053) (xy 120.807714 -348.61307)
			(xy 119.324866 -348.61307) (xy 119.317105 -348.667047) (xy 119.301741 -348.719373) (xy 119.279088 -348.76898)
			(xy 119.249605 -348.814858) (xy 119.213894 -348.856074) (xy 119.172681 -348.891789) (xy 119.126805 -348.921274)
			(xy 119.077199 -348.943932) (xy 119.024875 -348.959299) (xy 118.970895 -348.967064) (xy 118.943628 -348.967552)
			(xy 118.080028 -348.967552) (xy 118.052755 -348.96711) (xy 117.998764 -348.959351) (xy 117.946426 -348.943987)
			(xy 117.896808 -348.92133) (xy 117.85092 -348.891843) (xy 117.809695 -348.856124) (xy 117.773974 -348.814903)
			(xy 117.744483 -348.769016) (xy 117.721823 -348.7194) (xy 117.706455 -348.667064) (xy 117.698692 -348.613073)
			(xy 116.215988 -348.613073) (xy 116.208226 -348.66706) (xy 116.192858 -348.719394) (xy 116.170199 -348.769008)
			(xy 116.140709 -348.814892) (xy 116.104989 -348.856112) (xy 116.063766 -348.891828) (xy 116.01788 -348.921314)
			(xy 115.968264 -348.943969) (xy 115.915929 -348.959332) (xy 115.86194 -348.967091) (xy 115.834668 -348.967552)
			(xy 114.971068 -348.967552) (xy 114.943799 -348.967083) (xy 114.889818 -348.959318) (xy 114.837491 -348.943949)
			(xy 114.787883 -348.921291) (xy 114.742005 -348.891803) (xy 114.70079 -348.856087) (xy 114.665078 -348.814869)
			(xy 114.635594 -348.768989) (xy 114.61294 -348.719379) (xy 114.597575 -348.667051) (xy 114.589814 -348.613069)
			(xy 113.106966 -348.613069) (xy 113.099204 -348.66705) (xy 113.08384 -348.719377) (xy 113.061185 -348.768986)
			(xy 113.0317 -348.814865) (xy 112.995987 -348.856081) (xy 112.954771 -348.891796) (xy 112.908893 -348.921281)
			(xy 112.859285 -348.943937) (xy 112.806958 -348.959303) (xy 112.752976 -348.967065) (xy 112.725708 -348.967552)
			(xy 111.862108 -348.967552) (xy 111.834836 -348.967109) (xy 111.780847 -348.959348) (xy 111.728512 -348.943982)
			(xy 111.678896 -348.921324) (xy 111.63301 -348.891836) (xy 111.591788 -348.856117) (xy 111.556069 -348.814896)
			(xy 111.52658 -348.769011) (xy 111.503921 -348.719396) (xy 111.488554 -348.667061) (xy 111.480792 -348.613072)
			(xy 93.706665 -348.613072) (xy 93.698905 -348.667045) (xy 93.683543 -348.71937) (xy 93.66089 -348.768976)
			(xy 93.631409 -348.814854) (xy 93.595699 -348.856069) (xy 93.554487 -348.891784) (xy 93.508613 -348.92127)
			(xy 93.459009 -348.943928) (xy 93.406686 -348.959296) (xy 93.352709 -348.967063) (xy 93.325442 -348.967552)
			(xy 92.461842 -348.967552) (xy 92.434568 -348.967111) (xy 92.380576 -348.959354) (xy 92.328236 -348.943991)
			(xy 92.278617 -348.921335) (xy 92.232727 -348.891848) (xy 92.1915 -348.856129) (xy 92.155777 -348.814907)
			(xy 92.126285 -348.76902) (xy 92.103624 -348.719403) (xy 92.088255 -348.667066) (xy 92.080492 -348.613074)
			(xy 90.597788 -348.613074) (xy 90.590026 -348.667058) (xy 90.574659 -348.719391) (xy 90.552001 -348.769004)
			(xy 90.522512 -348.814887) (xy 90.486794 -348.856107) (xy 90.445573 -348.891823) (xy 90.399688 -348.92131)
			(xy 90.350074 -348.943966) (xy 90.297741 -348.95933) (xy 90.243753 -348.96709) (xy 90.216482 -348.967552)
			(xy 89.352882 -348.967552) (xy 89.325613 -348.967084) (xy 89.27163 -348.95932) (xy 89.219301 -348.943953)
			(xy 89.169692 -348.921295) (xy 89.123812 -348.891808) (xy 89.082595 -348.856092) (xy 89.046881 -348.814874)
			(xy 89.017396 -348.768992) (xy 88.994741 -348.719382) (xy 88.979376 -348.667053) (xy 88.971614 -348.613069)
			(xy 87.488766 -348.613069) (xy 87.481005 -348.667048) (xy 87.465641 -348.719374) (xy 87.442987 -348.768982)
			(xy 87.413504 -348.81486) (xy 87.377792 -348.856076) (xy 87.336578 -348.891791) (xy 87.290701 -348.921276)
			(xy 87.241095 -348.943933) (xy 87.188769 -348.9593) (xy 87.13479 -348.967064) (xy 87.107522 -348.967552)
			(xy 86.243922 -348.967552) (xy 86.216649 -348.96711) (xy 86.162659 -348.95935) (xy 86.110322 -348.943985)
			(xy 86.060705 -348.921329) (xy 86.014817 -348.891841) (xy 85.973593 -348.856122) (xy 85.937872 -348.814901)
			(xy 85.908382 -348.769015) (xy 85.885722 -348.719399) (xy 85.870354 -348.667063) (xy 85.862592 -348.613073)
			(xy 84.379888 -348.613073) (xy 84.372126 -348.667061) (xy 84.356758 -348.719395) (xy 84.334098 -348.76901)
			(xy 84.304608 -348.814894) (xy 84.268887 -348.856114) (xy 84.227663 -348.89183) (xy 84.181776 -348.921316)
			(xy 84.13216 -348.943971) (xy 84.079824 -348.959334) (xy 84.025834 -348.967091) (xy 83.998562 -348.967552)
			(xy 83.134962 -348.967552) (xy 83.107694 -348.967083) (xy 83.053713 -348.959317) (xy 83.001386 -348.943948)
			(xy 82.95178 -348.921289) (xy 82.905902 -348.891801) (xy 82.864688 -348.856085) (xy 82.828976 -348.814867)
			(xy 82.799493 -348.768987) (xy 82.776839 -348.719378) (xy 82.761475 -348.66705) (xy 82.753714 -348.613068)
			(xy 81.270866 -348.613068) (xy 81.270866 -348.613069) (xy 81.263104 -348.667051) (xy 81.247739 -348.719379)
			(xy 81.225084 -348.768987) (xy 81.195599 -348.814867) (xy 81.159885 -348.856083) (xy 81.118669 -348.891798)
			(xy 81.072789 -348.921283) (xy 81.02318 -348.943939) (xy 80.970853 -348.959304) (xy 80.916871 -348.967065)
			(xy 80.889602 -348.967552) (xy 80.026002 -348.967552) (xy 79.99873 -348.967109) (xy 79.944742 -348.959347)
			(xy 79.892407 -348.94398) (xy 79.842793 -348.921322) (xy 79.796908 -348.891834) (xy 79.755686 -348.856115)
			(xy 79.719968 -348.814894) (xy 79.690479 -348.769009) (xy 79.667821 -348.719394) (xy 79.652454 -348.66706)
			(xy 79.644692 -348.613072) (xy 78.161865 -348.613072) (xy 78.154105 -348.667045) (xy 78.138743 -348.71937)
			(xy 78.11609 -348.768976) (xy 78.086609 -348.814854) (xy 78.050899 -348.856069) (xy 78.009687 -348.891784)
			(xy 77.963813 -348.92127) (xy 77.914209 -348.943928) (xy 77.861886 -348.959296) (xy 77.807909 -348.967063)
			(xy 77.780642 -348.967552) (xy 76.917042 -348.967552) (xy 76.889768 -348.967111) (xy 76.835776 -348.959354)
			(xy 76.783436 -348.943991) (xy 76.733817 -348.921335) (xy 76.687927 -348.891848) (xy 76.6467 -348.856129)
			(xy 76.610977 -348.814907) (xy 76.581485 -348.76902) (xy 76.558824 -348.719403) (xy 76.543455 -348.667066)
			(xy 76.535692 -348.613074) (xy 75.052988 -348.613074) (xy 75.045226 -348.667058) (xy 75.029859 -348.719391)
			(xy 75.007201 -348.769004) (xy 74.977712 -348.814887) (xy 74.941994 -348.856107) (xy 74.900773 -348.891823)
			(xy 74.854888 -348.92131) (xy 74.805274 -348.943966) (xy 74.752941 -348.95933) (xy 74.698953 -348.96709)
			(xy 74.671682 -348.967552) (xy 73.808082 -348.967552) (xy 73.780813 -348.967084) (xy 73.72683 -348.95932)
			(xy 73.674501 -348.943953) (xy 73.624892 -348.921295) (xy 73.579012 -348.891808) (xy 73.537795 -348.856092)
			(xy 73.502081 -348.814874) (xy 73.472596 -348.768992) (xy 73.449941 -348.719382) (xy 73.434576 -348.667053)
			(xy 73.426814 -348.613069) (xy 71.943966 -348.613069) (xy 71.936205 -348.667048) (xy 71.920841 -348.719374)
			(xy 71.898187 -348.768982) (xy 71.868704 -348.81486) (xy 71.832992 -348.856076) (xy 71.791778 -348.891791)
			(xy 71.745901 -348.921276) (xy 71.696295 -348.943933) (xy 71.643969 -348.9593) (xy 71.58999 -348.967064)
			(xy 71.562722 -348.967552) (xy 70.699122 -348.967552) (xy 70.671849 -348.96711) (xy 70.617859 -348.95935)
			(xy 70.565522 -348.943985) (xy 70.515905 -348.921329) (xy 70.470017 -348.891841) (xy 70.428793 -348.856122)
			(xy 70.393072 -348.814901) (xy 70.363582 -348.769015) (xy 70.340922 -348.719399) (xy 70.325554 -348.667063)
			(xy 70.317792 -348.613073) (xy 68.835088 -348.613073) (xy 68.827326 -348.667061) (xy 68.811958 -348.719395)
			(xy 68.789298 -348.76901) (xy 68.759808 -348.814894) (xy 68.724087 -348.856114) (xy 68.682863 -348.89183)
			(xy 68.636976 -348.921316) (xy 68.58736 -348.943971) (xy 68.535024 -348.959334) (xy 68.481034 -348.967091)
			(xy 68.453762 -348.967552) (xy 67.590162 -348.967552) (xy 67.562894 -348.967083) (xy 67.508913 -348.959317)
			(xy 67.456586 -348.943948) (xy 67.40698 -348.921289) (xy 67.361102 -348.891801) (xy 67.319888 -348.856085)
			(xy 67.284176 -348.814867) (xy 67.254693 -348.768987) (xy 67.232039 -348.719378) (xy 67.216675 -348.66705)
			(xy 67.208914 -348.613068) (xy 65.726066 -348.613068) (xy 65.726066 -348.613069) (xy 65.718304 -348.667051)
			(xy 65.702939 -348.719379) (xy 65.680284 -348.768987) (xy 65.650799 -348.814867) (xy 65.615085 -348.856083)
			(xy 65.573869 -348.891798) (xy 65.527989 -348.921283) (xy 65.47838 -348.943939) (xy 65.426053 -348.959304)
			(xy 65.372071 -348.967065) (xy 65.344802 -348.967552) (xy 64.481202 -348.967552) (xy 64.45393 -348.967109)
			(xy 64.399942 -348.959347) (xy 64.347607 -348.94398) (xy 64.297993 -348.921322) (xy 64.252108 -348.891834)
			(xy 64.210886 -348.856115) (xy 64.175168 -348.814894) (xy 64.145679 -348.769009) (xy 64.123021 -348.719394)
			(xy 64.107654 -348.66706) (xy 64.099892 -348.613072) (xy 62.617065 -348.613072) (xy 62.609305 -348.667045)
			(xy 62.593943 -348.71937) (xy 62.57129 -348.768976) (xy 62.541809 -348.814854) (xy 62.506099 -348.856069)
			(xy 62.464887 -348.891784) (xy 62.419013 -348.92127) (xy 62.369409 -348.943928) (xy 62.317086 -348.959296)
			(xy 62.263109 -348.967063) (xy 62.235842 -348.967552) (xy 61.372242 -348.967552) (xy 61.344968 -348.967111)
			(xy 61.290976 -348.959354) (xy 61.238636 -348.943991) (xy 61.189017 -348.921335) (xy 61.143127 -348.891848)
			(xy 61.1019 -348.856129) (xy 61.066177 -348.814907) (xy 61.036685 -348.76902) (xy 61.014024 -348.719403)
			(xy 60.998655 -348.667066) (xy 60.990892 -348.613074) (xy 51.666865 -348.613074) (xy 51.659106 -348.667044)
			(xy 51.643743 -348.719369) (xy 51.621091 -348.768974) (xy 51.59161 -348.814852) (xy 51.555901 -348.856067)
			(xy 51.51469 -348.891781) (xy 51.468817 -348.921268) (xy 51.419214 -348.943926) (xy 51.366891 -348.959295)
			(xy 51.312914 -348.967062) (xy 51.285648 -348.967552) (xy 50.422048 -348.967552) (xy 50.394774 -348.967112)
			(xy 50.340781 -348.959355) (xy 50.288441 -348.943992) (xy 50.23882 -348.921337) (xy 50.192929 -348.89185)
			(xy 50.151702 -348.856132) (xy 50.115979 -348.814909) (xy 50.086486 -348.769022) (xy 50.063824 -348.719404)
			(xy 50.048455 -348.667066) (xy 50.040692 -348.613074) (xy 48.557989 -348.613074) (xy 48.550226 -348.667057)
			(xy 48.53486 -348.71939) (xy 48.512202 -348.769002) (xy 48.482714 -348.814885) (xy 48.446996 -348.856105)
			(xy 48.405776 -348.891821) (xy 48.359892 -348.921308) (xy 48.310278 -348.943964) (xy 48.257946 -348.959329)
			(xy 48.203959 -348.967089) (xy 48.176688 -348.967552) (xy 47.313088 -348.967552) (xy 47.285818 -348.967085)
			(xy 47.231835 -348.959321) (xy 47.179505 -348.943955) (xy 47.129895 -348.921297) (xy 47.084015 -348.89181)
			(xy 47.042797 -348.856094) (xy 47.007083 -348.814876) (xy 46.977597 -348.768994) (xy 46.954941 -348.719383)
			(xy 46.939576 -348.667053) (xy 46.931814 -348.61307) (xy 45.448966 -348.61307) (xy 45.441205 -348.667047)
			(xy 45.425841 -348.719373) (xy 45.403188 -348.76898) (xy 45.373705 -348.814858) (xy 45.337994 -348.856074)
			(xy 45.296781 -348.891789) (xy 45.250905 -348.921274) (xy 45.201299 -348.943932) (xy 45.148975 -348.959299)
			(xy 45.094995 -348.967064) (xy 45.067728 -348.967552) (xy 44.204128 -348.967552) (xy 44.176855 -348.96711)
			(xy 44.122864 -348.959351) (xy 44.070526 -348.943987) (xy 44.020908 -348.92133) (xy 43.97502 -348.891843)
			(xy 43.933795 -348.856124) (xy 43.898074 -348.814903) (xy 43.868583 -348.769016) (xy 43.845923 -348.7194)
			(xy 43.830555 -348.667064) (xy 43.822792 -348.613073) (xy 42.340088 -348.613073) (xy 42.332326 -348.66706)
			(xy 42.316958 -348.719394) (xy 42.294299 -348.769008) (xy 42.264809 -348.814892) (xy 42.229089 -348.856112)
			(xy 42.187866 -348.891828) (xy 42.14198 -348.921314) (xy 42.092364 -348.943969) (xy 42.040029 -348.959332)
			(xy 41.98604 -348.967091) (xy 41.958768 -348.967552) (xy 41.095168 -348.967552) (xy 41.067899 -348.967083)
			(xy 41.013918 -348.959318) (xy 40.961591 -348.943949) (xy 40.911983 -348.921291) (xy 40.866105 -348.891803)
			(xy 40.82489 -348.856087) (xy 40.789178 -348.814869) (xy 40.759694 -348.768989) (xy 40.73704 -348.719379)
			(xy 40.721675 -348.667051) (xy 40.713914 -348.613069) (xy 39.231066 -348.613069) (xy 39.223304 -348.66705)
			(xy 39.20794 -348.719377) (xy 39.185285 -348.768986) (xy 39.1558 -348.814865) (xy 39.120087 -348.856081)
			(xy 39.078871 -348.891796) (xy 39.032993 -348.921281) (xy 38.983385 -348.943937) (xy 38.931058 -348.959303)
			(xy 38.877076 -348.967065) (xy 38.849808 -348.967552) (xy 37.986208 -348.967552) (xy 37.958936 -348.967109)
			(xy 37.904947 -348.959348) (xy 37.852612 -348.943982) (xy 37.802996 -348.921324) (xy 37.75711 -348.891836)
			(xy 37.715888 -348.856117) (xy 37.680169 -348.814896) (xy 37.65068 -348.769011) (xy 37.628021 -348.719396)
			(xy 37.612654 -348.667061) (xy 37.604892 -348.613072) (xy 36.122065 -348.613072) (xy 36.114306 -348.667044)
			(xy 36.098943 -348.719369) (xy 36.076291 -348.768974) (xy 36.04681 -348.814852) (xy 36.011101 -348.856067)
			(xy 35.96989 -348.891781) (xy 35.924017 -348.921268) (xy 35.874414 -348.943926) (xy 35.822091 -348.959295)
			(xy 35.768114 -348.967062) (xy 35.740848 -348.967552) (xy 34.877248 -348.967552) (xy 34.849974 -348.967112)
			(xy 34.795981 -348.959355) (xy 34.743641 -348.943992) (xy 34.69402 -348.921337) (xy 34.648129 -348.89185)
			(xy 34.606902 -348.856132) (xy 34.571179 -348.814909) (xy 34.541686 -348.769022) (xy 34.519024 -348.719404)
			(xy 34.503655 -348.667066) (xy 34.495892 -348.613074) (xy 33.013189 -348.613074) (xy 33.005426 -348.667057)
			(xy 32.99006 -348.71939) (xy 32.967402 -348.769002) (xy 32.937914 -348.814885) (xy 32.902196 -348.856105)
			(xy 32.860976 -348.891821) (xy 32.815092 -348.921308) (xy 32.765478 -348.943964) (xy 32.713146 -348.959329)
			(xy 32.659159 -348.967089) (xy 32.631888 -348.967552) (xy 31.768288 -348.967552) (xy 31.741018 -348.967085)
			(xy 31.687035 -348.959321) (xy 31.634705 -348.943955) (xy 31.585095 -348.921297) (xy 31.539215 -348.89181)
			(xy 31.497997 -348.856094) (xy 31.462283 -348.814876) (xy 31.432797 -348.768994) (xy 31.410141 -348.719383)
			(xy 31.394776 -348.667053) (xy 31.387014 -348.61307) (xy 29.904166 -348.61307) (xy 29.896405 -348.667047)
			(xy 29.881041 -348.719373) (xy 29.858388 -348.76898) (xy 29.828905 -348.814858) (xy 29.793194 -348.856074)
			(xy 29.751981 -348.891789) (xy 29.706105 -348.921274) (xy 29.656499 -348.943932) (xy 29.604175 -348.959299)
			(xy 29.550195 -348.967064) (xy 29.522928 -348.967552) (xy 28.659328 -348.967552) (xy 28.632055 -348.96711)
			(xy 28.578064 -348.959351) (xy 28.525726 -348.943987) (xy 28.476108 -348.92133) (xy 28.43022 -348.891843)
			(xy 28.388995 -348.856124) (xy 28.353274 -348.814903) (xy 28.323783 -348.769016) (xy 28.301123 -348.7194)
			(xy 28.285755 -348.667064) (xy 28.277992 -348.613073) (xy 26.795288 -348.613073) (xy 26.787526 -348.66706)
			(xy 26.772158 -348.719394) (xy 26.749499 -348.769008) (xy 26.720009 -348.814892) (xy 26.684289 -348.856112)
			(xy 26.643066 -348.891828) (xy 26.59718 -348.921314) (xy 26.547564 -348.943969) (xy 26.495229 -348.959332)
			(xy 26.44124 -348.967091) (xy 26.413968 -348.967552) (xy 25.550368 -348.967552) (xy 25.523099 -348.967083)
			(xy 25.469118 -348.959318) (xy 25.416791 -348.943949) (xy 25.367183 -348.921291) (xy 25.321305 -348.891803)
			(xy 25.28009 -348.856087) (xy 25.244378 -348.814869) (xy 25.214894 -348.768989) (xy 25.19224 -348.719379)
			(xy 25.176875 -348.667051) (xy 25.169114 -348.613069) (xy 23.686266 -348.613069) (xy 23.678504 -348.66705)
			(xy 23.66314 -348.719377) (xy 23.640485 -348.768986) (xy 23.611 -348.814865) (xy 23.575287 -348.856081)
			(xy 23.534071 -348.891796) (xy 23.488193 -348.921281) (xy 23.438585 -348.943937) (xy 23.386258 -348.959303)
			(xy 23.332276 -348.967065) (xy 23.305008 -348.967552) (xy 22.441408 -348.967552) (xy 22.414136 -348.967109)
			(xy 22.360147 -348.959348) (xy 22.307812 -348.943982) (xy 22.258196 -348.921324) (xy 22.21231 -348.891836)
			(xy 22.171088 -348.856117) (xy 22.135369 -348.814896) (xy 22.10588 -348.769011) (xy 22.083221 -348.719396)
			(xy 22.067854 -348.667061) (xy 22.060092 -348.613072) (xy 20.577347 -348.613072) (xy 20.569586 -348.667048)
			(xy 20.55422 -348.719381) (xy 20.531562 -348.768994) (xy 20.502074 -348.814878) (xy 20.466357 -348.856098)
			(xy 20.425136 -348.891816) (xy 20.379253 -348.921303) (xy 20.329639 -348.943961) (xy 20.277306 -348.959327)
			(xy 20.223319 -348.967089) (xy 20.196048 -348.967552) (xy 19.332448 -348.967552) (xy 19.305179 -348.967065)
			(xy 19.251195 -348.959304) (xy 19.198866 -348.943938) (xy 19.149256 -348.921282) (xy 19.103375 -348.891796)
			(xy 19.062158 -348.856081) (xy 19.026443 -348.814863) (xy 18.996957 -348.768982) (xy 18.974301 -348.719372)
			(xy 18.958936 -348.667043) (xy 18.951174 -348.613059) (xy 8.879169 -348.613059) (xy 8.892221 -348.718461)
			(xy 8.900171 -348.847356) (xy 8.900668 -348.911926) (xy 8.900171 -348.976496) (xy 8.892221 -349.105391)
			(xy 8.876351 -349.233551) (xy 8.852622 -349.360492) (xy 8.821123 -349.485731) (xy 8.781974 -349.608794)
			(xy 8.735323 -349.729213) (xy 8.681348 -349.846532) (xy 8.620253 -349.960306) (xy 8.55227 -350.070103)
			(xy 8.477656 -350.175506) (xy 8.396695 -350.276116) (xy 8.309695 -350.371551) (xy 8.216984 -350.46145)
			(xy 8.210606 -350.466914) (xy 19.115532 -350.466914) (xy 19.115532 -349.730314) (xy 19.115975 -349.720144)
			(xy 19.123754 -349.701351) (xy 19.138134 -349.686966) (xy 19.156924 -349.679179) (xy 19.167094 -349.678752)
			(xy 19.409918 -349.678752) (xy 19.73961 -349.894906) (xy 19.750648 -349.900407) (xy 19.775277 -349.901067)
			(xy 19.7866 -349.896176) (xy 20.10156 -349.690944) (xy 20.10791 -349.68688) (xy 20.108418 -349.686372)
			(xy 20.12061 -349.678752) (xy 20.363434 -349.678752) (xy 20.373596 -349.679206) (xy 20.392368 -349.686994)
			(xy 20.406733 -349.701372) (xy 20.414504 -349.720152) (xy 20.414996 -349.730314) (xy 20.414996 -350.466914)
			(xy 22.224492 -350.466914) (xy 22.224492 -349.730314) (xy 22.225044 -349.720163) (xy 22.232805 -349.701403)
			(xy 22.247152 -349.687039) (xy 22.265903 -349.679255) (xy 22.276054 -349.678752) (xy 22.518878 -349.678752)
			(xy 22.84857 -349.894906) (xy 22.859619 -349.90038) (xy 22.884238 -349.901057) (xy 22.89556 -349.896176)
			(xy 23.21052 -349.690944) (xy 23.21687 -349.68688) (xy 23.217378 -349.686372) (xy 23.22957 -349.678752)
			(xy 23.472394 -349.678752) (xy 23.482567 -349.679169) (xy 23.501364 -349.686955) (xy 23.51575 -349.701342)
			(xy 23.523533 -349.720141) (xy 23.523956 -349.730314) (xy 23.523956 -350.466914) (xy 25.333452 -350.466914)
			(xy 25.333452 -349.730314) (xy 25.333875 -349.720142) (xy 25.341659 -349.701344) (xy 25.356044 -349.686959)
			(xy 25.374842 -349.679175) (xy 25.385014 -349.678752) (xy 25.627838 -349.678752) (xy 25.95753 -349.894906)
			(xy 25.968563 -349.900421) (xy 25.993197 -349.901072) (xy 26.00452 -349.896176) (xy 26.31948 -349.690944)
			(xy 26.32583 -349.68688) (xy 26.326338 -349.686372) (xy 26.33853 -349.678752) (xy 26.581354 -349.678752)
			(xy 26.591524 -349.679202) (xy 26.610321 -349.686974) (xy 26.624708 -349.701352) (xy 26.632492 -349.720144)
			(xy 26.632916 -349.730314) (xy 26.632916 -350.466914) (xy 28.442412 -350.466914) (xy 28.442412 -349.730314)
			(xy 28.442944 -349.72016) (xy 28.450709 -349.701396) (xy 28.465063 -349.687032) (xy 28.483821 -349.679252)
			(xy 28.493974 -349.678752) (xy 28.736798 -349.678752) (xy 29.06649 -349.894906) (xy 29.077533 -349.900394)
			(xy 29.102158 -349.901062) (xy 29.11348 -349.896176) (xy 29.42844 -349.690944) (xy 29.43479 -349.68688)
			(xy 29.435298 -349.686372) (xy 29.44749 -349.678752) (xy 29.690314 -349.678752) (xy 29.700474 -349.679222)
			(xy 29.719246 -349.687004) (xy 29.733612 -349.701377) (xy 29.741383 -349.720153) (xy 29.741876 -349.730314)
			(xy 29.741876 -350.466914) (xy 31.551372 -350.466914) (xy 31.551372 -349.730314) (xy 31.551776 -349.720139)
			(xy 31.559563 -349.701338) (xy 31.573955 -349.686951) (xy 31.592759 -349.679172) (xy 31.602934 -349.678752)
			(xy 31.845758 -349.678752) (xy 32.17545 -349.894906) (xy 32.186504 -349.900367) (xy 32.211118 -349.901052)
			(xy 32.22244 -349.896176) (xy 32.5374 -349.690944) (xy 32.54375 -349.68688) (xy 32.544258 -349.686372)
			(xy 32.55645 -349.678752) (xy 32.799274 -349.678752) (xy 32.809446 -349.679186) (xy 32.828242 -349.686965)
			(xy 32.842629 -349.701348) (xy 32.850412 -349.720142) (xy 32.850836 -349.730314) (xy 32.850836 -350.466914)
			(xy 34.660332 -350.466914) (xy 34.660332 -349.730314) (xy 34.660775 -349.720144) (xy 34.668554 -349.701351)
			(xy 34.682934 -349.686966) (xy 34.701724 -349.679179) (xy 34.711894 -349.678752) (xy 34.954718 -349.678752)
			(xy 35.28441 -349.894906) (xy 35.295448 -349.900407) (xy 35.320077 -349.901067) (xy 35.3314 -349.896176)
			(xy 35.64636 -349.690944) (xy 35.65271 -349.68688) (xy 35.653218 -349.686372) (xy 35.66541 -349.678752)
			(xy 35.908234 -349.678752) (xy 35.918396 -349.679206) (xy 35.937168 -349.686994) (xy 35.951533 -349.701372)
			(xy 35.959304 -349.720152) (xy 35.959796 -349.730314) (xy 35.959796 -350.466914) (xy 37.769292 -350.466914)
			(xy 37.769292 -349.730314) (xy 37.769844 -349.720163) (xy 37.777605 -349.701403) (xy 37.791952 -349.687039)
			(xy 37.810703 -349.679255) (xy 37.820854 -349.678752) (xy 38.063678 -349.678752) (xy 38.39337 -349.894906)
			(xy 38.404419 -349.90038) (xy 38.429038 -349.901057) (xy 38.44036 -349.896176) (xy 38.75532 -349.690944)
			(xy 38.76167 -349.68688) (xy 38.762178 -349.686372) (xy 38.77437 -349.678752) (xy 39.017194 -349.678752)
			(xy 39.027367 -349.679169) (xy 39.046164 -349.686955) (xy 39.06055 -349.701342) (xy 39.068333 -349.720141)
			(xy 39.068756 -349.730314) (xy 39.068756 -350.466914) (xy 40.878252 -350.466914) (xy 40.878252 -349.730314)
			(xy 40.878675 -349.720142) (xy 40.886459 -349.701344) (xy 40.900844 -349.686959) (xy 40.919642 -349.679175)
			(xy 40.929814 -349.678752) (xy 41.172638 -349.678752) (xy 41.50233 -349.894906) (xy 41.513363 -349.900421)
			(xy 41.537997 -349.901072) (xy 41.54932 -349.896176) (xy 41.86428 -349.690944) (xy 41.87063 -349.68688)
			(xy 41.871138 -349.686372) (xy 41.88333 -349.678752) (xy 42.126154 -349.678752) (xy 42.136324 -349.679202)
			(xy 42.155121 -349.686974) (xy 42.169508 -349.701352) (xy 42.177292 -349.720144) (xy 42.177716 -349.730314)
			(xy 42.177716 -350.466914) (xy 43.987212 -350.466914) (xy 43.987212 -349.730314) (xy 43.987744 -349.72016)
			(xy 43.995509 -349.701396) (xy 44.009863 -349.687032) (xy 44.028621 -349.679252) (xy 44.038774 -349.678752)
			(xy 44.281598 -349.678752) (xy 44.61129 -349.894906) (xy 44.622333 -349.900394) (xy 44.646958 -349.901062)
			(xy 44.65828 -349.896176) (xy 44.97324 -349.690944) (xy 44.97959 -349.68688) (xy 44.980098 -349.686372)
			(xy 44.99229 -349.678752) (xy 45.235114 -349.678752) (xy 45.245274 -349.679222) (xy 45.264046 -349.687004)
			(xy 45.278412 -349.701377) (xy 45.286183 -349.720153) (xy 45.286676 -349.730314) (xy 45.286676 -350.466914)
			(xy 47.096172 -350.466914) (xy 47.096172 -349.730314) (xy 47.096576 -349.720139) (xy 47.104363 -349.701338)
			(xy 47.118755 -349.686951) (xy 47.137559 -349.679172) (xy 47.147734 -349.678752) (xy 47.390558 -349.678752)
			(xy 47.72025 -349.894906) (xy 47.731304 -349.900367) (xy 47.755918 -349.901052) (xy 47.76724 -349.896176)
			(xy 48.0822 -349.690944) (xy 48.08855 -349.68688) (xy 48.089058 -349.686372) (xy 48.10125 -349.678752)
			(xy 48.344074 -349.678752) (xy 48.354246 -349.679186) (xy 48.373042 -349.686965) (xy 48.387429 -349.701348)
			(xy 48.395212 -349.720142) (xy 48.395636 -349.730314) (xy 48.395636 -350.466914) (xy 50.205132 -350.466914)
			(xy 50.205132 -349.730314) (xy 50.205575 -349.720144) (xy 50.213354 -349.701351) (xy 50.227734 -349.686966)
			(xy 50.246524 -349.679179) (xy 50.256694 -349.678752) (xy 50.499518 -349.678752) (xy 50.82921 -349.894906)
			(xy 50.840248 -349.900407) (xy 50.864877 -349.901067) (xy 50.8762 -349.896176) (xy 51.19116 -349.690944)
			(xy 51.19751 -349.68688) (xy 51.198018 -349.686372) (xy 51.21021 -349.678752) (xy 51.453034 -349.678752)
			(xy 51.463196 -349.679206) (xy 51.481968 -349.686994) (xy 51.496333 -349.701372) (xy 51.504104 -349.720152)
			(xy 51.504596 -349.730314) (xy 51.504596 -350.466914) (xy 61.155072 -350.466914) (xy 61.155072 -349.730314)
			(xy 61.155481 -349.720107) (xy 61.163316 -349.701258) (xy 61.177788 -349.686862) (xy 61.196679 -349.679128)
			(xy 61.206888 -349.678752) (xy 61.449712 -349.678752) (xy 61.779404 -349.894906) (xy 61.790444 -349.900403)
			(xy 61.815071 -349.901065) (xy 61.826394 -349.896176) (xy 62.141354 -349.690944) (xy 62.147704 -349.68688)
			(xy 62.148212 -349.686372) (xy 62.160404 -349.678752) (xy 62.403228 -349.678752) (xy 62.413402 -349.679251)
			(xy 62.43221 -349.68702) (xy 62.446635 -349.701373) (xy 62.454498 -349.720142) (xy 62.455044 -349.730314)
			(xy 62.455044 -350.466914) (xy 64.264032 -350.466914) (xy 64.264032 -349.730314) (xy 64.264481 -349.720112)
			(xy 64.272307 -349.70127) (xy 64.286767 -349.686876) (xy 64.305645 -349.679135) (xy 64.315848 -349.678752)
			(xy 64.558672 -349.678752) (xy 64.888364 -349.894906) (xy 64.899414 -349.900376) (xy 64.924032 -349.901056)
			(xy 64.935354 -349.896176) (xy 65.250314 -349.690944) (xy 65.256664 -349.68688) (xy 65.257172 -349.686372)
			(xy 65.269364 -349.678752) (xy 65.512188 -349.678752) (xy 65.52236 -349.679284) (xy 65.541167 -349.68704)
			(xy 65.555593 -349.701383) (xy 65.563457 -349.720145) (xy 65.564004 -349.730314) (xy 65.564004 -350.466914)
			(xy 67.372992 -350.466914) (xy 67.372992 -349.730314) (xy 67.37348 -349.720117) (xy 67.381299 -349.701283)
			(xy 67.395746 -349.68689) (xy 67.41461 -349.679142) (xy 67.424808 -349.678752) (xy 67.667632 -349.678752)
			(xy 67.997324 -349.894906) (xy 68.008359 -349.900417) (xy 68.032991 -349.90107) (xy 68.044314 -349.896176)
			(xy 68.359274 -349.690944) (xy 68.365624 -349.68688) (xy 68.366132 -349.686372) (xy 68.378324 -349.678752)
			(xy 68.621148 -349.678752) (xy 68.631324 -349.679235) (xy 68.650132 -349.68701) (xy 68.664556 -349.701368)
			(xy 68.672418 -349.720141) (xy 68.672964 -349.730314) (xy 68.672964 -350.466914) (xy 70.481952 -350.466914)
			(xy 70.481952 -349.730314) (xy 70.482381 -349.72011) (xy 70.490212 -349.701264) (xy 70.504678 -349.686869)
			(xy 70.523562 -349.679131) (xy 70.533768 -349.678752) (xy 70.776592 -349.678752) (xy 71.106284 -349.894906)
			(xy 71.117329 -349.90039) (xy 71.141952 -349.90106) (xy 71.153274 -349.896176) (xy 71.468234 -349.690944)
			(xy 71.474584 -349.68688) (xy 71.475092 -349.686372) (xy 71.487284 -349.678752) (xy 71.730108 -349.678752)
			(xy 71.740281 -349.679268) (xy 71.759088 -349.68703) (xy 71.773514 -349.701378) (xy 71.781377 -349.720144)
			(xy 71.781924 -349.730314) (xy 71.781924 -350.466914) (xy 73.590912 -350.466914) (xy 73.590912 -349.730314)
			(xy 73.59138 -349.720115) (xy 73.599203 -349.701277) (xy 73.613657 -349.686883) (xy 73.632527 -349.679138)
			(xy 73.642728 -349.678752) (xy 73.885552 -349.678752) (xy 74.215244 -349.894906) (xy 74.226274 -349.90043)
			(xy 74.250911 -349.901075) (xy 74.262234 -349.896176) (xy 74.577194 -349.690944) (xy 74.583544 -349.68688)
			(xy 74.584052 -349.686372) (xy 74.596244 -349.678752) (xy 74.839068 -349.678752) (xy 74.849239 -349.6793)
			(xy 74.868045 -349.687049) (xy 74.882472 -349.701388) (xy 74.890337 -349.720147) (xy 74.890884 -349.730314)
			(xy 74.890884 -350.466914) (xy 76.699872 -350.466914) (xy 76.699872 -349.730314) (xy 76.700281 -349.720107)
			(xy 76.708116 -349.701258) (xy 76.722588 -349.686862) (xy 76.741479 -349.679128) (xy 76.751688 -349.678752)
			(xy 76.994512 -349.678752) (xy 77.324204 -349.894906) (xy 77.335244 -349.900403) (xy 77.359871 -349.901065)
			(xy 77.371194 -349.896176) (xy 77.686154 -349.690944) (xy 77.692504 -349.68688) (xy 77.693012 -349.686372)
			(xy 77.705204 -349.678752) (xy 77.948028 -349.678752) (xy 77.958202 -349.679251) (xy 77.97701 -349.68702)
			(xy 77.991435 -349.701373) (xy 77.999298 -349.720142) (xy 77.999844 -349.730314) (xy 77.999844 -350.466914)
			(xy 79.808832 -350.466914) (xy 79.808832 -349.730314) (xy 79.809281 -349.720112) (xy 79.817107 -349.70127)
			(xy 79.831567 -349.686876) (xy 79.850445 -349.679135) (xy 79.860648 -349.678752) (xy 80.103472 -349.678752)
			(xy 80.433164 -349.894906) (xy 80.444214 -349.900376) (xy 80.468832 -349.901056) (xy 80.480154 -349.896176)
			(xy 80.795114 -349.690944) (xy 80.801464 -349.68688) (xy 80.801972 -349.686372) (xy 80.814164 -349.678752)
			(xy 81.056988 -349.678752) (xy 81.06716 -349.679284) (xy 81.085967 -349.68704) (xy 81.100393 -349.701383)
			(xy 81.108257 -349.720145) (xy 81.108804 -349.730314) (xy 81.108804 -350.466914) (xy 82.917792 -350.466914)
			(xy 82.917792 -349.730314) (xy 82.91828 -349.720117) (xy 82.926099 -349.701283) (xy 82.940546 -349.68689)
			(xy 82.95941 -349.679142) (xy 82.969608 -349.678752) (xy 83.212432 -349.678752) (xy 83.542124 -349.894906)
			(xy 83.553159 -349.900417) (xy 83.577791 -349.90107) (xy 83.589114 -349.896176) (xy 83.904074 -349.690944)
			(xy 83.910424 -349.68688) (xy 83.910932 -349.686372) (xy 83.923124 -349.678752) (xy 84.165948 -349.678752)
			(xy 84.176124 -349.679235) (xy 84.194932 -349.68701) (xy 84.209356 -349.701368) (xy 84.217218 -349.720141)
			(xy 84.217764 -349.730314) (xy 84.217764 -350.466914) (xy 86.026752 -350.466914) (xy 86.026752 -349.730314)
			(xy 86.027181 -349.72011) (xy 86.035012 -349.701264) (xy 86.049478 -349.686869) (xy 86.068362 -349.679131)
			(xy 86.078568 -349.678752) (xy 86.321392 -349.678752) (xy 86.651084 -349.894906) (xy 86.662129 -349.90039)
			(xy 86.686752 -349.90106) (xy 86.698074 -349.896176) (xy 87.013034 -349.690944) (xy 87.019384 -349.68688)
			(xy 87.019892 -349.686372) (xy 87.032084 -349.678752) (xy 87.274908 -349.678752) (xy 87.285081 -349.679268)
			(xy 87.303888 -349.68703) (xy 87.318314 -349.701378) (xy 87.326177 -349.720144) (xy 87.326724 -349.730314)
			(xy 87.326724 -350.466914) (xy 89.135712 -350.466914) (xy 89.135712 -349.730314) (xy 89.13618 -349.720115)
			(xy 89.144003 -349.701277) (xy 89.158457 -349.686883) (xy 89.177327 -349.679138) (xy 89.187528 -349.678752)
			(xy 89.430352 -349.678752) (xy 89.760044 -349.894906) (xy 89.771074 -349.90043) (xy 89.795711 -349.901075)
			(xy 89.807034 -349.896176) (xy 90.121994 -349.690944) (xy 90.128344 -349.68688) (xy 90.128852 -349.686372)
			(xy 90.141044 -349.678752) (xy 90.383868 -349.678752) (xy 90.394039 -349.6793) (xy 90.412845 -349.687049)
			(xy 90.427272 -349.701388) (xy 90.435137 -349.720147) (xy 90.435684 -349.730314) (xy 90.435684 -350.466914)
			(xy 92.244672 -350.466914) (xy 92.244672 -349.730314) (xy 92.245081 -349.720107) (xy 92.252916 -349.701258)
			(xy 92.267388 -349.686862) (xy 92.286279 -349.679128) (xy 92.296488 -349.678752) (xy 92.539312 -349.678752)
			(xy 92.869004 -349.894906) (xy 92.880044 -349.900403) (xy 92.904671 -349.901065) (xy 92.915994 -349.896176)
			(xy 93.230954 -349.690944) (xy 93.237304 -349.68688) (xy 93.237812 -349.686372) (xy 93.250004 -349.678752)
			(xy 93.492828 -349.678752) (xy 93.503002 -349.679251) (xy 93.52181 -349.68702) (xy 93.536235 -349.701373)
			(xy 93.544098 -349.720142) (xy 93.544644 -349.730314) (xy 93.544644 -350.466914) (xy 111.645192 -350.466914)
			(xy 111.645192 -349.730314) (xy 111.645744 -349.720163) (xy 111.653505 -349.701403) (xy 111.667852 -349.687039)
			(xy 111.686603 -349.679255) (xy 111.696754 -349.678752) (xy 111.939578 -349.678752) (xy 112.26927 -349.894906)
			(xy 112.280319 -349.90038) (xy 112.304938 -349.901057) (xy 112.31626 -349.896176) (xy 112.63122 -349.690944)
			(xy 112.63757 -349.68688) (xy 112.638078 -349.686372) (xy 112.65027 -349.678752) (xy 112.893094 -349.678752)
			(xy 112.903267 -349.679169) (xy 112.922064 -349.686955) (xy 112.93645 -349.701342) (xy 112.944233 -349.720141)
			(xy 112.944656 -349.730314) (xy 112.944656 -350.466914) (xy 114.754152 -350.466914) (xy 114.754152 -349.730314)
			(xy 114.754575 -349.720142) (xy 114.762359 -349.701344) (xy 114.776744 -349.686959) (xy 114.795542 -349.679175)
			(xy 114.805714 -349.678752) (xy 115.048538 -349.678752) (xy 115.37823 -349.894906) (xy 115.389263 -349.900421)
			(xy 115.413897 -349.901072) (xy 115.42522 -349.896176) (xy 115.74018 -349.690944) (xy 115.74653 -349.68688)
			(xy 115.747038 -349.686372) (xy 115.75923 -349.678752) (xy 116.002054 -349.678752) (xy 116.012224 -349.679202)
			(xy 116.031021 -349.686974) (xy 116.045408 -349.701352) (xy 116.053192 -349.720144) (xy 116.053616 -349.730314)
			(xy 116.053616 -350.466914) (xy 117.863112 -350.466914) (xy 117.863112 -349.730314) (xy 117.863644 -349.72016)
			(xy 117.871409 -349.701396) (xy 117.885763 -349.687032) (xy 117.904521 -349.679252) (xy 117.914674 -349.678752)
			(xy 118.157498 -349.678752) (xy 118.48719 -349.894906) (xy 118.498233 -349.900394) (xy 118.522858 -349.901062)
			(xy 118.53418 -349.896176) (xy 118.84914 -349.690944) (xy 118.85549 -349.68688) (xy 118.855998 -349.686372)
			(xy 118.86819 -349.678752) (xy 119.111014 -349.678752) (xy 119.121174 -349.679222) (xy 119.139946 -349.687004)
			(xy 119.154312 -349.701377) (xy 119.162083 -349.720153) (xy 119.162576 -349.730314) (xy 119.162576 -350.466914)
			(xy 120.972072 -350.466914) (xy 120.972072 -349.730314) (xy 120.972476 -349.720139) (xy 120.980263 -349.701338)
			(xy 120.994655 -349.686951) (xy 121.013459 -349.679172) (xy 121.023634 -349.678752) (xy 121.266458 -349.678752)
			(xy 121.59615 -349.894906) (xy 121.607204 -349.900367) (xy 121.631818 -349.901052) (xy 121.64314 -349.896176)
			(xy 121.9581 -349.690944) (xy 121.96445 -349.68688) (xy 121.964958 -349.686372) (xy 121.97715 -349.678752)
			(xy 122.219974 -349.678752) (xy 122.230146 -349.679186) (xy 122.248942 -349.686965) (xy 122.263329 -349.701348)
			(xy 122.271112 -349.720142) (xy 122.271536 -349.730314) (xy 122.271536 -350.466914) (xy 124.081032 -350.466914)
			(xy 124.081032 -349.730314) (xy 124.081475 -349.720144) (xy 124.089254 -349.701351) (xy 124.103634 -349.686966)
			(xy 124.122424 -349.679179) (xy 124.132594 -349.678752) (xy 124.375418 -349.678752) (xy 124.70511 -349.894906)
			(xy 124.716148 -349.900407) (xy 124.740777 -349.901067) (xy 124.7521 -349.896176) (xy 125.06706 -349.690944)
			(xy 125.07341 -349.68688) (xy 125.073918 -349.686372) (xy 125.08611 -349.678752) (xy 125.328934 -349.678752)
			(xy 125.339096 -349.679206) (xy 125.357868 -349.686994) (xy 125.372233 -349.701372) (xy 125.380004 -349.720152)
			(xy 125.380496 -349.730314) (xy 125.380496 -350.466914) (xy 127.189992 -350.466914) (xy 127.189992 -349.730314)
			(xy 127.190544 -349.720163) (xy 127.198305 -349.701403) (xy 127.212652 -349.687039) (xy 127.231403 -349.679255)
			(xy 127.241554 -349.678752) (xy 127.484378 -349.678752) (xy 127.81407 -349.894906) (xy 127.825119 -349.90038)
			(xy 127.849738 -349.901057) (xy 127.86106 -349.896176) (xy 128.17602 -349.690944) (xy 128.18237 -349.68688)
			(xy 128.182878 -349.686372) (xy 128.19507 -349.678752) (xy 128.437894 -349.678752) (xy 128.448067 -349.679169)
			(xy 128.466864 -349.686955) (xy 128.48125 -349.701342) (xy 128.489033 -349.720141) (xy 128.489456 -349.730314)
			(xy 128.489456 -350.466914) (xy 130.298952 -350.466914) (xy 130.298952 -349.730314) (xy 130.299375 -349.720142)
			(xy 130.307159 -349.701344) (xy 130.321544 -349.686959) (xy 130.340342 -349.679175) (xy 130.350514 -349.678752)
			(xy 130.593338 -349.678752) (xy 130.92303 -349.894906) (xy 130.934063 -349.900421) (xy 130.958697 -349.901072)
			(xy 130.97002 -349.896176) (xy 131.28498 -349.690944) (xy 131.29133 -349.68688) (xy 131.291838 -349.686372)
			(xy 131.30403 -349.678752) (xy 131.546854 -349.678752) (xy 131.557024 -349.679202) (xy 131.575821 -349.686974)
			(xy 131.590208 -349.701352) (xy 131.597992 -349.720144) (xy 131.598416 -349.730314) (xy 131.598416 -350.466914)
			(xy 133.407912 -350.466914) (xy 133.407912 -349.730314) (xy 133.408444 -349.72016) (xy 133.416209 -349.701396)
			(xy 133.430563 -349.687032) (xy 133.449321 -349.679252) (xy 133.459474 -349.678752) (xy 133.702298 -349.678752)
			(xy 134.03199 -349.894906) (xy 134.043033 -349.900394) (xy 134.067658 -349.901062) (xy 134.07898 -349.896176)
			(xy 134.39394 -349.690944) (xy 134.40029 -349.68688) (xy 134.400798 -349.686372) (xy 134.41299 -349.678752)
			(xy 134.655814 -349.678752) (xy 134.665974 -349.679222) (xy 134.684746 -349.687004) (xy 134.699112 -349.701377)
			(xy 134.706883 -349.720153) (xy 134.707376 -349.730314) (xy 134.707376 -350.466914) (xy 136.516872 -350.466914)
			(xy 136.516872 -349.730314) (xy 136.517276 -349.720139) (xy 136.525063 -349.701338) (xy 136.539455 -349.686951)
			(xy 136.558259 -349.679172) (xy 136.568434 -349.678752) (xy 136.811258 -349.678752) (xy 137.14095 -349.894906)
			(xy 137.152004 -349.900367) (xy 137.176618 -349.901052) (xy 137.18794 -349.896176) (xy 137.5029 -349.690944)
			(xy 137.50925 -349.68688) (xy 137.509758 -349.686372) (xy 137.52195 -349.678752) (xy 137.764774 -349.678752)
			(xy 137.774946 -349.679186) (xy 137.793742 -349.686965) (xy 137.808129 -349.701348) (xy 137.815912 -349.720142)
			(xy 137.816336 -349.730314) (xy 137.816336 -350.466914) (xy 139.625832 -350.466914) (xy 139.625832 -349.730314)
			(xy 139.626275 -349.720144) (xy 139.634054 -349.701351) (xy 139.648434 -349.686966) (xy 139.667224 -349.679179)
			(xy 139.677394 -349.678752) (xy 139.920218 -349.678752) (xy 140.24991 -349.894906) (xy 140.260948 -349.900407)
			(xy 140.285577 -349.901067) (xy 140.2969 -349.896176) (xy 140.61186 -349.690944) (xy 140.61821 -349.68688)
			(xy 140.618718 -349.686372) (xy 140.63091 -349.678752) (xy 140.873734 -349.678752) (xy 140.883896 -349.679206)
			(xy 140.902668 -349.686994) (xy 140.917033 -349.701372) (xy 140.924804 -349.720152) (xy 140.925296 -349.730314)
			(xy 140.925296 -350.466914) (xy 142.734792 -350.466914) (xy 142.734792 -349.730314) (xy 142.735344 -349.720163)
			(xy 142.743105 -349.701403) (xy 142.757452 -349.687039) (xy 142.776203 -349.679255) (xy 142.786354 -349.678752)
			(xy 143.029178 -349.678752) (xy 143.35887 -349.894906) (xy 143.369919 -349.90038) (xy 143.394538 -349.901057)
			(xy 143.40586 -349.896176) (xy 143.72082 -349.690944) (xy 143.72717 -349.68688) (xy 143.727678 -349.686372)
			(xy 143.73987 -349.678752) (xy 143.982694 -349.678752) (xy 143.992867 -349.679169) (xy 144.011664 -349.686955)
			(xy 144.02605 -349.701342) (xy 144.033833 -349.720141) (xy 144.034256 -349.730314) (xy 144.034256 -350.466914)
			(xy 161.969196 -350.466914) (xy 161.969196 -349.730314) (xy 161.969744 -349.720162) (xy 161.977506 -349.701401)
			(xy 161.991854 -349.687037) (xy 162.010607 -349.679255) (xy 162.020758 -349.678752) (xy 162.263582 -349.678752)
			(xy 162.593274 -349.894906) (xy 162.604322 -349.900383) (xy 162.628942 -349.901058) (xy 162.640264 -349.896176)
			(xy 162.955224 -349.690944) (xy 162.961574 -349.68688) (xy 162.962082 -349.686372) (xy 162.974274 -349.678752)
			(xy 163.217098 -349.678752) (xy 163.227271 -349.679166) (xy 163.246069 -349.686953) (xy 163.260454 -349.701342)
			(xy 163.268237 -349.720141) (xy 163.26866 -349.730314) (xy 163.26866 -350.466914) (xy 165.078156 -350.466914)
			(xy 165.078156 -349.730314) (xy 165.078576 -349.720141) (xy 165.086359 -349.701343) (xy 165.100746 -349.686957)
			(xy 165.119545 -349.679175) (xy 165.129718 -349.678752) (xy 165.372542 -349.678752) (xy 165.702234 -349.894906)
			(xy 165.713266 -349.900423) (xy 165.737901 -349.901073) (xy 165.749224 -349.896176) (xy 166.064184 -349.690944)
			(xy 166.070534 -349.68688) (xy 166.071042 -349.686372) (xy 166.083234 -349.678752) (xy 166.326058 -349.678752)
			(xy 166.336229 -349.679199) (xy 166.355025 -349.686972) (xy 166.369412 -349.701351) (xy 166.377196 -349.720144)
			(xy 166.37762 -349.730314) (xy 166.37762 -350.466914) (xy 168.187116 -350.466914) (xy 168.187116 -349.730314)
			(xy 168.187644 -349.72016) (xy 168.19541 -349.701395) (xy 168.209765 -349.68703) (xy 168.228524 -349.679251)
			(xy 168.238678 -349.678752) (xy 168.481502 -349.678752) (xy 168.811194 -349.894906) (xy 168.822236 -349.900396)
			(xy 168.846862 -349.901063) (xy 168.858184 -349.896176) (xy 169.173144 -349.690944) (xy 169.179494 -349.68688)
			(xy 169.180002 -349.686372) (xy 169.192194 -349.678752) (xy 169.435018 -349.678752) (xy 169.445179 -349.679219)
			(xy 169.463951 -349.687002) (xy 169.478316 -349.701376) (xy 169.486088 -349.720153) (xy 169.48658 -349.730314)
			(xy 169.48658 -350.466914) (xy 171.296076 -350.466914) (xy 171.296076 -349.730314) (xy 171.296476 -349.720139)
			(xy 171.304264 -349.701337) (xy 171.318657 -349.68695) (xy 171.337462 -349.679171) (xy 171.347638 -349.678752)
			(xy 171.590462 -349.678752) (xy 171.920154 -349.894906) (xy 171.931207 -349.90037) (xy 171.955822 -349.901053)
			(xy 171.967144 -349.896176) (xy 172.282104 -349.690944) (xy 172.288454 -349.68688) (xy 172.288962 -349.686372)
			(xy 172.301154 -349.678752) (xy 172.543978 -349.678752) (xy 172.55415 -349.679182) (xy 172.572947 -349.686963)
			(xy 172.587333 -349.701347) (xy 172.595116 -349.720142) (xy 172.59554 -349.730314) (xy 172.59554 -350.466914)
			(xy 174.405036 -350.466914) (xy 174.405036 -349.730314) (xy 174.405475 -349.720144) (xy 174.413255 -349.701349)
			(xy 174.427636 -349.686964) (xy 174.446428 -349.679178) (xy 174.456598 -349.678752) (xy 174.699422 -349.678752)
			(xy 175.029114 -349.894906) (xy 175.040151 -349.90041) (xy 175.064781 -349.901068) (xy 175.076104 -349.896176)
			(xy 175.391064 -349.690944) (xy 175.397414 -349.68688) (xy 175.397922 -349.686372) (xy 175.410114 -349.678752)
			(xy 175.652938 -349.678752) (xy 175.6631 -349.679203) (xy 175.681873 -349.686992) (xy 175.696237 -349.701371)
			(xy 175.704008 -349.720152) (xy 175.7045 -349.730314) (xy 175.7045 -350.466914) (xy 177.513996 -350.466914)
			(xy 177.513996 -349.730314) (xy 177.514544 -349.720162) (xy 177.522306 -349.701401) (xy 177.536654 -349.687037)
			(xy 177.555407 -349.679255) (xy 177.565558 -349.678752) (xy 177.808382 -349.678752) (xy 178.138074 -349.894906)
			(xy 178.149122 -349.900383) (xy 178.173742 -349.901058) (xy 178.185064 -349.896176) (xy 178.500024 -349.690944)
			(xy 178.506374 -349.68688) (xy 178.506882 -349.686372) (xy 178.519074 -349.678752) (xy 178.761898 -349.678752)
			(xy 178.772071 -349.679166) (xy 178.790869 -349.686953) (xy 178.805254 -349.701342) (xy 178.813037 -349.720141)
			(xy 178.81346 -349.730314) (xy 178.81346 -350.466914) (xy 180.622956 -350.466914) (xy 180.622956 -349.730314)
			(xy 180.623376 -349.720141) (xy 180.631159 -349.701343) (xy 180.645546 -349.686957) (xy 180.664345 -349.679175)
			(xy 180.674518 -349.678752) (xy 180.917342 -349.678752) (xy 181.247034 -349.894906) (xy 181.258066 -349.900423)
			(xy 181.282701 -349.901073) (xy 181.294024 -349.896176) (xy 181.608984 -349.690944) (xy 181.615334 -349.68688)
			(xy 181.615842 -349.686372) (xy 181.628034 -349.678752) (xy 181.870858 -349.678752) (xy 181.881029 -349.679199)
			(xy 181.899825 -349.686972) (xy 181.914212 -349.701351) (xy 181.921996 -349.720144) (xy 181.92242 -349.730314)
			(xy 181.92242 -350.466914) (xy 183.731916 -350.466914) (xy 183.731916 -349.730314) (xy 183.732444 -349.72016)
			(xy 183.74021 -349.701395) (xy 183.754565 -349.68703) (xy 183.773324 -349.679251) (xy 183.783478 -349.678752)
			(xy 184.026302 -349.678752) (xy 184.355994 -349.894906) (xy 184.367036 -349.900396) (xy 184.391662 -349.901063)
			(xy 184.402984 -349.896176) (xy 184.717944 -349.690944) (xy 184.724294 -349.68688) (xy 184.724802 -349.686372)
			(xy 184.736994 -349.678752) (xy 184.979818 -349.678752) (xy 184.989979 -349.679219) (xy 185.008751 -349.687002)
			(xy 185.023116 -349.701376) (xy 185.030888 -349.720153) (xy 185.03138 -349.730314) (xy 185.03138 -350.466914)
			(xy 186.840876 -350.466914) (xy 186.840876 -349.730314) (xy 186.841276 -349.720139) (xy 186.849064 -349.701337)
			(xy 186.863457 -349.68695) (xy 186.882262 -349.679171) (xy 186.892438 -349.678752) (xy 187.135262 -349.678752)
			(xy 187.464954 -349.894906) (xy 187.476007 -349.90037) (xy 187.500622 -349.901053) (xy 187.511944 -349.896176)
			(xy 187.826904 -349.690944) (xy 187.833254 -349.68688) (xy 187.833762 -349.686372) (xy 187.845954 -349.678752)
			(xy 188.088778 -349.678752) (xy 188.09895 -349.679182) (xy 188.117747 -349.686963) (xy 188.132133 -349.701347)
			(xy 188.139916 -349.720142) (xy 188.14034 -349.730314) (xy 188.14034 -350.466914) (xy 189.949836 -350.466914)
			(xy 189.949836 -349.730314) (xy 189.950275 -349.720144) (xy 189.958055 -349.701349) (xy 189.972436 -349.686964)
			(xy 189.991228 -349.679178) (xy 190.001398 -349.678752) (xy 190.244222 -349.678752) (xy 190.573914 -349.894906)
			(xy 190.584951 -349.90041) (xy 190.609581 -349.901068) (xy 190.620904 -349.896176) (xy 190.935864 -349.690944)
			(xy 190.942214 -349.68688) (xy 190.942722 -349.686372) (xy 190.954914 -349.678752) (xy 191.197738 -349.678752)
			(xy 191.2079 -349.679203) (xy 191.226673 -349.686992) (xy 191.241037 -349.701371) (xy 191.248808 -349.720152)
			(xy 191.2493 -349.730314) (xy 191.2493 -350.466914) (xy 193.058796 -350.466914) (xy 193.058796 -349.730314)
			(xy 193.059344 -349.720162) (xy 193.067106 -349.701401) (xy 193.081454 -349.687037) (xy 193.100207 -349.679255)
			(xy 193.110358 -349.678752) (xy 193.353182 -349.678752) (xy 193.682874 -349.894906) (xy 193.693922 -349.900383)
			(xy 193.718542 -349.901058) (xy 193.729864 -349.896176) (xy 194.044824 -349.690944) (xy 194.051174 -349.68688)
			(xy 194.051682 -349.686372) (xy 194.063874 -349.678752) (xy 194.306698 -349.678752) (xy 194.316871 -349.679166)
			(xy 194.335669 -349.686953) (xy 194.350054 -349.701342) (xy 194.357837 -349.720141) (xy 194.35826 -349.730314)
			(xy 194.35826 -350.466914) (xy 267.679932 -350.466914) (xy 267.679932 -349.730314) (xy 267.680381 -349.720112)
			(xy 267.688207 -349.70127) (xy 267.702667 -349.686876) (xy 267.721545 -349.679135) (xy 267.731748 -349.678752)
			(xy 267.974572 -349.678752) (xy 268.304264 -349.894906) (xy 268.315314 -349.900376) (xy 268.339932 -349.901056)
			(xy 268.351254 -349.896176) (xy 268.666214 -349.690944) (xy 268.672564 -349.68688) (xy 268.673072 -349.686372)
			(xy 268.685264 -349.678752) (xy 268.928088 -349.678752) (xy 268.93826 -349.679284) (xy 268.957067 -349.68704)
			(xy 268.971493 -349.701383) (xy 268.979357 -349.720145) (xy 268.979904 -349.730314) (xy 268.979904 -350.466914)
			(xy 270.788892 -350.466914) (xy 270.788892 -349.730314) (xy 270.78938 -349.720117) (xy 270.797199 -349.701283)
			(xy 270.811646 -349.68689) (xy 270.83051 -349.679142) (xy 270.840708 -349.678752) (xy 271.083532 -349.678752)
			(xy 271.413224 -349.894906) (xy 271.424259 -349.900417) (xy 271.448891 -349.90107) (xy 271.460214 -349.896176)
			(xy 271.775174 -349.690944) (xy 271.781524 -349.68688) (xy 271.782032 -349.686372) (xy 271.794224 -349.678752)
			(xy 272.037048 -349.678752) (xy 272.047224 -349.679235) (xy 272.066032 -349.68701) (xy 272.080456 -349.701368)
			(xy 272.088318 -349.720141) (xy 272.088864 -349.730314) (xy 272.088864 -350.466914) (xy 273.897852 -350.466914)
			(xy 273.897852 -349.730314) (xy 273.898281 -349.72011) (xy 273.906112 -349.701264) (xy 273.920578 -349.686869)
			(xy 273.939462 -349.679131) (xy 273.949668 -349.678752) (xy 274.192492 -349.678752) (xy 274.522184 -349.894906)
			(xy 274.533229 -349.90039) (xy 274.557852 -349.90106) (xy 274.569174 -349.896176) (xy 274.884134 -349.690944)
			(xy 274.890484 -349.68688) (xy 274.890992 -349.686372) (xy 274.903184 -349.678752) (xy 275.146008 -349.678752)
			(xy 275.156181 -349.679268) (xy 275.174988 -349.68703) (xy 275.189414 -349.701378) (xy 275.197277 -349.720144)
			(xy 275.197824 -349.730314) (xy 275.197824 -350.466914) (xy 277.006812 -350.466914) (xy 277.006812 -349.730314)
			(xy 277.00728 -349.720115) (xy 277.015103 -349.701277) (xy 277.029557 -349.686883) (xy 277.048427 -349.679138)
			(xy 277.058628 -349.678752) (xy 277.301452 -349.678752) (xy 277.631144 -349.894906) (xy 277.642174 -349.90043)
			(xy 277.666811 -349.901075) (xy 277.678134 -349.896176) (xy 277.993094 -349.690944) (xy 277.999444 -349.68688)
			(xy 277.999952 -349.686372) (xy 278.012144 -349.678752) (xy 278.254968 -349.678752) (xy 278.265139 -349.6793)
			(xy 278.283945 -349.687049) (xy 278.298372 -349.701388) (xy 278.306237 -349.720147) (xy 278.306784 -349.730314)
			(xy 278.306784 -350.466914) (xy 280.115772 -350.466914) (xy 280.115772 -349.730314) (xy 280.116181 -349.720107)
			(xy 280.124016 -349.701258) (xy 280.138488 -349.686862) (xy 280.157379 -349.679128) (xy 280.167588 -349.678752)
			(xy 280.410412 -349.678752) (xy 280.740104 -349.894906) (xy 280.751144 -349.900403) (xy 280.775771 -349.901065)
			(xy 280.787094 -349.896176) (xy 281.102054 -349.690944) (xy 281.108404 -349.68688) (xy 281.108912 -349.686372)
			(xy 281.121104 -349.678752) (xy 281.363928 -349.678752) (xy 281.374102 -349.679251) (xy 281.39291 -349.68702)
			(xy 281.407335 -349.701373) (xy 281.415198 -349.720142) (xy 281.415744 -349.730314) (xy 281.415744 -350.466914)
			(xy 283.224732 -350.466914) (xy 283.224732 -349.730314) (xy 283.225181 -349.720112) (xy 283.233007 -349.70127)
			(xy 283.247467 -349.686876) (xy 283.266345 -349.679135) (xy 283.276548 -349.678752) (xy 283.519372 -349.678752)
			(xy 283.849064 -349.894906) (xy 283.860114 -349.900376) (xy 283.884732 -349.901056) (xy 283.896054 -349.896176)
			(xy 284.211014 -349.690944) (xy 284.217364 -349.68688) (xy 284.217872 -349.686372) (xy 284.230064 -349.678752)
			(xy 284.472888 -349.678752) (xy 284.48306 -349.679284) (xy 284.501867 -349.68704) (xy 284.516293 -349.701383)
			(xy 284.524157 -349.720145) (xy 284.524704 -349.730314) (xy 284.524704 -350.466914) (xy 286.333692 -350.466914)
			(xy 286.333692 -349.730314) (xy 286.33418 -349.720117) (xy 286.341999 -349.701283) (xy 286.356446 -349.68689)
			(xy 286.37531 -349.679142) (xy 286.385508 -349.678752) (xy 286.628332 -349.678752) (xy 286.958024 -349.894906)
			(xy 286.969059 -349.900417) (xy 286.993691 -349.90107) (xy 287.005014 -349.896176) (xy 287.319974 -349.690944)
			(xy 287.326324 -349.68688) (xy 287.326832 -349.686372) (xy 287.339024 -349.678752) (xy 287.581848 -349.678752)
			(xy 287.592024 -349.679235) (xy 287.610832 -349.68701) (xy 287.625256 -349.701368) (xy 287.633118 -349.720141)
			(xy 287.633664 -349.730314) (xy 287.633664 -350.466914) (xy 289.442652 -350.466914) (xy 289.442652 -349.730314)
			(xy 289.443081 -349.72011) (xy 289.450912 -349.701264) (xy 289.465378 -349.686869) (xy 289.484262 -349.679131)
			(xy 289.494468 -349.678752) (xy 289.737292 -349.678752) (xy 290.066984 -349.894906) (xy 290.078029 -349.90039)
			(xy 290.102652 -349.90106) (xy 290.113974 -349.896176) (xy 290.428934 -349.690944) (xy 290.435284 -349.68688)
			(xy 290.435792 -349.686372) (xy 290.447984 -349.678752) (xy 290.690808 -349.678752) (xy 290.700981 -349.679268)
			(xy 290.719788 -349.68703) (xy 290.734214 -349.701378) (xy 290.742077 -349.720144) (xy 290.742624 -349.730314)
			(xy 290.742624 -350.466914) (xy 292.551612 -350.466914) (xy 292.551612 -349.730314) (xy 292.55208 -349.720115)
			(xy 292.559903 -349.701277) (xy 292.574357 -349.686883) (xy 292.593227 -349.679138) (xy 292.603428 -349.678752)
			(xy 292.846252 -349.678752) (xy 293.175944 -349.894906) (xy 293.186974 -349.90043) (xy 293.211611 -349.901075)
			(xy 293.222934 -349.896176) (xy 293.537894 -349.690944) (xy 293.544244 -349.68688) (xy 293.544752 -349.686372)
			(xy 293.556944 -349.678752) (xy 293.799768 -349.678752) (xy 293.809939 -349.6793) (xy 293.828745 -349.687049)
			(xy 293.843172 -349.701388) (xy 293.851037 -349.720147) (xy 293.851584 -349.730314) (xy 293.851584 -350.466914)
			(xy 295.660572 -350.466914) (xy 295.660572 -349.730314) (xy 295.660981 -349.720107) (xy 295.668816 -349.701258)
			(xy 295.683288 -349.686862) (xy 295.702179 -349.679128) (xy 295.712388 -349.678752) (xy 295.955212 -349.678752)
			(xy 296.284904 -349.894906) (xy 296.295944 -349.900403) (xy 296.320571 -349.901065) (xy 296.331894 -349.896176)
			(xy 296.646854 -349.690944) (xy 296.653204 -349.68688) (xy 296.653712 -349.686372) (xy 296.665904 -349.678752)
			(xy 296.908728 -349.678752) (xy 296.918902 -349.679251) (xy 296.93771 -349.68702) (xy 296.952135 -349.701373)
			(xy 296.959998 -349.720142) (xy 296.960544 -349.730314) (xy 296.960544 -350.466914) (xy 298.769532 -350.466914)
			(xy 298.769532 -349.730314) (xy 298.769981 -349.720112) (xy 298.777807 -349.70127) (xy 298.792267 -349.686876)
			(xy 298.811145 -349.679135) (xy 298.821348 -349.678752) (xy 299.064172 -349.678752) (xy 299.393864 -349.894906)
			(xy 299.404914 -349.900376) (xy 299.429532 -349.901056) (xy 299.440854 -349.896176) (xy 299.755814 -349.690944)
			(xy 299.762164 -349.68688) (xy 299.762672 -349.686372) (xy 299.774864 -349.678752) (xy 300.017688 -349.678752)
			(xy 300.02786 -349.679284) (xy 300.046667 -349.68704) (xy 300.061093 -349.701383) (xy 300.068957 -349.720145)
			(xy 300.069504 -349.730314) (xy 300.069504 -350.466914) (xy 312.285888 -350.466914) (xy 312.285888 -349.730314)
			(xy 312.286276 -349.720137) (xy 312.294066 -349.701333) (xy 312.308463 -349.686946) (xy 312.327273 -349.679169)
			(xy 312.33745 -349.678752) (xy 312.580274 -349.678752) (xy 312.909966 -349.894906) (xy 312.921016 -349.900378)
			(xy 312.945634 -349.901056) (xy 312.956956 -349.896176) (xy 313.271916 -349.690944) (xy 313.278266 -349.68688)
			(xy 313.278774 -349.686372) (xy 313.290966 -349.678752) (xy 313.53379 -349.678752) (xy 313.543963 -349.679172)
			(xy 313.56276 -349.686957) (xy 313.577146 -349.701343) (xy 313.584929 -349.720141) (xy 313.585352 -349.730314)
			(xy 313.585352 -350.466914) (xy 315.394848 -350.466914) (xy 315.394848 -349.730314) (xy 315.395275 -349.720142)
			(xy 315.403058 -349.701346) (xy 315.417442 -349.68696) (xy 315.436238 -349.679176) (xy 315.44641 -349.678752)
			(xy 315.689234 -349.678752) (xy 316.018926 -349.894906) (xy 316.02996 -349.900418) (xy 316.054593 -349.901071)
			(xy 316.065916 -349.896176) (xy 316.380876 -349.690944) (xy 316.387226 -349.68688) (xy 316.387734 -349.686372)
			(xy 316.399926 -349.678752) (xy 316.64275 -349.678752) (xy 316.65292 -349.679205) (xy 316.671716 -349.686976)
			(xy 316.686104 -349.701353) (xy 316.693888 -349.720144) (xy 316.694312 -349.730314) (xy 316.694312 -350.466914)
			(xy 318.503808 -350.466914) (xy 318.503808 -349.730314) (xy 318.504344 -349.720161) (xy 318.512108 -349.701398)
			(xy 318.526461 -349.687033) (xy 318.545217 -349.679253) (xy 318.55537 -349.678752) (xy 318.798194 -349.678752)
			(xy 319.127886 -349.894906) (xy 319.13893 -349.900391) (xy 319.163554 -349.901061) (xy 319.174876 -349.896176)
			(xy 319.489836 -349.690944) (xy 319.496186 -349.68688) (xy 319.496694 -349.686372) (xy 319.508886 -349.678752)
			(xy 319.75171 -349.678752) (xy 319.761884 -349.679156) (xy 319.780682 -349.686947) (xy 319.795067 -349.701339)
			(xy 319.802849 -349.72014) (xy 319.803272 -349.730314) (xy 319.803272 -350.466914) (xy 321.612768 -350.466914)
			(xy 321.612768 -349.730314) (xy 321.613176 -349.72014) (xy 321.620962 -349.701339) (xy 321.635353 -349.686953)
			(xy 321.654155 -349.679173) (xy 321.66433 -349.678752) (xy 321.907154 -349.678752) (xy 322.236846 -349.894906)
			(xy 322.247901 -349.900365) (xy 322.272515 -349.901051) (xy 322.283836 -349.896176) (xy 322.598796 -349.690944)
			(xy 322.605146 -349.68688) (xy 322.605654 -349.686372) (xy 322.617846 -349.678752) (xy 322.86067 -349.678752)
			(xy 322.870841 -349.679189) (xy 322.889638 -349.686967) (xy 322.904024 -349.701349) (xy 322.911808 -349.720143)
			(xy 322.912232 -349.730314) (xy 322.912232 -350.466914) (xy 324.721728 -350.466914) (xy 324.721728 -349.730314)
			(xy 324.722175 -349.720144) (xy 324.729953 -349.701352) (xy 324.744332 -349.686967) (xy 324.763121 -349.67918)
			(xy 324.77329 -349.678752) (xy 325.016114 -349.678752) (xy 325.345806 -349.894906) (xy 325.356845 -349.900404)
			(xy 325.381473 -349.901065) (xy 325.392796 -349.896176) (xy 325.707756 -349.690944) (xy 325.714106 -349.68688)
			(xy 325.714614 -349.686372) (xy 325.726806 -349.678752) (xy 325.96963 -349.678752) (xy 325.979791 -349.679209)
			(xy 325.998564 -349.686996) (xy 326.012929 -349.701373) (xy 326.0207 -349.720152) (xy 326.021192 -349.730314)
			(xy 326.021192 -350.466914) (xy 327.830688 -350.466914) (xy 327.830688 -349.730314) (xy 327.831076 -349.720137)
			(xy 327.838866 -349.701333) (xy 327.853263 -349.686946) (xy 327.872073 -349.679169) (xy 327.88225 -349.678752)
			(xy 328.125074 -349.678752) (xy 328.454766 -349.894906) (xy 328.465816 -349.900378) (xy 328.490434 -349.901056)
			(xy 328.501756 -349.896176) (xy 328.816716 -349.690944) (xy 328.823066 -349.68688) (xy 328.823574 -349.686372)
			(xy 328.835766 -349.678752) (xy 329.07859 -349.678752) (xy 329.088763 -349.679172) (xy 329.10756 -349.686957)
			(xy 329.121946 -349.701343) (xy 329.129729 -349.720141) (xy 329.130152 -349.730314) (xy 329.130152 -350.466914)
			(xy 330.939648 -350.466914) (xy 330.939648 -349.730314) (xy 330.940075 -349.720142) (xy 330.947858 -349.701346)
			(xy 330.962242 -349.68696) (xy 330.981038 -349.679176) (xy 330.99121 -349.678752) (xy 331.234034 -349.678752)
			(xy 331.563726 -349.894906) (xy 331.57476 -349.900418) (xy 331.599393 -349.901071) (xy 331.610716 -349.896176)
			(xy 331.925676 -349.690944) (xy 331.932026 -349.68688) (xy 331.932534 -349.686372) (xy 331.944726 -349.678752)
			(xy 332.18755 -349.678752) (xy 332.19772 -349.679205) (xy 332.216516 -349.686976) (xy 332.230904 -349.701353)
			(xy 332.238688 -349.720144) (xy 332.239112 -349.730314) (xy 332.239112 -350.466914) (xy 334.048608 -350.466914)
			(xy 334.048608 -349.730314) (xy 334.049144 -349.720161) (xy 334.056908 -349.701398) (xy 334.071261 -349.687033)
			(xy 334.090017 -349.679253) (xy 334.10017 -349.678752) (xy 334.342994 -349.678752) (xy 334.672686 -349.894906)
			(xy 334.68373 -349.900391) (xy 334.708354 -349.901061) (xy 334.719676 -349.896176) (xy 335.034636 -349.690944)
			(xy 335.040986 -349.68688) (xy 335.041494 -349.686372) (xy 335.053686 -349.678752) (xy 335.29651 -349.678752)
			(xy 335.306684 -349.679156) (xy 335.325482 -349.686947) (xy 335.339867 -349.701339) (xy 335.347649 -349.72014)
			(xy 335.348072 -349.730314) (xy 335.348072 -350.466914) (xy 337.157568 -350.466914) (xy 337.157568 -349.730314)
			(xy 337.157976 -349.72014) (xy 337.165762 -349.701339) (xy 337.180153 -349.686953) (xy 337.198955 -349.679173)
			(xy 337.20913 -349.678752) (xy 337.451954 -349.678752) (xy 337.781646 -349.894906) (xy 337.792701 -349.900365)
			(xy 337.817315 -349.901051) (xy 337.828636 -349.896176) (xy 338.143596 -349.690944) (xy 338.149946 -349.68688)
			(xy 338.150454 -349.686372) (xy 338.162646 -349.678752) (xy 338.40547 -349.678752) (xy 338.415641 -349.679189)
			(xy 338.434438 -349.686967) (xy 338.448824 -349.701349) (xy 338.456608 -349.720143) (xy 338.457032 -349.730314)
			(xy 338.457032 -350.466914) (xy 340.266528 -350.466914) (xy 340.266528 -349.730314) (xy 340.266975 -349.720144)
			(xy 340.274753 -349.701352) (xy 340.289132 -349.686967) (xy 340.307921 -349.67918) (xy 340.31809 -349.678752)
			(xy 340.560914 -349.678752) (xy 340.890606 -349.894906) (xy 340.901645 -349.900404) (xy 340.926273 -349.901065)
			(xy 340.937596 -349.896176) (xy 341.252556 -349.690944) (xy 341.258906 -349.68688) (xy 341.259414 -349.686372)
			(xy 341.271606 -349.678752) (xy 341.51443 -349.678752) (xy 341.524591 -349.679209) (xy 341.543364 -349.686996)
			(xy 341.557729 -349.701373) (xy 341.5655 -349.720152) (xy 341.565992 -349.730314) (xy 341.565992 -350.466914)
			(xy 343.375488 -350.466914) (xy 343.375488 -349.730314) (xy 343.375876 -349.720137) (xy 343.383666 -349.701333)
			(xy 343.398063 -349.686946) (xy 343.416873 -349.679169) (xy 343.42705 -349.678752) (xy 343.669874 -349.678752)
			(xy 343.999566 -349.894906) (xy 344.010616 -349.900378) (xy 344.035234 -349.901056) (xy 344.046556 -349.896176)
			(xy 344.361516 -349.690944) (xy 344.367866 -349.68688) (xy 344.368374 -349.686372) (xy 344.380566 -349.678752)
			(xy 344.62339 -349.678752) (xy 344.633563 -349.679172) (xy 344.65236 -349.686957) (xy 344.666746 -349.701343)
			(xy 344.674529 -349.720141) (xy 344.674952 -349.730314) (xy 344.674952 -350.466914) (xy 370.971064 -350.466914)
			(xy 370.971064 -349.730314) (xy 370.971476 -349.72014) (xy 370.979261 -349.701341) (xy 370.993651 -349.686954)
			(xy 371.012452 -349.679173) (xy 371.022626 -349.678752) (xy 371.26545 -349.678752) (xy 371.595142 -349.894906)
			(xy 371.606172 -349.900429) (xy 371.630809 -349.901075) (xy 371.642132 -349.896176) (xy 371.957092 -349.690944)
			(xy 371.963442 -349.68688) (xy 371.96395 -349.686372) (xy 371.976142 -349.678752) (xy 372.218966 -349.678752)
			(xy 372.229137 -349.679192) (xy 372.247934 -349.686969) (xy 372.26232 -349.701349) (xy 372.270104 -349.720143)
			(xy 372.270528 -349.730314) (xy 372.270528 -350.466914) (xy 374.080024 -350.466914) (xy 374.080024 -349.730314)
			(xy 374.080544 -349.720159) (xy 374.088312 -349.701393) (xy 374.102669 -349.687027) (xy 374.121431 -349.67925)
			(xy 374.131586 -349.678752) (xy 374.37441 -349.678752) (xy 374.704102 -349.894906) (xy 374.715142 -349.900402)
			(xy 374.739769 -349.901065) (xy 374.751092 -349.896176) (xy 375.066052 -349.690944) (xy 375.072402 -349.68688)
			(xy 375.07291 -349.686372) (xy 375.085102 -349.678752) (xy 375.327926 -349.678752) (xy 375.338087 -349.679212)
			(xy 375.35686 -349.686998) (xy 375.371225 -349.701374) (xy 375.378996 -349.720152) (xy 375.379488 -349.730314)
			(xy 375.379488 -350.466914) (xy 377.188984 -350.466914) (xy 377.188984 -349.730314) (xy 377.189376 -349.720138)
			(xy 377.197165 -349.701334) (xy 377.211561 -349.686947) (xy 377.230369 -349.67917) (xy 377.240546 -349.678752)
			(xy 377.48337 -349.678752) (xy 377.813062 -349.894906) (xy 377.824113 -349.900375) (xy 377.84873 -349.901055)
			(xy 377.860052 -349.896176) (xy 378.175012 -349.690944) (xy 378.181362 -349.68688) (xy 378.18187 -349.686372)
			(xy 378.194062 -349.678752) (xy 378.436886 -349.678752) (xy 378.447058 -349.679175) (xy 378.465856 -349.686959)
			(xy 378.480241 -349.701344) (xy 378.488025 -349.720142) (xy 378.488448 -349.730314) (xy 378.488448 -350.466914)
			(xy 380.297944 -350.466914) (xy 380.297944 -349.730314) (xy 380.298375 -349.720143) (xy 380.306157 -349.701347)
			(xy 380.32054 -349.686961) (xy 380.339335 -349.679177) (xy 380.349506 -349.678752) (xy 380.59233 -349.678752)
			(xy 380.922022 -349.894906) (xy 380.933057 -349.900415) (xy 380.957689 -349.90107) (xy 380.969012 -349.896176)
			(xy 381.283972 -349.690944) (xy 381.290322 -349.68688) (xy 381.29083 -349.686372) (xy 381.303022 -349.678752)
			(xy 381.545846 -349.678752) (xy 381.556008 -349.679196) (xy 381.574781 -349.686988) (xy 381.589145 -349.701369)
			(xy 381.596916 -349.720151) (xy 381.597408 -349.730314) (xy 381.597408 -350.466914) (xy 383.406904 -350.466914)
			(xy 383.406904 -349.730314) (xy 383.407444 -349.720161) (xy 383.415207 -349.701399) (xy 383.429559 -349.687034)
			(xy 383.448314 -349.679253) (xy 383.458466 -349.678752) (xy 383.70129 -349.678752) (xy 384.030982 -349.894906)
			(xy 384.042027 -349.900388) (xy 384.06665 -349.90106) (xy 384.077972 -349.896176) (xy 384.392932 -349.690944)
			(xy 384.399282 -349.68688) (xy 384.39979 -349.686372) (xy 384.411982 -349.678752) (xy 384.654806 -349.678752)
			(xy 384.66498 -349.679159) (xy 384.683777 -349.686949) (xy 384.698162 -349.70134) (xy 384.705945 -349.72014)
			(xy 384.706368 -349.730314) (xy 384.706368 -350.466914) (xy 386.515864 -350.466914) (xy 386.515864 -349.730314)
			(xy 386.516276 -349.72014) (xy 386.524061 -349.701341) (xy 386.538451 -349.686954) (xy 386.557252 -349.679173)
			(xy 386.567426 -349.678752) (xy 386.81025 -349.678752) (xy 387.139942 -349.894906) (xy 387.150972 -349.900429)
			(xy 387.175609 -349.901075) (xy 387.186932 -349.896176) (xy 387.501892 -349.690944) (xy 387.508242 -349.68688)
			(xy 387.50875 -349.686372) (xy 387.520942 -349.678752) (xy 387.763766 -349.678752) (xy 387.773937 -349.679192)
			(xy 387.792734 -349.686969) (xy 387.80712 -349.701349) (xy 387.814904 -349.720143) (xy 387.815328 -349.730314)
			(xy 387.815328 -350.466914) (xy 389.624824 -350.466914) (xy 389.624824 -349.730314) (xy 389.625344 -349.720159)
			(xy 389.633112 -349.701393) (xy 389.647469 -349.687027) (xy 389.666231 -349.67925) (xy 389.676386 -349.678752)
			(xy 389.91921 -349.678752) (xy 390.248902 -349.894906) (xy 390.259942 -349.900402) (xy 390.284569 -349.901065)
			(xy 390.295892 -349.896176) (xy 390.610852 -349.690944) (xy 390.617202 -349.68688) (xy 390.61771 -349.686372)
			(xy 390.629902 -349.678752) (xy 390.872726 -349.678752) (xy 390.882887 -349.679212) (xy 390.90166 -349.686998)
			(xy 390.916025 -349.701374) (xy 390.923796 -349.720152) (xy 390.924288 -349.730314) (xy 390.924288 -350.466914)
			(xy 392.733784 -350.466914) (xy 392.733784 -349.730314) (xy 392.734176 -349.720138) (xy 392.741965 -349.701334)
			(xy 392.756361 -349.686947) (xy 392.775169 -349.67917) (xy 392.785346 -349.678752) (xy 393.02817 -349.678752)
			(xy 393.357862 -349.894906) (xy 393.368913 -349.900375) (xy 393.39353 -349.901055) (xy 393.404852 -349.896176)
			(xy 393.719812 -349.690944) (xy 393.726162 -349.68688) (xy 393.72667 -349.686372) (xy 393.738862 -349.678752)
			(xy 393.981686 -349.678752) (xy 393.991858 -349.679175) (xy 394.010656 -349.686959) (xy 394.025041 -349.701344)
			(xy 394.032825 -349.720142) (xy 394.033248 -349.730314) (xy 394.033248 -350.466914) (xy 395.842744 -350.466914)
			(xy 395.842744 -349.730314) (xy 395.843175 -349.720143) (xy 395.850957 -349.701347) (xy 395.86534 -349.686961)
			(xy 395.884135 -349.679177) (xy 395.894306 -349.678752) (xy 396.13713 -349.678752) (xy 396.466822 -349.894906)
			(xy 396.477857 -349.900415) (xy 396.502489 -349.90107) (xy 396.513812 -349.896176) (xy 396.828772 -349.690944)
			(xy 396.835122 -349.68688) (xy 396.83563 -349.686372) (xy 396.847822 -349.678752) (xy 397.090646 -349.678752)
			(xy 397.100808 -349.679196) (xy 397.119581 -349.686988) (xy 397.133945 -349.701369) (xy 397.141716 -349.720151)
			(xy 397.142208 -349.730314) (xy 397.142208 -350.466914) (xy 398.951704 -350.466914) (xy 398.951704 -349.730314)
			(xy 398.952244 -349.720161) (xy 398.960007 -349.701399) (xy 398.974359 -349.687034) (xy 398.993114 -349.679253)
			(xy 399.003266 -349.678752) (xy 399.24609 -349.678752) (xy 399.575782 -349.894906) (xy 399.586827 -349.900388)
			(xy 399.61145 -349.90106) (xy 399.622772 -349.896176) (xy 399.937732 -349.690944) (xy 399.944082 -349.68688)
			(xy 399.94459 -349.686372) (xy 399.956782 -349.678752) (xy 400.199606 -349.678752) (xy 400.20978 -349.679159)
			(xy 400.228577 -349.686949) (xy 400.242962 -349.70134) (xy 400.250745 -349.72014) (xy 400.251168 -349.730314)
			(xy 400.251168 -350.466914) (xy 402.060664 -350.466914) (xy 402.060664 -349.730314) (xy 402.061076 -349.72014)
			(xy 402.068861 -349.701341) (xy 402.083251 -349.686954) (xy 402.102052 -349.679173) (xy 402.112226 -349.678752)
			(xy 402.35505 -349.678752) (xy 402.684742 -349.894906) (xy 402.695772 -349.900429) (xy 402.720409 -349.901075)
			(xy 402.731732 -349.896176) (xy 403.046692 -349.690944) (xy 403.053042 -349.68688) (xy 403.05355 -349.686372)
			(xy 403.065742 -349.678752) (xy 403.308566 -349.678752) (xy 403.318737 -349.679192) (xy 403.337534 -349.686969)
			(xy 403.35192 -349.701349) (xy 403.359704 -349.720143) (xy 403.360128 -349.730314) (xy 403.360128 -350.466914)
			(xy 409.078176 -350.466914) (xy 409.078176 -349.730314) (xy 409.078576 -349.720139) (xy 409.086364 -349.701337)
			(xy 409.100757 -349.68695) (xy 409.119562 -349.679171) (xy 409.129738 -349.678752) (xy 409.372562 -349.678752)
			(xy 409.702254 -349.894906) (xy 409.713307 -349.90037) (xy 409.737922 -349.901053) (xy 409.749244 -349.896176)
			(xy 410.064204 -349.690944) (xy 410.070554 -349.68688) (xy 410.071062 -349.686372) (xy 410.083254 -349.678752)
			(xy 410.326078 -349.678752) (xy 410.33625 -349.679182) (xy 410.355047 -349.686963) (xy 410.369433 -349.701347)
			(xy 410.377216 -349.720142) (xy 410.37764 -349.730314) (xy 410.37764 -350.466914) (xy 412.187136 -350.466914)
			(xy 412.187136 -349.730314) (xy 412.187575 -349.720144) (xy 412.195355 -349.701349) (xy 412.209736 -349.686964)
			(xy 412.228528 -349.679178) (xy 412.238698 -349.678752) (xy 412.481522 -349.678752) (xy 412.811214 -349.894906)
			(xy 412.822251 -349.90041) (xy 412.846881 -349.901068) (xy 412.858204 -349.896176) (xy 413.173164 -349.690944)
			(xy 413.179514 -349.68688) (xy 413.180022 -349.686372) (xy 413.192214 -349.678752) (xy 413.435038 -349.678752)
			(xy 413.4452 -349.679203) (xy 413.463973 -349.686992) (xy 413.478337 -349.701371) (xy 413.486108 -349.720152)
			(xy 413.4866 -349.730314) (xy 413.4866 -350.466914) (xy 415.296096 -350.466914) (xy 415.296096 -349.730314)
			(xy 415.296644 -349.720162) (xy 415.304406 -349.701401) (xy 415.318754 -349.687037) (xy 415.337507 -349.679255)
			(xy 415.347658 -349.678752) (xy 415.590482 -349.678752) (xy 415.920174 -349.894906) (xy 415.931222 -349.900383)
			(xy 415.955842 -349.901058) (xy 415.967164 -349.896176) (xy 416.282124 -349.690944) (xy 416.288474 -349.68688)
			(xy 416.288982 -349.686372) (xy 416.301174 -349.678752) (xy 416.543998 -349.678752) (xy 416.554171 -349.679166)
			(xy 416.572969 -349.686953) (xy 416.587354 -349.701342) (xy 416.595137 -349.720141) (xy 416.59556 -349.730314)
			(xy 416.59556 -350.466914) (xy 418.405056 -350.466914) (xy 418.405056 -349.730314) (xy 418.405476 -349.720141)
			(xy 418.413259 -349.701343) (xy 418.427646 -349.686957) (xy 418.446445 -349.679175) (xy 418.456618 -349.678752)
			(xy 418.699442 -349.678752) (xy 419.029134 -349.894906) (xy 419.040166 -349.900423) (xy 419.064801 -349.901073)
			(xy 419.076124 -349.896176) (xy 419.391084 -349.690944) (xy 419.397434 -349.68688) (xy 419.397942 -349.686372)
			(xy 419.410134 -349.678752) (xy 419.652958 -349.678752) (xy 419.663129 -349.679199) (xy 419.681925 -349.686972)
			(xy 419.696312 -349.701351) (xy 419.704096 -349.720144) (xy 419.70452 -349.730314) (xy 419.70452 -350.466914)
			(xy 421.514016 -350.466914) (xy 421.514016 -349.730314) (xy 421.514544 -349.72016) (xy 421.52231 -349.701395)
			(xy 421.536665 -349.68703) (xy 421.555424 -349.679251) (xy 421.565578 -349.678752) (xy 421.808402 -349.678752)
			(xy 422.138094 -349.894906) (xy 422.149136 -349.900396) (xy 422.173762 -349.901063) (xy 422.185084 -349.896176)
			(xy 422.500044 -349.690944) (xy 422.506394 -349.68688) (xy 422.506902 -349.686372) (xy 422.519094 -349.678752)
			(xy 422.761918 -349.678752) (xy 422.772079 -349.679219) (xy 422.790851 -349.687002) (xy 422.805216 -349.701376)
			(xy 422.812988 -349.720153) (xy 422.81348 -349.730314) (xy 422.81348 -350.466914) (xy 424.622976 -350.466914)
			(xy 424.622976 -349.730314) (xy 424.623376 -349.720139) (xy 424.631164 -349.701337) (xy 424.645557 -349.68695)
			(xy 424.664362 -349.679171) (xy 424.674538 -349.678752) (xy 424.917362 -349.678752) (xy 425.247054 -349.894906)
			(xy 425.258107 -349.90037) (xy 425.282722 -349.901053) (xy 425.294044 -349.896176) (xy 425.609004 -349.690944)
			(xy 425.615354 -349.68688) (xy 425.615862 -349.686372) (xy 425.628054 -349.678752) (xy 425.870878 -349.678752)
			(xy 425.88105 -349.679182) (xy 425.899847 -349.686963) (xy 425.914233 -349.701347) (xy 425.922016 -349.720142)
			(xy 425.92244 -349.730314) (xy 425.92244 -350.466914) (xy 427.731936 -350.466914) (xy 427.731936 -349.730314)
			(xy 427.732375 -349.720144) (xy 427.740155 -349.701349) (xy 427.754536 -349.686964) (xy 427.773328 -349.679178)
			(xy 427.783498 -349.678752) (xy 428.026322 -349.678752) (xy 428.356014 -349.894906) (xy 428.367051 -349.90041)
			(xy 428.391681 -349.901068) (xy 428.403004 -349.896176) (xy 428.717964 -349.690944) (xy 428.724314 -349.68688)
			(xy 428.724822 -349.686372) (xy 428.737014 -349.678752) (xy 428.979838 -349.678752) (xy 428.99 -349.679203)
			(xy 429.008773 -349.686992) (xy 429.023137 -349.701371) (xy 429.030908 -349.720152) (xy 429.0314 -349.730314)
			(xy 429.0314 -350.466914) (xy 430.840896 -350.466914) (xy 430.840896 -349.730314) (xy 430.841444 -349.720162)
			(xy 430.849206 -349.701401) (xy 430.863554 -349.687037) (xy 430.882307 -349.679255) (xy 430.892458 -349.678752)
			(xy 431.135282 -349.678752) (xy 431.464974 -349.894906) (xy 431.476022 -349.900383) (xy 431.500642 -349.901058)
			(xy 431.511964 -349.896176) (xy 431.826924 -349.690944) (xy 431.833274 -349.68688) (xy 431.833782 -349.686372)
			(xy 431.845974 -349.678752) (xy 432.088798 -349.678752) (xy 432.098971 -349.679166) (xy 432.117769 -349.686953)
			(xy 432.132154 -349.701342) (xy 432.139937 -349.720141) (xy 432.14036 -349.730314) (xy 432.14036 -350.466914)
			(xy 433.949856 -350.466914) (xy 433.949856 -349.730314) (xy 433.950276 -349.720141) (xy 433.958059 -349.701343)
			(xy 433.972446 -349.686957) (xy 433.991245 -349.679175) (xy 434.001418 -349.678752) (xy 434.244242 -349.678752)
			(xy 434.573934 -349.894906) (xy 434.584966 -349.900423) (xy 434.609601 -349.901073) (xy 434.620924 -349.896176)
			(xy 434.935884 -349.690944) (xy 434.942234 -349.68688) (xy 434.942742 -349.686372) (xy 434.954934 -349.678752)
			(xy 435.197758 -349.678752) (xy 435.207929 -349.679199) (xy 435.226725 -349.686972) (xy 435.241112 -349.701351)
			(xy 435.248896 -349.720144) (xy 435.24932 -349.730314) (xy 435.24932 -350.466914) (xy 437.058816 -350.466914)
			(xy 437.058816 -349.730314) (xy 437.059344 -349.72016) (xy 437.06711 -349.701395) (xy 437.081465 -349.68703)
			(xy 437.100224 -349.679251) (xy 437.110378 -349.678752) (xy 437.353202 -349.678752) (xy 437.682894 -349.894906)
			(xy 437.693936 -349.900396) (xy 437.718562 -349.901063) (xy 437.729884 -349.896176) (xy 438.044844 -349.690944)
			(xy 438.051194 -349.68688) (xy 438.051702 -349.686372) (xy 438.063894 -349.678752) (xy 438.306718 -349.678752)
			(xy 438.316879 -349.679219) (xy 438.335651 -349.687002) (xy 438.350016 -349.701376) (xy 438.357788 -349.720153)
			(xy 438.35828 -349.730314) (xy 438.35828 -350.466914) (xy 440.167776 -350.466914) (xy 440.167776 -349.730314)
			(xy 440.168176 -349.720139) (xy 440.175964 -349.701337) (xy 440.190357 -349.68695) (xy 440.209162 -349.679171)
			(xy 440.219338 -349.678752) (xy 440.462162 -349.678752) (xy 440.791854 -349.894906) (xy 440.802907 -349.90037)
			(xy 440.827522 -349.901053) (xy 440.838844 -349.896176) (xy 441.153804 -349.690944) (xy 441.160154 -349.68688)
			(xy 441.160662 -349.686372) (xy 441.172854 -349.678752) (xy 441.415678 -349.678752) (xy 441.42585 -349.679182)
			(xy 441.444647 -349.686963) (xy 441.459033 -349.701347) (xy 441.466816 -349.720142) (xy 441.46724 -349.730314)
			(xy 441.46724 -350.466914) (xy 441.466847 -350.477089) (xy 441.459053 -350.495888) (xy 441.444658 -350.510273)
			(xy 441.425854 -350.518054) (xy 441.415678 -350.518476) (xy 441.172854 -350.518476) (xy 440.84113 -350.301814)
			(xy 440.829991 -350.296777) (xy 440.805583 -350.296637) (xy 440.794394 -350.30156) (xy 440.463432 -350.518476)
			(xy 440.219338 -350.518476) (xy 440.209171 -350.518005) (xy 440.190379 -350.510235) (xy 440.175994 -350.495864)
			(xy 440.168205 -350.477081) (xy 440.167776 -350.466914) (xy 438.35828 -350.466914) (xy 438.357778 -350.47707)
			(xy 438.350003 -350.495836) (xy 438.33564 -350.5102) (xy 438.316874 -350.517978) (xy 438.306718 -350.518476)
			(xy 438.063894 -350.518476) (xy 437.73217 -350.301814) (xy 437.721045 -350.296737) (xy 437.696624 -350.296622)
			(xy 437.685434 -350.30156) (xy 437.354472 -350.518476) (xy 437.110378 -350.518476) (xy 437.100221 -350.517985)
			(xy 437.081453 -350.510206) (xy 437.067089 -350.49584) (xy 437.059313 -350.477072) (xy 437.058816 -350.466914)
			(xy 435.24932 -350.466914) (xy 435.248946 -350.477092) (xy 435.241149 -350.495895) (xy 435.226748 -350.510281)
			(xy 435.207936 -350.518058) (xy 435.197758 -350.518476) (xy 434.954934 -350.518476) (xy 434.62321 -350.301814)
			(xy 434.612076 -350.296763) (xy 434.587663 -350.296632) (xy 434.576474 -350.30156) (xy 434.245512 -350.518476)
			(xy 434.001418 -350.518476) (xy 433.991249 -350.518022) (xy 433.972458 -350.510245) (xy 433.958073 -350.495869)
			(xy 433.950284 -350.477082) (xy 433.949856 -350.466914) (xy 432.14036 -350.466914) (xy 432.139878 -350.477073)
			(xy 432.132098 -350.495843) (xy 432.117729 -350.510207) (xy 432.098957 -350.517981) (xy 432.088798 -350.518476)
			(xy 431.845974 -350.518476) (xy 431.51425 -350.301814) (xy 431.503106 -350.29679) (xy 431.478703 -350.296642)
			(xy 431.467514 -350.30156) (xy 431.136552 -350.518476) (xy 430.892458 -350.518476) (xy 430.882299 -350.518001)
			(xy 430.863532 -350.510216) (xy 430.849169 -350.495845) (xy 430.841393 -350.477073) (xy 430.840896 -350.466914)
			(xy 429.0314 -350.466914) (xy 429.030879 -350.477068) (xy 429.023107 -350.49583) (xy 429.00875 -350.510193)
			(xy 428.989992 -350.517974) (xy 428.979838 -350.518476) (xy 428.737014 -350.518476) (xy 428.40529 -350.301814)
			(xy 428.39416 -350.29675) (xy 428.369744 -350.296627) (xy 428.358554 -350.30156) (xy 428.027592 -350.518476)
			(xy 427.783498 -350.518476) (xy 427.773342 -350.517969) (xy 427.754575 -350.510196) (xy 427.740211 -350.495835)
			(xy 427.732434 -350.47707) (xy 427.731936 -350.466914) (xy 425.92244 -350.466914) (xy 425.922047 -350.477089)
			(xy 425.914253 -350.495888) (xy 425.899858 -350.510273) (xy 425.881054 -350.518054) (xy 425.870878 -350.518476)
			(xy 425.628054 -350.518476) (xy 425.29633 -350.301814) (xy 425.285191 -350.296777) (xy 425.260783 -350.296637)
			(xy 425.249594 -350.30156) (xy 424.918632 -350.518476) (xy 424.674538 -350.518476) (xy 424.664371 -350.518005)
			(xy 424.645579 -350.510235) (xy 424.631194 -350.495864) (xy 424.623405 -350.477081) (xy 424.622976 -350.466914)
			(xy 422.81348 -350.466914) (xy 422.812978 -350.47707) (xy 422.805203 -350.495836) (xy 422.79084 -350.5102)
			(xy 422.772074 -350.517978) (xy 422.761918 -350.518476) (xy 422.519094 -350.518476) (xy 422.18737 -350.301814)
			(xy 422.176245 -350.296737) (xy 422.151824 -350.296622) (xy 422.140634 -350.30156) (xy 421.809672 -350.518476)
			(xy 421.565578 -350.518476) (xy 421.555421 -350.517985) (xy 421.536653 -350.510206) (xy 421.522289 -350.49584)
			(xy 421.514513 -350.477072) (xy 421.514016 -350.466914) (xy 419.70452 -350.466914) (xy 419.704146 -350.477092)
			(xy 419.696349 -350.495895) (xy 419.681948 -350.510281) (xy 419.663136 -350.518058) (xy 419.652958 -350.518476)
			(xy 419.410134 -350.518476) (xy 419.07841 -350.301814) (xy 419.067276 -350.296763) (xy 419.042863 -350.296632)
			(xy 419.031674 -350.30156) (xy 418.700712 -350.518476) (xy 418.456618 -350.518476) (xy 418.446449 -350.518022)
			(xy 418.427658 -350.510245) (xy 418.413273 -350.495869) (xy 418.405484 -350.477082) (xy 418.405056 -350.466914)
			(xy 416.59556 -350.466914) (xy 416.595078 -350.477073) (xy 416.587298 -350.495843) (xy 416.572929 -350.510207)
			(xy 416.554157 -350.517981) (xy 416.543998 -350.518476) (xy 416.301174 -350.518476) (xy 415.96945 -350.301814)
			(xy 415.958306 -350.29679) (xy 415.933903 -350.296642) (xy 415.922714 -350.30156) (xy 415.591752 -350.518476)
			(xy 415.347658 -350.518476) (xy 415.337499 -350.518001) (xy 415.318732 -350.510216) (xy 415.304369 -350.495845)
			(xy 415.296593 -350.477073) (xy 415.296096 -350.466914) (xy 413.4866 -350.466914) (xy 413.486079 -350.477068)
			(xy 413.478307 -350.49583) (xy 413.46395 -350.510193) (xy 413.445192 -350.517974) (xy 413.435038 -350.518476)
			(xy 413.192214 -350.518476) (xy 412.86049 -350.301814) (xy 412.84936 -350.29675) (xy 412.824944 -350.296627)
			(xy 412.813754 -350.30156) (xy 412.482792 -350.518476) (xy 412.238698 -350.518476) (xy 412.228542 -350.517969)
			(xy 412.209775 -350.510196) (xy 412.195411 -350.495835) (xy 412.187634 -350.47707) (xy 412.187136 -350.466914)
			(xy 410.37764 -350.466914) (xy 410.377247 -350.477089) (xy 410.369453 -350.495888) (xy 410.355058 -350.510273)
			(xy 410.336254 -350.518054) (xy 410.326078 -350.518476) (xy 410.083254 -350.518476) (xy 409.75153 -350.301814)
			(xy 409.740391 -350.296777) (xy 409.715983 -350.296637) (xy 409.704794 -350.30156) (xy 409.373832 -350.518476)
			(xy 409.129738 -350.518476) (xy 409.119571 -350.518005) (xy 409.100779 -350.510235) (xy 409.086394 -350.495864)
			(xy 409.078605 -350.477081) (xy 409.078176 -350.466914) (xy 403.360128 -350.466914) (xy 403.359747 -350.477091)
			(xy 403.351951 -350.495892) (xy 403.337552 -350.510278) (xy 403.318743 -350.518056) (xy 403.308566 -350.518476)
			(xy 403.065742 -350.518476) (xy 402.734018 -350.301814) (xy 402.722882 -350.296769) (xy 402.698471 -350.296634)
			(xy 402.687282 -350.30156) (xy 402.35632 -350.518476) (xy 402.112226 -350.518476) (xy 402.102058 -350.518015)
			(xy 402.083266 -350.510241) (xy 402.068881 -350.495867) (xy 402.061093 -350.477082) (xy 402.060664 -350.466914)
			(xy 400.251168 -350.466914) (xy 400.250678 -350.477072) (xy 400.2429 -350.49584) (xy 400.228533 -350.510205)
			(xy 400.209764 -350.51798) (xy 400.199606 -350.518476) (xy 399.956782 -350.518476) (xy 399.625058 -350.301814)
			(xy 399.613912 -350.296795) (xy 399.589511 -350.296644) (xy 399.578322 -350.30156) (xy 399.24736 -350.518476)
			(xy 399.003266 -350.518476) (xy 398.993108 -350.517995) (xy 398.974341 -350.510212) (xy 398.959977 -350.495843)
			(xy 398.952201 -350.477072) (xy 398.951704 -350.466914) (xy 397.142208 -350.466914) (xy 397.141679 -350.477067)
			(xy 397.133909 -350.495828) (xy 397.119554 -350.510191) (xy 397.100799 -350.517973) (xy 397.090646 -350.518476)
			(xy 396.847822 -350.518476) (xy 396.516098 -350.301814) (xy 396.504966 -350.296755) (xy 396.480552 -350.296629)
			(xy 396.469362 -350.30156) (xy 396.1384 -350.518476) (xy 395.894306 -350.518476) (xy 395.88415 -350.517962)
			(xy 395.865384 -350.510192) (xy 395.851019 -350.495833) (xy 395.843242 -350.477069) (xy 395.842744 -350.466914)
			(xy 394.033248 -350.466914) (xy 394.032778 -350.477074) (xy 394.024996 -350.495846) (xy 394.010623 -350.510212)
			(xy 393.991847 -350.517983) (xy 393.981686 -350.518476) (xy 393.738862 -350.518476) (xy 393.407138 -350.301814)
			(xy 393.395997 -350.296782) (xy 393.371591 -350.296639) (xy 393.360402 -350.30156) (xy 393.02944 -350.518476)
			(xy 392.785346 -350.518476) (xy 392.775179 -350.517999) (xy 392.756388 -350.510232) (xy 392.742002 -350.495862)
			(xy 392.734213 -350.47708) (xy 392.733784 -350.466914) (xy 390.924288 -350.466914) (xy 390.923779 -350.477069)
			(xy 390.916004 -350.495834) (xy 390.901644 -350.510198) (xy 390.882881 -350.517976) (xy 390.872726 -350.518476)
			(xy 390.629902 -350.518476) (xy 390.298178 -350.301814) (xy 390.287051 -350.296742) (xy 390.262632 -350.296624)
			(xy 390.251442 -350.30156) (xy 389.92048 -350.518476) (xy 389.676386 -350.518476) (xy 389.666229 -350.517978)
			(xy 389.647462 -350.510202) (xy 389.633098 -350.495838) (xy 389.625322 -350.477071) (xy 389.624824 -350.466914)
			(xy 387.815328 -350.466914) (xy 387.814947 -350.477091) (xy 387.807151 -350.495892) (xy 387.792752 -350.510278)
			(xy 387.773943 -350.518056) (xy 387.763766 -350.518476) (xy 387.520942 -350.518476) (xy 387.189218 -350.301814)
			(xy 387.178082 -350.296769) (xy 387.153671 -350.296634) (xy 387.142482 -350.30156) (xy 386.81152 -350.518476)
			(xy 386.567426 -350.518476) (xy 386.557258 -350.518015) (xy 386.538466 -350.510241) (xy 386.524081 -350.495867)
			(xy 386.516293 -350.477082) (xy 386.515864 -350.466914) (xy 384.706368 -350.466914) (xy 384.705878 -350.477072)
			(xy 384.6981 -350.49584) (xy 384.683733 -350.510205) (xy 384.664964 -350.51798) (xy 384.654806 -350.518476)
			(xy 384.411982 -350.518476) (xy 384.080258 -350.301814) (xy 384.069112 -350.296795) (xy 384.044711 -350.296644)
			(xy 384.033522 -350.30156) (xy 383.70256 -350.518476) (xy 383.458466 -350.518476) (xy 383.448308 -350.517995)
			(xy 383.429541 -350.510212) (xy 383.415177 -350.495843) (xy 383.407401 -350.477072) (xy 383.406904 -350.466914)
			(xy 381.597408 -350.466914) (xy 381.596879 -350.477067) (xy 381.589109 -350.495828) (xy 381.574754 -350.510191)
			(xy 381.555999 -350.517973) (xy 381.545846 -350.518476) (xy 381.303022 -350.518476) (xy 380.971298 -350.301814)
			(xy 380.960166 -350.296755) (xy 380.935752 -350.296629) (xy 380.924562 -350.30156) (xy 380.5936 -350.518476)
			(xy 380.349506 -350.518476) (xy 380.33935 -350.517962) (xy 380.320584 -350.510192) (xy 380.306219 -350.495833)
			(xy 380.298442 -350.477069) (xy 380.297944 -350.466914) (xy 378.488448 -350.466914) (xy 378.487978 -350.477074)
			(xy 378.480196 -350.495846) (xy 378.465823 -350.510212) (xy 378.447047 -350.517983) (xy 378.436886 -350.518476)
			(xy 378.194062 -350.518476) (xy 377.862338 -350.301814) (xy 377.851197 -350.296782) (xy 377.826791 -350.296639)
			(xy 377.815602 -350.30156) (xy 377.48464 -350.518476) (xy 377.240546 -350.518476) (xy 377.230379 -350.517999)
			(xy 377.211588 -350.510232) (xy 377.197202 -350.495862) (xy 377.189413 -350.47708) (xy 377.188984 -350.466914)
			(xy 375.379488 -350.466914) (xy 375.378979 -350.477069) (xy 375.371204 -350.495834) (xy 375.356844 -350.510198)
			(xy 375.338081 -350.517976) (xy 375.327926 -350.518476) (xy 375.085102 -350.518476) (xy 374.753378 -350.301814)
			(xy 374.742251 -350.296742) (xy 374.717832 -350.296624) (xy 374.706642 -350.30156) (xy 374.37568 -350.518476)
			(xy 374.131586 -350.518476) (xy 374.121429 -350.517978) (xy 374.102662 -350.510202) (xy 374.088298 -350.495838)
			(xy 374.080522 -350.477071) (xy 374.080024 -350.466914) (xy 372.270528 -350.466914) (xy 372.270147 -350.477091)
			(xy 372.262351 -350.495892) (xy 372.247952 -350.510278) (xy 372.229143 -350.518056) (xy 372.218966 -350.518476)
			(xy 371.976142 -350.518476) (xy 371.644418 -350.301814) (xy 371.633282 -350.296769) (xy 371.608871 -350.296634)
			(xy 371.597682 -350.30156) (xy 371.26672 -350.518476) (xy 371.022626 -350.518476) (xy 371.012458 -350.518015)
			(xy 370.993666 -350.510241) (xy 370.979281 -350.495867) (xy 370.971493 -350.477082) (xy 370.971064 -350.466914)
			(xy 344.674952 -350.466914) (xy 344.674478 -350.477074) (xy 344.666697 -350.495845) (xy 344.652325 -350.51021)
			(xy 344.63355 -350.517982) (xy 344.62339 -350.518476) (xy 344.380566 -350.518476) (xy 344.048842 -350.301814)
			(xy 344.0377 -350.296785) (xy 344.013295 -350.29664) (xy 344.002106 -350.30156) (xy 343.671144 -350.518476)
			(xy 343.42705 -350.518476) (xy 343.416883 -350.517996) (xy 343.398092 -350.51023) (xy 343.383706 -350.495861)
			(xy 343.375917 -350.47708) (xy 343.375488 -350.466914) (xy 341.565992 -350.466914) (xy 341.565479 -350.477069)
			(xy 341.557705 -350.495833) (xy 341.543346 -350.510196) (xy 341.524585 -350.517975) (xy 341.51443 -350.518476)
			(xy 341.271606 -350.518476) (xy 340.939882 -350.301814) (xy 340.928754 -350.296745) (xy 340.904336 -350.296625)
			(xy 340.893146 -350.30156) (xy 340.562184 -350.518476) (xy 340.31809 -350.518476) (xy 340.307933 -350.517975)
			(xy 340.289167 -350.5102) (xy 340.274802 -350.495837) (xy 340.267026 -350.477071) (xy 340.266528 -350.466914)
			(xy 338.457032 -350.466914) (xy 338.456647 -350.47709) (xy 338.448852 -350.495891) (xy 338.434454 -350.510276)
			(xy 338.415647 -350.518055) (xy 338.40547 -350.518476) (xy 338.162646 -350.518476) (xy 337.830922 -350.301814)
			(xy 337.819785 -350.296772) (xy 337.795375 -350.296635) (xy 337.784186 -350.30156) (xy 337.453224 -350.518476)
			(xy 337.20913 -350.518476) (xy 337.198962 -350.518012) (xy 337.180171 -350.510239) (xy 337.165785 -350.495866)
			(xy 337.157997 -350.477082) (xy 337.157568 -350.466914) (xy 335.348072 -350.466914) (xy 335.347578 -350.477071)
			(xy 335.339801 -350.495839) (xy 335.325435 -350.510203) (xy 335.306667 -350.517979) (xy 335.29651 -350.518476)
			(xy 335.053686 -350.518476) (xy 334.721962 -350.301814) (xy 334.710815 -350.296798) (xy 334.686415 -350.296644)
			(xy 334.675226 -350.30156) (xy 334.344264 -350.518476) (xy 334.10017 -350.518476) (xy 334.090012 -350.517992)
			(xy 334.071245 -350.51021) (xy 334.056881 -350.495842) (xy 334.049105 -350.477072) (xy 334.048608 -350.466914)
			(xy 332.239112 -350.466914) (xy 332.238746 -350.477093) (xy 332.230947 -350.495897) (xy 332.216543 -350.510283)
			(xy 332.197729 -350.518059) (xy 332.18755 -350.518476) (xy 331.944726 -350.518476) (xy 331.613002 -350.301814)
			(xy 331.601869 -350.296758) (xy 331.577456 -350.29663) (xy 331.566266 -350.30156) (xy 331.235304 -350.518476)
			(xy 330.99121 -350.518476) (xy 330.981055 -350.517959) (xy 330.962288 -350.51019) (xy 330.947923 -350.495832)
			(xy 330.940146 -350.477069) (xy 330.939648 -350.466914) (xy 329.130152 -350.466914) (xy 329.129678 -350.477074)
			(xy 329.121897 -350.495845) (xy 329.107525 -350.51021) (xy 329.08875 -350.517982) (xy 329.07859 -350.518476)
			(xy 328.835766 -350.518476) (xy 328.504042 -350.301814) (xy 328.4929 -350.296785) (xy 328.468495 -350.29664)
			(xy 328.457306 -350.30156) (xy 328.126344 -350.518476) (xy 327.88225 -350.518476) (xy 327.872083 -350.517996)
			(xy 327.853292 -350.51023) (xy 327.838906 -350.495861) (xy 327.831117 -350.47708) (xy 327.830688 -350.466914)
			(xy 326.021192 -350.466914) (xy 326.020679 -350.477069) (xy 326.012905 -350.495833) (xy 325.998546 -350.510196)
			(xy 325.979785 -350.517975) (xy 325.96963 -350.518476) (xy 325.726806 -350.518476) (xy 325.395082 -350.301814)
			(xy 325.383954 -350.296745) (xy 325.359536 -350.296625) (xy 325.348346 -350.30156) (xy 325.017384 -350.518476)
			(xy 324.77329 -350.518476) (xy 324.763133 -350.517975) (xy 324.744367 -350.5102) (xy 324.730002 -350.495837)
			(xy 324.722226 -350.477071) (xy 324.721728 -350.466914) (xy 322.912232 -350.466914) (xy 322.911847 -350.47709)
			(xy 322.904052 -350.495891) (xy 322.889654 -350.510276) (xy 322.870847 -350.518055) (xy 322.86067 -350.518476)
			(xy 322.617846 -350.518476) (xy 322.286122 -350.301814) (xy 322.274985 -350.296772) (xy 322.250575 -350.296635)
			(xy 322.239386 -350.30156) (xy 321.908424 -350.518476) (xy 321.66433 -350.518476) (xy 321.654162 -350.518012)
			(xy 321.635371 -350.510239) (xy 321.620985 -350.495866) (xy 321.613197 -350.477082) (xy 321.612768 -350.466914)
			(xy 319.803272 -350.466914) (xy 319.802778 -350.477071) (xy 319.795001 -350.495839) (xy 319.780635 -350.510203)
			(xy 319.761867 -350.517979) (xy 319.75171 -350.518476) (xy 319.508886 -350.518476) (xy 319.177162 -350.301814)
			(xy 319.166015 -350.296798) (xy 319.141615 -350.296644) (xy 319.130426 -350.30156) (xy 318.799464 -350.518476)
			(xy 318.55537 -350.518476) (xy 318.545212 -350.517992) (xy 318.526445 -350.51021) (xy 318.512081 -350.495842)
			(xy 318.504305 -350.477072) (xy 318.503808 -350.466914) (xy 316.694312 -350.466914) (xy 316.693946 -350.477093)
			(xy 316.686147 -350.495897) (xy 316.671743 -350.510283) (xy 316.652929 -350.518059) (xy 316.64275 -350.518476)
			(xy 316.399926 -350.518476) (xy 316.068202 -350.301814) (xy 316.057069 -350.296758) (xy 316.032656 -350.29663)
			(xy 316.021466 -350.30156) (xy 315.690504 -350.518476) (xy 315.44641 -350.518476) (xy 315.436255 -350.517959)
			(xy 315.417488 -350.51019) (xy 315.403123 -350.495832) (xy 315.395346 -350.477069) (xy 315.394848 -350.466914)
			(xy 313.585352 -350.466914) (xy 313.584878 -350.477074) (xy 313.577097 -350.495845) (xy 313.562725 -350.51021)
			(xy 313.54395 -350.517982) (xy 313.53379 -350.518476) (xy 313.290966 -350.518476) (xy 312.959242 -350.301814)
			(xy 312.9481 -350.296785) (xy 312.923695 -350.29664) (xy 312.912506 -350.30156) (xy 312.581544 -350.518476)
			(xy 312.33745 -350.518476) (xy 312.327283 -350.517996) (xy 312.308492 -350.51023) (xy 312.294106 -350.495861)
			(xy 312.286317 -350.47708) (xy 312.285888 -350.466914) (xy 300.069504 -350.466914) (xy 300.069043 -350.477113)
			(xy 300.061214 -350.495948) (xy 300.046758 -350.51034) (xy 300.027889 -350.518087) (xy 300.017688 -350.518476)
			(xy 299.774864 -350.518476) (xy 299.44314 -350.301814) (xy 299.431998 -350.296783) (xy 299.407593 -350.296639)
			(xy 299.396404 -350.30156) (xy 299.065442 -350.518476) (xy 298.821348 -350.518476) (xy 298.81117 -350.517984)
			(xy 298.79235 -350.510227) (xy 298.77792 -350.49587) (xy 298.770067 -350.47709) (xy 298.769532 -350.466914)
			(xy 296.960544 -350.466914) (xy 296.960141 -350.47712) (xy 296.952301 -350.495968) (xy 296.937827 -350.510362)
			(xy 296.918937 -350.518097) (xy 296.908728 -350.518476) (xy 296.665904 -350.518476) (xy 296.33418 -350.301814)
			(xy 296.323053 -350.296743) (xy 296.298634 -350.296625) (xy 296.287444 -350.30156) (xy 295.956482 -350.518476)
			(xy 295.712388 -350.518476) (xy 295.702206 -350.518034) (xy 295.683385 -350.510257) (xy 295.668957 -350.495885)
			(xy 295.661107 -350.477094) (xy 295.660572 -350.466914) (xy 293.851584 -350.466914) (xy 293.851142 -350.477115)
			(xy 293.843309 -350.495955) (xy 293.828848 -350.510347) (xy 293.809971 -350.51809) (xy 293.799768 -350.518476)
			(xy 293.556944 -350.518476) (xy 293.22522 -350.301814) (xy 293.214083 -350.29677) (xy 293.189673 -350.296635)
			(xy 293.178484 -350.30156) (xy 292.847522 -350.518476) (xy 292.603428 -350.518476) (xy 292.593248 -350.518001)
			(xy 292.574428 -350.510237) (xy 292.559999 -350.495875) (xy 292.552147 -350.477091) (xy 292.551612 -350.466914)
			(xy 290.742624 -350.466914) (xy 290.742241 -350.477123) (xy 290.734397 -350.495974) (xy 290.719917 -350.510369)
			(xy 290.701019 -350.518101) (xy 290.690808 -350.518476) (xy 290.447984 -350.518476) (xy 290.11626 -350.301814)
			(xy 290.105114 -350.296797) (xy 290.080713 -350.296644) (xy 290.069524 -350.30156) (xy 289.738562 -350.518476)
			(xy 289.494468 -350.518476) (xy 289.484284 -350.51805) (xy 289.465463 -350.510267) (xy 289.451036 -350.49589)
			(xy 289.443186 -350.477096) (xy 289.442652 -350.466914) (xy 287.633664 -350.466914) (xy 287.633242 -350.477118)
			(xy 287.625405 -350.495961) (xy 287.610937 -350.510355) (xy 287.592054 -350.518094) (xy 287.581848 -350.518476)
			(xy 287.339024 -350.518476) (xy 287.0073 -350.301814) (xy 286.996168 -350.296757) (xy 286.971754 -350.296629)
			(xy 286.960564 -350.30156) (xy 286.629602 -350.518476) (xy 286.385508 -350.518476) (xy 286.375327 -350.518017)
			(xy 286.356506 -350.510247) (xy 286.342078 -350.49588) (xy 286.334227 -350.477093) (xy 286.333692 -350.466914)
			(xy 284.524704 -350.466914) (xy 284.524243 -350.477113) (xy 284.516414 -350.495948) (xy 284.501958 -350.51034)
			(xy 284.483089 -350.518087) (xy 284.472888 -350.518476) (xy 284.230064 -350.518476) (xy 283.89834 -350.301814)
			(xy 283.887198 -350.296783) (xy 283.862793 -350.296639) (xy 283.851604 -350.30156) (xy 283.520642 -350.518476)
			(xy 283.276548 -350.518476) (xy 283.26637 -350.517984) (xy 283.24755 -350.510227) (xy 283.23312 -350.49587)
			(xy 283.225267 -350.47709) (xy 283.224732 -350.466914) (xy 281.415744 -350.466914) (xy 281.415341 -350.47712)
			(xy 281.407501 -350.495968) (xy 281.393027 -350.510362) (xy 281.374137 -350.518097) (xy 281.363928 -350.518476)
			(xy 281.121104 -350.518476) (xy 280.78938 -350.301814) (xy 280.778253 -350.296743) (xy 280.753834 -350.296625)
			(xy 280.742644 -350.30156) (xy 280.411682 -350.518476) (xy 280.167588 -350.518476) (xy 280.157406 -350.518034)
			(xy 280.138585 -350.510257) (xy 280.124157 -350.495885) (xy 280.116307 -350.477094) (xy 280.115772 -350.466914)
			(xy 278.306784 -350.466914) (xy 278.306342 -350.477115) (xy 278.298509 -350.495955) (xy 278.284048 -350.510347)
			(xy 278.265171 -350.51809) (xy 278.254968 -350.518476) (xy 278.012144 -350.518476) (xy 277.68042 -350.301814)
			(xy 277.669283 -350.29677) (xy 277.644873 -350.296635) (xy 277.633684 -350.30156) (xy 277.302722 -350.518476)
			(xy 277.058628 -350.518476) (xy 277.048448 -350.518001) (xy 277.029628 -350.510237) (xy 277.015199 -350.495875)
			(xy 277.007347 -350.477091) (xy 277.006812 -350.466914) (xy 275.197824 -350.466914) (xy 275.197441 -350.477123)
			(xy 275.189597 -350.495974) (xy 275.175117 -350.510369) (xy 275.156219 -350.518101) (xy 275.146008 -350.518476)
			(xy 274.903184 -350.518476) (xy 274.57146 -350.301814) (xy 274.560314 -350.296797) (xy 274.535913 -350.296644)
			(xy 274.524724 -350.30156) (xy 274.193762 -350.518476) (xy 273.949668 -350.518476) (xy 273.939484 -350.51805)
			(xy 273.920663 -350.510267) (xy 273.906236 -350.49589) (xy 273.898386 -350.477096) (xy 273.897852 -350.466914)
			(xy 272.088864 -350.466914) (xy 272.088442 -350.477118) (xy 272.080605 -350.495961) (xy 272.066137 -350.510355)
			(xy 272.047254 -350.518094) (xy 272.037048 -350.518476) (xy 271.794224 -350.518476) (xy 271.4625 -350.301814)
			(xy 271.451368 -350.296757) (xy 271.426954 -350.296629) (xy 271.415764 -350.30156) (xy 271.084802 -350.518476)
			(xy 270.840708 -350.518476) (xy 270.830527 -350.518017) (xy 270.811706 -350.510247) (xy 270.797278 -350.49588)
			(xy 270.789427 -350.477093) (xy 270.788892 -350.466914) (xy 268.979904 -350.466914) (xy 268.979443 -350.477113)
			(xy 268.971614 -350.495948) (xy 268.957158 -350.51034) (xy 268.938289 -350.518087) (xy 268.928088 -350.518476)
			(xy 268.685264 -350.518476) (xy 268.35354 -350.301814) (xy 268.342398 -350.296783) (xy 268.317993 -350.296639)
			(xy 268.306804 -350.30156) (xy 267.975842 -350.518476) (xy 267.731748 -350.518476) (xy 267.72157 -350.517984)
			(xy 267.70275 -350.510227) (xy 267.68832 -350.49587) (xy 267.680467 -350.47709) (xy 267.679932 -350.466914)
			(xy 194.35826 -350.466914) (xy 194.357778 -350.477073) (xy 194.349998 -350.495843) (xy 194.335629 -350.510207)
			(xy 194.316857 -350.517981) (xy 194.306698 -350.518476) (xy 194.063874 -350.518476) (xy 193.73215 -350.301814)
			(xy 193.721006 -350.29679) (xy 193.696603 -350.296642) (xy 193.685414 -350.30156) (xy 193.354452 -350.518476)
			(xy 193.110358 -350.518476) (xy 193.100199 -350.518001) (xy 193.081432 -350.510216) (xy 193.067069 -350.495845)
			(xy 193.059293 -350.477073) (xy 193.058796 -350.466914) (xy 191.2493 -350.466914) (xy 191.248779 -350.477068)
			(xy 191.241007 -350.49583) (xy 191.22665 -350.510193) (xy 191.207892 -350.517974) (xy 191.197738 -350.518476)
			(xy 190.954914 -350.518476) (xy 190.62319 -350.301814) (xy 190.61206 -350.29675) (xy 190.587644 -350.296627)
			(xy 190.576454 -350.30156) (xy 190.245492 -350.518476) (xy 190.001398 -350.518476) (xy 189.991242 -350.517969)
			(xy 189.972475 -350.510196) (xy 189.958111 -350.495835) (xy 189.950334 -350.47707) (xy 189.949836 -350.466914)
			(xy 188.14034 -350.466914) (xy 188.139947 -350.477089) (xy 188.132153 -350.495888) (xy 188.117758 -350.510273)
			(xy 188.098954 -350.518054) (xy 188.088778 -350.518476) (xy 187.845954 -350.518476) (xy 187.51423 -350.301814)
			(xy 187.503091 -350.296777) (xy 187.478683 -350.296637) (xy 187.467494 -350.30156) (xy 187.136532 -350.518476)
			(xy 186.892438 -350.518476) (xy 186.882271 -350.518005) (xy 186.863479 -350.510235) (xy 186.849094 -350.495864)
			(xy 186.841305 -350.477081) (xy 186.840876 -350.466914) (xy 185.03138 -350.466914) (xy 185.030878 -350.47707)
			(xy 185.023103 -350.495836) (xy 185.00874 -350.5102) (xy 184.989974 -350.517978) (xy 184.979818 -350.518476)
			(xy 184.736994 -350.518476) (xy 184.40527 -350.301814) (xy 184.394145 -350.296737) (xy 184.369724 -350.296622)
			(xy 184.358534 -350.30156) (xy 184.027572 -350.518476) (xy 183.783478 -350.518476) (xy 183.773321 -350.517985)
			(xy 183.754553 -350.510206) (xy 183.740189 -350.49584) (xy 183.732413 -350.477072) (xy 183.731916 -350.466914)
			(xy 181.92242 -350.466914) (xy 181.922046 -350.477092) (xy 181.914249 -350.495895) (xy 181.899848 -350.510281)
			(xy 181.881036 -350.518058) (xy 181.870858 -350.518476) (xy 181.628034 -350.518476) (xy 181.29631 -350.301814)
			(xy 181.285176 -350.296763) (xy 181.260763 -350.296632) (xy 181.249574 -350.30156) (xy 180.918612 -350.518476)
			(xy 180.674518 -350.518476) (xy 180.664349 -350.518022) (xy 180.645558 -350.510245) (xy 180.631173 -350.495869)
			(xy 180.623384 -350.477082) (xy 180.622956 -350.466914) (xy 178.81346 -350.466914) (xy 178.812978 -350.477073)
			(xy 178.805198 -350.495843) (xy 178.790829 -350.510207) (xy 178.772057 -350.517981) (xy 178.761898 -350.518476)
			(xy 178.519074 -350.518476) (xy 178.18735 -350.301814) (xy 178.176206 -350.29679) (xy 178.151803 -350.296642)
			(xy 178.140614 -350.30156) (xy 177.809652 -350.518476) (xy 177.565558 -350.518476) (xy 177.555399 -350.518001)
			(xy 177.536632 -350.510216) (xy 177.522269 -350.495845) (xy 177.514493 -350.477073) (xy 177.513996 -350.466914)
			(xy 175.7045 -350.466914) (xy 175.703979 -350.477068) (xy 175.696207 -350.49583) (xy 175.68185 -350.510193)
			(xy 175.663092 -350.517974) (xy 175.652938 -350.518476) (xy 175.410114 -350.518476) (xy 175.07839 -350.301814)
			(xy 175.06726 -350.29675) (xy 175.042844 -350.296627) (xy 175.031654 -350.30156) (xy 174.700692 -350.518476)
			(xy 174.456598 -350.518476) (xy 174.446442 -350.517969) (xy 174.427675 -350.510196) (xy 174.413311 -350.495835)
			(xy 174.405534 -350.47707) (xy 174.405036 -350.466914) (xy 172.59554 -350.466914) (xy 172.595147 -350.477089)
			(xy 172.587353 -350.495888) (xy 172.572958 -350.510273) (xy 172.554154 -350.518054) (xy 172.543978 -350.518476)
			(xy 172.301154 -350.518476) (xy 171.96943 -350.301814) (xy 171.958291 -350.296777) (xy 171.933883 -350.296637)
			(xy 171.922694 -350.30156) (xy 171.591732 -350.518476) (xy 171.347638 -350.518476) (xy 171.337471 -350.518005)
			(xy 171.318679 -350.510235) (xy 171.304294 -350.495864) (xy 171.296505 -350.477081) (xy 171.296076 -350.466914)
			(xy 169.48658 -350.466914) (xy 169.486078 -350.47707) (xy 169.478303 -350.495836) (xy 169.46394 -350.5102)
			(xy 169.445174 -350.517978) (xy 169.435018 -350.518476) (xy 169.192194 -350.518476) (xy 168.86047 -350.301814)
			(xy 168.849345 -350.296737) (xy 168.824924 -350.296622) (xy 168.813734 -350.30156) (xy 168.482772 -350.518476)
			(xy 168.238678 -350.518476) (xy 168.228521 -350.517985) (xy 168.209753 -350.510206) (xy 168.195389 -350.49584)
			(xy 168.187613 -350.477072) (xy 168.187116 -350.466914) (xy 166.37762 -350.466914) (xy 166.377246 -350.477092)
			(xy 166.369449 -350.495895) (xy 166.355048 -350.510281) (xy 166.336236 -350.518058) (xy 166.326058 -350.518476)
			(xy 166.083234 -350.518476) (xy 165.75151 -350.301814) (xy 165.740376 -350.296763) (xy 165.715963 -350.296632)
			(xy 165.704774 -350.30156) (xy 165.373812 -350.518476) (xy 165.129718 -350.518476) (xy 165.119549 -350.518022)
			(xy 165.100758 -350.510245) (xy 165.086373 -350.495869) (xy 165.078584 -350.477082) (xy 165.078156 -350.466914)
			(xy 163.26866 -350.466914) (xy 163.268178 -350.477073) (xy 163.260398 -350.495843) (xy 163.246029 -350.510207)
			(xy 163.227257 -350.517981) (xy 163.217098 -350.518476) (xy 162.974274 -350.518476) (xy 162.64255 -350.301814)
			(xy 162.631406 -350.29679) (xy 162.607003 -350.296642) (xy 162.595814 -350.30156) (xy 162.264852 -350.518476)
			(xy 162.020758 -350.518476) (xy 162.010599 -350.518001) (xy 161.991832 -350.510216) (xy 161.977469 -350.495845)
			(xy 161.969693 -350.477073) (xy 161.969196 -350.466914) (xy 144.034256 -350.466914) (xy 144.033778 -350.477073)
			(xy 144.025998 -350.495844) (xy 144.011627 -350.510209) (xy 143.992854 -350.517982) (xy 143.982694 -350.518476)
			(xy 143.73987 -350.518476) (xy 143.408146 -350.301814) (xy 143.397003 -350.296787) (xy 143.372599 -350.296641)
			(xy 143.36141 -350.30156) (xy 143.030448 -350.518476) (xy 142.786354 -350.518476) (xy 142.776195 -350.518005)
			(xy 142.757428 -350.510218) (xy 142.743064 -350.495846) (xy 142.735289 -350.477073) (xy 142.734792 -350.466914)
			(xy 140.925296 -350.466914) (xy 140.924779 -350.477068) (xy 140.917006 -350.495831) (xy 140.902648 -350.510195)
			(xy 140.883888 -350.517975) (xy 140.873734 -350.518476) (xy 140.63091 -350.518476) (xy 140.299186 -350.301814)
			(xy 140.288057 -350.296747) (xy 140.26364 -350.296626) (xy 140.25245 -350.30156) (xy 139.921488 -350.518476)
			(xy 139.677394 -350.518476) (xy 139.667238 -350.517972) (xy 139.648471 -350.510198) (xy 139.634107 -350.495836)
			(xy 139.62633 -350.47707) (xy 139.625832 -350.466914) (xy 137.816336 -350.466914) (xy 137.815947 -350.47709)
			(xy 137.808152 -350.49589) (xy 137.793756 -350.510275) (xy 137.77495 -350.518055) (xy 137.764774 -350.518476)
			(xy 137.52195 -350.518476) (xy 137.190226 -350.301814) (xy 137.179088 -350.296774) (xy 137.154679 -350.296636)
			(xy 137.14349 -350.30156) (xy 136.812528 -350.518476) (xy 136.568434 -350.518476) (xy 136.558266 -350.518009)
			(xy 136.539475 -350.510237) (xy 136.52509 -350.495865) (xy 136.517301 -350.477081) (xy 136.516872 -350.466914)
			(xy 134.707376 -350.466914) (xy 134.706878 -350.477071) (xy 134.699102 -350.495838) (xy 134.684738 -350.510202)
			(xy 134.665971 -350.517978) (xy 134.655814 -350.518476) (xy 134.41299 -350.518476) (xy 134.081266 -350.301814)
			(xy 134.070142 -350.296734) (xy 134.04572 -350.296622) (xy 134.03453 -350.30156) (xy 133.703568 -350.518476)
			(xy 133.459474 -350.518476) (xy 133.449316 -350.517988) (xy 133.430549 -350.510208) (xy 133.416185 -350.495841)
			(xy 133.408409 -350.477072) (xy 133.407912 -350.466914) (xy 131.598416 -350.466914) (xy 131.598046 -350.477092)
			(xy 131.590248 -350.495896) (xy 131.575846 -350.510282) (xy 131.557033 -350.518058) (xy 131.546854 -350.518476)
			(xy 131.30403 -350.518476) (xy 130.972306 -350.301814) (xy 130.961173 -350.296761) (xy 130.936759 -350.296631)
			(xy 130.92557 -350.30156) (xy 130.594608 -350.518476) (xy 130.350514 -350.518476) (xy 130.340359 -350.517956)
			(xy 130.321593 -350.510188) (xy 130.307227 -350.495831) (xy 130.29945 -350.477069) (xy 130.298952 -350.466914)
			(xy 128.489456 -350.466914) (xy 128.488978 -350.477073) (xy 128.481198 -350.495844) (xy 128.466827 -350.510209)
			(xy 128.448054 -350.517982) (xy 128.437894 -350.518476) (xy 128.19507 -350.518476) (xy 127.863346 -350.301814)
			(xy 127.852203 -350.296787) (xy 127.827799 -350.296641) (xy 127.81661 -350.30156) (xy 127.485648 -350.518476)
			(xy 127.241554 -350.518476) (xy 127.231395 -350.518005) (xy 127.212628 -350.510218) (xy 127.198264 -350.495846)
			(xy 127.190489 -350.477073) (xy 127.189992 -350.466914) (xy 125.380496 -350.466914) (xy 125.379979 -350.477068)
			(xy 125.372206 -350.495831) (xy 125.357848 -350.510195) (xy 125.339088 -350.517975) (xy 125.328934 -350.518476)
			(xy 125.08611 -350.518476) (xy 124.754386 -350.301814) (xy 124.743257 -350.296747) (xy 124.71884 -350.296626)
			(xy 124.70765 -350.30156) (xy 124.376688 -350.518476) (xy 124.132594 -350.518476) (xy 124.122438 -350.517972)
			(xy 124.103671 -350.510198) (xy 124.089307 -350.495836) (xy 124.08153 -350.47707) (xy 124.081032 -350.466914)
			(xy 122.271536 -350.466914) (xy 122.271147 -350.47709) (xy 122.263352 -350.49589) (xy 122.248956 -350.510275)
			(xy 122.23015 -350.518055) (xy 122.219974 -350.518476) (xy 121.97715 -350.518476) (xy 121.645426 -350.301814)
			(xy 121.634288 -350.296774) (xy 121.609879 -350.296636) (xy 121.59869 -350.30156) (xy 121.267728 -350.518476)
			(xy 121.023634 -350.518476) (xy 121.013466 -350.518009) (xy 120.994675 -350.510237) (xy 120.98029 -350.495865)
			(xy 120.972501 -350.477081) (xy 120.972072 -350.466914) (xy 119.162576 -350.466914) (xy 119.162078 -350.477071)
			(xy 119.154302 -350.495838) (xy 119.139938 -350.510202) (xy 119.121171 -350.517978) (xy 119.111014 -350.518476)
			(xy 118.86819 -350.518476) (xy 118.536466 -350.301814) (xy 118.525342 -350.296734) (xy 118.50092 -350.296622)
			(xy 118.48973 -350.30156) (xy 118.158768 -350.518476) (xy 117.914674 -350.518476) (xy 117.904516 -350.517988)
			(xy 117.885749 -350.510208) (xy 117.871385 -350.495841) (xy 117.863609 -350.477072) (xy 117.863112 -350.466914)
			(xy 116.053616 -350.466914) (xy 116.053246 -350.477092) (xy 116.045448 -350.495896) (xy 116.031046 -350.510282)
			(xy 116.012233 -350.518058) (xy 116.002054 -350.518476) (xy 115.75923 -350.518476) (xy 115.427506 -350.301814)
			(xy 115.416373 -350.296761) (xy 115.391959 -350.296631) (xy 115.38077 -350.30156) (xy 115.049808 -350.518476)
			(xy 114.805714 -350.518476) (xy 114.795559 -350.517956) (xy 114.776793 -350.510188) (xy 114.762427 -350.495831)
			(xy 114.75465 -350.477069) (xy 114.754152 -350.466914) (xy 112.944656 -350.466914) (xy 112.944178 -350.477073)
			(xy 112.936398 -350.495844) (xy 112.922027 -350.510209) (xy 112.903254 -350.517982) (xy 112.893094 -350.518476)
			(xy 112.65027 -350.518476) (xy 112.318546 -350.301814) (xy 112.307403 -350.296787) (xy 112.282999 -350.296641)
			(xy 112.27181 -350.30156) (xy 111.940848 -350.518476) (xy 111.696754 -350.518476) (xy 111.686595 -350.518005)
			(xy 111.667828 -350.510218) (xy 111.653464 -350.495846) (xy 111.645689 -350.477073) (xy 111.645192 -350.466914)
			(xy 93.544644 -350.466914) (xy 93.544241 -350.47712) (xy 93.536401 -350.495968) (xy 93.521927 -350.510362)
			(xy 93.503037 -350.518097) (xy 93.492828 -350.518476) (xy 93.250004 -350.518476) (xy 92.91828 -350.301814)
			(xy 92.907153 -350.296743) (xy 92.882734 -350.296625) (xy 92.871544 -350.30156) (xy 92.540582 -350.518476)
			(xy 92.296488 -350.518476) (xy 92.286306 -350.518034) (xy 92.267485 -350.510257) (xy 92.253057 -350.495885)
			(xy 92.245207 -350.477094) (xy 92.244672 -350.466914) (xy 90.435684 -350.466914) (xy 90.435242 -350.477115)
			(xy 90.427409 -350.495955) (xy 90.412948 -350.510347) (xy 90.394071 -350.51809) (xy 90.383868 -350.518476)
			(xy 90.141044 -350.518476) (xy 89.80932 -350.301814) (xy 89.798183 -350.29677) (xy 89.773773 -350.296635)
			(xy 89.762584 -350.30156) (xy 89.431622 -350.518476) (xy 89.187528 -350.518476) (xy 89.177348 -350.518001)
			(xy 89.158528 -350.510237) (xy 89.144099 -350.495875) (xy 89.136247 -350.477091) (xy 89.135712 -350.466914)
			(xy 87.326724 -350.466914) (xy 87.326341 -350.477123) (xy 87.318497 -350.495974) (xy 87.304017 -350.510369)
			(xy 87.285119 -350.518101) (xy 87.274908 -350.518476) (xy 87.032084 -350.518476) (xy 86.70036 -350.301814)
			(xy 86.689214 -350.296797) (xy 86.664813 -350.296644) (xy 86.653624 -350.30156) (xy 86.322662 -350.518476)
			(xy 86.078568 -350.518476) (xy 86.068384 -350.51805) (xy 86.049563 -350.510267) (xy 86.035136 -350.49589)
			(xy 86.027286 -350.477096) (xy 86.026752 -350.466914) (xy 84.217764 -350.466914) (xy 84.217342 -350.477118)
			(xy 84.209505 -350.495961) (xy 84.195037 -350.510355) (xy 84.176154 -350.518094) (xy 84.165948 -350.518476)
			(xy 83.923124 -350.518476) (xy 83.5914 -350.301814) (xy 83.580268 -350.296757) (xy 83.555854 -350.296629)
			(xy 83.544664 -350.30156) (xy 83.213702 -350.518476) (xy 82.969608 -350.518476) (xy 82.959427 -350.518017)
			(xy 82.940606 -350.510247) (xy 82.926178 -350.49588) (xy 82.918327 -350.477093) (xy 82.917792 -350.466914)
			(xy 81.108804 -350.466914) (xy 81.108343 -350.477113) (xy 81.100514 -350.495948) (xy 81.086058 -350.51034)
			(xy 81.067189 -350.518087) (xy 81.056988 -350.518476) (xy 80.814164 -350.518476) (xy 80.48244 -350.301814)
			(xy 80.471298 -350.296783) (xy 80.446893 -350.296639) (xy 80.435704 -350.30156) (xy 80.104742 -350.518476)
			(xy 79.860648 -350.518476) (xy 79.85047 -350.517984) (xy 79.83165 -350.510227) (xy 79.81722 -350.49587)
			(xy 79.809367 -350.47709) (xy 79.808832 -350.466914) (xy 77.999844 -350.466914) (xy 77.999441 -350.47712)
			(xy 77.991601 -350.495968) (xy 77.977127 -350.510362) (xy 77.958237 -350.518097) (xy 77.948028 -350.518476)
			(xy 77.705204 -350.518476) (xy 77.37348 -350.301814) (xy 77.362353 -350.296743) (xy 77.337934 -350.296625)
			(xy 77.326744 -350.30156) (xy 76.995782 -350.518476) (xy 76.751688 -350.518476) (xy 76.741506 -350.518034)
			(xy 76.722685 -350.510257) (xy 76.708257 -350.495885) (xy 76.700407 -350.477094) (xy 76.699872 -350.466914)
			(xy 74.890884 -350.466914) (xy 74.890442 -350.477115) (xy 74.882609 -350.495955) (xy 74.868148 -350.510347)
			(xy 74.849271 -350.51809) (xy 74.839068 -350.518476) (xy 74.596244 -350.518476) (xy 74.26452 -350.301814)
			(xy 74.253383 -350.29677) (xy 74.228973 -350.296635) (xy 74.217784 -350.30156) (xy 73.886822 -350.518476)
			(xy 73.642728 -350.518476) (xy 73.632548 -350.518001) (xy 73.613728 -350.510237) (xy 73.599299 -350.495875)
			(xy 73.591447 -350.477091) (xy 73.590912 -350.466914) (xy 71.781924 -350.466914) (xy 71.781541 -350.477123)
			(xy 71.773697 -350.495974) (xy 71.759217 -350.510369) (xy 71.740319 -350.518101) (xy 71.730108 -350.518476)
			(xy 71.487284 -350.518476) (xy 71.15556 -350.301814) (xy 71.144414 -350.296797) (xy 71.120013 -350.296644)
			(xy 71.108824 -350.30156) (xy 70.777862 -350.518476) (xy 70.533768 -350.518476) (xy 70.523584 -350.51805)
			(xy 70.504763 -350.510267) (xy 70.490336 -350.49589) (xy 70.482486 -350.477096) (xy 70.481952 -350.466914)
			(xy 68.672964 -350.466914) (xy 68.672542 -350.477118) (xy 68.664705 -350.495961) (xy 68.650237 -350.510355)
			(xy 68.631354 -350.518094) (xy 68.621148 -350.518476) (xy 68.378324 -350.518476) (xy 68.0466 -350.301814)
			(xy 68.035468 -350.296757) (xy 68.011054 -350.296629) (xy 67.999864 -350.30156) (xy 67.668902 -350.518476)
			(xy 67.424808 -350.518476) (xy 67.414627 -350.518017) (xy 67.395806 -350.510247) (xy 67.381378 -350.49588)
			(xy 67.373527 -350.477093) (xy 67.372992 -350.466914) (xy 65.564004 -350.466914) (xy 65.563543 -350.477113)
			(xy 65.555714 -350.495948) (xy 65.541258 -350.51034) (xy 65.522389 -350.518087) (xy 65.512188 -350.518476)
			(xy 65.269364 -350.518476) (xy 64.93764 -350.301814) (xy 64.926498 -350.296783) (xy 64.902093 -350.296639)
			(xy 64.890904 -350.30156) (xy 64.559942 -350.518476) (xy 64.315848 -350.518476) (xy 64.30567 -350.517984)
			(xy 64.28685 -350.510227) (xy 64.27242 -350.49587) (xy 64.264567 -350.47709) (xy 64.264032 -350.466914)
			(xy 62.455044 -350.466914) (xy 62.454641 -350.47712) (xy 62.446801 -350.495968) (xy 62.432327 -350.510362)
			(xy 62.413437 -350.518097) (xy 62.403228 -350.518476) (xy 62.160404 -350.518476) (xy 61.82868 -350.301814)
			(xy 61.817553 -350.296743) (xy 61.793134 -350.296625) (xy 61.781944 -350.30156) (xy 61.450982 -350.518476)
			(xy 61.206888 -350.518476) (xy 61.196706 -350.518034) (xy 61.177885 -350.510257) (xy 61.163457 -350.495885)
			(xy 61.155607 -350.477094) (xy 61.155072 -350.466914) (xy 51.504596 -350.466914) (xy 51.504079 -350.477068)
			(xy 51.496306 -350.495831) (xy 51.481948 -350.510195) (xy 51.463188 -350.517975) (xy 51.453034 -350.518476)
			(xy 51.21021 -350.518476) (xy 50.878486 -350.301814) (xy 50.867357 -350.296747) (xy 50.84294 -350.296626)
			(xy 50.83175 -350.30156) (xy 50.500788 -350.518476) (xy 50.256694 -350.518476) (xy 50.246538 -350.517972)
			(xy 50.227771 -350.510198) (xy 50.213407 -350.495836) (xy 50.20563 -350.47707) (xy 50.205132 -350.466914)
			(xy 48.395636 -350.466914) (xy 48.395247 -350.47709) (xy 48.387452 -350.49589) (xy 48.373056 -350.510275)
			(xy 48.35425 -350.518055) (xy 48.344074 -350.518476) (xy 48.10125 -350.518476) (xy 47.769526 -350.301814)
			(xy 47.758388 -350.296774) (xy 47.733979 -350.296636) (xy 47.72279 -350.30156) (xy 47.391828 -350.518476)
			(xy 47.147734 -350.518476) (xy 47.137566 -350.518009) (xy 47.118775 -350.510237) (xy 47.10439 -350.495865)
			(xy 47.096601 -350.477081) (xy 47.096172 -350.466914) (xy 45.286676 -350.466914) (xy 45.286178 -350.477071)
			(xy 45.278402 -350.495838) (xy 45.264038 -350.510202) (xy 45.245271 -350.517978) (xy 45.235114 -350.518476)
			(xy 44.99229 -350.518476) (xy 44.660566 -350.301814) (xy 44.649442 -350.296734) (xy 44.62502 -350.296622)
			(xy 44.61383 -350.30156) (xy 44.282868 -350.518476) (xy 44.038774 -350.518476) (xy 44.028616 -350.517988)
			(xy 44.009849 -350.510208) (xy 43.995485 -350.495841) (xy 43.987709 -350.477072) (xy 43.987212 -350.466914)
			(xy 42.177716 -350.466914) (xy 42.177346 -350.477092) (xy 42.169548 -350.495896) (xy 42.155146 -350.510282)
			(xy 42.136333 -350.518058) (xy 42.126154 -350.518476) (xy 41.88333 -350.518476) (xy 41.551606 -350.301814)
			(xy 41.540473 -350.296761) (xy 41.516059 -350.296631) (xy 41.50487 -350.30156) (xy 41.173908 -350.518476)
			(xy 40.929814 -350.518476) (xy 40.919659 -350.517956) (xy 40.900893 -350.510188) (xy 40.886527 -350.495831)
			(xy 40.87875 -350.477069) (xy 40.878252 -350.466914) (xy 39.068756 -350.466914) (xy 39.068278 -350.477073)
			(xy 39.060498 -350.495844) (xy 39.046127 -350.510209) (xy 39.027354 -350.517982) (xy 39.017194 -350.518476)
			(xy 38.77437 -350.518476) (xy 38.442646 -350.301814) (xy 38.431503 -350.296787) (xy 38.407099 -350.296641)
			(xy 38.39591 -350.30156) (xy 38.064948 -350.518476) (xy 37.820854 -350.518476) (xy 37.810695 -350.518005)
			(xy 37.791928 -350.510218) (xy 37.777564 -350.495846) (xy 37.769789 -350.477073) (xy 37.769292 -350.466914)
			(xy 35.959796 -350.466914) (xy 35.959279 -350.477068) (xy 35.951506 -350.495831) (xy 35.937148 -350.510195)
			(xy 35.918388 -350.517975) (xy 35.908234 -350.518476) (xy 35.66541 -350.518476) (xy 35.333686 -350.301814)
			(xy 35.322557 -350.296747) (xy 35.29814 -350.296626) (xy 35.28695 -350.30156) (xy 34.955988 -350.518476)
			(xy 34.711894 -350.518476) (xy 34.701738 -350.517972) (xy 34.682971 -350.510198) (xy 34.668607 -350.495836)
			(xy 34.66083 -350.47707) (xy 34.660332 -350.466914) (xy 32.850836 -350.466914) (xy 32.850447 -350.47709)
			(xy 32.842652 -350.49589) (xy 32.828256 -350.510275) (xy 32.80945 -350.518055) (xy 32.799274 -350.518476)
			(xy 32.55645 -350.518476) (xy 32.224726 -350.301814) (xy 32.213588 -350.296774) (xy 32.189179 -350.296636)
			(xy 32.17799 -350.30156) (xy 31.847028 -350.518476) (xy 31.602934 -350.518476) (xy 31.592766 -350.518009)
			(xy 31.573975 -350.510237) (xy 31.55959 -350.495865) (xy 31.551801 -350.477081) (xy 31.551372 -350.466914)
			(xy 29.741876 -350.466914) (xy 29.741378 -350.477071) (xy 29.733602 -350.495838) (xy 29.719238 -350.510202)
			(xy 29.700471 -350.517978) (xy 29.690314 -350.518476) (xy 29.44749 -350.518476) (xy 29.115766 -350.301814)
			(xy 29.104642 -350.296734) (xy 29.08022 -350.296622) (xy 29.06903 -350.30156) (xy 28.738068 -350.518476)
			(xy 28.493974 -350.518476) (xy 28.483816 -350.517988) (xy 28.465049 -350.510208) (xy 28.450685 -350.495841)
			(xy 28.442909 -350.477072) (xy 28.442412 -350.466914) (xy 26.632916 -350.466914) (xy 26.632546 -350.477092)
			(xy 26.624748 -350.495896) (xy 26.610346 -350.510282) (xy 26.591533 -350.518058) (xy 26.581354 -350.518476)
			(xy 26.33853 -350.518476) (xy 26.006806 -350.301814) (xy 25.995673 -350.296761) (xy 25.971259 -350.296631)
			(xy 25.96007 -350.30156) (xy 25.629108 -350.518476) (xy 25.385014 -350.518476) (xy 25.374859 -350.517956)
			(xy 25.356093 -350.510188) (xy 25.341727 -350.495831) (xy 25.33395 -350.477069) (xy 25.333452 -350.466914)
			(xy 23.523956 -350.466914) (xy 23.523478 -350.477073) (xy 23.515698 -350.495844) (xy 23.501327 -350.510209)
			(xy 23.482554 -350.517982) (xy 23.472394 -350.518476) (xy 23.22957 -350.518476) (xy 22.897846 -350.301814)
			(xy 22.886703 -350.296787) (xy 22.862299 -350.296641) (xy 22.85111 -350.30156) (xy 22.520148 -350.518476)
			(xy 22.276054 -350.518476) (xy 22.265895 -350.518005) (xy 22.247128 -350.510218) (xy 22.232764 -350.495846)
			(xy 22.224989 -350.477073) (xy 22.224492 -350.466914) (xy 20.414996 -350.466914) (xy 20.414479 -350.477068)
			(xy 20.406706 -350.495831) (xy 20.392348 -350.510195) (xy 20.373588 -350.517975) (xy 20.363434 -350.518476)
			(xy 20.12061 -350.518476) (xy 19.788886 -350.301814) (xy 19.777757 -350.296747) (xy 19.75334 -350.296626)
			(xy 19.74215 -350.30156) (xy 19.411188 -350.518476) (xy 19.167094 -350.518476) (xy 19.156938 -350.517972)
			(xy 19.138171 -350.510198) (xy 19.123807 -350.495836) (xy 19.11603 -350.47707) (xy 19.115532 -350.466914)
			(xy 8.210606 -350.466914) (xy 8.118914 -350.545471) (xy 8.015859 -350.623295) (xy 7.908208 -350.694627)
			(xy 7.796369 -350.759197) (xy 7.680768 -350.816759) (xy 7.561843 -350.867096) (xy 7.440044 -350.910016)
			(xy 7.315834 -350.945357) (xy 7.189685 -350.972984) (xy 7.062073 -350.992793) (xy 6.933484 -351.004709)
			(xy 6.804406 -351.008686) (xy 6.675328 -351.004709) (xy 6.546739 -350.992793) (xy 6.419127 -350.972984)
			(xy 6.292978 -350.945357) (xy 6.168768 -350.910016) (xy 6.046969 -350.867096) (xy 5.928044 -350.816759)
			(xy 5.812443 -350.759197) (xy 5.700604 -350.694627) (xy 5.592953 -350.623295) (xy 5.489898 -350.545471)
			(xy 5.391828 -350.46145) (xy 5.299117 -350.371551) (xy 5.212117 -350.276116) (xy 5.131156 -350.175506)
			(xy 5.056542 -350.070103) (xy 4.988559 -349.960306) (xy 4.927464 -349.846532) (xy 4.873489 -349.729213)
			(xy 4.826838 -349.608794) (xy 4.787689 -349.485731) (xy 4.75619 -349.360492) (xy 4.732461 -349.233551)
			(xy 4.716591 -349.105391) (xy 4.708641 -348.976496) (xy 0.509016 -348.976496) (xy 0.509016 -351.638709)
			(xy 18.951172 -351.638709) (xy 18.951172 -351.584171) (xy 18.958934 -351.530187) (xy 18.974299 -351.477857)
			(xy 18.996956 -351.428247) (xy 19.026441 -351.382366) (xy 19.062157 -351.341148) (xy 19.103374 -351.305433)
			(xy 19.149255 -351.275947) (xy 19.198865 -351.25329) (xy 19.251195 -351.237925) (xy 19.305179 -351.230163)
			(xy 19.332448 -351.229676) (xy 20.196048 -351.229676) (xy 20.223319 -351.230143) (xy 20.277306 -351.237905)
			(xy 20.329638 -351.253271) (xy 20.379252 -351.275929) (xy 20.425135 -351.305416) (xy 20.466355 -351.341133)
			(xy 20.502073 -351.382353) (xy 20.53156 -351.428237) (xy 20.554218 -351.47785) (xy 20.569584 -351.530182)
			(xy 20.577347 -351.584169) (xy 20.577347 -351.638669) (xy 22.060139 -351.638669) (xy 22.060139 -351.584131)
			(xy 22.067901 -351.530149) (xy 22.083266 -351.477821) (xy 22.105922 -351.428212) (xy 22.135407 -351.382333)
			(xy 22.171122 -351.341117) (xy 22.212339 -351.305403) (xy 22.258219 -351.275918) (xy 22.307829 -351.253263)
			(xy 22.360157 -351.237899) (xy 22.414139 -351.230139) (xy 22.441408 -351.229676) (xy 23.305008 -351.229676)
			(xy 23.33228 -351.230087) (xy 23.386268 -351.23785) (xy 23.438602 -351.253218) (xy 23.488216 -351.275877)
			(xy 23.5341 -351.305366) (xy 23.575321 -351.341085) (xy 23.611039 -351.382306) (xy 23.640527 -351.428191)
			(xy 23.663185 -351.477806) (xy 23.678551 -351.53014) (xy 23.686314 -351.584128) (xy 23.686314 -351.638665)
			(xy 25.169162 -351.638665) (xy 25.169162 -351.584135) (xy 25.176922 -351.530159) (xy 25.192284 -351.477838)
			(xy 25.214936 -351.428234) (xy 25.244416 -351.38236) (xy 25.280124 -351.341147) (xy 25.321334 -351.305435)
			(xy 25.367206 -351.275951) (xy 25.416808 -351.253296) (xy 25.469128 -351.237929) (xy 25.523103 -351.230165)
			(xy 25.550368 -351.229676) (xy 26.413968 -351.229676) (xy 26.441243 -351.230061) (xy 26.495239 -351.237821)
			(xy 26.547581 -351.253186) (xy 26.597203 -351.275844) (xy 26.643095 -351.305333) (xy 26.684323 -351.341054)
			(xy 26.720047 -351.382279) (xy 26.749541 -351.428169) (xy 26.772203 -351.477789) (xy 26.787573 -351.53013)
			(xy 26.795336 -351.584125) (xy 26.795336 -351.63867) (xy 28.278039 -351.63867) (xy 28.278039 -351.58413)
			(xy 28.285802 -351.530146) (xy 28.301168 -351.477817) (xy 28.323825 -351.428207) (xy 28.353312 -351.382326)
			(xy 28.389029 -351.341109) (xy 28.430249 -351.305396) (xy 28.476131 -351.275912) (xy 28.525743 -351.253258)
			(xy 28.578074 -351.237896) (xy 28.632058 -351.230137) (xy 28.659328 -351.229676) (xy 29.522928 -351.229676)
			(xy 29.550199 -351.230088) (xy 29.604185 -351.237854) (xy 29.656516 -351.253223) (xy 29.706128 -351.275883)
			(xy 29.75201 -351.305373) (xy 29.793228 -351.341092) (xy 29.828944 -351.382313) (xy 29.85843 -351.428197)
			(xy 29.881086 -351.47781) (xy 29.896452 -351.530143) (xy 29.904214 -351.584129) (xy 29.904214 -351.638666)
			(xy 31.387062 -351.638666) (xy 31.387062 -351.584134) (xy 31.394823 -351.530157) (xy 31.410186 -351.477833)
			(xy 31.432839 -351.428229) (xy 31.462321 -351.382353) (xy 31.498031 -351.34114) (xy 31.539243 -351.305428)
			(xy 31.585118 -351.275945) (xy 31.634722 -351.25329) (xy 31.687045 -351.237925) (xy 31.741022 -351.230163)
			(xy 31.768288 -351.229676) (xy 32.631888 -351.229676) (xy 32.659162 -351.230063) (xy 32.713156 -351.237824)
			(xy 32.765495 -351.253191) (xy 32.815115 -351.27585) (xy 32.861004 -351.30534) (xy 32.90223 -351.341061)
			(xy 32.937952 -351.382286) (xy 32.967444 -351.428175) (xy 32.990105 -351.477794) (xy 33.005473 -351.530132)
			(xy 33.013236 -351.584126) (xy 33.013236 -351.63867) (xy 34.49594 -351.63867) (xy 34.49594 -351.58413)
			(xy 34.503702 -351.530144) (xy 34.519069 -351.477812) (xy 34.541728 -351.428201) (xy 34.571217 -351.38232)
			(xy 34.606936 -351.341102) (xy 34.648158 -351.305388) (xy 34.694043 -351.275905) (xy 34.743658 -351.253253)
			(xy 34.795991 -351.237892) (xy 34.849977 -351.230136) (xy 34.877248 -351.229676) (xy 35.740848 -351.229676)
			(xy 35.768118 -351.23009) (xy 35.822102 -351.237858) (xy 35.874431 -351.253229) (xy 35.92404 -351.27589)
			(xy 35.969919 -351.30538) (xy 36.011135 -351.341099) (xy 36.046849 -351.382319) (xy 36.076333 -351.428203)
			(xy 36.098988 -351.477814) (xy 36.114352 -351.530145) (xy 36.122114 -351.58413) (xy 36.122114 -351.638669)
			(xy 37.604939 -351.638669) (xy 37.604939 -351.584131) (xy 37.612701 -351.530149) (xy 37.628066 -351.477821)
			(xy 37.650722 -351.428212) (xy 37.680207 -351.382333) (xy 37.715922 -351.341117) (xy 37.757139 -351.305403)
			(xy 37.803019 -351.275918) (xy 37.852629 -351.253263) (xy 37.904957 -351.237899) (xy 37.958939 -351.230139)
			(xy 37.986208 -351.229676) (xy 38.849808 -351.229676) (xy 38.87708 -351.230087) (xy 38.931068 -351.23785)
			(xy 38.983402 -351.253218) (xy 39.033016 -351.275877) (xy 39.0789 -351.305366) (xy 39.120121 -351.341085)
			(xy 39.155839 -351.382306) (xy 39.185327 -351.428191) (xy 39.207985 -351.477806) (xy 39.223351 -351.53014)
			(xy 39.231114 -351.584128) (xy 39.231114 -351.638665) (xy 40.713962 -351.638665) (xy 40.713962 -351.584135)
			(xy 40.721722 -351.530159) (xy 40.737084 -351.477838) (xy 40.759736 -351.428234) (xy 40.789216 -351.38236)
			(xy 40.824924 -351.341147) (xy 40.866134 -351.305435) (xy 40.912006 -351.275951) (xy 40.961608 -351.253296)
			(xy 41.013928 -351.237929) (xy 41.067903 -351.230165) (xy 41.095168 -351.229676) (xy 41.958768 -351.229676)
			(xy 41.986043 -351.230061) (xy 42.040039 -351.237821) (xy 42.092381 -351.253186) (xy 42.142003 -351.275844)
			(xy 42.187895 -351.305333) (xy 42.229123 -351.341054) (xy 42.264847 -351.382279) (xy 42.294341 -351.428169)
			(xy 42.317003 -351.477789) (xy 42.332373 -351.53013) (xy 42.340136 -351.584125) (xy 42.340136 -351.63867)
			(xy 43.822839 -351.63867) (xy 43.822839 -351.58413) (xy 43.830602 -351.530146) (xy 43.845968 -351.477817)
			(xy 43.868625 -351.428207) (xy 43.898112 -351.382326) (xy 43.933829 -351.341109) (xy 43.975049 -351.305396)
			(xy 44.020931 -351.275912) (xy 44.070543 -351.253258) (xy 44.122874 -351.237896) (xy 44.176858 -351.230137)
			(xy 44.204128 -351.229676) (xy 45.067728 -351.229676) (xy 45.094999 -351.230088) (xy 45.148985 -351.237854)
			(xy 45.201316 -351.253223) (xy 45.250928 -351.275883) (xy 45.29681 -351.305373) (xy 45.338028 -351.341092)
			(xy 45.373744 -351.382313) (xy 45.40323 -351.428197) (xy 45.425886 -351.47781) (xy 45.441252 -351.530143)
			(xy 45.449014 -351.584129) (xy 45.449014 -351.638666) (xy 46.931862 -351.638666) (xy 46.931862 -351.584134)
			(xy 46.939623 -351.530157) (xy 46.954986 -351.477833) (xy 46.977639 -351.428229) (xy 47.007121 -351.382353)
			(xy 47.042831 -351.34114) (xy 47.084043 -351.305428) (xy 47.129918 -351.275945) (xy 47.179522 -351.25329)
			(xy 47.231845 -351.237925) (xy 47.285822 -351.230163) (xy 47.313088 -351.229676) (xy 48.176688 -351.229676)
			(xy 48.203962 -351.230063) (xy 48.257956 -351.237824) (xy 48.310295 -351.253191) (xy 48.359915 -351.27585)
			(xy 48.405804 -351.30534) (xy 48.44703 -351.341061) (xy 48.482752 -351.382286) (xy 48.512244 -351.428175)
			(xy 48.534905 -351.477794) (xy 48.550273 -351.530132) (xy 48.558036 -351.584126) (xy 48.558036 -351.63867)
			(xy 50.04074 -351.63867) (xy 50.04074 -351.58413) (xy 50.048502 -351.530144) (xy 50.063869 -351.477812)
			(xy 50.086528 -351.428201) (xy 50.116017 -351.38232) (xy 50.151736 -351.341102) (xy 50.192958 -351.305388)
			(xy 50.238843 -351.275905) (xy 50.288458 -351.253253) (xy 50.340791 -351.237892) (xy 50.394777 -351.230136)
			(xy 50.422048 -351.229676) (xy 51.285648 -351.229676) (xy 51.312918 -351.23009) (xy 51.366902 -351.237858)
			(xy 51.419231 -351.253229) (xy 51.46884 -351.27589) (xy 51.514719 -351.30538) (xy 51.555935 -351.341099)
			(xy 51.591649 -351.382319) (xy 51.621133 -351.428203) (xy 51.643788 -351.477814) (xy 51.659152 -351.530145)
			(xy 51.666914 -351.58413) (xy 51.666914 -351.63867) (xy 60.99094 -351.63867) (xy 60.99094 -351.58413)
			(xy 60.998702 -351.530145) (xy 61.014069 -351.477814) (xy 61.036727 -351.428203) (xy 61.066216 -351.382322)
			(xy 61.101934 -351.341105) (xy 61.143155 -351.305391) (xy 61.18904 -351.275907) (xy 61.238653 -351.253254)
			(xy 61.290986 -351.237893) (xy 61.344972 -351.230137) (xy 61.372242 -351.229676) (xy 62.235842 -351.229676)
			(xy 62.263112 -351.230089) (xy 62.317097 -351.237857) (xy 62.369426 -351.253227) (xy 62.419036 -351.275888)
			(xy 62.464916 -351.305378) (xy 62.506133 -351.341097) (xy 62.541847 -351.382317) (xy 62.571332 -351.428201)
			(xy 62.593988 -351.477813) (xy 62.609352 -351.530145) (xy 62.617114 -351.58413) (xy 62.617114 -351.638668)
			(xy 64.099939 -351.638668) (xy 64.099939 -351.584132) (xy 64.107701 -351.53015) (xy 64.123066 -351.477822)
			(xy 64.145721 -351.428214) (xy 64.175206 -351.382335) (xy 64.21092 -351.341119) (xy 64.252136 -351.305405)
			(xy 64.298016 -351.27592) (xy 64.347624 -351.253265) (xy 64.399952 -351.2379) (xy 64.453934 -351.230139)
			(xy 64.481202 -351.229676) (xy 65.344802 -351.229676) (xy 65.372074 -351.230087) (xy 65.426063 -351.237849)
			(xy 65.478397 -351.253216) (xy 65.528012 -351.275875) (xy 65.573897 -351.305364) (xy 65.615119 -351.341083)
			(xy 65.650837 -351.382304) (xy 65.680326 -351.42819) (xy 65.702984 -351.477805) (xy 65.718351 -351.530139)
			(xy 65.726113 -351.584128) (xy 65.726113 -351.638665) (xy 67.208962 -351.638665) (xy 67.208962 -351.584135)
			(xy 67.216722 -351.53016) (xy 67.232084 -351.477839) (xy 67.254735 -351.428236) (xy 67.284215 -351.382362)
			(xy 67.319922 -351.341149) (xy 67.361131 -351.305437) (xy 67.407003 -351.275953) (xy 67.456603 -351.253297)
			(xy 67.508923 -351.23793) (xy 67.562897 -351.230165) (xy 67.590162 -351.229676) (xy 68.453762 -351.229676)
			(xy 68.481037 -351.230061) (xy 68.535034 -351.23782) (xy 68.587376 -351.253184) (xy 68.636999 -351.275842)
			(xy 68.682892 -351.305331) (xy 68.724121 -351.341052) (xy 68.759846 -351.382277) (xy 68.78934 -351.428167)
			(xy 68.812003 -351.477788) (xy 68.827372 -351.530129) (xy 68.835136 -351.584125) (xy 68.835136 -351.638669)
			(xy 70.317839 -351.638669) (xy 70.317839 -351.584131) (xy 70.325601 -351.530147) (xy 70.340967 -351.477818)
			(xy 70.363624 -351.428208) (xy 70.393111 -351.382328) (xy 70.428827 -351.341112) (xy 70.470046 -351.305398)
			(xy 70.515928 -351.275914) (xy 70.565539 -351.25326) (xy 70.617869 -351.237897) (xy 70.671853 -351.230138)
			(xy 70.699122 -351.229676) (xy 71.562722 -351.229676) (xy 71.589993 -351.230088) (xy 71.64398 -351.237853)
			(xy 71.696312 -351.253222) (xy 71.745924 -351.275881) (xy 71.791807 -351.305371) (xy 71.833026 -351.34109)
			(xy 71.868742 -351.382311) (xy 71.898229 -351.428195) (xy 71.920886 -351.477809) (xy 71.936252 -351.530142)
			(xy 71.944014 -351.584129) (xy 71.944014 -351.638666) (xy 73.426862 -351.638666) (xy 73.426862 -351.584134)
			(xy 73.434623 -351.530158) (xy 73.449986 -351.477835) (xy 73.472638 -351.428231) (xy 73.50212 -351.382355)
			(xy 73.537829 -351.341142) (xy 73.579041 -351.30543) (xy 73.624915 -351.275947) (xy 73.674518 -351.253292)
			(xy 73.72684 -351.237927) (xy 73.780816 -351.230164) (xy 73.808082 -351.229676) (xy 74.671682 -351.229676)
			(xy 74.698957 -351.230062) (xy 74.752951 -351.237823) (xy 74.805291 -351.253189) (xy 74.854911 -351.275848)
			(xy 74.900802 -351.305338) (xy 74.942028 -351.341059) (xy 74.977751 -351.382284) (xy 75.007243 -351.428173)
			(xy 75.029904 -351.477792) (xy 75.045273 -351.530132) (xy 75.053036 -351.584125) (xy 75.053036 -351.63867)
			(xy 76.53574 -351.63867) (xy 76.53574 -351.58413) (xy 76.543502 -351.530145) (xy 76.558869 -351.477814)
			(xy 76.581527 -351.428203) (xy 76.611016 -351.382322) (xy 76.646734 -351.341105) (xy 76.687955 -351.305391)
			(xy 76.73384 -351.275907) (xy 76.783453 -351.253254) (xy 76.835786 -351.237893) (xy 76.889772 -351.230137)
			(xy 76.917042 -351.229676) (xy 77.780642 -351.229676) (xy 77.807912 -351.230089) (xy 77.861897 -351.237857)
			(xy 77.914226 -351.253227) (xy 77.963836 -351.275888) (xy 78.009716 -351.305378) (xy 78.050933 -351.341097)
			(xy 78.086647 -351.382317) (xy 78.116132 -351.428201) (xy 78.138788 -351.477813) (xy 78.154152 -351.530145)
			(xy 78.161914 -351.58413) (xy 78.161914 -351.638668) (xy 79.644739 -351.638668) (xy 79.644739 -351.584132)
			(xy 79.652501 -351.53015) (xy 79.667866 -351.477822) (xy 79.690521 -351.428214) (xy 79.720006 -351.382335)
			(xy 79.75572 -351.341119) (xy 79.796936 -351.305405) (xy 79.842816 -351.27592) (xy 79.892424 -351.253265)
			(xy 79.944752 -351.2379) (xy 79.998734 -351.230139) (xy 80.026002 -351.229676) (xy 80.889602 -351.229676)
			(xy 80.916874 -351.230087) (xy 80.970863 -351.237849) (xy 81.023197 -351.253216) (xy 81.072812 -351.275875)
			(xy 81.118697 -351.305364) (xy 81.159919 -351.341083) (xy 81.195637 -351.382304) (xy 81.225126 -351.42819)
			(xy 81.247784 -351.477805) (xy 81.263151 -351.530139) (xy 81.270913 -351.584128) (xy 81.270913 -351.638665)
			(xy 82.753762 -351.638665) (xy 82.753762 -351.584135) (xy 82.761522 -351.53016) (xy 82.776884 -351.477839)
			(xy 82.799535 -351.428236) (xy 82.829015 -351.382362) (xy 82.864722 -351.341149) (xy 82.905931 -351.305437)
			(xy 82.951803 -351.275953) (xy 83.001403 -351.253297) (xy 83.053723 -351.23793) (xy 83.107697 -351.230165)
			(xy 83.134962 -351.229676) (xy 83.998562 -351.229676) (xy 84.025837 -351.230061) (xy 84.079834 -351.23782)
			(xy 84.132176 -351.253184) (xy 84.181799 -351.275842) (xy 84.227692 -351.305331) (xy 84.268921 -351.341052)
			(xy 84.304646 -351.382277) (xy 84.33414 -351.428167) (xy 84.356803 -351.477788) (xy 84.372172 -351.530129)
			(xy 84.379936 -351.584125) (xy 84.379936 -351.638669) (xy 85.862639 -351.638669) (xy 85.862639 -351.584131)
			(xy 85.870401 -351.530147) (xy 85.885767 -351.477818) (xy 85.908424 -351.428208) (xy 85.937911 -351.382328)
			(xy 85.973627 -351.341112) (xy 86.014846 -351.305398) (xy 86.060728 -351.275914) (xy 86.110339 -351.25326)
			(xy 86.162669 -351.237897) (xy 86.216653 -351.230138) (xy 86.243922 -351.229676) (xy 87.107522 -351.229676)
			(xy 87.134793 -351.230088) (xy 87.18878 -351.237853) (xy 87.241112 -351.253222) (xy 87.290724 -351.275881)
			(xy 87.336607 -351.305371) (xy 87.377826 -351.34109) (xy 87.413542 -351.382311) (xy 87.443029 -351.428195)
			(xy 87.465686 -351.477809) (xy 87.481052 -351.530142) (xy 87.488814 -351.584129) (xy 87.488814 -351.638666)
			(xy 88.971662 -351.638666) (xy 88.971662 -351.584134) (xy 88.979423 -351.530158) (xy 88.994786 -351.477835)
			(xy 89.017438 -351.428231) (xy 89.04692 -351.382355) (xy 89.082629 -351.341142) (xy 89.123841 -351.30543)
			(xy 89.169715 -351.275947) (xy 89.219318 -351.253292) (xy 89.27164 -351.237927) (xy 89.325616 -351.230164)
			(xy 89.352882 -351.229676) (xy 90.216482 -351.229676) (xy 90.243757 -351.230062) (xy 90.297751 -351.237823)
			(xy 90.350091 -351.253189) (xy 90.399711 -351.275848) (xy 90.445602 -351.305338) (xy 90.486828 -351.341059)
			(xy 90.522551 -351.382284) (xy 90.552043 -351.428173) (xy 90.574704 -351.477792) (xy 90.590073 -351.530132)
			(xy 90.597836 -351.584125) (xy 90.597836 -351.63867) (xy 92.08054 -351.63867) (xy 92.08054 -351.58413)
			(xy 92.088302 -351.530145) (xy 92.103669 -351.477814) (xy 92.126327 -351.428203) (xy 92.155816 -351.382322)
			(xy 92.191534 -351.341105) (xy 92.232755 -351.305391) (xy 92.27864 -351.275907) (xy 92.328253 -351.253254)
			(xy 92.380586 -351.237893) (xy 92.434572 -351.230137) (xy 92.461842 -351.229676) (xy 93.325442 -351.229676)
			(xy 93.352712 -351.230089) (xy 93.406697 -351.237857) (xy 93.459026 -351.253227) (xy 93.508636 -351.275888)
			(xy 93.554516 -351.305378) (xy 93.595733 -351.341097) (xy 93.631447 -351.382317) (xy 93.660932 -351.428201)
			(xy 93.683588 -351.477813) (xy 93.698952 -351.530145) (xy 93.706714 -351.58413) (xy 93.706714 -351.638669)
			(xy 111.480839 -351.638669) (xy 111.480839 -351.584131) (xy 111.488601 -351.530149) (xy 111.503966 -351.477821)
			(xy 111.526622 -351.428212) (xy 111.556107 -351.382333) (xy 111.591822 -351.341117) (xy 111.633039 -351.305403)
			(xy 111.678919 -351.275918) (xy 111.728529 -351.253263) (xy 111.780857 -351.237899) (xy 111.834839 -351.230139)
			(xy 111.862108 -351.229676) (xy 112.725708 -351.229676) (xy 112.75298 -351.230087) (xy 112.806968 -351.23785)
			(xy 112.859302 -351.253218) (xy 112.908916 -351.275877) (xy 112.9548 -351.305366) (xy 112.996021 -351.341085)
			(xy 113.031739 -351.382306) (xy 113.061227 -351.428191) (xy 113.083885 -351.477806) (xy 113.099251 -351.53014)
			(xy 113.107014 -351.584128) (xy 113.107014 -351.638665) (xy 114.589862 -351.638665) (xy 114.589862 -351.584135)
			(xy 114.597622 -351.530159) (xy 114.612984 -351.477838) (xy 114.635636 -351.428234) (xy 114.665116 -351.38236)
			(xy 114.700824 -351.341147) (xy 114.742034 -351.305435) (xy 114.787906 -351.275951) (xy 114.837508 -351.253296)
			(xy 114.889828 -351.237929) (xy 114.943803 -351.230165) (xy 114.971068 -351.229676) (xy 115.834668 -351.229676)
			(xy 115.861943 -351.230061) (xy 115.915939 -351.237821) (xy 115.968281 -351.253186) (xy 116.017903 -351.275844)
			(xy 116.063795 -351.305333) (xy 116.105023 -351.341054) (xy 116.140747 -351.382279) (xy 116.170241 -351.428169)
			(xy 116.192903 -351.477789) (xy 116.208273 -351.53013) (xy 116.216036 -351.584125) (xy 116.216036 -351.63867)
			(xy 117.698739 -351.63867) (xy 117.698739 -351.58413) (xy 117.706502 -351.530146) (xy 117.721868 -351.477817)
			(xy 117.744525 -351.428207) (xy 117.774012 -351.382326) (xy 117.809729 -351.341109) (xy 117.850949 -351.305396)
			(xy 117.896831 -351.275912) (xy 117.946443 -351.253258) (xy 117.998774 -351.237896) (xy 118.052758 -351.230137)
			(xy 118.080028 -351.229676) (xy 118.943628 -351.229676) (xy 118.970899 -351.230088) (xy 119.024885 -351.237854)
			(xy 119.077216 -351.253223) (xy 119.126828 -351.275883) (xy 119.17271 -351.305373) (xy 119.213928 -351.341092)
			(xy 119.249644 -351.382313) (xy 119.27913 -351.428197) (xy 119.301786 -351.47781) (xy 119.317152 -351.530143)
			(xy 119.324914 -351.584129) (xy 119.324914 -351.638666) (xy 120.807762 -351.638666) (xy 120.807762 -351.584134)
			(xy 120.815523 -351.530157) (xy 120.830886 -351.477833) (xy 120.853539 -351.428229) (xy 120.883021 -351.382353)
			(xy 120.918731 -351.34114) (xy 120.959943 -351.305428) (xy 121.005818 -351.275945) (xy 121.055422 -351.25329)
			(xy 121.107745 -351.237925) (xy 121.161722 -351.230163) (xy 121.188988 -351.229676) (xy 122.052588 -351.229676)
			(xy 122.079862 -351.230063) (xy 122.133856 -351.237824) (xy 122.186195 -351.253191) (xy 122.235815 -351.27585)
			(xy 122.281704 -351.30534) (xy 122.32293 -351.341061) (xy 122.358652 -351.382286) (xy 122.388144 -351.428175)
			(xy 122.410805 -351.477794) (xy 122.426173 -351.530132) (xy 122.433936 -351.584126) (xy 122.433936 -351.63867)
			(xy 123.91664 -351.63867) (xy 123.91664 -351.58413) (xy 123.924402 -351.530144) (xy 123.939769 -351.477812)
			(xy 123.962428 -351.428201) (xy 123.991917 -351.38232) (xy 124.027636 -351.341102) (xy 124.068858 -351.305388)
			(xy 124.114743 -351.275905) (xy 124.164358 -351.253253) (xy 124.216691 -351.237892) (xy 124.270677 -351.230136)
			(xy 124.297948 -351.229676) (xy 125.161548 -351.229676) (xy 125.188818 -351.23009) (xy 125.242802 -351.237858)
			(xy 125.295131 -351.253229) (xy 125.34474 -351.27589) (xy 125.390619 -351.30538) (xy 125.431835 -351.341099)
			(xy 125.467549 -351.382319) (xy 125.497033 -351.428203) (xy 125.519688 -351.477814) (xy 125.535052 -351.530145)
			(xy 125.542814 -351.58413) (xy 125.542814 -351.638669) (xy 127.025639 -351.638669) (xy 127.025639 -351.584131)
			(xy 127.033401 -351.530149) (xy 127.048766 -351.477821) (xy 127.071422 -351.428212) (xy 127.100907 -351.382333)
			(xy 127.136622 -351.341117) (xy 127.177839 -351.305403) (xy 127.223719 -351.275918) (xy 127.273329 -351.253263)
			(xy 127.325657 -351.237899) (xy 127.379639 -351.230139) (xy 127.406908 -351.229676) (xy 128.270508 -351.229676)
			(xy 128.29778 -351.230087) (xy 128.351768 -351.23785) (xy 128.404102 -351.253218) (xy 128.453716 -351.275877)
			(xy 128.4996 -351.305366) (xy 128.540821 -351.341085) (xy 128.576539 -351.382306) (xy 128.606027 -351.428191)
			(xy 128.628685 -351.477806) (xy 128.644051 -351.53014) (xy 128.651814 -351.584128) (xy 128.651814 -351.638665)
			(xy 130.134662 -351.638665) (xy 130.134662 -351.584135) (xy 130.142422 -351.530159) (xy 130.157784 -351.477838)
			(xy 130.180436 -351.428234) (xy 130.209916 -351.38236) (xy 130.245624 -351.341147) (xy 130.286834 -351.305435)
			(xy 130.332706 -351.275951) (xy 130.382308 -351.253296) (xy 130.434628 -351.237929) (xy 130.488603 -351.230165)
			(xy 130.515868 -351.229676) (xy 131.379468 -351.229676) (xy 131.406743 -351.230061) (xy 131.460739 -351.237821)
			(xy 131.513081 -351.253186) (xy 131.562703 -351.275844) (xy 131.608595 -351.305333) (xy 131.649823 -351.341054)
			(xy 131.685547 -351.382279) (xy 131.715041 -351.428169) (xy 131.737703 -351.477789) (xy 131.753073 -351.53013)
			(xy 131.760836 -351.584125) (xy 131.760836 -351.63867) (xy 133.243539 -351.63867) (xy 133.243539 -351.58413)
			(xy 133.251302 -351.530146) (xy 133.266668 -351.477817) (xy 133.289325 -351.428207) (xy 133.318812 -351.382326)
			(xy 133.354529 -351.341109) (xy 133.395749 -351.305396) (xy 133.441631 -351.275912) (xy 133.491243 -351.253258)
			(xy 133.543574 -351.237896) (xy 133.597558 -351.230137) (xy 133.624828 -351.229676) (xy 134.488428 -351.229676)
			(xy 134.515699 -351.230088) (xy 134.569685 -351.237854) (xy 134.622016 -351.253223) (xy 134.671628 -351.275883)
			(xy 134.71751 -351.305373) (xy 134.758728 -351.341092) (xy 134.794444 -351.382313) (xy 134.82393 -351.428197)
			(xy 134.846586 -351.47781) (xy 134.861952 -351.530143) (xy 134.869714 -351.584129) (xy 134.869714 -351.638666)
			(xy 136.352562 -351.638666) (xy 136.352562 -351.584134) (xy 136.360323 -351.530157) (xy 136.375686 -351.477833)
			(xy 136.398339 -351.428229) (xy 136.427821 -351.382353) (xy 136.463531 -351.34114) (xy 136.504743 -351.305428)
			(xy 136.550618 -351.275945) (xy 136.600222 -351.25329) (xy 136.652545 -351.237925) (xy 136.706522 -351.230163)
			(xy 136.733788 -351.229676) (xy 137.597388 -351.229676) (xy 137.624662 -351.230063) (xy 137.678656 -351.237824)
			(xy 137.730995 -351.253191) (xy 137.780615 -351.27585) (xy 137.826504 -351.30534) (xy 137.86773 -351.341061)
			(xy 137.903452 -351.382286) (xy 137.932944 -351.428175) (xy 137.955605 -351.477794) (xy 137.970973 -351.530132)
			(xy 137.978736 -351.584126) (xy 137.978736 -351.63867) (xy 139.46144 -351.63867) (xy 139.46144 -351.58413)
			(xy 139.469202 -351.530144) (xy 139.484569 -351.477812) (xy 139.507228 -351.428201) (xy 139.536717 -351.38232)
			(xy 139.572436 -351.341102) (xy 139.613658 -351.305388) (xy 139.659543 -351.275905) (xy 139.709158 -351.253253)
			(xy 139.761491 -351.237892) (xy 139.815477 -351.230136) (xy 139.842748 -351.229676) (xy 140.706348 -351.229676)
			(xy 140.733618 -351.23009) (xy 140.787602 -351.237858) (xy 140.839931 -351.253229) (xy 140.88954 -351.27589)
			(xy 140.935419 -351.30538) (xy 140.976635 -351.341099) (xy 141.012349 -351.382319) (xy 141.041833 -351.428203)
			(xy 141.064488 -351.477814) (xy 141.079852 -351.530145) (xy 141.087614 -351.58413) (xy 141.087614 -351.638669)
			(xy 142.570439 -351.638669) (xy 142.570439 -351.584131) (xy 142.578201 -351.530149) (xy 142.593566 -351.477821)
			(xy 142.616222 -351.428212) (xy 142.645707 -351.382333) (xy 142.681422 -351.341117) (xy 142.722639 -351.305403)
			(xy 142.768519 -351.275918) (xy 142.818129 -351.253263) (xy 142.870457 -351.237899) (xy 142.924439 -351.230139)
			(xy 142.951708 -351.229676) (xy 143.815308 -351.229676) (xy 143.84258 -351.230087) (xy 143.896568 -351.23785)
			(xy 143.948902 -351.253218) (xy 143.998516 -351.275877) (xy 144.0444 -351.305366) (xy 144.085621 -351.341085)
			(xy 144.121339 -351.382306) (xy 144.150827 -351.428191) (xy 144.173485 -351.477806) (xy 144.188851 -351.53014)
			(xy 144.196614 -351.584128) (xy 144.196614 -351.638669) (xy 161.804839 -351.638669) (xy 161.804839 -351.584131)
			(xy 161.812601 -351.530149) (xy 161.827966 -351.47782) (xy 161.850623 -351.428211) (xy 161.880108 -351.382331)
			(xy 161.915824 -351.341115) (xy 161.957041 -351.305401) (xy 162.002922 -351.275917) (xy 162.052531 -351.253262)
			(xy 162.10486 -351.237899) (xy 162.158843 -351.230139) (xy 162.186112 -351.229676) (xy 163.049712 -351.229676)
			(xy 163.076984 -351.230087) (xy 163.130971 -351.237851) (xy 163.183304 -351.253219) (xy 163.232918 -351.275878)
			(xy 163.278802 -351.305367) (xy 163.320022 -351.341086) (xy 163.35574 -351.382308) (xy 163.385228 -351.428192)
			(xy 163.407885 -351.477807) (xy 163.423251 -351.530141) (xy 163.431014 -351.584128) (xy 163.431014 -351.638665)
			(xy 164.913862 -351.638665) (xy 164.913862 -351.584135) (xy 164.921622 -351.530159) (xy 164.936985 -351.477837)
			(xy 164.959637 -351.428233) (xy 164.989117 -351.382358) (xy 165.024826 -351.341146) (xy 165.066036 -351.305434)
			(xy 165.111909 -351.27595) (xy 165.16151 -351.253295) (xy 165.213831 -351.237928) (xy 165.267807 -351.230164)
			(xy 165.295072 -351.229676) (xy 166.158672 -351.229676) (xy 166.185947 -351.230062) (xy 166.239942 -351.237821)
			(xy 166.292284 -351.253187) (xy 166.341905 -351.275845) (xy 166.387797 -351.305335) (xy 166.429024 -351.341056)
			(xy 166.464748 -351.382281) (xy 166.494242 -351.42817) (xy 166.516903 -351.47779) (xy 166.532273 -351.53013)
			(xy 166.540036 -351.584125) (xy 166.540036 -351.63867) (xy 168.022739 -351.63867) (xy 168.022739 -351.58413)
			(xy 168.030502 -351.530146) (xy 168.045868 -351.477816) (xy 168.068526 -351.428206) (xy 168.098013 -351.382325)
			(xy 168.133731 -351.341108) (xy 168.174951 -351.305394) (xy 168.220834 -351.27591) (xy 168.270446 -351.253257)
			(xy 168.322777 -351.237895) (xy 168.376762 -351.230137) (xy 168.404032 -351.229676) (xy 169.267632 -351.229676)
			(xy 169.294903 -351.230089) (xy 169.348888 -351.237855) (xy 169.401219 -351.253224) (xy 169.45083 -351.275885)
			(xy 169.496712 -351.305374) (xy 169.537929 -351.341093) (xy 169.573645 -351.382314) (xy 169.603131 -351.428198)
			(xy 169.625787 -351.477811) (xy 169.641152 -351.530143) (xy 169.648914 -351.584129) (xy 169.648914 -351.638666)
			(xy 171.131762 -351.638666) (xy 171.131762 -351.584134) (xy 171.139523 -351.530156) (xy 171.154886 -351.477832)
			(xy 171.17754 -351.428228) (xy 171.207022 -351.382352) (xy 171.242733 -351.341138) (xy 171.283945 -351.305427)
			(xy 171.329821 -351.275944) (xy 171.379425 -351.253289) (xy 171.431748 -351.237925) (xy 171.485726 -351.230163)
			(xy 171.512992 -351.229676) (xy 172.376592 -351.229676) (xy 172.403866 -351.230063) (xy 172.457859 -351.237825)
			(xy 172.510198 -351.253192) (xy 172.559817 -351.275851) (xy 172.605706 -351.305342) (xy 172.646932 -351.341063)
			(xy 172.682653 -351.382287) (xy 172.712145 -351.428176) (xy 172.734805 -351.477794) (xy 172.750173 -351.530133)
			(xy 172.757936 -351.584126) (xy 172.757936 -351.638664) (xy 174.240762 -351.638664) (xy 174.240762 -351.584136)
			(xy 174.248522 -351.530162) (xy 174.263883 -351.477841) (xy 174.286534 -351.428239) (xy 174.316012 -351.382365)
			(xy 174.351719 -351.341153) (xy 174.392926 -351.305441) (xy 174.438797 -351.275957) (xy 174.488396 -351.2533)
			(xy 174.540715 -351.237932) (xy 174.594688 -351.230166) (xy 174.621952 -351.229676) (xy 175.485552 -351.229676)
			(xy 175.512828 -351.23006) (xy 175.566825 -351.237818) (xy 175.619169 -351.253181) (xy 175.668793 -351.275838)
			(xy 175.714687 -351.305328) (xy 175.755917 -351.341049) (xy 175.791644 -351.382274) (xy 175.821139 -351.428165)
			(xy 175.843802 -351.477786) (xy 175.859172 -351.530128) (xy 175.866936 -351.584124) (xy 175.866936 -351.638669)
			(xy 177.349639 -351.638669) (xy 177.349639 -351.584131) (xy 177.357401 -351.530149) (xy 177.372766 -351.47782)
			(xy 177.395423 -351.428211) (xy 177.424908 -351.382331) (xy 177.460624 -351.341115) (xy 177.501841 -351.305401)
			(xy 177.547722 -351.275917) (xy 177.597331 -351.253262) (xy 177.64966 -351.237899) (xy 177.703643 -351.230139)
			(xy 177.730912 -351.229676) (xy 178.594512 -351.229676) (xy 178.621784 -351.230087) (xy 178.675771 -351.237851)
			(xy 178.728104 -351.253219) (xy 178.777718 -351.275878) (xy 178.823602 -351.305367) (xy 178.864822 -351.341086)
			(xy 178.90054 -351.382308) (xy 178.930028 -351.428192) (xy 178.952685 -351.477807) (xy 178.968051 -351.530141)
			(xy 178.975814 -351.584128) (xy 178.975814 -351.638665) (xy 180.458662 -351.638665) (xy 180.458662 -351.584135)
			(xy 180.466422 -351.530159) (xy 180.481785 -351.477837) (xy 180.504437 -351.428233) (xy 180.533917 -351.382358)
			(xy 180.569626 -351.341146) (xy 180.610836 -351.305434) (xy 180.656709 -351.27595) (xy 180.70631 -351.253295)
			(xy 180.758631 -351.237928) (xy 180.812607 -351.230164) (xy 180.839872 -351.229676) (xy 181.703472 -351.229676)
			(xy 181.730747 -351.230062) (xy 181.784742 -351.237821) (xy 181.837084 -351.253187) (xy 181.886705 -351.275845)
			(xy 181.932597 -351.305335) (xy 181.973824 -351.341056) (xy 182.009548 -351.382281) (xy 182.039042 -351.42817)
			(xy 182.061703 -351.47779) (xy 182.077073 -351.53013) (xy 182.084836 -351.584125) (xy 182.084836 -351.63867)
			(xy 183.567539 -351.63867) (xy 183.567539 -351.58413) (xy 183.575302 -351.530146) (xy 183.590668 -351.477816)
			(xy 183.613326 -351.428206) (xy 183.642813 -351.382325) (xy 183.678531 -351.341108) (xy 183.719751 -351.305394)
			(xy 183.765634 -351.27591) (xy 183.815246 -351.253257) (xy 183.867577 -351.237895) (xy 183.921562 -351.230137)
			(xy 183.948832 -351.229676) (xy 184.812432 -351.229676) (xy 184.839703 -351.230089) (xy 184.893688 -351.237855)
			(xy 184.946019 -351.253224) (xy 184.99563 -351.275885) (xy 185.041512 -351.305374) (xy 185.082729 -351.341093)
			(xy 185.118445 -351.382314) (xy 185.147931 -351.428198) (xy 185.170587 -351.477811) (xy 185.185952 -351.530143)
			(xy 185.193714 -351.584129) (xy 185.193714 -351.638666) (xy 186.676562 -351.638666) (xy 186.676562 -351.584134)
			(xy 186.684323 -351.530156) (xy 186.699686 -351.477832) (xy 186.72234 -351.428228) (xy 186.751822 -351.382352)
			(xy 186.787533 -351.341138) (xy 186.828745 -351.305427) (xy 186.874621 -351.275944) (xy 186.924225 -351.253289)
			(xy 186.976548 -351.237925) (xy 187.030526 -351.230163) (xy 187.057792 -351.229676) (xy 187.921392 -351.229676)
			(xy 187.948666 -351.230063) (xy 188.002659 -351.237825) (xy 188.054998 -351.253192) (xy 188.104617 -351.275851)
			(xy 188.150506 -351.305342) (xy 188.191732 -351.341063) (xy 188.227453 -351.382287) (xy 188.256945 -351.428176)
			(xy 188.279605 -351.477794) (xy 188.294973 -351.530133) (xy 188.302736 -351.584126) (xy 188.302736 -351.638664)
			(xy 189.785562 -351.638664) (xy 189.785562 -351.584136) (xy 189.793322 -351.530162) (xy 189.808683 -351.477841)
			(xy 189.831334 -351.428239) (xy 189.860812 -351.382365) (xy 189.896519 -351.341153) (xy 189.937726 -351.305441)
			(xy 189.983597 -351.275957) (xy 190.033196 -351.2533) (xy 190.085515 -351.237932) (xy 190.139488 -351.230166)
			(xy 190.166752 -351.229676) (xy 191.030352 -351.229676) (xy 191.057628 -351.23006) (xy 191.111625 -351.237818)
			(xy 191.163969 -351.253181) (xy 191.213593 -351.275838) (xy 191.259487 -351.305328) (xy 191.300717 -351.341049)
			(xy 191.336444 -351.382274) (xy 191.365939 -351.428165) (xy 191.388602 -351.477786) (xy 191.403972 -351.530128)
			(xy 191.411736 -351.584124) (xy 191.411736 -351.638669) (xy 192.894439 -351.638669) (xy 192.894439 -351.584131)
			(xy 192.902201 -351.530149) (xy 192.917566 -351.47782) (xy 192.940223 -351.428211) (xy 192.969708 -351.382331)
			(xy 193.005424 -351.341115) (xy 193.046641 -351.305401) (xy 193.092522 -351.275917) (xy 193.142131 -351.253262)
			(xy 193.19446 -351.237899) (xy 193.248443 -351.230139) (xy 193.275712 -351.229676) (xy 194.139312 -351.229676)
			(xy 194.166584 -351.230087) (xy 194.220571 -351.237851) (xy 194.272904 -351.253219) (xy 194.322518 -351.275878)
			(xy 194.368402 -351.305367) (xy 194.409622 -351.341086) (xy 194.44534 -351.382308) (xy 194.474828 -351.428192)
			(xy 194.497485 -351.477807) (xy 194.512851 -351.530141) (xy 194.520614 -351.584128) (xy 194.520614 -351.638668)
			(xy 267.515839 -351.638668) (xy 267.515839 -351.584132) (xy 267.523601 -351.53015) (xy 267.538966 -351.477822)
			(xy 267.561621 -351.428214) (xy 267.591106 -351.382335) (xy 267.62682 -351.341119) (xy 267.668036 -351.305405)
			(xy 267.713916 -351.27592) (xy 267.763524 -351.253265) (xy 267.815852 -351.2379) (xy 267.869834 -351.230139)
			(xy 267.897102 -351.229676) (xy 268.760702 -351.229676) (xy 268.787974 -351.230087) (xy 268.841963 -351.237849)
			(xy 268.894297 -351.253216) (xy 268.943912 -351.275875) (xy 268.989797 -351.305364) (xy 269.031019 -351.341083)
			(xy 269.066737 -351.382304) (xy 269.096226 -351.42819) (xy 269.118884 -351.477805) (xy 269.134251 -351.530139)
			(xy 269.142013 -351.584128) (xy 269.142013 -351.638665) (xy 270.624862 -351.638665) (xy 270.624862 -351.584135)
			(xy 270.632622 -351.53016) (xy 270.647984 -351.477839) (xy 270.670635 -351.428236) (xy 270.700115 -351.382362)
			(xy 270.735822 -351.341149) (xy 270.777031 -351.305437) (xy 270.822903 -351.275953) (xy 270.872503 -351.253297)
			(xy 270.924823 -351.23793) (xy 270.978797 -351.230165) (xy 271.006062 -351.229676) (xy 271.869662 -351.229676)
			(xy 271.896937 -351.230061) (xy 271.950934 -351.23782) (xy 272.003276 -351.253184) (xy 272.052899 -351.275842)
			(xy 272.098792 -351.305331) (xy 272.140021 -351.341052) (xy 272.175746 -351.382277) (xy 272.20524 -351.428167)
			(xy 272.227903 -351.477788) (xy 272.243272 -351.530129) (xy 272.251036 -351.584125) (xy 272.251036 -351.638669)
			(xy 273.733739 -351.638669) (xy 273.733739 -351.584131) (xy 273.741501 -351.530147) (xy 273.756867 -351.477818)
			(xy 273.779524 -351.428208) (xy 273.809011 -351.382328) (xy 273.844727 -351.341112) (xy 273.885946 -351.305398)
			(xy 273.931828 -351.275914) (xy 273.981439 -351.25326) (xy 274.033769 -351.237897) (xy 274.087753 -351.230138)
			(xy 274.115022 -351.229676) (xy 274.978622 -351.229676) (xy 275.005893 -351.230088) (xy 275.05988 -351.237853)
			(xy 275.112212 -351.253222) (xy 275.161824 -351.275881) (xy 275.207707 -351.305371) (xy 275.248926 -351.34109)
			(xy 275.284642 -351.382311) (xy 275.314129 -351.428195) (xy 275.336786 -351.477809) (xy 275.352152 -351.530142)
			(xy 275.359914 -351.584129) (xy 275.359914 -351.638666) (xy 276.842762 -351.638666) (xy 276.842762 -351.584134)
			(xy 276.850523 -351.530158) (xy 276.865886 -351.477835) (xy 276.888538 -351.428231) (xy 276.91802 -351.382355)
			(xy 276.953729 -351.341142) (xy 276.994941 -351.30543) (xy 277.040815 -351.275947) (xy 277.090418 -351.253292)
			(xy 277.14274 -351.237927) (xy 277.196716 -351.230164) (xy 277.223982 -351.229676) (xy 278.087582 -351.229676)
			(xy 278.114857 -351.230062) (xy 278.168851 -351.237823) (xy 278.221191 -351.253189) (xy 278.270811 -351.275848)
			(xy 278.316702 -351.305338) (xy 278.357928 -351.341059) (xy 278.393651 -351.382284) (xy 278.423143 -351.428173)
			(xy 278.445804 -351.477792) (xy 278.461173 -351.530132) (xy 278.468936 -351.584125) (xy 278.468936 -351.63867)
			(xy 279.95164 -351.63867) (xy 279.95164 -351.58413) (xy 279.959402 -351.530145) (xy 279.974769 -351.477814)
			(xy 279.997427 -351.428203) (xy 280.026916 -351.382322) (xy 280.062634 -351.341105) (xy 280.103855 -351.305391)
			(xy 280.14974 -351.275907) (xy 280.199353 -351.253254) (xy 280.251686 -351.237893) (xy 280.305672 -351.230137)
			(xy 280.332942 -351.229676) (xy 281.196542 -351.229676) (xy 281.223812 -351.230089) (xy 281.277797 -351.237857)
			(xy 281.330126 -351.253227) (xy 281.379736 -351.275888) (xy 281.425616 -351.305378) (xy 281.466833 -351.341097)
			(xy 281.502547 -351.382317) (xy 281.532032 -351.428201) (xy 281.554688 -351.477813) (xy 281.570052 -351.530145)
			(xy 281.577814 -351.58413) (xy 281.577814 -351.638668) (xy 283.060639 -351.638668) (xy 283.060639 -351.584132)
			(xy 283.068401 -351.53015) (xy 283.083766 -351.477822) (xy 283.106421 -351.428214) (xy 283.135906 -351.382335)
			(xy 283.17162 -351.341119) (xy 283.212836 -351.305405) (xy 283.258716 -351.27592) (xy 283.308324 -351.253265)
			(xy 283.360652 -351.2379) (xy 283.414634 -351.230139) (xy 283.441902 -351.229676) (xy 284.305502 -351.229676)
			(xy 284.332774 -351.230087) (xy 284.386763 -351.237849) (xy 284.439097 -351.253216) (xy 284.488712 -351.275875)
			(xy 284.534597 -351.305364) (xy 284.575819 -351.341083) (xy 284.611537 -351.382304) (xy 284.641026 -351.42819)
			(xy 284.663684 -351.477805) (xy 284.679051 -351.530139) (xy 284.686813 -351.584128) (xy 284.686813 -351.638665)
			(xy 286.169662 -351.638665) (xy 286.169662 -351.584135) (xy 286.177422 -351.53016) (xy 286.192784 -351.477839)
			(xy 286.215435 -351.428236) (xy 286.244915 -351.382362) (xy 286.280622 -351.341149) (xy 286.321831 -351.305437)
			(xy 286.367703 -351.275953) (xy 286.417303 -351.253297) (xy 286.469623 -351.23793) (xy 286.523597 -351.230165)
			(xy 286.550862 -351.229676) (xy 287.414462 -351.229676) (xy 287.441737 -351.230061) (xy 287.495734 -351.23782)
			(xy 287.548076 -351.253184) (xy 287.597699 -351.275842) (xy 287.643592 -351.305331) (xy 287.684821 -351.341052)
			(xy 287.720546 -351.382277) (xy 287.75004 -351.428167) (xy 287.772703 -351.477788) (xy 287.788072 -351.530129)
			(xy 287.795836 -351.584125) (xy 287.795836 -351.638669) (xy 289.278539 -351.638669) (xy 289.278539 -351.584131)
			(xy 289.286301 -351.530147) (xy 289.301667 -351.477818) (xy 289.324324 -351.428208) (xy 289.353811 -351.382328)
			(xy 289.389527 -351.341112) (xy 289.430746 -351.305398) (xy 289.476628 -351.275914) (xy 289.526239 -351.25326)
			(xy 289.578569 -351.237897) (xy 289.632553 -351.230138) (xy 289.659822 -351.229676) (xy 290.523422 -351.229676)
			(xy 290.550693 -351.230088) (xy 290.60468 -351.237853) (xy 290.657012 -351.253222) (xy 290.706624 -351.275881)
			(xy 290.752507 -351.305371) (xy 290.793726 -351.34109) (xy 290.829442 -351.382311) (xy 290.858929 -351.428195)
			(xy 290.881586 -351.477809) (xy 290.896952 -351.530142) (xy 290.904714 -351.584129) (xy 290.904714 -351.638666)
			(xy 292.387562 -351.638666) (xy 292.387562 -351.584134) (xy 292.395323 -351.530158) (xy 292.410686 -351.477835)
			(xy 292.433338 -351.428231) (xy 292.46282 -351.382355) (xy 292.498529 -351.341142) (xy 292.539741 -351.30543)
			(xy 292.585615 -351.275947) (xy 292.635218 -351.253292) (xy 292.68754 -351.237927) (xy 292.741516 -351.230164)
			(xy 292.768782 -351.229676) (xy 293.632382 -351.229676) (xy 293.659657 -351.230062) (xy 293.713651 -351.237823)
			(xy 293.765991 -351.253189) (xy 293.815611 -351.275848) (xy 293.861502 -351.305338) (xy 293.902728 -351.341059)
			(xy 293.938451 -351.382284) (xy 293.967943 -351.428173) (xy 293.990604 -351.477792) (xy 294.005973 -351.530132)
			(xy 294.013736 -351.584125) (xy 294.013736 -351.63867) (xy 295.49644 -351.63867) (xy 295.49644 -351.58413)
			(xy 295.504202 -351.530145) (xy 295.519569 -351.477814) (xy 295.542227 -351.428203) (xy 295.571716 -351.382322)
			(xy 295.607434 -351.341105) (xy 295.648655 -351.305391) (xy 295.69454 -351.275907) (xy 295.744153 -351.253254)
			(xy 295.796486 -351.237893) (xy 295.850472 -351.230137) (xy 295.877742 -351.229676) (xy 296.741342 -351.229676)
			(xy 296.768612 -351.230089) (xy 296.822597 -351.237857) (xy 296.874926 -351.253227) (xy 296.924536 -351.275888)
			(xy 296.970416 -351.305378) (xy 297.011633 -351.341097) (xy 297.047347 -351.382317) (xy 297.076832 -351.428201)
			(xy 297.099488 -351.477813) (xy 297.114852 -351.530145) (xy 297.122614 -351.58413) (xy 297.122614 -351.638668)
			(xy 298.605439 -351.638668) (xy 298.605439 -351.584132) (xy 298.613201 -351.53015) (xy 298.628566 -351.477822)
			(xy 298.651221 -351.428214) (xy 298.680706 -351.382335) (xy 298.71642 -351.341119) (xy 298.757636 -351.305405)
			(xy 298.803516 -351.27592) (xy 298.853124 -351.253265) (xy 298.905452 -351.2379) (xy 298.959434 -351.230139)
			(xy 298.986702 -351.229676) (xy 299.850302 -351.229676) (xy 299.877574 -351.230087) (xy 299.931563 -351.237849)
			(xy 299.983897 -351.253216) (xy 300.033512 -351.275875) (xy 300.079397 -351.305364) (xy 300.120619 -351.341083)
			(xy 300.156337 -351.382304) (xy 300.185826 -351.42819) (xy 300.208484 -351.477805) (xy 300.223851 -351.530139)
			(xy 300.231613 -351.584128) (xy 300.231613 -351.638668) (xy 312.121539 -351.638668) (xy 312.121539 -351.584132)
			(xy 312.129301 -351.53015) (xy 312.144666 -351.477822) (xy 312.167321 -351.428213) (xy 312.196807 -351.382334)
			(xy 312.232521 -351.341118) (xy 312.273737 -351.305404) (xy 312.319617 -351.27592) (xy 312.369226 -351.253264)
			(xy 312.421554 -351.2379) (xy 312.475536 -351.230139) (xy 312.502804 -351.229676) (xy 313.366404 -351.229676)
			(xy 313.393676 -351.230087) (xy 313.447664 -351.23785) (xy 313.499999 -351.253217) (xy 313.549613 -351.275876)
			(xy 313.595498 -351.305365) (xy 313.63672 -351.341083) (xy 313.672438 -351.382305) (xy 313.701926 -351.42819)
			(xy 313.724584 -351.477805) (xy 313.739951 -351.530139) (xy 313.747713 -351.584128) (xy 313.747713 -351.638665)
			(xy 315.230562 -351.638665) (xy 315.230562 -351.584135) (xy 315.238322 -351.53016) (xy 315.253684 -351.477838)
			(xy 315.276335 -351.428236) (xy 315.305815 -351.382361) (xy 315.341523 -351.341148) (xy 315.382732 -351.305437)
			(xy 315.428604 -351.275953) (xy 315.478205 -351.253297) (xy 315.530525 -351.23793) (xy 315.584499 -351.230165)
			(xy 315.611764 -351.229676) (xy 316.475364 -351.229676) (xy 316.502639 -351.230061) (xy 316.556636 -351.23782)
			(xy 316.608978 -351.253185) (xy 316.6586 -351.275842) (xy 316.704493 -351.305332) (xy 316.745722 -351.341053)
			(xy 316.781446 -351.382278) (xy 316.81094 -351.428168) (xy 316.833603 -351.477788) (xy 316.848972 -351.530129)
			(xy 316.856736 -351.584125) (xy 316.856736 -351.638669) (xy 318.339439 -351.638669) (xy 318.339439 -351.584131)
			(xy 318.347201 -351.530147) (xy 318.362567 -351.477818) (xy 318.385224 -351.428208) (xy 318.414711 -351.382328)
			(xy 318.450428 -351.341111) (xy 318.491647 -351.305397) (xy 318.537529 -351.275913) (xy 318.58714 -351.253259)
			(xy 318.63947 -351.237896) (xy 318.693455 -351.230138) (xy 318.720724 -351.229676) (xy 319.584324 -351.229676)
			(xy 319.611595 -351.230088) (xy 319.665581 -351.237853) (xy 319.717913 -351.253222) (xy 319.767525 -351.275882)
			(xy 319.813408 -351.305372) (xy 319.854627 -351.34109) (xy 319.890343 -351.382312) (xy 319.919829 -351.428196)
			(xy 319.942486 -351.477809) (xy 319.957852 -351.530142) (xy 319.965614 -351.584129) (xy 319.965614 -351.638666)
			(xy 321.448462 -351.638666) (xy 321.448462 -351.584134) (xy 321.456223 -351.530157) (xy 321.471586 -351.477834)
			(xy 321.494239 -351.42823) (xy 321.52372 -351.382354) (xy 321.55943 -351.341141) (xy 321.600642 -351.30543)
			(xy 321.646516 -351.275946) (xy 321.696119 -351.253291) (xy 321.748442 -351.237926) (xy 321.802418 -351.230163)
			(xy 321.829684 -351.229676) (xy 322.693284 -351.229676) (xy 322.720558 -351.230062) (xy 322.774552 -351.237824)
			(xy 322.826892 -351.25319) (xy 322.876512 -351.275849) (xy 322.922403 -351.305339) (xy 322.963629 -351.34106)
			(xy 322.999351 -351.382285) (xy 323.028843 -351.428174) (xy 323.051504 -351.477793) (xy 323.066873 -351.530132)
			(xy 323.074636 -351.584126) (xy 323.074636 -351.63867) (xy 324.55734 -351.63867) (xy 324.55734 -351.58413)
			(xy 324.565102 -351.530144) (xy 324.580469 -351.477813) (xy 324.603128 -351.428202) (xy 324.632616 -351.382321)
			(xy 324.668335 -351.341104) (xy 324.709556 -351.30539) (xy 324.755441 -351.275906) (xy 324.805055 -351.253254)
			(xy 324.857387 -351.237893) (xy 324.911374 -351.230136) (xy 324.938644 -351.229676) (xy 325.802244 -351.229676)
			(xy 325.829514 -351.23009) (xy 325.883498 -351.237857) (xy 325.935828 -351.253228) (xy 325.985437 -351.275889)
			(xy 326.031317 -351.305379) (xy 326.072534 -351.341097) (xy 326.108248 -351.382318) (xy 326.137732 -351.428201)
			(xy 326.160388 -351.477814) (xy 326.175752 -351.530145) (xy 326.183514 -351.58413) (xy 326.183514 -351.638668)
			(xy 327.666339 -351.638668) (xy 327.666339 -351.584132) (xy 327.674101 -351.53015) (xy 327.689466 -351.477822)
			(xy 327.712121 -351.428213) (xy 327.741607 -351.382334) (xy 327.777321 -351.341118) (xy 327.818537 -351.305404)
			(xy 327.864417 -351.27592) (xy 327.914026 -351.253264) (xy 327.966354 -351.2379) (xy 328.020336 -351.230139)
			(xy 328.047604 -351.229676) (xy 328.911204 -351.229676) (xy 328.938476 -351.230087) (xy 328.992464 -351.23785)
			(xy 329.044799 -351.253217) (xy 329.094413 -351.275876) (xy 329.140298 -351.305365) (xy 329.18152 -351.341083)
			(xy 329.217238 -351.382305) (xy 329.246726 -351.42819) (xy 329.269384 -351.477805) (xy 329.284751 -351.530139)
			(xy 329.292513 -351.584128) (xy 329.292513 -351.638665) (xy 330.775362 -351.638665) (xy 330.775362 -351.584135)
			(xy 330.783122 -351.53016) (xy 330.798484 -351.477838) (xy 330.821135 -351.428236) (xy 330.850615 -351.382361)
			(xy 330.886323 -351.341148) (xy 330.927532 -351.305437) (xy 330.973404 -351.275953) (xy 331.023005 -351.253297)
			(xy 331.075325 -351.23793) (xy 331.129299 -351.230165) (xy 331.156564 -351.229676) (xy 332.020164 -351.229676)
			(xy 332.047439 -351.230061) (xy 332.101436 -351.23782) (xy 332.153778 -351.253185) (xy 332.2034 -351.275842)
			(xy 332.249293 -351.305332) (xy 332.290522 -351.341053) (xy 332.326246 -351.382278) (xy 332.35574 -351.428168)
			(xy 332.378403 -351.477788) (xy 332.393772 -351.530129) (xy 332.401536 -351.584125) (xy 332.401536 -351.638669)
			(xy 333.884239 -351.638669) (xy 333.884239 -351.584131) (xy 333.892001 -351.530147) (xy 333.907367 -351.477818)
			(xy 333.930024 -351.428208) (xy 333.959511 -351.382328) (xy 333.995228 -351.341111) (xy 334.036447 -351.305397)
			(xy 334.082329 -351.275913) (xy 334.13194 -351.253259) (xy 334.18427 -351.237896) (xy 334.238255 -351.230138)
			(xy 334.265524 -351.229676) (xy 335.129124 -351.229676) (xy 335.156395 -351.230088) (xy 335.210381 -351.237853)
			(xy 335.262713 -351.253222) (xy 335.312325 -351.275882) (xy 335.358208 -351.305372) (xy 335.399427 -351.34109)
			(xy 335.435143 -351.382312) (xy 335.464629 -351.428196) (xy 335.487286 -351.477809) (xy 335.502652 -351.530142)
			(xy 335.510414 -351.584129) (xy 335.510414 -351.638666) (xy 336.993262 -351.638666) (xy 336.993262 -351.584134)
			(xy 337.001023 -351.530157) (xy 337.016386 -351.477834) (xy 337.039039 -351.42823) (xy 337.06852 -351.382354)
			(xy 337.10423 -351.341141) (xy 337.145442 -351.30543) (xy 337.191316 -351.275946) (xy 337.240919 -351.253291)
			(xy 337.293242 -351.237926) (xy 337.347218 -351.230163) (xy 337.374484 -351.229676) (xy 338.238084 -351.229676)
			(xy 338.265358 -351.230062) (xy 338.319352 -351.237824) (xy 338.371692 -351.25319) (xy 338.421312 -351.275849)
			(xy 338.467203 -351.305339) (xy 338.508429 -351.34106) (xy 338.544151 -351.382285) (xy 338.573643 -351.428174)
			(xy 338.596304 -351.477793) (xy 338.611673 -351.530132) (xy 338.619436 -351.584126) (xy 338.619436 -351.63867)
			(xy 340.10214 -351.63867) (xy 340.10214 -351.58413) (xy 340.109902 -351.530144) (xy 340.125269 -351.477813)
			(xy 340.147928 -351.428202) (xy 340.177416 -351.382321) (xy 340.213135 -351.341104) (xy 340.254356 -351.30539)
			(xy 340.300241 -351.275906) (xy 340.349855 -351.253254) (xy 340.402187 -351.237893) (xy 340.456174 -351.230136)
			(xy 340.483444 -351.229676) (xy 341.347044 -351.229676) (xy 341.374314 -351.23009) (xy 341.428298 -351.237857)
			(xy 341.480628 -351.253228) (xy 341.530237 -351.275889) (xy 341.576117 -351.305379) (xy 341.617334 -351.341097)
			(xy 341.653048 -351.382318) (xy 341.682532 -351.428201) (xy 341.705188 -351.477814) (xy 341.720552 -351.530145)
			(xy 341.728314 -351.58413) (xy 341.728314 -351.638668) (xy 343.211139 -351.638668) (xy 343.211139 -351.584132)
			(xy 343.218901 -351.53015) (xy 343.234266 -351.477822) (xy 343.256921 -351.428213) (xy 343.286407 -351.382334)
			(xy 343.322121 -351.341118) (xy 343.363337 -351.305404) (xy 343.409217 -351.27592) (xy 343.458826 -351.253264)
			(xy 343.511154 -351.2379) (xy 343.565136 -351.230139) (xy 343.592404 -351.229676) (xy 344.456004 -351.229676)
			(xy 344.483276 -351.230087) (xy 344.537264 -351.23785) (xy 344.589599 -351.253217) (xy 344.639213 -351.275876)
			(xy 344.685098 -351.305365) (xy 344.72632 -351.341083) (xy 344.762038 -351.382305) (xy 344.791526 -351.42819)
			(xy 344.814184 -351.477805) (xy 344.829551 -351.530139) (xy 344.837313 -351.584128) (xy 344.837313 -351.638666)
			(xy 370.806762 -351.638666) (xy 370.806762 -351.584134) (xy 370.814523 -351.530158) (xy 370.829885 -351.477835)
			(xy 370.852538 -351.428231) (xy 370.882019 -351.382356) (xy 370.917729 -351.341143) (xy 370.95894 -351.305431)
			(xy 371.004814 -351.275948) (xy 371.054416 -351.253292) (xy 371.106738 -351.237927) (xy 371.160714 -351.230164)
			(xy 371.18798 -351.229676) (xy 372.05158 -351.229676) (xy 372.078855 -351.230062) (xy 372.132849 -351.237823)
			(xy 372.185189 -351.253189) (xy 372.23481 -351.275848) (xy 372.280701 -351.305338) (xy 372.321927 -351.341059)
			(xy 372.35765 -351.382283) (xy 372.387143 -351.428172) (xy 372.409804 -351.477792) (xy 372.425173 -351.530131)
			(xy 372.432936 -351.584125) (xy 372.432936 -351.63867) (xy 373.91564 -351.63867) (xy 373.91564 -351.58413)
			(xy 373.923402 -351.530145) (xy 373.938769 -351.477814) (xy 373.961427 -351.428203) (xy 373.990915 -351.382322)
			(xy 374.026634 -351.341105) (xy 374.067854 -351.305391) (xy 374.113738 -351.275908) (xy 374.163352 -351.253255)
			(xy 374.215684 -351.237893) (xy 374.26967 -351.230137) (xy 374.29694 -351.229676) (xy 375.16054 -351.229676)
			(xy 375.18781 -351.230089) (xy 375.241795 -351.237856) (xy 375.294125 -351.253227) (xy 375.343735 -351.275887)
			(xy 375.389615 -351.305377) (xy 375.430832 -351.341096) (xy 375.466547 -351.382317) (xy 375.496032 -351.4282)
			(xy 375.518687 -351.477813) (xy 375.534052 -351.530144) (xy 375.541814 -351.58413) (xy 375.541814 -351.638667)
			(xy 377.024662 -351.638667) (xy 377.024662 -351.584133) (xy 377.032423 -351.530155) (xy 377.047787 -351.477831)
			(xy 377.070441 -351.428226) (xy 377.099924 -351.382349) (xy 377.135636 -351.341136) (xy 377.176849 -351.305424)
			(xy 377.222726 -351.275941) (xy 377.272331 -351.253287) (xy 377.324655 -351.237923) (xy 377.378633 -351.230162)
			(xy 377.4059 -351.229676) (xy 378.2695 -351.229676) (xy 378.296772 -351.230087) (xy 378.350761 -351.237849)
			(xy 378.403096 -351.253216) (xy 378.452711 -351.275874) (xy 378.498596 -351.305363) (xy 378.539818 -351.341082)
			(xy 378.575537 -351.382304) (xy 378.605026 -351.428189) (xy 378.627684 -351.477804) (xy 378.643051 -351.530139)
			(xy 378.650813 -351.584128) (xy 378.650813 -351.638665) (xy 380.133662 -351.638665) (xy 380.133662 -351.584135)
			(xy 380.141422 -351.53016) (xy 380.156784 -351.477839) (xy 380.179435 -351.428237) (xy 380.208914 -351.382362)
			(xy 380.244621 -351.34115) (xy 380.28583 -351.305438) (xy 380.331702 -351.275954) (xy 380.381302 -351.253298)
			(xy 380.433621 -351.237931) (xy 380.487595 -351.230165) (xy 380.51486 -351.229676) (xy 381.37846 -351.229676)
			(xy 381.405736 -351.230061) (xy 381.459732 -351.237819) (xy 381.512075 -351.253183) (xy 381.561698 -351.275841)
			(xy 381.607591 -351.30533) (xy 381.64882 -351.341051) (xy 381.684546 -351.382277) (xy 381.71404 -351.428167)
			(xy 381.736703 -351.477788) (xy 381.752072 -351.530129) (xy 381.759836 -351.584124) (xy 381.759836 -351.638669)
			(xy 383.242539 -351.638669) (xy 383.242539 -351.584131) (xy 383.250301 -351.530148) (xy 383.265667 -351.477818)
			(xy 383.288324 -351.428209) (xy 383.31781 -351.382329) (xy 383.353526 -351.341112) (xy 383.394745 -351.305398)
			(xy 383.440626 -351.275914) (xy 383.490237 -351.25326) (xy 383.542567 -351.237897) (xy 383.596551 -351.230138)
			(xy 383.62382 -351.229676) (xy 384.48742 -351.229676) (xy 384.514691 -351.230088) (xy 384.568678 -351.237853)
			(xy 384.62101 -351.253221) (xy 384.670623 -351.275881) (xy 384.716506 -351.30537) (xy 384.757725 -351.341089)
			(xy 384.793442 -351.38231) (xy 384.822929 -351.428195) (xy 384.845586 -351.477808) (xy 384.860952 -351.530142)
			(xy 384.868714 -351.584129) (xy 384.868714 -351.638666) (xy 386.351562 -351.638666) (xy 386.351562 -351.584134)
			(xy 386.359323 -351.530158) (xy 386.374685 -351.477835) (xy 386.397338 -351.428231) (xy 386.426819 -351.382356)
			(xy 386.462529 -351.341143) (xy 386.50374 -351.305431) (xy 386.549614 -351.275948) (xy 386.599216 -351.253292)
			(xy 386.651538 -351.237927) (xy 386.705514 -351.230164) (xy 386.73278 -351.229676) (xy 387.59638 -351.229676)
			(xy 387.623655 -351.230062) (xy 387.677649 -351.237823) (xy 387.729989 -351.253189) (xy 387.77961 -351.275848)
			(xy 387.825501 -351.305338) (xy 387.866727 -351.341059) (xy 387.90245 -351.382283) (xy 387.931943 -351.428172)
			(xy 387.954604 -351.477792) (xy 387.969973 -351.530131) (xy 387.977736 -351.584125) (xy 387.977736 -351.63867)
			(xy 389.46044 -351.63867) (xy 389.46044 -351.58413) (xy 389.468202 -351.530145) (xy 389.483569 -351.477814)
			(xy 389.506227 -351.428203) (xy 389.535715 -351.382322) (xy 389.571434 -351.341105) (xy 389.612654 -351.305391)
			(xy 389.658538 -351.275908) (xy 389.708152 -351.253255) (xy 389.760484 -351.237893) (xy 389.81447 -351.230137)
			(xy 389.84174 -351.229676) (xy 390.70534 -351.229676) (xy 390.73261 -351.230089) (xy 390.786595 -351.237856)
			(xy 390.838925 -351.253227) (xy 390.888535 -351.275887) (xy 390.934415 -351.305377) (xy 390.975632 -351.341096)
			(xy 391.011347 -351.382317) (xy 391.040832 -351.4282) (xy 391.063487 -351.477813) (xy 391.078852 -351.530144)
			(xy 391.086614 -351.58413) (xy 391.086614 -351.638667) (xy 392.569462 -351.638667) (xy 392.569462 -351.584133)
			(xy 392.577223 -351.530155) (xy 392.592587 -351.477831) (xy 392.615241 -351.428226) (xy 392.644724 -351.382349)
			(xy 392.680436 -351.341136) (xy 392.721649 -351.305424) (xy 392.767526 -351.275941) (xy 392.817131 -351.253287)
			(xy 392.869455 -351.237923) (xy 392.923433 -351.230162) (xy 392.9507 -351.229676) (xy 393.8143 -351.229676)
			(xy 393.841572 -351.230087) (xy 393.895561 -351.237849) (xy 393.947896 -351.253216) (xy 393.997511 -351.275874)
			(xy 394.043396 -351.305363) (xy 394.084618 -351.341082) (xy 394.120337 -351.382304) (xy 394.149826 -351.428189)
			(xy 394.172484 -351.477804) (xy 394.187851 -351.530139) (xy 394.195613 -351.584128) (xy 394.195613 -351.638665)
			(xy 395.678462 -351.638665) (xy 395.678462 -351.584135) (xy 395.686222 -351.53016) (xy 395.701584 -351.477839)
			(xy 395.724235 -351.428237) (xy 395.753714 -351.382362) (xy 395.789421 -351.34115) (xy 395.83063 -351.305438)
			(xy 395.876502 -351.275954) (xy 395.926102 -351.253298) (xy 395.978421 -351.237931) (xy 396.032395 -351.230165)
			(xy 396.05966 -351.229676) (xy 396.92326 -351.229676) (xy 396.950536 -351.230061) (xy 397.004532 -351.237819)
			(xy 397.056875 -351.253183) (xy 397.106498 -351.275841) (xy 397.152391 -351.30533) (xy 397.19362 -351.341051)
			(xy 397.229346 -351.382277) (xy 397.25884 -351.428167) (xy 397.281503 -351.477788) (xy 397.296872 -351.530129)
			(xy 397.304636 -351.584124) (xy 397.304636 -351.638669) (xy 398.787339 -351.638669) (xy 398.787339 -351.584131)
			(xy 398.795101 -351.530148) (xy 398.810467 -351.477818) (xy 398.833124 -351.428209) (xy 398.86261 -351.382329)
			(xy 398.898326 -351.341112) (xy 398.939545 -351.305398) (xy 398.985426 -351.275914) (xy 399.035037 -351.25326)
			(xy 399.087367 -351.237897) (xy 399.141351 -351.230138) (xy 399.16862 -351.229676) (xy 400.03222 -351.229676)
			(xy 400.059491 -351.230088) (xy 400.113478 -351.237853) (xy 400.16581 -351.253221) (xy 400.215423 -351.275881)
			(xy 400.261306 -351.30537) (xy 400.302525 -351.341089) (xy 400.338242 -351.38231) (xy 400.367729 -351.428195)
			(xy 400.390386 -351.477808) (xy 400.405752 -351.530142) (xy 400.413514 -351.584129) (xy 400.413514 -351.638666)
			(xy 401.896362 -351.638666) (xy 401.896362 -351.584134) (xy 401.904123 -351.530158) (xy 401.919485 -351.477835)
			(xy 401.942138 -351.428231) (xy 401.971619 -351.382356) (xy 402.007329 -351.341143) (xy 402.04854 -351.305431)
			(xy 402.094414 -351.275948) (xy 402.144016 -351.253292) (xy 402.196338 -351.237927) (xy 402.250314 -351.230164)
			(xy 402.27758 -351.229676) (xy 403.14118 -351.229676) (xy 403.168455 -351.230062) (xy 403.222449 -351.237823)
			(xy 403.274789 -351.253189) (xy 403.32441 -351.275848) (xy 403.370301 -351.305338) (xy 403.411527 -351.341059)
			(xy 403.44725 -351.382283) (xy 403.476743 -351.428172) (xy 403.499404 -351.477792) (xy 403.514773 -351.530131)
			(xy 403.522536 -351.584125) (xy 403.522536 -351.638666) (xy 408.913862 -351.638666) (xy 408.913862 -351.584134)
			(xy 408.921623 -351.530156) (xy 408.936986 -351.477832) (xy 408.95964 -351.428228) (xy 408.989122 -351.382352)
			(xy 409.024833 -351.341138) (xy 409.066045 -351.305427) (xy 409.111921 -351.275944) (xy 409.161525 -351.253289)
			(xy 409.213848 -351.237925) (xy 409.267826 -351.230163) (xy 409.295092 -351.229676) (xy 410.158692 -351.229676)
			(xy 410.185966 -351.230063) (xy 410.239959 -351.237825) (xy 410.292298 -351.253192) (xy 410.341917 -351.275851)
			(xy 410.387806 -351.305342) (xy 410.429032 -351.341063) (xy 410.464753 -351.382287) (xy 410.494245 -351.428176)
			(xy 410.516905 -351.477794) (xy 410.532273 -351.530133) (xy 410.540036 -351.584126) (xy 410.540036 -351.638664)
			(xy 412.022862 -351.638664) (xy 412.022862 -351.584136) (xy 412.030622 -351.530162) (xy 412.045983 -351.477841)
			(xy 412.068634 -351.428239) (xy 412.098112 -351.382365) (xy 412.133819 -351.341153) (xy 412.175026 -351.305441)
			(xy 412.220897 -351.275957) (xy 412.270496 -351.2533) (xy 412.322815 -351.237932) (xy 412.376788 -351.230166)
			(xy 412.404052 -351.229676) (xy 413.267652 -351.229676) (xy 413.294928 -351.23006) (xy 413.348925 -351.237818)
			(xy 413.401269 -351.253181) (xy 413.450893 -351.275838) (xy 413.496787 -351.305328) (xy 413.538017 -351.341049)
			(xy 413.573744 -351.382274) (xy 413.603239 -351.428165) (xy 413.625902 -351.477786) (xy 413.641272 -351.530128)
			(xy 413.649036 -351.584124) (xy 413.649036 -351.638669) (xy 415.131739 -351.638669) (xy 415.131739 -351.584131)
			(xy 415.139501 -351.530149) (xy 415.154866 -351.47782) (xy 415.177523 -351.428211) (xy 415.207008 -351.382331)
			(xy 415.242724 -351.341115) (xy 415.283941 -351.305401) (xy 415.329822 -351.275917) (xy 415.379431 -351.253262)
			(xy 415.43176 -351.237899) (xy 415.485743 -351.230139) (xy 415.513012 -351.229676) (xy 416.376612 -351.229676)
			(xy 416.403884 -351.230087) (xy 416.457871 -351.237851) (xy 416.510204 -351.253219) (xy 416.559818 -351.275878)
			(xy 416.605702 -351.305367) (xy 416.646922 -351.341086) (xy 416.68264 -351.382308) (xy 416.712128 -351.428192)
			(xy 416.734785 -351.477807) (xy 416.750151 -351.530141) (xy 416.757914 -351.584128) (xy 416.757914 -351.638665)
			(xy 418.240762 -351.638665) (xy 418.240762 -351.584135) (xy 418.248522 -351.530159) (xy 418.263885 -351.477837)
			(xy 418.286537 -351.428233) (xy 418.316017 -351.382358) (xy 418.351726 -351.341146) (xy 418.392936 -351.305434)
			(xy 418.438809 -351.27595) (xy 418.48841 -351.253295) (xy 418.540731 -351.237928) (xy 418.594707 -351.230164)
			(xy 418.621972 -351.229676) (xy 419.485572 -351.229676) (xy 419.512847 -351.230062) (xy 419.566842 -351.237821)
			(xy 419.619184 -351.253187) (xy 419.668805 -351.275845) (xy 419.714697 -351.305335) (xy 419.755924 -351.341056)
			(xy 419.791648 -351.382281) (xy 419.821142 -351.42817) (xy 419.843803 -351.47779) (xy 419.859173 -351.53013)
			(xy 419.866936 -351.584125) (xy 419.866936 -351.63867) (xy 421.349639 -351.63867) (xy 421.349639 -351.58413)
			(xy 421.357402 -351.530146) (xy 421.372768 -351.477816) (xy 421.395426 -351.428206) (xy 421.424913 -351.382325)
			(xy 421.460631 -351.341108) (xy 421.501851 -351.305394) (xy 421.547734 -351.27591) (xy 421.597346 -351.253257)
			(xy 421.649677 -351.237895) (xy 421.703662 -351.230137) (xy 421.730932 -351.229676) (xy 422.594532 -351.229676)
			(xy 422.621803 -351.230089) (xy 422.675788 -351.237855) (xy 422.728119 -351.253224) (xy 422.77773 -351.275885)
			(xy 422.823612 -351.305374) (xy 422.864829 -351.341093) (xy 422.900545 -351.382314) (xy 422.930031 -351.428198)
			(xy 422.952687 -351.477811) (xy 422.968052 -351.530143) (xy 422.975814 -351.584129) (xy 422.975814 -351.638666)
			(xy 424.458662 -351.638666) (xy 424.458662 -351.584134) (xy 424.466423 -351.530156) (xy 424.481786 -351.477832)
			(xy 424.50444 -351.428228) (xy 424.533922 -351.382352) (xy 424.569633 -351.341138) (xy 424.610845 -351.305427)
			(xy 424.656721 -351.275944) (xy 424.706325 -351.253289) (xy 424.758648 -351.237925) (xy 424.812626 -351.230163)
			(xy 424.839892 -351.229676) (xy 425.703492 -351.229676) (xy 425.730766 -351.230063) (xy 425.784759 -351.237825)
			(xy 425.837098 -351.253192) (xy 425.886717 -351.275851) (xy 425.932606 -351.305342) (xy 425.973832 -351.341063)
			(xy 426.009553 -351.382287) (xy 426.039045 -351.428176) (xy 426.061705 -351.477794) (xy 426.077073 -351.530133)
			(xy 426.084836 -351.584126) (xy 426.084836 -351.638664) (xy 427.567662 -351.638664) (xy 427.567662 -351.584136)
			(xy 427.575422 -351.530162) (xy 427.590783 -351.477841) (xy 427.613434 -351.428239) (xy 427.642912 -351.382365)
			(xy 427.678619 -351.341153) (xy 427.719826 -351.305441) (xy 427.765697 -351.275957) (xy 427.815296 -351.2533)
			(xy 427.867615 -351.237932) (xy 427.921588 -351.230166) (xy 427.948852 -351.229676) (xy 428.812452 -351.229676)
			(xy 428.839728 -351.23006) (xy 428.893725 -351.237818) (xy 428.946069 -351.253181) (xy 428.995693 -351.275838)
			(xy 429.041587 -351.305328) (xy 429.082817 -351.341049) (xy 429.118544 -351.382274) (xy 429.148039 -351.428165)
			(xy 429.170702 -351.477786) (xy 429.186072 -351.530128) (xy 429.193836 -351.584124) (xy 429.193836 -351.638669)
			(xy 430.676539 -351.638669) (xy 430.676539 -351.584131) (xy 430.684301 -351.530149) (xy 430.699666 -351.47782)
			(xy 430.722323 -351.428211) (xy 430.751808 -351.382331) (xy 430.787524 -351.341115) (xy 430.828741 -351.305401)
			(xy 430.874622 -351.275917) (xy 430.924231 -351.253262) (xy 430.97656 -351.237899) (xy 431.030543 -351.230139)
			(xy 431.057812 -351.229676) (xy 431.921412 -351.229676) (xy 431.948684 -351.230087) (xy 432.002671 -351.237851)
			(xy 432.055004 -351.253219) (xy 432.104618 -351.275878) (xy 432.150502 -351.305367) (xy 432.191722 -351.341086)
			(xy 432.22744 -351.382308) (xy 432.256928 -351.428192) (xy 432.279585 -351.477807) (xy 432.294951 -351.530141)
			(xy 432.302714 -351.584128) (xy 432.302714 -351.638665) (xy 433.785562 -351.638665) (xy 433.785562 -351.584135)
			(xy 433.793322 -351.530159) (xy 433.808685 -351.477837) (xy 433.831337 -351.428233) (xy 433.860817 -351.382358)
			(xy 433.896526 -351.341146) (xy 433.937736 -351.305434) (xy 433.983609 -351.27595) (xy 434.03321 -351.253295)
			(xy 434.085531 -351.237928) (xy 434.139507 -351.230164) (xy 434.166772 -351.229676) (xy 435.030372 -351.229676)
			(xy 435.057647 -351.230062) (xy 435.111642 -351.237821) (xy 435.163984 -351.253187) (xy 435.213605 -351.275845)
			(xy 435.259497 -351.305335) (xy 435.300724 -351.341056) (xy 435.336448 -351.382281) (xy 435.365942 -351.42817)
			(xy 435.388603 -351.47779) (xy 435.403973 -351.53013) (xy 435.411736 -351.584125) (xy 435.411736 -351.63867)
			(xy 436.894439 -351.63867) (xy 436.894439 -351.58413) (xy 436.902202 -351.530146) (xy 436.917568 -351.477816)
			(xy 436.940226 -351.428206) (xy 436.969713 -351.382325) (xy 437.005431 -351.341108) (xy 437.046651 -351.305394)
			(xy 437.092534 -351.27591) (xy 437.142146 -351.253257) (xy 437.194477 -351.237895) (xy 437.248462 -351.230137)
			(xy 437.275732 -351.229676) (xy 438.139332 -351.229676) (xy 438.166603 -351.230089) (xy 438.220588 -351.237855)
			(xy 438.272919 -351.253224) (xy 438.32253 -351.275885) (xy 438.368412 -351.305374) (xy 438.409629 -351.341093)
			(xy 438.445345 -351.382314) (xy 438.474831 -351.428198) (xy 438.497487 -351.477811) (xy 438.512852 -351.530143)
			(xy 438.520614 -351.584129) (xy 438.520614 -351.638666) (xy 440.003462 -351.638666) (xy 440.003462 -351.584134)
			(xy 440.011223 -351.530156) (xy 440.026586 -351.477832) (xy 440.04924 -351.428228) (xy 440.078722 -351.382352)
			(xy 440.114433 -351.341138) (xy 440.155645 -351.305427) (xy 440.201521 -351.275944) (xy 440.251125 -351.253289)
			(xy 440.303448 -351.237925) (xy 440.357426 -351.230163) (xy 440.384692 -351.229676) (xy 441.248292 -351.229676)
			(xy 441.275566 -351.230063) (xy 441.329559 -351.237825) (xy 441.381898 -351.253192) (xy 441.431517 -351.275851)
			(xy 441.477406 -351.305342) (xy 441.518632 -351.341063) (xy 441.554353 -351.382287) (xy 441.583845 -351.428176)
			(xy 441.606505 -351.477794) (xy 441.621873 -351.530133) (xy 441.629636 -351.584126) (xy 441.629636 -351.638674)
			(xy 441.621873 -351.692667) (xy 441.606505 -351.745006) (xy 441.583845 -351.794624) (xy 441.554353 -351.840513)
			(xy 441.518632 -351.881737) (xy 441.477406 -351.917458) (xy 441.431517 -351.946949) (xy 441.381898 -351.969608)
			(xy 441.329559 -351.984975) (xy 441.275566 -351.992737) (xy 441.248292 -351.9932) (xy 440.384692 -351.9932)
			(xy 440.357426 -351.992637) (xy 440.303448 -351.984875) (xy 440.251125 -351.969511) (xy 440.201521 -351.946856)
			(xy 440.155645 -351.917373) (xy 440.114433 -351.881662) (xy 440.078722 -351.840448) (xy 440.04924 -351.794572)
			(xy 440.026586 -351.744968) (xy 440.011223 -351.692644) (xy 440.003462 -351.638666) (xy 438.520614 -351.638666)
			(xy 438.520614 -351.638671) (xy 438.512852 -351.692657) (xy 438.497487 -351.744989) (xy 438.474831 -351.794602)
			(xy 438.445345 -351.840486) (xy 438.409629 -351.881707) (xy 438.368412 -351.917426) (xy 438.32253 -351.946915)
			(xy 438.272919 -351.969576) (xy 438.220588 -351.984945) (xy 438.166603 -351.992711) (xy 438.139332 -351.9932)
			(xy 437.275732 -351.9932) (xy 437.248462 -351.992663) (xy 437.194477 -351.984905) (xy 437.142146 -351.969543)
			(xy 437.092534 -351.94689) (xy 437.046651 -351.917406) (xy 437.005431 -351.881692) (xy 436.969713 -351.840475)
			(xy 436.940226 -351.794594) (xy 436.917568 -351.744984) (xy 436.902202 -351.692654) (xy 436.894439 -351.63867)
			(xy 435.411736 -351.63867) (xy 435.411736 -351.638675) (xy 435.403973 -351.69267) (xy 435.388603 -351.74501)
			(xy 435.365942 -351.79463) (xy 435.336448 -351.840519) (xy 435.300724 -351.881744) (xy 435.259497 -351.917465)
			(xy 435.213605 -351.946955) (xy 435.163984 -351.969613) (xy 435.111642 -351.984979) (xy 435.057647 -351.992738)
			(xy 435.030372 -351.9932) (xy 434.166772 -351.9932) (xy 434.139507 -351.992636) (xy 434.085531 -351.984872)
			(xy 434.03321 -351.969505) (xy 433.983609 -351.94685) (xy 433.937736 -351.917366) (xy 433.896526 -351.881654)
			(xy 433.860817 -351.840442) (xy 433.831337 -351.794567) (xy 433.808685 -351.744963) (xy 433.793322 -351.692641)
			(xy 433.785562 -351.638665) (xy 432.302714 -351.638665) (xy 432.302714 -351.638672) (xy 432.294951 -351.692659)
			(xy 432.279585 -351.744993) (xy 432.256928 -351.794608) (xy 432.22744 -351.840492) (xy 432.191722 -351.881714)
			(xy 432.150502 -351.917433) (xy 432.104618 -351.946922) (xy 432.055004 -351.969581) (xy 432.002671 -351.984949)
			(xy 431.948684 -351.992713) (xy 431.921412 -351.9932) (xy 431.057812 -351.9932) (xy 431.030543 -351.992661)
			(xy 430.97656 -351.984901) (xy 430.924231 -351.969538) (xy 430.874622 -351.946883) (xy 430.828741 -351.917399)
			(xy 430.787524 -351.881685) (xy 430.751808 -351.840469) (xy 430.722323 -351.794589) (xy 430.699666 -351.74498)
			(xy 430.684301 -351.692651) (xy 430.676539 -351.638669) (xy 429.193836 -351.638669) (xy 429.193836 -351.638676)
			(xy 429.186072 -351.692672) (xy 429.170702 -351.745014) (xy 429.148039 -351.794635) (xy 429.118544 -351.840526)
			(xy 429.082817 -351.881751) (xy 429.041587 -351.917472) (xy 428.995693 -351.946962) (xy 428.946069 -351.969619)
			(xy 428.893725 -351.984982) (xy 428.839728 -351.99274) (xy 428.812452 -351.9932) (xy 427.948852 -351.9932)
			(xy 427.921588 -351.992634) (xy 427.867615 -351.984868) (xy 427.815296 -351.9695) (xy 427.765697 -351.946843)
			(xy 427.719826 -351.917359) (xy 427.678619 -351.881647) (xy 427.642912 -351.840435) (xy 427.613434 -351.794561)
			(xy 427.590783 -351.744959) (xy 427.575422 -351.692639) (xy 427.567662 -351.638664) (xy 426.084836 -351.638664)
			(xy 426.084836 -351.638674) (xy 426.077073 -351.692667) (xy 426.061705 -351.745006) (xy 426.039045 -351.794624)
			(xy 426.009553 -351.840513) (xy 425.973832 -351.881737) (xy 425.932606 -351.917458) (xy 425.886717 -351.946949)
			(xy 425.837098 -351.969608) (xy 425.784759 -351.984975) (xy 425.730766 -351.992737) (xy 425.703492 -351.9932)
			(xy 424.839892 -351.9932) (xy 424.812626 -351.992637) (xy 424.758648 -351.984875) (xy 424.706325 -351.969511)
			(xy 424.656721 -351.946856) (xy 424.610845 -351.917373) (xy 424.569633 -351.881662) (xy 424.533922 -351.840448)
			(xy 424.50444 -351.794572) (xy 424.481786 -351.744968) (xy 424.466423 -351.692644) (xy 424.458662 -351.638666)
			(xy 422.975814 -351.638666) (xy 422.975814 -351.638671) (xy 422.968052 -351.692657) (xy 422.952687 -351.744989)
			(xy 422.930031 -351.794602) (xy 422.900545 -351.840486) (xy 422.864829 -351.881707) (xy 422.823612 -351.917426)
			(xy 422.77773 -351.946915) (xy 422.728119 -351.969576) (xy 422.675788 -351.984945) (xy 422.621803 -351.992711)
			(xy 422.594532 -351.9932) (xy 421.730932 -351.9932) (xy 421.703662 -351.992663) (xy 421.649677 -351.984905)
			(xy 421.597346 -351.969543) (xy 421.547734 -351.94689) (xy 421.501851 -351.917406) (xy 421.460631 -351.881692)
			(xy 421.424913 -351.840475) (xy 421.395426 -351.794594) (xy 421.372768 -351.744984) (xy 421.357402 -351.692654)
			(xy 421.349639 -351.63867) (xy 419.866936 -351.63867) (xy 419.866936 -351.638675) (xy 419.859173 -351.69267)
			(xy 419.843803 -351.74501) (xy 419.821142 -351.79463) (xy 419.791648 -351.840519) (xy 419.755924 -351.881744)
			(xy 419.714697 -351.917465) (xy 419.668805 -351.946955) (xy 419.619184 -351.969613) (xy 419.566842 -351.984979)
			(xy 419.512847 -351.992738) (xy 419.485572 -351.9932) (xy 418.621972 -351.9932) (xy 418.594707 -351.992636)
			(xy 418.540731 -351.984872) (xy 418.48841 -351.969505) (xy 418.438809 -351.94685) (xy 418.392936 -351.917366)
			(xy 418.351726 -351.881654) (xy 418.316017 -351.840442) (xy 418.286537 -351.794567) (xy 418.263885 -351.744963)
			(xy 418.248522 -351.692641) (xy 418.240762 -351.638665) (xy 416.757914 -351.638665) (xy 416.757914 -351.638672)
			(xy 416.750151 -351.692659) (xy 416.734785 -351.744993) (xy 416.712128 -351.794608) (xy 416.68264 -351.840492)
			(xy 416.646922 -351.881714) (xy 416.605702 -351.917433) (xy 416.559818 -351.946922) (xy 416.510204 -351.969581)
			(xy 416.457871 -351.984949) (xy 416.403884 -351.992713) (xy 416.376612 -351.9932) (xy 415.513012 -351.9932)
			(xy 415.485743 -351.992661) (xy 415.43176 -351.984901) (xy 415.379431 -351.969538) (xy 415.329822 -351.946883)
			(xy 415.283941 -351.917399) (xy 415.242724 -351.881685) (xy 415.207008 -351.840469) (xy 415.177523 -351.794589)
			(xy 415.154866 -351.74498) (xy 415.139501 -351.692651) (xy 415.131739 -351.638669) (xy 413.649036 -351.638669)
			(xy 413.649036 -351.638676) (xy 413.641272 -351.692672) (xy 413.625902 -351.745014) (xy 413.603239 -351.794635)
			(xy 413.573744 -351.840526) (xy 413.538017 -351.881751) (xy 413.496787 -351.917472) (xy 413.450893 -351.946962)
			(xy 413.401269 -351.969619) (xy 413.348925 -351.984982) (xy 413.294928 -351.99274) (xy 413.267652 -351.9932)
			(xy 412.404052 -351.9932) (xy 412.376788 -351.992634) (xy 412.322815 -351.984868) (xy 412.270496 -351.9695)
			(xy 412.220897 -351.946843) (xy 412.175026 -351.917359) (xy 412.133819 -351.881647) (xy 412.098112 -351.840435)
			(xy 412.068634 -351.794561) (xy 412.045983 -351.744959) (xy 412.030622 -351.692639) (xy 412.022862 -351.638664)
			(xy 410.540036 -351.638664) (xy 410.540036 -351.638674) (xy 410.532273 -351.692667) (xy 410.516905 -351.745006)
			(xy 410.494245 -351.794624) (xy 410.464753 -351.840513) (xy 410.429032 -351.881737) (xy 410.387806 -351.917458)
			(xy 410.341917 -351.946949) (xy 410.292298 -351.969608) (xy 410.239959 -351.984975) (xy 410.185966 -351.992737)
			(xy 410.158692 -351.9932) (xy 409.295092 -351.9932) (xy 409.267826 -351.992637) (xy 409.213848 -351.984875)
			(xy 409.161525 -351.969511) (xy 409.111921 -351.946856) (xy 409.066045 -351.917373) (xy 409.024833 -351.881662)
			(xy 408.989122 -351.840448) (xy 408.95964 -351.794572) (xy 408.936986 -351.744968) (xy 408.921623 -351.692644)
			(xy 408.913862 -351.638666) (xy 403.522536 -351.638666) (xy 403.522536 -351.638675) (xy 403.514773 -351.692669)
			(xy 403.499404 -351.745008) (xy 403.476743 -351.794628) (xy 403.44725 -351.840517) (xy 403.411527 -351.881741)
			(xy 403.370301 -351.917462) (xy 403.32441 -351.946952) (xy 403.274789 -351.969611) (xy 403.222449 -351.984977)
			(xy 403.168455 -351.992738) (xy 403.14118 -351.9932) (xy 402.27758 -351.9932) (xy 402.250314 -351.992636)
			(xy 402.196338 -351.984873) (xy 402.144016 -351.969508) (xy 402.094414 -351.946852) (xy 402.04854 -351.917369)
			(xy 402.007329 -351.881657) (xy 401.971619 -351.840444) (xy 401.942138 -351.794569) (xy 401.919485 -351.744965)
			(xy 401.904123 -351.692642) (xy 401.896362 -351.638666) (xy 400.413514 -351.638666) (xy 400.413514 -351.638671)
			(xy 400.405752 -351.692658) (xy 400.390386 -351.744992) (xy 400.367729 -351.794605) (xy 400.338242 -351.84049)
			(xy 400.302525 -351.881711) (xy 400.261306 -351.91743) (xy 400.215423 -351.946919) (xy 400.16581 -351.969579)
			(xy 400.113478 -351.984947) (xy 400.059491 -351.992712) (xy 400.03222 -351.9932) (xy 399.16862 -351.9932)
			(xy 399.141351 -351.992662) (xy 399.087367 -351.984903) (xy 399.035037 -351.96954) (xy 398.985426 -351.946886)
			(xy 398.939545 -351.917402) (xy 398.898326 -351.881688) (xy 398.86261 -351.840471) (xy 398.833124 -351.794591)
			(xy 398.810467 -351.744982) (xy 398.795101 -351.692652) (xy 398.787339 -351.638669) (xy 397.304636 -351.638669)
			(xy 397.304636 -351.638676) (xy 397.296872 -351.692671) (xy 397.281503 -351.745012) (xy 397.25884 -351.794633)
			(xy 397.229346 -351.840523) (xy 397.19362 -351.881749) (xy 397.152391 -351.91747) (xy 397.106498 -351.946959)
			(xy 397.056875 -351.969617) (xy 397.004532 -351.984981) (xy 396.950536 -351.992739) (xy 396.92326 -351.9932)
			(xy 396.05966 -351.9932) (xy 396.032395 -351.992635) (xy 395.978421 -351.984869) (xy 395.926102 -351.969502)
			(xy 395.876502 -351.946846) (xy 395.83063 -351.917362) (xy 395.789421 -351.88165) (xy 395.753714 -351.840438)
			(xy 395.724235 -351.794563) (xy 395.701584 -351.744961) (xy 395.686222 -351.69264) (xy 395.678462 -351.638665)
			(xy 394.195613 -351.638665) (xy 394.195613 -351.638672) (xy 394.187851 -351.692661) (xy 394.172484 -351.744996)
			(xy 394.149826 -351.794611) (xy 394.120337 -351.840496) (xy 394.084618 -351.881718) (xy 394.043396 -351.917437)
			(xy 393.997511 -351.946926) (xy 393.947896 -351.969584) (xy 393.895561 -351.984951) (xy 393.841572 -351.992713)
			(xy 393.8143 -351.9932) (xy 392.9507 -351.9932) (xy 392.923433 -351.992638) (xy 392.869455 -351.984877)
			(xy 392.817131 -351.969513) (xy 392.767526 -351.946859) (xy 392.721649 -351.917376) (xy 392.680436 -351.881664)
			(xy 392.644724 -351.840451) (xy 392.615241 -351.794574) (xy 392.592587 -351.744969) (xy 392.577223 -351.692645)
			(xy 392.569462 -351.638667) (xy 391.086614 -351.638667) (xy 391.086614 -351.63867) (xy 391.078852 -351.692656)
			(xy 391.063487 -351.744987) (xy 391.040832 -351.7946) (xy 391.011347 -351.840483) (xy 390.975632 -351.881704)
			(xy 390.934415 -351.917423) (xy 390.888535 -351.946913) (xy 390.838925 -351.969573) (xy 390.786595 -351.984944)
			(xy 390.73261 -351.992711) (xy 390.70534 -351.9932) (xy 389.84174 -351.9932) (xy 389.81447 -351.992663)
			(xy 389.760484 -351.984907) (xy 389.708152 -351.969545) (xy 389.658538 -351.946892) (xy 389.612654 -351.917409)
			(xy 389.571434 -351.881695) (xy 389.535715 -351.840478) (xy 389.506227 -351.794597) (xy 389.483569 -351.744986)
			(xy 389.468202 -351.692655) (xy 389.46044 -351.63867) (xy 387.977736 -351.63867) (xy 387.977736 -351.638675)
			(xy 387.969973 -351.692669) (xy 387.954604 -351.745008) (xy 387.931943 -351.794628) (xy 387.90245 -351.840517)
			(xy 387.866727 -351.881741) (xy 387.825501 -351.917462) (xy 387.77961 -351.946952) (xy 387.729989 -351.969611)
			(xy 387.677649 -351.984977) (xy 387.623655 -351.992738) (xy 387.59638 -351.9932) (xy 386.73278 -351.9932)
			(xy 386.705514 -351.992636) (xy 386.651538 -351.984873) (xy 386.599216 -351.969508) (xy 386.549614 -351.946852)
			(xy 386.50374 -351.917369) (xy 386.462529 -351.881657) (xy 386.426819 -351.840444) (xy 386.397338 -351.794569)
			(xy 386.374685 -351.744965) (xy 386.359323 -351.692642) (xy 386.351562 -351.638666) (xy 384.868714 -351.638666)
			(xy 384.868714 -351.638671) (xy 384.860952 -351.692658) (xy 384.845586 -351.744992) (xy 384.822929 -351.794605)
			(xy 384.793442 -351.84049) (xy 384.757725 -351.881711) (xy 384.716506 -351.91743) (xy 384.670623 -351.946919)
			(xy 384.62101 -351.969579) (xy 384.568678 -351.984947) (xy 384.514691 -351.992712) (xy 384.48742 -351.9932)
			(xy 383.62382 -351.9932) (xy 383.596551 -351.992662) (xy 383.542567 -351.984903) (xy 383.490237 -351.96954)
			(xy 383.440626 -351.946886) (xy 383.394745 -351.917402) (xy 383.353526 -351.881688) (xy 383.31781 -351.840471)
			(xy 383.288324 -351.794591) (xy 383.265667 -351.744982) (xy 383.250301 -351.692652) (xy 383.242539 -351.638669)
			(xy 381.759836 -351.638669) (xy 381.759836 -351.638676) (xy 381.752072 -351.692671) (xy 381.736703 -351.745012)
			(xy 381.71404 -351.794633) (xy 381.684546 -351.840523) (xy 381.64882 -351.881749) (xy 381.607591 -351.91747)
			(xy 381.561698 -351.946959) (xy 381.512075 -351.969617) (xy 381.459732 -351.984981) (xy 381.405736 -351.992739)
			(xy 381.37846 -351.9932) (xy 380.51486 -351.9932) (xy 380.487595 -351.992635) (xy 380.433621 -351.984869)
			(xy 380.381302 -351.969502) (xy 380.331702 -351.946846) (xy 380.28583 -351.917362) (xy 380.244621 -351.88165)
			(xy 380.208914 -351.840438) (xy 380.179435 -351.794563) (xy 380.156784 -351.744961) (xy 380.141422 -351.69264)
			(xy 380.133662 -351.638665) (xy 378.650813 -351.638665) (xy 378.650813 -351.638672) (xy 378.643051 -351.692661)
			(xy 378.627684 -351.744996) (xy 378.605026 -351.794611) (xy 378.575537 -351.840496) (xy 378.539818 -351.881718)
			(xy 378.498596 -351.917437) (xy 378.452711 -351.946926) (xy 378.403096 -351.969584) (xy 378.350761 -351.984951)
			(xy 378.296772 -351.992713) (xy 378.2695 -351.9932) (xy 377.4059 -351.9932) (xy 377.378633 -351.992638)
			(xy 377.324655 -351.984877) (xy 377.272331 -351.969513) (xy 377.222726 -351.946859) (xy 377.176849 -351.917376)
			(xy 377.135636 -351.881664) (xy 377.099924 -351.840451) (xy 377.070441 -351.794574) (xy 377.047787 -351.744969)
			(xy 377.032423 -351.692645) (xy 377.024662 -351.638667) (xy 375.541814 -351.638667) (xy 375.541814 -351.63867)
			(xy 375.534052 -351.692656) (xy 375.518687 -351.744987) (xy 375.496032 -351.7946) (xy 375.466547 -351.840483)
			(xy 375.430832 -351.881704) (xy 375.389615 -351.917423) (xy 375.343735 -351.946913) (xy 375.294125 -351.969573)
			(xy 375.241795 -351.984944) (xy 375.18781 -351.992711) (xy 375.16054 -351.9932) (xy 374.29694 -351.9932)
			(xy 374.26967 -351.992663) (xy 374.215684 -351.984907) (xy 374.163352 -351.969545) (xy 374.113738 -351.946892)
			(xy 374.067854 -351.917409) (xy 374.026634 -351.881695) (xy 373.990915 -351.840478) (xy 373.961427 -351.794597)
			(xy 373.938769 -351.744986) (xy 373.923402 -351.692655) (xy 373.91564 -351.63867) (xy 372.432936 -351.63867)
			(xy 372.432936 -351.638675) (xy 372.425173 -351.692669) (xy 372.409804 -351.745008) (xy 372.387143 -351.794628)
			(xy 372.35765 -351.840517) (xy 372.321927 -351.881741) (xy 372.280701 -351.917462) (xy 372.23481 -351.946952)
			(xy 372.185189 -351.969611) (xy 372.132849 -351.984977) (xy 372.078855 -351.992738) (xy 372.05158 -351.9932)
			(xy 371.18798 -351.9932) (xy 371.160714 -351.992636) (xy 371.106738 -351.984873) (xy 371.054416 -351.969508)
			(xy 371.004814 -351.946852) (xy 370.95894 -351.917369) (xy 370.917729 -351.881657) (xy 370.882019 -351.840444)
			(xy 370.852538 -351.794569) (xy 370.829885 -351.744965) (xy 370.814523 -351.692642) (xy 370.806762 -351.638666)
			(xy 344.837313 -351.638666) (xy 344.837313 -351.638672) (xy 344.829551 -351.692661) (xy 344.814184 -351.744995)
			(xy 344.791526 -351.79461) (xy 344.762038 -351.840495) (xy 344.726319 -351.881717) (xy 344.685098 -351.917435)
			(xy 344.639213 -351.946924) (xy 344.589599 -351.969583) (xy 344.537264 -351.98495) (xy 344.483276 -351.992713)
			(xy 344.456004 -351.9932) (xy 343.592404 -351.9932) (xy 343.565136 -351.992661) (xy 343.511154 -351.9849)
			(xy 343.458826 -351.969536) (xy 343.409217 -351.94688) (xy 343.363337 -351.917396) (xy 343.322121 -351.881682)
			(xy 343.286407 -351.840466) (xy 343.256921 -351.794587) (xy 343.234266 -351.744978) (xy 343.218901 -351.69265)
			(xy 343.211139 -351.638668) (xy 341.728314 -351.638668) (xy 341.728314 -351.63867) (xy 341.720552 -351.692655)
			(xy 341.705188 -351.744986) (xy 341.682532 -351.794599) (xy 341.653048 -351.840482) (xy 341.617334 -351.881703)
			(xy 341.576117 -351.917421) (xy 341.530237 -351.946911) (xy 341.480628 -351.969572) (xy 341.428298 -351.984943)
			(xy 341.374314 -351.99271) (xy 341.347044 -351.9932) (xy 340.483444 -351.9932) (xy 340.456174 -351.992664)
			(xy 340.402187 -351.984907) (xy 340.349855 -351.969546) (xy 340.300241 -351.946894) (xy 340.254356 -351.91741)
			(xy 340.213135 -351.881696) (xy 340.177416 -351.840479) (xy 340.147928 -351.794598) (xy 340.125269 -351.744987)
			(xy 340.109902 -351.692656) (xy 340.10214 -351.63867) (xy 338.619436 -351.63867) (xy 338.619436 -351.638674)
			(xy 338.611673 -351.692668) (xy 338.596304 -351.745007) (xy 338.573643 -351.794626) (xy 338.544151 -351.840515)
			(xy 338.508429 -351.88174) (xy 338.467203 -351.917461) (xy 338.421312 -351.946951) (xy 338.371692 -351.96961)
			(xy 338.319352 -351.984976) (xy 338.265358 -351.992738) (xy 338.238084 -351.9932) (xy 337.374484 -351.9932)
			(xy 337.347218 -351.992637) (xy 337.293242 -351.984874) (xy 337.240919 -351.969509) (xy 337.191316 -351.946854)
			(xy 337.145442 -351.91737) (xy 337.10423 -351.881659) (xy 337.06852 -351.840446) (xy 337.039039 -351.79457)
			(xy 337.016386 -351.744966) (xy 337.001023 -351.692643) (xy 336.993262 -351.638666) (xy 335.510414 -351.638666)
			(xy 335.510414 -351.638671) (xy 335.502652 -351.692658) (xy 335.487286 -351.744991) (xy 335.464629 -351.794604)
			(xy 335.435143 -351.840488) (xy 335.399427 -351.88171) (xy 335.358208 -351.917428) (xy 335.312325 -351.946918)
			(xy 335.262713 -351.969578) (xy 335.210381 -351.984947) (xy 335.156395 -351.992712) (xy 335.129124 -351.9932)
			(xy 334.265524 -351.9932) (xy 334.238255 -351.992662) (xy 334.18427 -351.984904) (xy 334.13194 -351.969541)
			(xy 334.082329 -351.946887) (xy 334.036447 -351.917403) (xy 333.995228 -351.881689) (xy 333.959511 -351.840472)
			(xy 333.930024 -351.794592) (xy 333.907367 -351.744982) (xy 333.892001 -351.692653) (xy 333.884239 -351.638669)
			(xy 332.401536 -351.638669) (xy 332.401536 -351.638675) (xy 332.393772 -351.692671) (xy 332.378403 -351.745011)
			(xy 332.35574 -351.794632) (xy 332.326246 -351.840522) (xy 332.290522 -351.881747) (xy 332.249293 -351.917468)
			(xy 332.2034 -351.946958) (xy 332.153778 -351.969615) (xy 332.101436 -351.98498) (xy 332.047439 -351.992739)
			(xy 332.020164 -351.9932) (xy 331.156564 -351.9932) (xy 331.129299 -351.992635) (xy 331.075325 -351.98487)
			(xy 331.023005 -351.969503) (xy 330.973404 -351.946847) (xy 330.927532 -351.917363) (xy 330.886323 -351.881652)
			(xy 330.850615 -351.840439) (xy 330.821136 -351.794564) (xy 330.798484 -351.744962) (xy 330.783122 -351.69264)
			(xy 330.775362 -351.638665) (xy 329.292513 -351.638665) (xy 329.292513 -351.638672) (xy 329.284751 -351.692661)
			(xy 329.269384 -351.744995) (xy 329.246726 -351.79461) (xy 329.217238 -351.840495) (xy 329.181519 -351.881717)
			(xy 329.140298 -351.917435) (xy 329.094413 -351.946924) (xy 329.044799 -351.969583) (xy 328.992464 -351.98495)
			(xy 328.938476 -351.992713) (xy 328.911204 -351.9932) (xy 328.047604 -351.9932) (xy 328.020336 -351.992661)
			(xy 327.966354 -351.9849) (xy 327.914026 -351.969536) (xy 327.864417 -351.94688) (xy 327.818537 -351.917396)
			(xy 327.777321 -351.881682) (xy 327.741607 -351.840466) (xy 327.712121 -351.794587) (xy 327.689466 -351.744978)
			(xy 327.674101 -351.69265) (xy 327.666339 -351.638668) (xy 326.183514 -351.638668) (xy 326.183514 -351.63867)
			(xy 326.175752 -351.692655) (xy 326.160388 -351.744986) (xy 326.137732 -351.794599) (xy 326.108248 -351.840482)
			(xy 326.072534 -351.881703) (xy 326.031317 -351.917421) (xy 325.985437 -351.946911) (xy 325.935828 -351.969572)
			(xy 325.883498 -351.984943) (xy 325.829514 -351.99271) (xy 325.802244 -351.9932) (xy 324.938644 -351.9932)
			(xy 324.911374 -351.992664) (xy 324.857387 -351.984907) (xy 324.805055 -351.969546) (xy 324.755441 -351.946894)
			(xy 324.709556 -351.91741) (xy 324.668335 -351.881696) (xy 324.632616 -351.840479) (xy 324.603128 -351.794598)
			(xy 324.580469 -351.744987) (xy 324.565102 -351.692656) (xy 324.55734 -351.63867) (xy 323.074636 -351.63867)
			(xy 323.074636 -351.638674) (xy 323.066873 -351.692668) (xy 323.051504 -351.745007) (xy 323.028843 -351.794626)
			(xy 322.999351 -351.840515) (xy 322.963629 -351.88174) (xy 322.922403 -351.917461) (xy 322.876512 -351.946951)
			(xy 322.826892 -351.96961) (xy 322.774552 -351.984976) (xy 322.720558 -351.992738) (xy 322.693284 -351.9932)
			(xy 321.829684 -351.9932) (xy 321.802418 -351.992637) (xy 321.748442 -351.984874) (xy 321.696119 -351.969509)
			(xy 321.646516 -351.946854) (xy 321.600642 -351.91737) (xy 321.55943 -351.881659) (xy 321.52372 -351.840446)
			(xy 321.494239 -351.79457) (xy 321.471586 -351.744966) (xy 321.456223 -351.692643) (xy 321.448462 -351.638666)
			(xy 319.965614 -351.638666) (xy 319.965614 -351.638671) (xy 319.957852 -351.692658) (xy 319.942486 -351.744991)
			(xy 319.919829 -351.794604) (xy 319.890343 -351.840488) (xy 319.854627 -351.88171) (xy 319.813408 -351.917428)
			(xy 319.767525 -351.946918) (xy 319.717913 -351.969578) (xy 319.665581 -351.984947) (xy 319.611595 -351.992712)
			(xy 319.584324 -351.9932) (xy 318.720724 -351.9932) (xy 318.693455 -351.992662) (xy 318.63947 -351.984904)
			(xy 318.58714 -351.969541) (xy 318.537529 -351.946887) (xy 318.491647 -351.917403) (xy 318.450428 -351.881689)
			(xy 318.414711 -351.840472) (xy 318.385224 -351.794592) (xy 318.362567 -351.744982) (xy 318.347201 -351.692653)
			(xy 318.339439 -351.638669) (xy 316.856736 -351.638669) (xy 316.856736 -351.638675) (xy 316.848972 -351.692671)
			(xy 316.833603 -351.745011) (xy 316.81094 -351.794632) (xy 316.781446 -351.840522) (xy 316.745722 -351.881747)
			(xy 316.704493 -351.917468) (xy 316.6586 -351.946958) (xy 316.608978 -351.969615) (xy 316.556636 -351.98498)
			(xy 316.502639 -351.992739) (xy 316.475364 -351.9932) (xy 315.611764 -351.9932) (xy 315.584499 -351.992635)
			(xy 315.530525 -351.98487) (xy 315.478205 -351.969503) (xy 315.428604 -351.946847) (xy 315.382732 -351.917363)
			(xy 315.341523 -351.881652) (xy 315.305815 -351.840439) (xy 315.276336 -351.794564) (xy 315.253684 -351.744962)
			(xy 315.238322 -351.69264) (xy 315.230562 -351.638665) (xy 313.747713 -351.638665) (xy 313.747713 -351.638672)
			(xy 313.739951 -351.692661) (xy 313.724584 -351.744995) (xy 313.701926 -351.79461) (xy 313.672438 -351.840495)
			(xy 313.636719 -351.881717) (xy 313.595498 -351.917435) (xy 313.549613 -351.946924) (xy 313.499999 -351.969583)
			(xy 313.447664 -351.98495) (xy 313.393676 -351.992713) (xy 313.366404 -351.9932) (xy 312.502804 -351.9932)
			(xy 312.475536 -351.992661) (xy 312.421554 -351.9849) (xy 312.369226 -351.969536) (xy 312.319617 -351.94688)
			(xy 312.273737 -351.917396) (xy 312.232521 -351.881682) (xy 312.196807 -351.840466) (xy 312.167321 -351.794587)
			(xy 312.144666 -351.744978) (xy 312.129301 -351.69265) (xy 312.121539 -351.638668) (xy 300.231613 -351.638668)
			(xy 300.231613 -351.638672) (xy 300.223851 -351.692661) (xy 300.208484 -351.744995) (xy 300.185826 -351.79461)
			(xy 300.156337 -351.840496) (xy 300.120619 -351.881717) (xy 300.079397 -351.917436) (xy 300.033512 -351.946925)
			(xy 299.983897 -351.969584) (xy 299.931563 -351.984951) (xy 299.877574 -351.992713) (xy 299.850302 -351.9932)
			(xy 298.986702 -351.9932) (xy 298.959434 -351.992661) (xy 298.905452 -351.9849) (xy 298.853124 -351.969535)
			(xy 298.803516 -351.94688) (xy 298.757636 -351.917395) (xy 298.71642 -351.881681) (xy 298.680706 -351.840465)
			(xy 298.651221 -351.794586) (xy 298.628566 -351.744978) (xy 298.613201 -351.69265) (xy 298.605439 -351.638668)
			(xy 297.122614 -351.638668) (xy 297.122614 -351.63867) (xy 297.114852 -351.692655) (xy 297.099488 -351.744987)
			(xy 297.076832 -351.794599) (xy 297.047347 -351.840483) (xy 297.011633 -351.881703) (xy 296.970416 -351.917422)
			(xy 296.924536 -351.946912) (xy 296.874926 -351.969573) (xy 296.822597 -351.984943) (xy 296.768612 -351.992711)
			(xy 296.741342 -351.9932) (xy 295.877742 -351.9932) (xy 295.850472 -351.992663) (xy 295.796486 -351.984907)
			(xy 295.744153 -351.969546) (xy 295.69454 -351.946893) (xy 295.648655 -351.917409) (xy 295.607434 -351.881695)
			(xy 295.571716 -351.840478) (xy 295.542227 -351.794597) (xy 295.519569 -351.744986) (xy 295.504202 -351.692655)
			(xy 295.49644 -351.63867) (xy 294.013736 -351.63867) (xy 294.013736 -351.638675) (xy 294.005973 -351.692668)
			(xy 293.990604 -351.745008) (xy 293.967943 -351.794627) (xy 293.938451 -351.840516) (xy 293.902728 -351.881741)
			(xy 293.861502 -351.917462) (xy 293.815611 -351.946952) (xy 293.765991 -351.969611) (xy 293.713651 -351.984977)
			(xy 293.659657 -351.992738) (xy 293.632382 -351.9932) (xy 292.768782 -351.9932) (xy 292.741516 -351.992636)
			(xy 292.68754 -351.984873) (xy 292.635218 -351.969508) (xy 292.585615 -351.946853) (xy 292.539741 -351.91737)
			(xy 292.498529 -351.881658) (xy 292.46282 -351.840445) (xy 292.433338 -351.794569) (xy 292.410686 -351.744965)
			(xy 292.395323 -351.692642) (xy 292.387562 -351.638666) (xy 290.904714 -351.638666) (xy 290.904714 -351.638671)
			(xy 290.896952 -351.692658) (xy 290.881586 -351.744991) (xy 290.858929 -351.794605) (xy 290.829442 -351.840489)
			(xy 290.793726 -351.88171) (xy 290.752507 -351.917429) (xy 290.706624 -351.946919) (xy 290.657012 -351.969578)
			(xy 290.60468 -351.984947) (xy 290.550693 -351.992712) (xy 290.523422 -351.9932) (xy 289.659822 -351.9932)
			(xy 289.632553 -351.992662) (xy 289.578569 -351.984903) (xy 289.526239 -351.96954) (xy 289.476628 -351.946886)
			(xy 289.430746 -351.917402) (xy 289.389527 -351.881688) (xy 289.353811 -351.840472) (xy 289.324324 -351.794592)
			(xy 289.301667 -351.744982) (xy 289.286301 -351.692653) (xy 289.278539 -351.638669) (xy 287.795836 -351.638669)
			(xy 287.795836 -351.638675) (xy 287.788072 -351.692671) (xy 287.772703 -351.745012) (xy 287.75004 -351.794633)
			(xy 287.720546 -351.840523) (xy 287.684821 -351.881748) (xy 287.643592 -351.917469) (xy 287.597699 -351.946958)
			(xy 287.548076 -351.969616) (xy 287.495734 -351.98498) (xy 287.441737 -351.992739) (xy 287.414462 -351.9932)
			(xy 286.550862 -351.9932) (xy 286.523597 -351.992635) (xy 286.469623 -351.98487) (xy 286.417303 -351.969503)
			(xy 286.367703 -351.946847) (xy 286.321831 -351.917363) (xy 286.280622 -351.881651) (xy 286.244915 -351.840438)
			(xy 286.215435 -351.794564) (xy 286.192784 -351.744961) (xy 286.177422 -351.69264) (xy 286.169662 -351.638665)
			(xy 284.686813 -351.638665) (xy 284.686813 -351.638672) (xy 284.679051 -351.692661) (xy 284.663684 -351.744995)
			(xy 284.641026 -351.79461) (xy 284.611537 -351.840496) (xy 284.575819 -351.881717) (xy 284.534597 -351.917436)
			(xy 284.488712 -351.946925) (xy 284.439097 -351.969584) (xy 284.386763 -351.984951) (xy 284.332774 -351.992713)
			(xy 284.305502 -351.9932) (xy 283.441902 -351.9932) (xy 283.414634 -351.992661) (xy 283.360652 -351.9849)
			(xy 283.308324 -351.969535) (xy 283.258716 -351.94688) (xy 283.212836 -351.917395) (xy 283.17162 -351.881681)
			(xy 283.135906 -351.840465) (xy 283.106421 -351.794586) (xy 283.083766 -351.744978) (xy 283.068401 -351.69265)
			(xy 283.060639 -351.638668) (xy 281.577814 -351.638668) (xy 281.577814 -351.63867) (xy 281.570052 -351.692655)
			(xy 281.554688 -351.744987) (xy 281.532032 -351.794599) (xy 281.502547 -351.840483) (xy 281.466833 -351.881703)
			(xy 281.425616 -351.917422) (xy 281.379736 -351.946912) (xy 281.330126 -351.969573) (xy 281.277797 -351.984943)
			(xy 281.223812 -351.992711) (xy 281.196542 -351.9932) (xy 280.332942 -351.9932) (xy 280.305672 -351.992663)
			(xy 280.251686 -351.984907) (xy 280.199353 -351.969546) (xy 280.14974 -351.946893) (xy 280.103855 -351.917409)
			(xy 280.062634 -351.881695) (xy 280.026916 -351.840478) (xy 279.997427 -351.794597) (xy 279.974769 -351.744986)
			(xy 279.959402 -351.692655) (xy 279.95164 -351.63867) (xy 278.468936 -351.63867) (xy 278.468936 -351.638675)
			(xy 278.461173 -351.692668) (xy 278.445804 -351.745008) (xy 278.423143 -351.794627) (xy 278.393651 -351.840516)
			(xy 278.357928 -351.881741) (xy 278.316702 -351.917462) (xy 278.270811 -351.946952) (xy 278.221191 -351.969611)
			(xy 278.168851 -351.984977) (xy 278.114857 -351.992738) (xy 278.087582 -351.9932) (xy 277.223982 -351.9932)
			(xy 277.196716 -351.992636) (xy 277.14274 -351.984873) (xy 277.090418 -351.969508) (xy 277.040815 -351.946853)
			(xy 276.994941 -351.91737) (xy 276.953729 -351.881658) (xy 276.91802 -351.840445) (xy 276.888538 -351.794569)
			(xy 276.865886 -351.744965) (xy 276.850523 -351.692642) (xy 276.842762 -351.638666) (xy 275.359914 -351.638666)
			(xy 275.359914 -351.638671) (xy 275.352152 -351.692658) (xy 275.336786 -351.744991) (xy 275.314129 -351.794605)
			(xy 275.284642 -351.840489) (xy 275.248926 -351.88171) (xy 275.207707 -351.917429) (xy 275.161824 -351.946919)
			(xy 275.112212 -351.969578) (xy 275.05988 -351.984947) (xy 275.005893 -351.992712) (xy 274.978622 -351.9932)
			(xy 274.115022 -351.9932) (xy 274.087753 -351.992662) (xy 274.033769 -351.984903) (xy 273.981439 -351.96954)
			(xy 273.931828 -351.946886) (xy 273.885946 -351.917402) (xy 273.844727 -351.881688) (xy 273.809011 -351.840472)
			(xy 273.779524 -351.794592) (xy 273.756867 -351.744982) (xy 273.741501 -351.692653) (xy 273.733739 -351.638669)
			(xy 272.251036 -351.638669) (xy 272.251036 -351.638675) (xy 272.243272 -351.692671) (xy 272.227903 -351.745012)
			(xy 272.20524 -351.794633) (xy 272.175746 -351.840523) (xy 272.140021 -351.881748) (xy 272.098792 -351.917469)
			(xy 272.052899 -351.946958) (xy 272.003276 -351.969616) (xy 271.950934 -351.98498) (xy 271.896937 -351.992739)
			(xy 271.869662 -351.9932) (xy 271.006062 -351.9932) (xy 270.978797 -351.992635) (xy 270.924823 -351.98487)
			(xy 270.872503 -351.969503) (xy 270.822903 -351.946847) (xy 270.777031 -351.917363) (xy 270.735822 -351.881651)
			(xy 270.700115 -351.840438) (xy 270.670635 -351.794564) (xy 270.647984 -351.744961) (xy 270.632622 -351.69264)
			(xy 270.624862 -351.638665) (xy 269.142013 -351.638665) (xy 269.142013 -351.638672) (xy 269.134251 -351.692661)
			(xy 269.118884 -351.744995) (xy 269.096226 -351.79461) (xy 269.066737 -351.840496) (xy 269.031019 -351.881717)
			(xy 268.989797 -351.917436) (xy 268.943912 -351.946925) (xy 268.894297 -351.969584) (xy 268.841963 -351.984951)
			(xy 268.787974 -351.992713) (xy 268.760702 -351.9932) (xy 267.897102 -351.9932) (xy 267.869834 -351.992661)
			(xy 267.815852 -351.9849) (xy 267.763524 -351.969535) (xy 267.713916 -351.94688) (xy 267.668036 -351.917395)
			(xy 267.62682 -351.881681) (xy 267.591106 -351.840465) (xy 267.561621 -351.794586) (xy 267.538966 -351.744978)
			(xy 267.523601 -351.69265) (xy 267.515839 -351.638668) (xy 194.520614 -351.638668) (xy 194.520614 -351.638672)
			(xy 194.512851 -351.692659) (xy 194.497485 -351.744993) (xy 194.474828 -351.794608) (xy 194.44534 -351.840492)
			(xy 194.409622 -351.881714) (xy 194.368402 -351.917433) (xy 194.322518 -351.946922) (xy 194.272904 -351.969581)
			(xy 194.220571 -351.984949) (xy 194.166584 -351.992713) (xy 194.139312 -351.9932) (xy 193.275712 -351.9932)
			(xy 193.248443 -351.992661) (xy 193.19446 -351.984901) (xy 193.142131 -351.969538) (xy 193.092522 -351.946883)
			(xy 193.046641 -351.917399) (xy 193.005424 -351.881685) (xy 192.969708 -351.840469) (xy 192.940223 -351.794589)
			(xy 192.917566 -351.74498) (xy 192.902201 -351.692651) (xy 192.894439 -351.638669) (xy 191.411736 -351.638669)
			(xy 191.411736 -351.638676) (xy 191.403972 -351.692672) (xy 191.388602 -351.745014) (xy 191.365939 -351.794635)
			(xy 191.336444 -351.840526) (xy 191.300717 -351.881751) (xy 191.259487 -351.917472) (xy 191.213593 -351.946962)
			(xy 191.163969 -351.969619) (xy 191.111625 -351.984982) (xy 191.057628 -351.99274) (xy 191.030352 -351.9932)
			(xy 190.166752 -351.9932) (xy 190.139488 -351.992634) (xy 190.085515 -351.984868) (xy 190.033196 -351.9695)
			(xy 189.983597 -351.946843) (xy 189.937726 -351.917359) (xy 189.896519 -351.881647) (xy 189.860812 -351.840435)
			(xy 189.831334 -351.794561) (xy 189.808683 -351.744959) (xy 189.793322 -351.692639) (xy 189.785562 -351.638664)
			(xy 188.302736 -351.638664) (xy 188.302736 -351.638674) (xy 188.294973 -351.692667) (xy 188.279605 -351.745006)
			(xy 188.256945 -351.794624) (xy 188.227453 -351.840513) (xy 188.191732 -351.881737) (xy 188.150506 -351.917458)
			(xy 188.104617 -351.946949) (xy 188.054998 -351.969608) (xy 188.002659 -351.984975) (xy 187.948666 -351.992737)
			(xy 187.921392 -351.9932) (xy 187.057792 -351.9932) (xy 187.030526 -351.992637) (xy 186.976548 -351.984875)
			(xy 186.924225 -351.969511) (xy 186.874621 -351.946856) (xy 186.828745 -351.917373) (xy 186.787533 -351.881662)
			(xy 186.751822 -351.840448) (xy 186.72234 -351.794572) (xy 186.699686 -351.744968) (xy 186.684323 -351.692644)
			(xy 186.676562 -351.638666) (xy 185.193714 -351.638666) (xy 185.193714 -351.638671) (xy 185.185952 -351.692657)
			(xy 185.170587 -351.744989) (xy 185.147931 -351.794602) (xy 185.118445 -351.840486) (xy 185.082729 -351.881707)
			(xy 185.041512 -351.917426) (xy 184.99563 -351.946915) (xy 184.946019 -351.969576) (xy 184.893688 -351.984945)
			(xy 184.839703 -351.992711) (xy 184.812432 -351.9932) (xy 183.948832 -351.9932) (xy 183.921562 -351.992663)
			(xy 183.867577 -351.984905) (xy 183.815246 -351.969543) (xy 183.765634 -351.94689) (xy 183.719751 -351.917406)
			(xy 183.678531 -351.881692) (xy 183.642813 -351.840475) (xy 183.613326 -351.794594) (xy 183.590668 -351.744984)
			(xy 183.575302 -351.692654) (xy 183.567539 -351.63867) (xy 182.084836 -351.63867) (xy 182.084836 -351.638675)
			(xy 182.077073 -351.69267) (xy 182.061703 -351.74501) (xy 182.039042 -351.79463) (xy 182.009548 -351.840519)
			(xy 181.973824 -351.881744) (xy 181.932597 -351.917465) (xy 181.886705 -351.946955) (xy 181.837084 -351.969613)
			(xy 181.784742 -351.984979) (xy 181.730747 -351.992738) (xy 181.703472 -351.9932) (xy 180.839872 -351.9932)
			(xy 180.812607 -351.992636) (xy 180.758631 -351.984872) (xy 180.70631 -351.969505) (xy 180.656709 -351.94685)
			(xy 180.610836 -351.917366) (xy 180.569626 -351.881654) (xy 180.533917 -351.840442) (xy 180.504437 -351.794567)
			(xy 180.481785 -351.744963) (xy 180.466422 -351.692641) (xy 180.458662 -351.638665) (xy 178.975814 -351.638665)
			(xy 178.975814 -351.638672) (xy 178.968051 -351.692659) (xy 178.952685 -351.744993) (xy 178.930028 -351.794608)
			(xy 178.90054 -351.840492) (xy 178.864822 -351.881714) (xy 178.823602 -351.917433) (xy 178.777718 -351.946922)
			(xy 178.728104 -351.969581) (xy 178.675771 -351.984949) (xy 178.621784 -351.992713) (xy 178.594512 -351.9932)
			(xy 177.730912 -351.9932) (xy 177.703643 -351.992661) (xy 177.64966 -351.984901) (xy 177.597331 -351.969538)
			(xy 177.547722 -351.946883) (xy 177.501841 -351.917399) (xy 177.460624 -351.881685) (xy 177.424908 -351.840469)
			(xy 177.395423 -351.794589) (xy 177.372766 -351.74498) (xy 177.357401 -351.692651) (xy 177.349639 -351.638669)
			(xy 175.866936 -351.638669) (xy 175.866936 -351.638676) (xy 175.859172 -351.692672) (xy 175.843802 -351.745014)
			(xy 175.821139 -351.794635) (xy 175.791644 -351.840526) (xy 175.755917 -351.881751) (xy 175.714687 -351.917472)
			(xy 175.668793 -351.946962) (xy 175.619169 -351.969619) (xy 175.566825 -351.984982) (xy 175.512828 -351.99274)
			(xy 175.485552 -351.9932) (xy 174.621952 -351.9932) (xy 174.594688 -351.992634) (xy 174.540715 -351.984868)
			(xy 174.488396 -351.9695) (xy 174.438797 -351.946843) (xy 174.392926 -351.917359) (xy 174.351719 -351.881647)
			(xy 174.316012 -351.840435) (xy 174.286534 -351.794561) (xy 174.263883 -351.744959) (xy 174.248522 -351.692639)
			(xy 174.240762 -351.638664) (xy 172.757936 -351.638664) (xy 172.757936 -351.638674) (xy 172.750173 -351.692667)
			(xy 172.734805 -351.745006) (xy 172.712145 -351.794624) (xy 172.682653 -351.840513) (xy 172.646932 -351.881737)
			(xy 172.605706 -351.917458) (xy 172.559817 -351.946949) (xy 172.510198 -351.969608) (xy 172.457859 -351.984975)
			(xy 172.403866 -351.992737) (xy 172.376592 -351.9932) (xy 171.512992 -351.9932) (xy 171.485726 -351.992637)
			(xy 171.431748 -351.984875) (xy 171.379425 -351.969511) (xy 171.329821 -351.946856) (xy 171.283945 -351.917373)
			(xy 171.242733 -351.881662) (xy 171.207022 -351.840448) (xy 171.17754 -351.794572) (xy 171.154886 -351.744968)
			(xy 171.139523 -351.692644) (xy 171.131762 -351.638666) (xy 169.648914 -351.638666) (xy 169.648914 -351.638671)
			(xy 169.641152 -351.692657) (xy 169.625787 -351.744989) (xy 169.603131 -351.794602) (xy 169.573645 -351.840486)
			(xy 169.537929 -351.881707) (xy 169.496712 -351.917426) (xy 169.45083 -351.946915) (xy 169.401219 -351.969576)
			(xy 169.348888 -351.984945) (xy 169.294903 -351.992711) (xy 169.267632 -351.9932) (xy 168.404032 -351.9932)
			(xy 168.376762 -351.992663) (xy 168.322777 -351.984905) (xy 168.270446 -351.969543) (xy 168.220834 -351.94689)
			(xy 168.174951 -351.917406) (xy 168.133731 -351.881692) (xy 168.098013 -351.840475) (xy 168.068526 -351.794594)
			(xy 168.045868 -351.744984) (xy 168.030502 -351.692654) (xy 168.022739 -351.63867) (xy 166.540036 -351.63867)
			(xy 166.540036 -351.638675) (xy 166.532273 -351.69267) (xy 166.516903 -351.74501) (xy 166.494242 -351.79463)
			(xy 166.464748 -351.840519) (xy 166.429024 -351.881744) (xy 166.387797 -351.917465) (xy 166.341905 -351.946955)
			(xy 166.292284 -351.969613) (xy 166.239942 -351.984979) (xy 166.185947 -351.992738) (xy 166.158672 -351.9932)
			(xy 165.295072 -351.9932) (xy 165.267807 -351.992636) (xy 165.213831 -351.984872) (xy 165.16151 -351.969505)
			(xy 165.111909 -351.94685) (xy 165.066036 -351.917366) (xy 165.024826 -351.881654) (xy 164.989117 -351.840442)
			(xy 164.959637 -351.794567) (xy 164.936985 -351.744963) (xy 164.921622 -351.692641) (xy 164.913862 -351.638665)
			(xy 163.431014 -351.638665) (xy 163.431014 -351.638672) (xy 163.423251 -351.692659) (xy 163.407885 -351.744993)
			(xy 163.385228 -351.794608) (xy 163.35574 -351.840492) (xy 163.320022 -351.881714) (xy 163.278802 -351.917433)
			(xy 163.232918 -351.946922) (xy 163.183304 -351.969581) (xy 163.130971 -351.984949) (xy 163.076984 -351.992713)
			(xy 163.049712 -351.9932) (xy 162.186112 -351.9932) (xy 162.158843 -351.992661) (xy 162.10486 -351.984901)
			(xy 162.052531 -351.969538) (xy 162.002922 -351.946883) (xy 161.957041 -351.917399) (xy 161.915824 -351.881685)
			(xy 161.880108 -351.840469) (xy 161.850623 -351.794589) (xy 161.827966 -351.74498) (xy 161.812601 -351.692651)
			(xy 161.804839 -351.638669) (xy 144.196614 -351.638669) (xy 144.196614 -351.638672) (xy 144.188851 -351.69266)
			(xy 144.173485 -351.744994) (xy 144.150827 -351.794609) (xy 144.121339 -351.840494) (xy 144.085621 -351.881715)
			(xy 144.0444 -351.917434) (xy 143.998516 -351.946923) (xy 143.948902 -351.969582) (xy 143.896568 -351.98495)
			(xy 143.84258 -351.992713) (xy 143.815308 -351.9932) (xy 142.951708 -351.9932) (xy 142.924439 -351.992661)
			(xy 142.870457 -351.984901) (xy 142.818129 -351.969537) (xy 142.768519 -351.946882) (xy 142.722639 -351.917397)
			(xy 142.681422 -351.881683) (xy 142.645707 -351.840467) (xy 142.616222 -351.794588) (xy 142.593566 -351.744979)
			(xy 142.578201 -351.692651) (xy 142.570439 -351.638669) (xy 141.087614 -351.638669) (xy 141.087614 -351.63867)
			(xy 141.079852 -351.692655) (xy 141.064488 -351.744986) (xy 141.041833 -351.794597) (xy 141.012349 -351.840481)
			(xy 140.976635 -351.881701) (xy 140.935419 -351.91742) (xy 140.88954 -351.94691) (xy 140.839931 -351.969571)
			(xy 140.787602 -351.984942) (xy 140.733618 -351.99271) (xy 140.706348 -351.9932) (xy 139.842748 -351.9932)
			(xy 139.815477 -351.992664) (xy 139.761491 -351.984908) (xy 139.709158 -351.969547) (xy 139.659543 -351.946895)
			(xy 139.613658 -351.917411) (xy 139.572436 -351.881698) (xy 139.536717 -351.84048) (xy 139.507228 -351.794599)
			(xy 139.484569 -351.744987) (xy 139.469202 -351.692656) (xy 139.46144 -351.63867) (xy 137.978736 -351.63867)
			(xy 137.978736 -351.638674) (xy 137.970973 -351.692668) (xy 137.955605 -351.745006) (xy 137.932944 -351.794625)
			(xy 137.903452 -351.840514) (xy 137.86773 -351.881739) (xy 137.826504 -351.91746) (xy 137.780615 -351.94695)
			(xy 137.730995 -351.969609) (xy 137.678656 -351.984976) (xy 137.624662 -351.992737) (xy 137.597388 -351.9932)
			(xy 136.733788 -351.9932) (xy 136.706522 -351.992637) (xy 136.652545 -351.984875) (xy 136.600222 -351.96951)
			(xy 136.550618 -351.946855) (xy 136.504744 -351.917372) (xy 136.463531 -351.88166) (xy 136.427821 -351.840447)
			(xy 136.398339 -351.794571) (xy 136.375686 -351.744967) (xy 136.360323 -351.692643) (xy 136.352562 -351.638666)
			(xy 134.869714 -351.638666) (xy 134.869714 -351.638671) (xy 134.861952 -351.692657) (xy 134.846586 -351.74499)
			(xy 134.82393 -351.794603) (xy 134.794444 -351.840487) (xy 134.758728 -351.881708) (xy 134.71751 -351.917427)
			(xy 134.671628 -351.946917) (xy 134.622016 -351.969577) (xy 134.569685 -351.984946) (xy 134.515699 -351.992712)
			(xy 134.488428 -351.9932) (xy 133.624828 -351.9932) (xy 133.597558 -351.992663) (xy 133.543574 -351.984904)
			(xy 133.491243 -351.969542) (xy 133.441631 -351.946888) (xy 133.395749 -351.917404) (xy 133.354529 -351.881691)
			(xy 133.318812 -351.840474) (xy 133.289325 -351.794593) (xy 133.266668 -351.744983) (xy 133.251302 -351.692654)
			(xy 133.243539 -351.63867) (xy 131.760836 -351.63867) (xy 131.760836 -351.638675) (xy 131.753073 -351.69267)
			(xy 131.737703 -351.745011) (xy 131.715041 -351.794631) (xy 131.685547 -351.840521) (xy 131.649823 -351.881746)
			(xy 131.608595 -351.917467) (xy 131.562703 -351.946956) (xy 131.513081 -351.969614) (xy 131.460739 -351.984979)
			(xy 131.406743 -351.992739) (xy 131.379468 -351.9932) (xy 130.515868 -351.9932) (xy 130.488603 -351.992635)
			(xy 130.434628 -351.984871) (xy 130.382308 -351.969504) (xy 130.332706 -351.946849) (xy 130.286834 -351.917365)
			(xy 130.245624 -351.881653) (xy 130.209916 -351.84044) (xy 130.180436 -351.794566) (xy 130.157784 -351.744962)
			(xy 130.142422 -351.692641) (xy 130.134662 -351.638665) (xy 128.651814 -351.638665) (xy 128.651814 -351.638672)
			(xy 128.644051 -351.69266) (xy 128.628685 -351.744994) (xy 128.606027 -351.794609) (xy 128.576539 -351.840494)
			(xy 128.540821 -351.881715) (xy 128.4996 -351.917434) (xy 128.453716 -351.946923) (xy 128.404102 -351.969582)
			(xy 128.351768 -351.98495) (xy 128.29778 -351.992713) (xy 128.270508 -351.9932) (xy 127.406908 -351.9932)
			(xy 127.379639 -351.992661) (xy 127.325657 -351.984901) (xy 127.273329 -351.969537) (xy 127.223719 -351.946882)
			(xy 127.177839 -351.917397) (xy 127.136622 -351.881683) (xy 127.100907 -351.840467) (xy 127.071422 -351.794588)
			(xy 127.048766 -351.744979) (xy 127.033401 -351.692651) (xy 127.025639 -351.638669) (xy 125.542814 -351.638669)
			(xy 125.542814 -351.63867) (xy 125.535052 -351.692655) (xy 125.519688 -351.744986) (xy 125.497033 -351.794597)
			(xy 125.467549 -351.840481) (xy 125.431835 -351.881701) (xy 125.390619 -351.91742) (xy 125.34474 -351.94691)
			(xy 125.295131 -351.969571) (xy 125.242802 -351.984942) (xy 125.188818 -351.99271) (xy 125.161548 -351.9932)
			(xy 124.297948 -351.9932) (xy 124.270677 -351.992664) (xy 124.216691 -351.984908) (xy 124.164358 -351.969547)
			(xy 124.114743 -351.946895) (xy 124.068858 -351.917411) (xy 124.027636 -351.881698) (xy 123.991917 -351.84048)
			(xy 123.962428 -351.794599) (xy 123.939769 -351.744987) (xy 123.924402 -351.692656) (xy 123.91664 -351.63867)
			(xy 122.433936 -351.63867) (xy 122.433936 -351.638674) (xy 122.426173 -351.692668) (xy 122.410805 -351.745006)
			(xy 122.388144 -351.794625) (xy 122.358652 -351.840514) (xy 122.32293 -351.881739) (xy 122.281704 -351.91746)
			(xy 122.235815 -351.94695) (xy 122.186195 -351.969609) (xy 122.133856 -351.984976) (xy 122.079862 -351.992737)
			(xy 122.052588 -351.9932) (xy 121.188988 -351.9932) (xy 121.161722 -351.992637) (xy 121.107745 -351.984875)
			(xy 121.055422 -351.96951) (xy 121.005818 -351.946855) (xy 120.959944 -351.917372) (xy 120.918731 -351.88166)
			(xy 120.883021 -351.840447) (xy 120.853539 -351.794571) (xy 120.830886 -351.744967) (xy 120.815523 -351.692643)
			(xy 120.807762 -351.638666) (xy 119.324914 -351.638666) (xy 119.324914 -351.638671) (xy 119.317152 -351.692657)
			(xy 119.301786 -351.74499) (xy 119.27913 -351.794603) (xy 119.249644 -351.840487) (xy 119.213928 -351.881708)
			(xy 119.17271 -351.917427) (xy 119.126828 -351.946917) (xy 119.077216 -351.969577) (xy 119.024885 -351.984946)
			(xy 118.970899 -351.992712) (xy 118.943628 -351.9932) (xy 118.080028 -351.9932) (xy 118.052758 -351.992663)
			(xy 117.998774 -351.984904) (xy 117.946443 -351.969542) (xy 117.896831 -351.946888) (xy 117.850949 -351.917404)
			(xy 117.809729 -351.881691) (xy 117.774012 -351.840474) (xy 117.744525 -351.794593) (xy 117.721868 -351.744983)
			(xy 117.706502 -351.692654) (xy 117.698739 -351.63867) (xy 116.216036 -351.63867) (xy 116.216036 -351.638675)
			(xy 116.208273 -351.69267) (xy 116.192903 -351.745011) (xy 116.170241 -351.794631) (xy 116.140747 -351.840521)
			(xy 116.105023 -351.881746) (xy 116.063795 -351.917467) (xy 116.017903 -351.946956) (xy 115.968281 -351.969614)
			(xy 115.915939 -351.984979) (xy 115.861943 -351.992739) (xy 115.834668 -351.9932) (xy 114.971068 -351.9932)
			(xy 114.943803 -351.992635) (xy 114.889828 -351.984871) (xy 114.837508 -351.969504) (xy 114.787906 -351.946849)
			(xy 114.742034 -351.917365) (xy 114.700824 -351.881653) (xy 114.665116 -351.84044) (xy 114.635636 -351.794566)
			(xy 114.612984 -351.744962) (xy 114.597622 -351.692641) (xy 114.589862 -351.638665) (xy 113.107014 -351.638665)
			(xy 113.107014 -351.638672) (xy 113.099251 -351.69266) (xy 113.083885 -351.744994) (xy 113.061227 -351.794609)
			(xy 113.031739 -351.840494) (xy 112.996021 -351.881715) (xy 112.9548 -351.917434) (xy 112.908916 -351.946923)
			(xy 112.859302 -351.969582) (xy 112.806968 -351.98495) (xy 112.75298 -351.992713) (xy 112.725708 -351.9932)
			(xy 111.862108 -351.9932) (xy 111.834839 -351.992661) (xy 111.780857 -351.984901) (xy 111.728529 -351.969537)
			(xy 111.678919 -351.946882) (xy 111.633039 -351.917397) (xy 111.591822 -351.881683) (xy 111.556107 -351.840467)
			(xy 111.526622 -351.794588) (xy 111.503966 -351.744979) (xy 111.488601 -351.692651) (xy 111.480839 -351.638669)
			(xy 93.706714 -351.638669) (xy 93.706714 -351.63867) (xy 93.698952 -351.692655) (xy 93.683588 -351.744987)
			(xy 93.660932 -351.794599) (xy 93.631447 -351.840483) (xy 93.595733 -351.881703) (xy 93.554516 -351.917422)
			(xy 93.508636 -351.946912) (xy 93.459026 -351.969573) (xy 93.406697 -351.984943) (xy 93.352712 -351.992711)
			(xy 93.325442 -351.9932) (xy 92.461842 -351.9932) (xy 92.434572 -351.992663) (xy 92.380586 -351.984907)
			(xy 92.328253 -351.969546) (xy 92.27864 -351.946893) (xy 92.232755 -351.917409) (xy 92.191534 -351.881695)
			(xy 92.155816 -351.840478) (xy 92.126327 -351.794597) (xy 92.103669 -351.744986) (xy 92.088302 -351.692655)
			(xy 92.08054 -351.63867) (xy 90.597836 -351.63867) (xy 90.597836 -351.638675) (xy 90.590073 -351.692668)
			(xy 90.574704 -351.745008) (xy 90.552043 -351.794627) (xy 90.522551 -351.840516) (xy 90.486828 -351.881741)
			(xy 90.445602 -351.917462) (xy 90.399711 -351.946952) (xy 90.350091 -351.969611) (xy 90.297751 -351.984977)
			(xy 90.243757 -351.992738) (xy 90.216482 -351.9932) (xy 89.352882 -351.9932) (xy 89.325616 -351.992636)
			(xy 89.27164 -351.984873) (xy 89.219318 -351.969508) (xy 89.169715 -351.946853) (xy 89.123841 -351.91737)
			(xy 89.082629 -351.881658) (xy 89.04692 -351.840445) (xy 89.017438 -351.794569) (xy 88.994786 -351.744965)
			(xy 88.979423 -351.692642) (xy 88.971662 -351.638666) (xy 87.488814 -351.638666) (xy 87.488814 -351.638671)
			(xy 87.481052 -351.692658) (xy 87.465686 -351.744991) (xy 87.443029 -351.794605) (xy 87.413542 -351.840489)
			(xy 87.377826 -351.88171) (xy 87.336607 -351.917429) (xy 87.290724 -351.946919) (xy 87.241112 -351.969578)
			(xy 87.18878 -351.984947) (xy 87.134793 -351.992712) (xy 87.107522 -351.9932) (xy 86.243922 -351.9932)
			(xy 86.216653 -351.992662) (xy 86.162669 -351.984903) (xy 86.110339 -351.96954) (xy 86.060728 -351.946886)
			(xy 86.014846 -351.917402) (xy 85.973627 -351.881688) (xy 85.937911 -351.840472) (xy 85.908424 -351.794592)
			(xy 85.885767 -351.744982) (xy 85.870401 -351.692653) (xy 85.862639 -351.638669) (xy 84.379936 -351.638669)
			(xy 84.379936 -351.638675) (xy 84.372172 -351.692671) (xy 84.356803 -351.745012) (xy 84.33414 -351.794633)
			(xy 84.304646 -351.840523) (xy 84.268921 -351.881748) (xy 84.227692 -351.917469) (xy 84.181799 -351.946958)
			(xy 84.132176 -351.969616) (xy 84.079834 -351.98498) (xy 84.025837 -351.992739) (xy 83.998562 -351.9932)
			(xy 83.134962 -351.9932) (xy 83.107697 -351.992635) (xy 83.053723 -351.98487) (xy 83.001403 -351.969503)
			(xy 82.951803 -351.946847) (xy 82.905931 -351.917363) (xy 82.864722 -351.881651) (xy 82.829015 -351.840438)
			(xy 82.799535 -351.794564) (xy 82.776884 -351.744961) (xy 82.761522 -351.69264) (xy 82.753762 -351.638665)
			(xy 81.270913 -351.638665) (xy 81.270913 -351.638672) (xy 81.263151 -351.692661) (xy 81.247784 -351.744995)
			(xy 81.225126 -351.79461) (xy 81.195637 -351.840496) (xy 81.159919 -351.881717) (xy 81.118697 -351.917436)
			(xy 81.072812 -351.946925) (xy 81.023197 -351.969584) (xy 80.970863 -351.984951) (xy 80.916874 -351.992713)
			(xy 80.889602 -351.9932) (xy 80.026002 -351.9932) (xy 79.998734 -351.992661) (xy 79.944752 -351.9849)
			(xy 79.892424 -351.969535) (xy 79.842816 -351.94688) (xy 79.796936 -351.917395) (xy 79.75572 -351.881681)
			(xy 79.720006 -351.840465) (xy 79.690521 -351.794586) (xy 79.667866 -351.744978) (xy 79.652501 -351.69265)
			(xy 79.644739 -351.638668) (xy 78.161914 -351.638668) (xy 78.161914 -351.63867) (xy 78.154152 -351.692655)
			(xy 78.138788 -351.744987) (xy 78.116132 -351.794599) (xy 78.086647 -351.840483) (xy 78.050933 -351.881703)
			(xy 78.009716 -351.917422) (xy 77.963836 -351.946912) (xy 77.914226 -351.969573) (xy 77.861897 -351.984943)
			(xy 77.807912 -351.992711) (xy 77.780642 -351.9932) (xy 76.917042 -351.9932) (xy 76.889772 -351.992663)
			(xy 76.835786 -351.984907) (xy 76.783453 -351.969546) (xy 76.73384 -351.946893) (xy 76.687955 -351.917409)
			(xy 76.646734 -351.881695) (xy 76.611016 -351.840478) (xy 76.581527 -351.794597) (xy 76.558869 -351.744986)
			(xy 76.543502 -351.692655) (xy 76.53574 -351.63867) (xy 75.053036 -351.63867) (xy 75.053036 -351.638675)
			(xy 75.045273 -351.692668) (xy 75.029904 -351.745008) (xy 75.007243 -351.794627) (xy 74.977751 -351.840516)
			(xy 74.942028 -351.881741) (xy 74.900802 -351.917462) (xy 74.854911 -351.946952) (xy 74.805291 -351.969611)
			(xy 74.752951 -351.984977) (xy 74.698957 -351.992738) (xy 74.671682 -351.9932) (xy 73.808082 -351.9932)
			(xy 73.780816 -351.992636) (xy 73.72684 -351.984873) (xy 73.674518 -351.969508) (xy 73.624915 -351.946853)
			(xy 73.579041 -351.91737) (xy 73.537829 -351.881658) (xy 73.50212 -351.840445) (xy 73.472638 -351.794569)
			(xy 73.449986 -351.744965) (xy 73.434623 -351.692642) (xy 73.426862 -351.638666) (xy 71.944014 -351.638666)
			(xy 71.944014 -351.638671) (xy 71.936252 -351.692658) (xy 71.920886 -351.744991) (xy 71.898229 -351.794605)
			(xy 71.868742 -351.840489) (xy 71.833026 -351.88171) (xy 71.791807 -351.917429) (xy 71.745924 -351.946919)
			(xy 71.696312 -351.969578) (xy 71.64398 -351.984947) (xy 71.589993 -351.992712) (xy 71.562722 -351.9932)
			(xy 70.699122 -351.9932) (xy 70.671853 -351.992662) (xy 70.617869 -351.984903) (xy 70.565539 -351.96954)
			(xy 70.515928 -351.946886) (xy 70.470046 -351.917402) (xy 70.428827 -351.881688) (xy 70.393111 -351.840472)
			(xy 70.363624 -351.794592) (xy 70.340967 -351.744982) (xy 70.325601 -351.692653) (xy 70.317839 -351.638669)
			(xy 68.835136 -351.638669) (xy 68.835136 -351.638675) (xy 68.827372 -351.692671) (xy 68.812003 -351.745012)
			(xy 68.78934 -351.794633) (xy 68.759846 -351.840523) (xy 68.724121 -351.881748) (xy 68.682892 -351.917469)
			(xy 68.636999 -351.946958) (xy 68.587376 -351.969616) (xy 68.535034 -351.98498) (xy 68.481037 -351.992739)
			(xy 68.453762 -351.9932) (xy 67.590162 -351.9932) (xy 67.562897 -351.992635) (xy 67.508923 -351.98487)
			(xy 67.456603 -351.969503) (xy 67.407003 -351.946847) (xy 67.361131 -351.917363) (xy 67.319922 -351.881651)
			(xy 67.284215 -351.840438) (xy 67.254735 -351.794564) (xy 67.232084 -351.744961) (xy 67.216722 -351.69264)
			(xy 67.208962 -351.638665) (xy 65.726113 -351.638665) (xy 65.726113 -351.638672) (xy 65.718351 -351.692661)
			(xy 65.702984 -351.744995) (xy 65.680326 -351.79461) (xy 65.650837 -351.840496) (xy 65.615119 -351.881717)
			(xy 65.573897 -351.917436) (xy 65.528012 -351.946925) (xy 65.478397 -351.969584) (xy 65.426063 -351.984951)
			(xy 65.372074 -351.992713) (xy 65.344802 -351.9932) (xy 64.481202 -351.9932) (xy 64.453934 -351.992661)
			(xy 64.399952 -351.9849) (xy 64.347624 -351.969535) (xy 64.298016 -351.94688) (xy 64.252136 -351.917395)
			(xy 64.21092 -351.881681) (xy 64.175206 -351.840465) (xy 64.145721 -351.794586) (xy 64.123066 -351.744978)
			(xy 64.107701 -351.69265) (xy 64.099939 -351.638668) (xy 62.617114 -351.638668) (xy 62.617114 -351.63867)
			(xy 62.609352 -351.692655) (xy 62.593988 -351.744987) (xy 62.571332 -351.794599) (xy 62.541847 -351.840483)
			(xy 62.506133 -351.881703) (xy 62.464916 -351.917422) (xy 62.419036 -351.946912) (xy 62.369426 -351.969573)
			(xy 62.317097 -351.984943) (xy 62.263112 -351.992711) (xy 62.235842 -351.9932) (xy 61.372242 -351.9932)
			(xy 61.344972 -351.992663) (xy 61.290986 -351.984907) (xy 61.238653 -351.969546) (xy 61.18904 -351.946893)
			(xy 61.143155 -351.917409) (xy 61.101934 -351.881695) (xy 61.066216 -351.840478) (xy 61.036727 -351.794597)
			(xy 61.014069 -351.744986) (xy 60.998702 -351.692655) (xy 60.99094 -351.63867) (xy 51.666914 -351.63867)
			(xy 51.659152 -351.692655) (xy 51.643788 -351.744986) (xy 51.621133 -351.794597) (xy 51.591649 -351.840481)
			(xy 51.555935 -351.881701) (xy 51.514719 -351.91742) (xy 51.46884 -351.94691) (xy 51.419231 -351.969571)
			(xy 51.366902 -351.984942) (xy 51.312918 -351.99271) (xy 51.285648 -351.9932) (xy 50.422048 -351.9932)
			(xy 50.394777 -351.992664) (xy 50.340791 -351.984908) (xy 50.288458 -351.969547) (xy 50.238843 -351.946895)
			(xy 50.192958 -351.917411) (xy 50.151736 -351.881698) (xy 50.116017 -351.84048) (xy 50.086528 -351.794599)
			(xy 50.063869 -351.744987) (xy 50.048502 -351.692656) (xy 50.04074 -351.63867) (xy 48.558036 -351.63867)
			(xy 48.558036 -351.638674) (xy 48.550273 -351.692668) (xy 48.534905 -351.745006) (xy 48.512244 -351.794625)
			(xy 48.482752 -351.840514) (xy 48.44703 -351.881739) (xy 48.405804 -351.91746) (xy 48.359915 -351.94695)
			(xy 48.310295 -351.969609) (xy 48.257956 -351.984976) (xy 48.203962 -351.992737) (xy 48.176688 -351.9932)
			(xy 47.313088 -351.9932) (xy 47.285822 -351.992637) (xy 47.231845 -351.984875) (xy 47.179522 -351.96951)
			(xy 47.129918 -351.946855) (xy 47.084044 -351.917372) (xy 47.042831 -351.88166) (xy 47.007121 -351.840447)
			(xy 46.977639 -351.794571) (xy 46.954986 -351.744967) (xy 46.939623 -351.692643) (xy 46.931862 -351.638666)
			(xy 45.449014 -351.638666) (xy 45.449014 -351.638671) (xy 45.441252 -351.692657) (xy 45.425886 -351.74499)
			(xy 45.40323 -351.794603) (xy 45.373744 -351.840487) (xy 45.338028 -351.881708) (xy 45.29681 -351.917427)
			(xy 45.250928 -351.946917) (xy 45.201316 -351.969577) (xy 45.148985 -351.984946) (xy 45.094999 -351.992712)
			(xy 45.067728 -351.9932) (xy 44.204128 -351.9932) (xy 44.176858 -351.992663) (xy 44.122874 -351.984904)
			(xy 44.070543 -351.969542) (xy 44.020931 -351.946888) (xy 43.975049 -351.917404) (xy 43.933829 -351.881691)
			(xy 43.898112 -351.840474) (xy 43.868625 -351.794593) (xy 43.845968 -351.744983) (xy 43.830602 -351.692654)
			(xy 43.822839 -351.63867) (xy 42.340136 -351.63867) (xy 42.340136 -351.638675) (xy 42.332373 -351.69267)
			(xy 42.317003 -351.745011) (xy 42.294341 -351.794631) (xy 42.264847 -351.840521) (xy 42.229123 -351.881746)
			(xy 42.187895 -351.917467) (xy 42.142003 -351.946956) (xy 42.092381 -351.969614) (xy 42.040039 -351.984979)
			(xy 41.986043 -351.992739) (xy 41.958768 -351.9932) (xy 41.095168 -351.9932) (xy 41.067903 -351.992635)
			(xy 41.013928 -351.984871) (xy 40.961608 -351.969504) (xy 40.912006 -351.946849) (xy 40.866134 -351.917365)
			(xy 40.824924 -351.881653) (xy 40.789216 -351.84044) (xy 40.759736 -351.794566) (xy 40.737084 -351.744962)
			(xy 40.721722 -351.692641) (xy 40.713962 -351.638665) (xy 39.231114 -351.638665) (xy 39.231114 -351.638672)
			(xy 39.223351 -351.69266) (xy 39.207985 -351.744994) (xy 39.185327 -351.794609) (xy 39.155839 -351.840494)
			(xy 39.120121 -351.881715) (xy 39.0789 -351.917434) (xy 39.033016 -351.946923) (xy 38.983402 -351.969582)
			(xy 38.931068 -351.98495) (xy 38.87708 -351.992713) (xy 38.849808 -351.9932) (xy 37.986208 -351.9932)
			(xy 37.958939 -351.992661) (xy 37.904957 -351.984901) (xy 37.852629 -351.969537) (xy 37.803019 -351.946882)
			(xy 37.757139 -351.917397) (xy 37.715922 -351.881683) (xy 37.680207 -351.840467) (xy 37.650722 -351.794588)
			(xy 37.628066 -351.744979) (xy 37.612701 -351.692651) (xy 37.604939 -351.638669) (xy 36.122114 -351.638669)
			(xy 36.122114 -351.63867) (xy 36.114352 -351.692655) (xy 36.098988 -351.744986) (xy 36.076333 -351.794597)
			(xy 36.046849 -351.840481) (xy 36.011135 -351.881701) (xy 35.969919 -351.91742) (xy 35.92404 -351.94691)
			(xy 35.874431 -351.969571) (xy 35.822102 -351.984942) (xy 35.768118 -351.99271) (xy 35.740848 -351.9932)
			(xy 34.877248 -351.9932) (xy 34.849977 -351.992664) (xy 34.795991 -351.984908) (xy 34.743658 -351.969547)
			(xy 34.694043 -351.946895) (xy 34.648158 -351.917411) (xy 34.606936 -351.881698) (xy 34.571217 -351.84048)
			(xy 34.541728 -351.794599) (xy 34.519069 -351.744987) (xy 34.503702 -351.692656) (xy 34.49594 -351.63867)
			(xy 33.013236 -351.63867) (xy 33.013236 -351.638674) (xy 33.005473 -351.692668) (xy 32.990105 -351.745006)
			(xy 32.967444 -351.794625) (xy 32.937952 -351.840514) (xy 32.90223 -351.881739) (xy 32.861004 -351.91746)
			(xy 32.815115 -351.94695) (xy 32.765495 -351.969609) (xy 32.713156 -351.984976) (xy 32.659162 -351.992737)
			(xy 32.631888 -351.9932) (xy 31.768288 -351.9932) (xy 31.741022 -351.992637) (xy 31.687045 -351.984875)
			(xy 31.634722 -351.96951) (xy 31.585118 -351.946855) (xy 31.539244 -351.917372) (xy 31.498031 -351.88166)
			(xy 31.462321 -351.840447) (xy 31.432839 -351.794571) (xy 31.410186 -351.744967) (xy 31.394823 -351.692643)
			(xy 31.387062 -351.638666) (xy 29.904214 -351.638666) (xy 29.904214 -351.638671) (xy 29.896452 -351.692657)
			(xy 29.881086 -351.74499) (xy 29.85843 -351.794603) (xy 29.828944 -351.840487) (xy 29.793228 -351.881708)
			(xy 29.75201 -351.917427) (xy 29.706128 -351.946917) (xy 29.656516 -351.969577) (xy 29.604185 -351.984946)
			(xy 29.550199 -351.992712) (xy 29.522928 -351.9932) (xy 28.659328 -351.9932) (xy 28.632058 -351.992663)
			(xy 28.578074 -351.984904) (xy 28.525743 -351.969542) (xy 28.476131 -351.946888) (xy 28.430249 -351.917404)
			(xy 28.389029 -351.881691) (xy 28.353312 -351.840474) (xy 28.323825 -351.794593) (xy 28.301168 -351.744983)
			(xy 28.285802 -351.692654) (xy 28.278039 -351.63867) (xy 26.795336 -351.63867) (xy 26.795336 -351.638675)
			(xy 26.787573 -351.69267) (xy 26.772203 -351.745011) (xy 26.749541 -351.794631) (xy 26.720047 -351.840521)
			(xy 26.684323 -351.881746) (xy 26.643095 -351.917467) (xy 26.597203 -351.946956) (xy 26.547581 -351.969614)
			(xy 26.495239 -351.984979) (xy 26.441243 -351.992739) (xy 26.413968 -351.9932) (xy 25.550368 -351.9932)
			(xy 25.523103 -351.992635) (xy 25.469128 -351.984871) (xy 25.416808 -351.969504) (xy 25.367206 -351.946849)
			(xy 25.321334 -351.917365) (xy 25.280124 -351.881653) (xy 25.244416 -351.84044) (xy 25.214936 -351.794566)
			(xy 25.192284 -351.744962) (xy 25.176922 -351.692641) (xy 25.169162 -351.638665) (xy 23.686314 -351.638665)
			(xy 23.686314 -351.638672) (xy 23.678551 -351.69266) (xy 23.663185 -351.744994) (xy 23.640527 -351.794609)
			(xy 23.611039 -351.840494) (xy 23.575321 -351.881715) (xy 23.5341 -351.917434) (xy 23.488216 -351.946923)
			(xy 23.438602 -351.969582) (xy 23.386268 -351.98495) (xy 23.33228 -351.992713) (xy 23.305008 -351.9932)
			(xy 22.441408 -351.9932) (xy 22.414139 -351.992661) (xy 22.360157 -351.984901) (xy 22.307829 -351.969537)
			(xy 22.258219 -351.946882) (xy 22.212339 -351.917397) (xy 22.171122 -351.881683) (xy 22.135407 -351.840467)
			(xy 22.105922 -351.794588) (xy 22.083266 -351.744979) (xy 22.067901 -351.692651) (xy 22.060139 -351.638669)
			(xy 20.577347 -351.638669) (xy 20.577347 -351.638711) (xy 20.569584 -351.692698) (xy 20.554218 -351.74503)
			(xy 20.53156 -351.794643) (xy 20.502073 -351.840527) (xy 20.466355 -351.881747) (xy 20.425135 -351.917464)
			(xy 20.379252 -351.946951) (xy 20.329638 -351.969609) (xy 20.277306 -351.984975) (xy 20.223319 -351.992737)
			(xy 20.196048 -351.9932) (xy 19.332448 -351.9932) (xy 19.305179 -351.992717) (xy 19.251195 -351.984955)
			(xy 19.198865 -351.96959) (xy 19.149255 -351.946933) (xy 19.103374 -351.917447) (xy 19.062157 -351.881732)
			(xy 19.026441 -351.840514) (xy 18.996956 -351.794633) (xy 18.974299 -351.745023) (xy 18.958934 -351.692693)
			(xy 18.951172 -351.638709) (xy 0.509016 -351.638709) (xy 0.509016 -354.759373) (xy 22.060084 -354.759373)
			(xy 22.060084 -354.704827) (xy 22.067846 -354.650837) (xy 22.083214 -354.598501) (xy 22.105873 -354.548885)
			(xy 22.135363 -354.502999) (xy 22.171083 -354.461777) (xy 22.212306 -354.426058) (xy 22.258192 -354.396569)
			(xy 22.307809 -354.373911) (xy 22.360145 -354.358545) (xy 22.414135 -354.350783) (xy 22.441408 -354.35032)
			(xy 23.305008 -354.35032) (xy 23.332276 -354.350843) (xy 23.386256 -354.358605) (xy 23.438582 -354.37397)
			(xy 23.488189 -354.396626) (xy 23.534067 -354.426111) (xy 23.575281 -354.461824) (xy 23.610994 -354.50304)
			(xy 23.640478 -354.548918) (xy 23.663132 -354.598525) (xy 23.678497 -354.650852) (xy 23.686258 -354.704832)
			(xy 23.686258 -354.759368) (xy 23.686258 -354.759369) (xy 25.169106 -354.759369) (xy 25.169106 -354.704831)
			(xy 25.176868 -354.650847) (xy 25.192232 -354.598518) (xy 25.214887 -354.548908) (xy 25.244371 -354.503026)
			(xy 25.280085 -354.461807) (xy 25.3213 -354.42609) (xy 25.36718 -354.396602) (xy 25.416788 -354.373943)
			(xy 25.469116 -354.358574) (xy 25.523099 -354.350809) (xy 25.550368 -354.35032) (xy 26.413968 -354.35032)
			(xy 26.441239 -354.350817) (xy 26.495227 -354.358575) (xy 26.547561 -354.373938) (xy 26.597176 -354.396593)
			(xy 26.643061 -354.426078) (xy 26.684283 -354.461794) (xy 26.720003 -354.503013) (xy 26.749492 -354.548896)
			(xy 26.772151 -354.598509) (xy 26.787518 -354.650842) (xy 26.79528 -354.704829) (xy 26.79528 -354.759371)
			(xy 26.79528 -354.759374) (xy 28.277984 -354.759374) (xy 28.277984 -354.704826) (xy 28.285747 -354.650835)
			(xy 28.301115 -354.598497) (xy 28.323776 -354.54888) (xy 28.353268 -354.502993) (xy 28.38899 -354.46177)
			(xy 28.430215 -354.426051) (xy 28.476104 -354.396562) (xy 28.525723 -354.373905) (xy 28.578062 -354.358541)
			(xy 28.632054 -354.350782) (xy 28.659328 -354.35032) (xy 29.522928 -354.35032) (xy 29.550195 -354.350844)
			(xy 29.604173 -354.358609) (xy 29.656497 -354.373976) (xy 29.706101 -354.396633) (xy 29.751976 -354.426118)
			(xy 29.793188 -354.461831) (xy 29.828899 -354.503046) (xy 29.858381 -354.548924) (xy 29.881034 -354.59853)
			(xy 29.896397 -354.650855) (xy 29.904158 -354.704833) (xy 29.904158 -354.759367) (xy 29.904158 -354.75937)
			(xy 31.387006 -354.75937) (xy 31.387006 -354.70483) (xy 31.394768 -354.650845) (xy 31.410134 -354.598514)
			(xy 31.43279 -354.548902) (xy 31.462276 -354.50302) (xy 31.497992 -354.4618) (xy 31.53921 -354.426083)
			(xy 31.585091 -354.396596) (xy 31.634703 -354.373938) (xy 31.687033 -354.358571) (xy 31.741018 -354.350807)
			(xy 31.768288 -354.35032) (xy 32.631888 -354.35032) (xy 32.659158 -354.350819) (xy 32.713144 -354.358579)
			(xy 32.765476 -354.373944) (xy 32.815088 -354.396599) (xy 32.860971 -354.426085) (xy 32.902191 -354.461801)
			(xy 32.937908 -354.503019) (xy 32.967395 -354.548902) (xy 32.990052 -354.598513) (xy 33.005418 -354.650844)
			(xy 33.013181 -354.70483) (xy 33.013181 -354.75937) (xy 33.01318 -354.759374) (xy 34.495884 -354.759374)
			(xy 34.495884 -354.704826) (xy 34.503647 -354.650832) (xy 34.519017 -354.598493) (xy 34.541679 -354.548874)
			(xy 34.571172 -354.502986) (xy 34.606897 -354.461763) (xy 34.648125 -354.426044) (xy 34.694016 -354.396556)
			(xy 34.743638 -354.3739) (xy 34.795979 -354.358537) (xy 34.849973 -354.35078) (xy 34.877248 -354.35032)
			(xy 35.740848 -354.35032) (xy 35.768114 -354.350846) (xy 35.82209 -354.358613) (xy 35.874411 -354.373981)
			(xy 35.924013 -354.396639) (xy 35.969886 -354.426125) (xy 36.011095 -354.461839) (xy 36.046804 -354.503053)
			(xy 36.076284 -354.548929) (xy 36.098936 -354.598534) (xy 36.114298 -354.650857) (xy 36.122058 -354.704834)
			(xy 36.122058 -354.759366) (xy 36.122057 -354.759373) (xy 37.604884 -354.759373) (xy 37.604884 -354.704827)
			(xy 37.612646 -354.650837) (xy 37.628014 -354.598501) (xy 37.650673 -354.548885) (xy 37.680163 -354.502999)
			(xy 37.715883 -354.461777) (xy 37.757106 -354.426058) (xy 37.802992 -354.396569) (xy 37.852609 -354.373911)
			(xy 37.904945 -354.358545) (xy 37.958935 -354.350783) (xy 37.986208 -354.35032) (xy 38.849808 -354.35032)
			(xy 38.877076 -354.350843) (xy 38.931056 -354.358605) (xy 38.983382 -354.37397) (xy 39.032989 -354.396626)
			(xy 39.078867 -354.426111) (xy 39.120081 -354.461824) (xy 39.155794 -354.50304) (xy 39.185278 -354.548918)
			(xy 39.207932 -354.598525) (xy 39.223297 -354.650852) (xy 39.231058 -354.704832) (xy 39.231058 -354.759368)
			(xy 39.231058 -354.759369) (xy 40.713906 -354.759369) (xy 40.713906 -354.704831) (xy 40.721668 -354.650847)
			(xy 40.737032 -354.598518) (xy 40.759687 -354.548908) (xy 40.789171 -354.503026) (xy 40.824885 -354.461807)
			(xy 40.8661 -354.42609) (xy 40.91198 -354.396602) (xy 40.961588 -354.373943) (xy 41.013916 -354.358574)
			(xy 41.067899 -354.350809) (xy 41.095168 -354.35032) (xy 41.958768 -354.35032) (xy 41.986039 -354.350817)
			(xy 42.040027 -354.358575) (xy 42.092361 -354.373938) (xy 42.141976 -354.396593) (xy 42.187861 -354.426078)
			(xy 42.229083 -354.461794) (xy 42.264803 -354.503013) (xy 42.294292 -354.548896) (xy 42.316951 -354.598509)
			(xy 42.332318 -354.650842) (xy 42.34008 -354.704829) (xy 42.34008 -354.759371) (xy 42.34008 -354.759374)
			(xy 43.822784 -354.759374) (xy 43.822784 -354.704826) (xy 43.830547 -354.650835) (xy 43.845915 -354.598497)
			(xy 43.868576 -354.54888) (xy 43.898068 -354.502993) (xy 43.93379 -354.46177) (xy 43.975015 -354.426051)
			(xy 44.020904 -354.396562) (xy 44.070523 -354.373905) (xy 44.122862 -354.358541) (xy 44.176854 -354.350782)
			(xy 44.204128 -354.35032) (xy 45.067728 -354.35032) (xy 45.094995 -354.350844) (xy 45.148973 -354.358609)
			(xy 45.201297 -354.373976) (xy 45.250901 -354.396633) (xy 45.296776 -354.426118) (xy 45.337988 -354.461831)
			(xy 45.373699 -354.503046) (xy 45.403181 -354.548924) (xy 45.425834 -354.59853) (xy 45.441197 -354.650855)
			(xy 45.448958 -354.704833) (xy 45.448958 -354.759367) (xy 45.448958 -354.75937) (xy 46.931806 -354.75937)
			(xy 46.931806 -354.70483) (xy 46.939568 -354.650845) (xy 46.954934 -354.598514) (xy 46.97759 -354.548902)
			(xy 47.007076 -354.50302) (xy 47.042792 -354.4618) (xy 47.08401 -354.426083) (xy 47.129891 -354.396596)
			(xy 47.179503 -354.373938) (xy 47.231833 -354.358571) (xy 47.285818 -354.350807) (xy 47.313088 -354.35032)
			(xy 48.176688 -354.35032) (xy 48.203958 -354.350819) (xy 48.257944 -354.358579) (xy 48.310276 -354.373944)
			(xy 48.359888 -354.396599) (xy 48.405771 -354.426085) (xy 48.446991 -354.461801) (xy 48.482708 -354.503019)
			(xy 48.512195 -354.548902) (xy 48.534852 -354.598513) (xy 48.550218 -354.650844) (xy 48.557981 -354.70483)
			(xy 48.557981 -354.75937) (xy 48.55798 -354.759374) (xy 50.040684 -354.759374) (xy 50.040684 -354.704826)
			(xy 50.048447 -354.650832) (xy 50.063817 -354.598493) (xy 50.086479 -354.548874) (xy 50.115972 -354.502986)
			(xy 50.151697 -354.461763) (xy 50.192925 -354.426044) (xy 50.238816 -354.396556) (xy 50.288438 -354.3739)
			(xy 50.340779 -354.358537) (xy 50.394773 -354.35078) (xy 50.422048 -354.35032) (xy 51.285648 -354.35032)
			(xy 51.312914 -354.350846) (xy 51.36689 -354.358613) (xy 51.419211 -354.373981) (xy 51.468813 -354.396639)
			(xy 51.514686 -354.426125) (xy 51.555895 -354.461839) (xy 51.591604 -354.503053) (xy 51.621084 -354.548929)
			(xy 51.643736 -354.598534) (xy 51.659098 -354.650857) (xy 51.666858 -354.704834) (xy 51.666858 -354.759366)
			(xy 51.666857 -354.759372) (xy 64.099884 -354.759372) (xy 64.099884 -354.704828) (xy 64.107646 -354.650838)
			(xy 64.123013 -354.598503) (xy 64.145672 -354.548887) (xy 64.175161 -354.503001) (xy 64.210881 -354.461779)
			(xy 64.252103 -354.42606) (xy 64.297989 -354.396571) (xy 64.347605 -354.373912) (xy 64.39994 -354.358546)
			(xy 64.45393 -354.350783) (xy 64.481202 -354.35032) (xy 65.344802 -354.35032) (xy 65.37207 -354.350843)
			(xy 65.426051 -354.358604) (xy 65.478378 -354.373969) (xy 65.527985 -354.396624) (xy 65.573864 -354.426109)
			(xy 65.615079 -354.461822) (xy 65.650793 -354.503038) (xy 65.680277 -354.548917) (xy 65.702932 -354.598524)
			(xy 65.718296 -354.650851) (xy 65.726058 -354.704832) (xy 65.726058 -354.759368) (xy 65.726058 -354.759369)
			(xy 67.208906 -354.759369) (xy 67.208906 -354.704831) (xy 67.216667 -354.650848) (xy 67.232032 -354.598519)
			(xy 67.254686 -354.548909) (xy 67.28417 -354.503028) (xy 67.319883 -354.46181) (xy 67.361098 -354.426093)
			(xy 67.406976 -354.396604) (xy 67.456584 -354.373945) (xy 67.508911 -354.358575) (xy 67.562893 -354.350809)
			(xy 67.590162 -354.35032) (xy 68.453762 -354.35032) (xy 68.481033 -354.350817) (xy 68.535022 -354.358574)
			(xy 68.587357 -354.373936) (xy 68.636972 -354.396591) (xy 68.682859 -354.426076) (xy 68.724081 -354.461792)
			(xy 68.759801 -354.503011) (xy 68.789291 -354.548894) (xy 68.81195 -354.598508) (xy 68.827318 -354.650841)
			(xy 68.83508 -354.704829) (xy 68.83508 -354.759371) (xy 68.83508 -354.759373) (xy 70.317784 -354.759373)
			(xy 70.317784 -354.704827) (xy 70.325547 -354.650835) (xy 70.340915 -354.598498) (xy 70.363575 -354.548882)
			(xy 70.393066 -354.502995) (xy 70.428788 -354.461772) (xy 70.470012 -354.426053) (xy 70.515901 -354.396564)
			(xy 70.565519 -354.373907) (xy 70.617857 -354.358542) (xy 70.671849 -354.350782) (xy 70.699122 -354.35032)
			(xy 71.562722 -354.35032) (xy 71.589989 -354.350844) (xy 71.643968 -354.358608) (xy 71.696292 -354.373974)
			(xy 71.745897 -354.396631) (xy 71.791773 -354.426116) (xy 71.832986 -354.461829) (xy 71.868697 -354.503044)
			(xy 71.89818 -354.548922) (xy 71.920833 -354.598528) (xy 71.936197 -354.650854) (xy 71.943958 -354.704833)
			(xy 71.943958 -354.759367) (xy 71.943958 -354.75937) (xy 73.426806 -354.75937) (xy 73.426806 -354.70483)
			(xy 73.434568 -354.650846) (xy 73.449933 -354.598515) (xy 73.472589 -354.548904) (xy 73.502075 -354.503022)
			(xy 73.53779 -354.461802) (xy 73.579007 -354.426085) (xy 73.624888 -354.396598) (xy 73.674498 -354.373939)
			(xy 73.726828 -354.358572) (xy 73.780812 -354.350808) (xy 73.808082 -354.35032) (xy 74.671682 -354.35032)
			(xy 74.698953 -354.350818) (xy 74.752939 -354.358578) (xy 74.805271 -354.373942) (xy 74.854884 -354.396597)
			(xy 74.900768 -354.426083) (xy 74.941988 -354.461799) (xy 74.977706 -354.503018) (xy 75.007194 -354.5489)
			(xy 75.029852 -354.598512) (xy 75.045218 -354.650844) (xy 75.052981 -354.704829) (xy 75.052981 -354.759371)
			(xy 75.052981 -354.759374) (xy 76.535684 -354.759374) (xy 76.535684 -354.704826) (xy 76.543447 -354.650833)
			(xy 76.558816 -354.598494) (xy 76.581478 -354.548876) (xy 76.610971 -354.502988) (xy 76.646695 -354.461765)
			(xy 76.687922 -354.426046) (xy 76.733813 -354.396558) (xy 76.783434 -354.373902) (xy 76.835774 -354.358538)
			(xy 76.889768 -354.350781) (xy 76.917042 -354.35032) (xy 77.780642 -354.35032) (xy 77.807908 -354.350845)
			(xy 77.861885 -354.358611) (xy 77.914207 -354.37398) (xy 77.963809 -354.396637) (xy 78.009683 -354.426123)
			(xy 78.050893 -354.461836) (xy 78.086602 -354.503051) (xy 78.116083 -354.548928) (xy 78.138735 -354.598533)
			(xy 78.154098 -354.650856) (xy 78.161858 -354.704834) (xy 78.161858 -354.759366) (xy 78.161857 -354.759372)
			(xy 79.644684 -354.759372) (xy 79.644684 -354.704828) (xy 79.652446 -354.650838) (xy 79.667813 -354.598503)
			(xy 79.690472 -354.548887) (xy 79.719961 -354.503001) (xy 79.755681 -354.461779) (xy 79.796903 -354.42606)
			(xy 79.842789 -354.396571) (xy 79.892405 -354.373912) (xy 79.94474 -354.358546) (xy 79.99873 -354.350783)
			(xy 80.026002 -354.35032) (xy 80.889602 -354.35032) (xy 80.91687 -354.350843) (xy 80.970851 -354.358604)
			(xy 81.023178 -354.373969) (xy 81.072785 -354.396624) (xy 81.118664 -354.426109) (xy 81.159879 -354.461822)
			(xy 81.195593 -354.503038) (xy 81.225077 -354.548917) (xy 81.247732 -354.598524) (xy 81.263096 -354.650851)
			(xy 81.270858 -354.704832) (xy 81.270858 -354.759368) (xy 81.270858 -354.759369) (xy 82.753706 -354.759369)
			(xy 82.753706 -354.704831) (xy 82.761467 -354.650848) (xy 82.776832 -354.598519) (xy 82.799486 -354.548909)
			(xy 82.82897 -354.503028) (xy 82.864683 -354.46181) (xy 82.905898 -354.426093) (xy 82.951776 -354.396604)
			(xy 83.001384 -354.373945) (xy 83.053711 -354.358575) (xy 83.107693 -354.350809) (xy 83.134962 -354.35032)
			(xy 83.998562 -354.35032) (xy 84.025833 -354.350817) (xy 84.079822 -354.358574) (xy 84.132157 -354.373936)
			(xy 84.181772 -354.396591) (xy 84.227659 -354.426076) (xy 84.268881 -354.461792) (xy 84.304601 -354.503011)
			(xy 84.334091 -354.548894) (xy 84.35675 -354.598508) (xy 84.372118 -354.650841) (xy 84.37988 -354.704829)
			(xy 84.37988 -354.759371) (xy 84.37988 -354.759373) (xy 85.862584 -354.759373) (xy 85.862584 -354.704827)
			(xy 85.870347 -354.650835) (xy 85.885715 -354.598498) (xy 85.908375 -354.548882) (xy 85.937866 -354.502995)
			(xy 85.973588 -354.461772) (xy 86.014812 -354.426053) (xy 86.060701 -354.396564) (xy 86.110319 -354.373907)
			(xy 86.162657 -354.358542) (xy 86.216649 -354.350782) (xy 86.243922 -354.35032) (xy 87.107522 -354.35032)
			(xy 87.134789 -354.350844) (xy 87.188768 -354.358608) (xy 87.241092 -354.373974) (xy 87.290697 -354.396631)
			(xy 87.336573 -354.426116) (xy 87.377786 -354.461829) (xy 87.413497 -354.503044) (xy 87.44298 -354.548922)
			(xy 87.465633 -354.598528) (xy 87.480997 -354.650854) (xy 87.488758 -354.704833) (xy 87.488758 -354.759367)
			(xy 87.488758 -354.75937) (xy 88.971606 -354.75937) (xy 88.971606 -354.70483) (xy 88.979368 -354.650846)
			(xy 88.994733 -354.598515) (xy 89.017389 -354.548904) (xy 89.046875 -354.503022) (xy 89.08259 -354.461802)
			(xy 89.123807 -354.426085) (xy 89.169688 -354.396598) (xy 89.219298 -354.373939) (xy 89.271628 -354.358572)
			(xy 89.325612 -354.350808) (xy 89.352882 -354.35032) (xy 90.216482 -354.35032) (xy 90.243753 -354.350818)
			(xy 90.297739 -354.358578) (xy 90.350071 -354.373942) (xy 90.399684 -354.396597) (xy 90.445568 -354.426083)
			(xy 90.486788 -354.461799) (xy 90.522506 -354.503018) (xy 90.551994 -354.5489) (xy 90.574652 -354.598512)
			(xy 90.590018 -354.650844) (xy 90.597781 -354.704829) (xy 90.597781 -354.759371) (xy 90.597781 -354.759374)
			(xy 92.080484 -354.759374) (xy 92.080484 -354.704826) (xy 92.088247 -354.650833) (xy 92.103616 -354.598494)
			(xy 92.126278 -354.548876) (xy 92.155771 -354.502988) (xy 92.191495 -354.461765) (xy 92.232722 -354.426046)
			(xy 92.278613 -354.396558) (xy 92.328234 -354.373902) (xy 92.380574 -354.358538) (xy 92.434568 -354.350781)
			(xy 92.461842 -354.35032) (xy 93.325442 -354.35032) (xy 93.352708 -354.350845) (xy 93.406685 -354.358611)
			(xy 93.459007 -354.37398) (xy 93.508609 -354.396637) (xy 93.554483 -354.426123) (xy 93.595693 -354.461836)
			(xy 93.631402 -354.503051) (xy 93.660883 -354.548928) (xy 93.683535 -354.598533) (xy 93.698898 -354.650856)
			(xy 93.706658 -354.704834) (xy 93.706658 -354.759366) (xy 93.706658 -354.759369) (xy 114.589806 -354.759369)
			(xy 114.589806 -354.704831) (xy 114.597568 -354.650847) (xy 114.612932 -354.598518) (xy 114.635587 -354.548908)
			(xy 114.665071 -354.503026) (xy 114.700785 -354.461807) (xy 114.742 -354.42609) (xy 114.78788 -354.396602)
			(xy 114.837488 -354.373943) (xy 114.889816 -354.358574) (xy 114.943799 -354.350809) (xy 114.971068 -354.35032)
			(xy 115.834668 -354.35032) (xy 115.861939 -354.350817) (xy 115.915927 -354.358575) (xy 115.968261 -354.373938)
			(xy 116.017876 -354.396593) (xy 116.063761 -354.426078) (xy 116.104983 -354.461794) (xy 116.140703 -354.503013)
			(xy 116.170192 -354.548896) (xy 116.192851 -354.598509) (xy 116.208218 -354.650842) (xy 116.21598 -354.704829)
			(xy 116.21598 -354.759371) (xy 116.21598 -354.759374) (xy 117.698684 -354.759374) (xy 117.698684 -354.704826)
			(xy 117.706447 -354.650835) (xy 117.721815 -354.598497) (xy 117.744476 -354.54888) (xy 117.773968 -354.502993)
			(xy 117.80969 -354.46177) (xy 117.850915 -354.426051) (xy 117.896804 -354.396562) (xy 117.946423 -354.373905)
			(xy 117.998762 -354.358541) (xy 118.052754 -354.350782) (xy 118.080028 -354.35032) (xy 118.943628 -354.35032)
			(xy 118.970895 -354.350844) (xy 119.024873 -354.358609) (xy 119.077197 -354.373976) (xy 119.126801 -354.396633)
			(xy 119.172676 -354.426118) (xy 119.213888 -354.461831) (xy 119.249599 -354.503046) (xy 119.279081 -354.548924)
			(xy 119.301734 -354.59853) (xy 119.317097 -354.650855) (xy 119.324858 -354.704833) (xy 119.324858 -354.759367)
			(xy 119.324858 -354.75937) (xy 120.807706 -354.75937) (xy 120.807706 -354.70483) (xy 120.815468 -354.650845)
			(xy 120.830834 -354.598514) (xy 120.85349 -354.548902) (xy 120.882976 -354.50302) (xy 120.918692 -354.4618)
			(xy 120.95991 -354.426083) (xy 121.005791 -354.396596) (xy 121.055403 -354.373938) (xy 121.107733 -354.358571)
			(xy 121.161718 -354.350807) (xy 121.188988 -354.35032) (xy 122.052588 -354.35032) (xy 122.079858 -354.350819)
			(xy 122.133844 -354.358579) (xy 122.186176 -354.373944) (xy 122.235788 -354.396599) (xy 122.281671 -354.426085)
			(xy 122.322891 -354.461801) (xy 122.358608 -354.503019) (xy 122.388095 -354.548902) (xy 122.410752 -354.598513)
			(xy 122.426118 -354.650844) (xy 122.433881 -354.70483) (xy 122.433881 -354.75937) (xy 122.43388 -354.759374)
			(xy 123.916584 -354.759374) (xy 123.916584 -354.704826) (xy 123.924347 -354.650832) (xy 123.939717 -354.598493)
			(xy 123.962379 -354.548874) (xy 123.991872 -354.502986) (xy 124.027597 -354.461763) (xy 124.068825 -354.426044)
			(xy 124.114716 -354.396556) (xy 124.164338 -354.3739) (xy 124.216679 -354.358537) (xy 124.270673 -354.35078)
			(xy 124.297948 -354.35032) (xy 125.161548 -354.35032) (xy 125.188814 -354.350846) (xy 125.24279 -354.358613)
			(xy 125.295111 -354.373981) (xy 125.344713 -354.396639) (xy 125.390586 -354.426125) (xy 125.431795 -354.461839)
			(xy 125.467504 -354.503053) (xy 125.496984 -354.548929) (xy 125.519636 -354.598534) (xy 125.534998 -354.650857)
			(xy 125.542758 -354.704834) (xy 125.542758 -354.759366) (xy 125.542757 -354.759373) (xy 127.025584 -354.759373)
			(xy 127.025584 -354.704827) (xy 127.033346 -354.650837) (xy 127.048714 -354.598501) (xy 127.071373 -354.548885)
			(xy 127.100863 -354.502999) (xy 127.136583 -354.461777) (xy 127.177806 -354.426058) (xy 127.223692 -354.396569)
			(xy 127.273309 -354.373911) (xy 127.325645 -354.358545) (xy 127.379635 -354.350783) (xy 127.406908 -354.35032)
			(xy 128.270508 -354.35032) (xy 128.297776 -354.350843) (xy 128.351756 -354.358605) (xy 128.404082 -354.37397)
			(xy 128.453689 -354.396626) (xy 128.499567 -354.426111) (xy 128.540781 -354.461824) (xy 128.576494 -354.50304)
			(xy 128.605978 -354.548918) (xy 128.628632 -354.598525) (xy 128.643997 -354.650852) (xy 128.651758 -354.704832)
			(xy 128.651758 -354.759368) (xy 128.651758 -354.759369) (xy 130.134606 -354.759369) (xy 130.134606 -354.704831)
			(xy 130.142368 -354.650847) (xy 130.157732 -354.598518) (xy 130.180387 -354.548908) (xy 130.209871 -354.503026)
			(xy 130.245585 -354.461807) (xy 130.2868 -354.42609) (xy 130.33268 -354.396602) (xy 130.382288 -354.373943)
			(xy 130.434616 -354.358574) (xy 130.488599 -354.350809) (xy 130.515868 -354.35032) (xy 131.379468 -354.35032)
			(xy 131.406739 -354.350817) (xy 131.460727 -354.358575) (xy 131.513061 -354.373938) (xy 131.562676 -354.396593)
			(xy 131.608561 -354.426078) (xy 131.649783 -354.461794) (xy 131.685503 -354.503013) (xy 131.714992 -354.548896)
			(xy 131.737651 -354.598509) (xy 131.753018 -354.650842) (xy 131.76078 -354.704829) (xy 131.76078 -354.759371)
			(xy 131.76078 -354.759374) (xy 133.243484 -354.759374) (xy 133.243484 -354.704826) (xy 133.251247 -354.650835)
			(xy 133.266615 -354.598497) (xy 133.289276 -354.54888) (xy 133.318768 -354.502993) (xy 133.35449 -354.46177)
			(xy 133.395715 -354.426051) (xy 133.441604 -354.396562) (xy 133.491223 -354.373905) (xy 133.543562 -354.358541)
			(xy 133.597554 -354.350782) (xy 133.624828 -354.35032) (xy 134.488428 -354.35032) (xy 134.515695 -354.350844)
			(xy 134.569673 -354.358609) (xy 134.621997 -354.373976) (xy 134.671601 -354.396633) (xy 134.717476 -354.426118)
			(xy 134.758688 -354.461831) (xy 134.794399 -354.503046) (xy 134.823881 -354.548924) (xy 134.846534 -354.59853)
			(xy 134.861897 -354.650855) (xy 134.869658 -354.704833) (xy 134.869658 -354.759367) (xy 134.869658 -354.75937)
			(xy 136.352506 -354.75937) (xy 136.352506 -354.70483) (xy 136.360268 -354.650845) (xy 136.375634 -354.598514)
			(xy 136.39829 -354.548902) (xy 136.427776 -354.50302) (xy 136.463492 -354.4618) (xy 136.50471 -354.426083)
			(xy 136.550591 -354.396596) (xy 136.600203 -354.373938) (xy 136.652533 -354.358571) (xy 136.706518 -354.350807)
			(xy 136.733788 -354.35032) (xy 137.597388 -354.35032) (xy 137.624658 -354.350819) (xy 137.678644 -354.358579)
			(xy 137.730976 -354.373944) (xy 137.780588 -354.396599) (xy 137.826471 -354.426085) (xy 137.867691 -354.461801)
			(xy 137.903408 -354.503019) (xy 137.932895 -354.548902) (xy 137.955552 -354.598513) (xy 137.970918 -354.650844)
			(xy 137.978681 -354.70483) (xy 137.978681 -354.75937) (xy 137.97868 -354.759374) (xy 139.461384 -354.759374)
			(xy 139.461384 -354.704826) (xy 139.469147 -354.650832) (xy 139.484517 -354.598493) (xy 139.507179 -354.548874)
			(xy 139.536672 -354.502986) (xy 139.572397 -354.461763) (xy 139.613625 -354.426044) (xy 139.659516 -354.396556)
			(xy 139.709138 -354.3739) (xy 139.761479 -354.358537) (xy 139.815473 -354.35078) (xy 139.842748 -354.35032)
			(xy 140.706348 -354.35032) (xy 140.733614 -354.350846) (xy 140.78759 -354.358613) (xy 140.839911 -354.373981)
			(xy 140.889513 -354.396639) (xy 140.935386 -354.426125) (xy 140.976595 -354.461839) (xy 141.012304 -354.503053)
			(xy 141.041784 -354.548929) (xy 141.064436 -354.598534) (xy 141.079798 -354.650857) (xy 141.087558 -354.704834)
			(xy 141.087558 -354.759366) (xy 141.087557 -354.759373) (xy 142.570384 -354.759373) (xy 142.570384 -354.704827)
			(xy 142.578146 -354.650837) (xy 142.593514 -354.598501) (xy 142.616173 -354.548885) (xy 142.645663 -354.502999)
			(xy 142.681383 -354.461777) (xy 142.722606 -354.426058) (xy 142.768492 -354.396569) (xy 142.818109 -354.373911)
			(xy 142.870445 -354.358545) (xy 142.924435 -354.350783) (xy 142.951708 -354.35032) (xy 143.815308 -354.35032)
			(xy 143.842576 -354.350843) (xy 143.896556 -354.358605) (xy 143.948882 -354.37397) (xy 143.998489 -354.396626)
			(xy 144.044367 -354.426111) (xy 144.085581 -354.461824) (xy 144.121294 -354.50304) (xy 144.150778 -354.548918)
			(xy 144.173432 -354.598525) (xy 144.188797 -354.650852) (xy 144.196558 -354.704832) (xy 144.196558 -354.759368)
			(xy 158.695906 -354.759368) (xy 158.695906 -354.704832) (xy 158.703667 -354.65085) (xy 158.719031 -354.598521)
			(xy 158.741685 -354.548912) (xy 158.771167 -354.503031) (xy 158.806879 -354.461813) (xy 158.848093 -354.426096)
			(xy 158.89397 -354.396608) (xy 158.943576 -354.373948) (xy 158.995903 -354.358577) (xy 159.049884 -354.35081)
			(xy 159.077152 -354.35032) (xy 159.940752 -354.35032) (xy 159.968024 -354.350816) (xy 160.022013 -354.358572)
			(xy 160.074349 -354.373934) (xy 160.123966 -354.396588) (xy 160.169854 -354.426072) (xy 160.211078 -354.461788)
			(xy 160.246799 -354.503008) (xy 160.276289 -354.548891) (xy 160.298949 -354.598506) (xy 160.314317 -354.65084)
			(xy 160.32208 -354.704828) (xy 160.32208 -354.759372) (xy 160.32208 -354.759373) (xy 161.804784 -354.759373)
			(xy 161.804784 -354.704827) (xy 161.812546 -354.650837) (xy 161.827914 -354.598501) (xy 161.850573 -354.548884)
			(xy 161.880064 -354.502998) (xy 161.915784 -354.461776) (xy 161.957008 -354.426056) (xy 162.002895 -354.396568)
			(xy 162.052512 -354.37391) (xy 162.104848 -354.358544) (xy 162.158839 -354.350783) (xy 162.186112 -354.35032)
			(xy 163.049712 -354.35032) (xy 163.07698 -354.350843) (xy 163.130959 -354.358606) (xy 163.183285 -354.373972)
			(xy 163.232891 -354.396627) (xy 163.278768 -354.426112) (xy 163.319983 -354.461826) (xy 163.355695 -354.503041)
			(xy 163.385178 -354.548919) (xy 163.407833 -354.598526) (xy 163.423197 -354.650852) (xy 163.430958 -354.704832)
			(xy 163.430958 -354.759368) (xy 163.430958 -354.759369) (xy 164.913806 -354.759369) (xy 164.913806 -354.704831)
			(xy 164.921568 -354.650847) (xy 164.936932 -354.598517) (xy 164.959588 -354.548907) (xy 164.989072 -354.503025)
			(xy 165.024786 -354.461806) (xy 165.066002 -354.426089) (xy 165.111882 -354.396601) (xy 165.161491 -354.373942)
			(xy 165.21382 -354.358574) (xy 165.267803 -354.350808) (xy 165.295072 -354.35032) (xy 166.158672 -354.35032)
			(xy 166.185943 -354.350818) (xy 166.23993 -354.358576) (xy 166.292264 -354.373939) (xy 166.341878 -354.396594)
			(xy 166.387763 -354.42608) (xy 166.428985 -354.461795) (xy 166.464704 -354.503014) (xy 166.494192 -354.548897)
			(xy 166.516851 -354.59851) (xy 166.532218 -354.650842) (xy 166.53998 -354.704829) (xy 166.53998 -354.759371)
			(xy 166.53998 -354.759374) (xy 168.022684 -354.759374) (xy 168.022684 -354.704826) (xy 168.030447 -354.650834)
			(xy 168.045816 -354.598496) (xy 168.068477 -354.548879) (xy 168.097969 -354.502991) (xy 168.133691 -354.461768)
			(xy 168.174917 -354.426049) (xy 168.220807 -354.396561) (xy 168.270426 -354.373904) (xy 168.322765 -354.35854)
			(xy 168.376758 -354.350781) (xy 168.404032 -354.35032) (xy 169.267632 -354.35032) (xy 169.294899 -354.350845)
			(xy 169.348876 -354.35861) (xy 169.401199 -354.373977) (xy 169.450803 -354.396634) (xy 169.496678 -354.426119)
			(xy 169.53789 -354.461833) (xy 169.5736 -354.503048) (xy 169.603081 -354.548925) (xy 169.625734 -354.598531)
			(xy 169.641097 -354.650855) (xy 169.648858 -354.704833) (xy 169.648858 -354.759367) (xy 169.648858 -354.75937)
			(xy 171.131706 -354.75937) (xy 171.131706 -354.70483) (xy 171.139468 -354.650844) (xy 171.154834 -354.598513)
			(xy 171.177491 -354.548901) (xy 171.206977 -354.503018) (xy 171.242693 -354.461799) (xy 171.283912 -354.426082)
			(xy 171.329794 -354.396594) (xy 171.379405 -354.373937) (xy 171.431736 -354.35857) (xy 171.485722 -354.350807)
			(xy 171.512992 -354.35032) (xy 172.376592 -354.35032) (xy 172.403862 -354.350819) (xy 172.457847 -354.35858)
			(xy 172.510178 -354.373945) (xy 172.55979 -354.396601) (xy 172.605673 -354.426087) (xy 172.646892 -354.461802)
			(xy 172.682609 -354.503021) (xy 172.712096 -354.548903) (xy 172.734753 -354.598514) (xy 172.750119 -354.650845)
			(xy 172.757881 -354.70483) (xy 172.757881 -354.759368) (xy 174.240706 -354.759368) (xy 174.240706 -354.704832)
			(xy 174.248467 -354.65085) (xy 174.263831 -354.598521) (xy 174.286485 -354.548912) (xy 174.315967 -354.503031)
			(xy 174.351679 -354.461813) (xy 174.392893 -354.426096) (xy 174.43877 -354.396608) (xy 174.488376 -354.373948)
			(xy 174.540703 -354.358577) (xy 174.594684 -354.35081) (xy 174.621952 -354.35032) (xy 175.485552 -354.35032)
			(xy 175.512824 -354.350816) (xy 175.566813 -354.358572) (xy 175.619149 -354.373934) (xy 175.668766 -354.396588)
			(xy 175.714654 -354.426072) (xy 175.755878 -354.461788) (xy 175.791599 -354.503008) (xy 175.821089 -354.548891)
			(xy 175.843749 -354.598506) (xy 175.859117 -354.65084) (xy 175.86688 -354.704828) (xy 175.86688 -354.759372)
			(xy 175.86688 -354.759373) (xy 177.349584 -354.759373) (xy 177.349584 -354.704827) (xy 177.357346 -354.650837)
			(xy 177.372714 -354.598501) (xy 177.395373 -354.548884) (xy 177.424864 -354.502998) (xy 177.460584 -354.461776)
			(xy 177.501808 -354.426056) (xy 177.547695 -354.396568) (xy 177.597312 -354.37391) (xy 177.649648 -354.358544)
			(xy 177.703639 -354.350783) (xy 177.730912 -354.35032) (xy 178.594512 -354.35032) (xy 178.62178 -354.350843)
			(xy 178.675759 -354.358606) (xy 178.728085 -354.373972) (xy 178.777691 -354.396627) (xy 178.823568 -354.426112)
			(xy 178.864783 -354.461826) (xy 178.900495 -354.503041) (xy 178.929978 -354.548919) (xy 178.952633 -354.598526)
			(xy 178.967997 -354.650852) (xy 178.975758 -354.704832) (xy 178.975758 -354.759368) (xy 178.975758 -354.759369)
			(xy 180.458606 -354.759369) (xy 180.458606 -354.704831) (xy 180.466368 -354.650847) (xy 180.481732 -354.598517)
			(xy 180.504388 -354.548907) (xy 180.533872 -354.503025) (xy 180.569586 -354.461806) (xy 180.610802 -354.426089)
			(xy 180.656682 -354.396601) (xy 180.706291 -354.373942) (xy 180.75862 -354.358574) (xy 180.812603 -354.350808)
			(xy 180.839872 -354.35032) (xy 181.703472 -354.35032) (xy 181.730743 -354.350818) (xy 181.78473 -354.358576)
			(xy 181.837064 -354.373939) (xy 181.886678 -354.396594) (xy 181.932563 -354.42608) (xy 181.973785 -354.461795)
			(xy 182.009504 -354.503014) (xy 182.038992 -354.548897) (xy 182.061651 -354.59851) (xy 182.077018 -354.650842)
			(xy 182.08478 -354.704829) (xy 182.08478 -354.735472) (xy 183.567508 -354.735472) (xy 183.567508 -354.680928)
			(xy 183.57527 -354.626939) (xy 183.590638 -354.574605) (xy 183.613298 -354.52499) (xy 183.642788 -354.479106)
			(xy 183.678508 -354.437885) (xy 183.719731 -354.402169) (xy 183.765618 -354.372682) (xy 183.815235 -354.350027)
			(xy 183.86757 -354.334664) (xy 183.92156 -354.326905) (xy 183.948832 -354.326444) (xy 184.812432 -354.326444)
			(xy 184.8397 -354.326921) (xy 184.893681 -354.334686) (xy 184.946008 -354.350054) (xy 184.995615 -354.372713)
			(xy 185.041492 -354.4022) (xy 185.082707 -354.437916) (xy 185.118419 -354.479133) (xy 185.147903 -354.525013)
			(xy 185.170557 -354.574622) (xy 185.185921 -354.62695) (xy 185.193682 -354.680932) (xy 185.193682 -354.735468)
			(xy 185.193682 -354.735469) (xy 186.67653 -354.735469) (xy 186.67653 -354.680931) (xy 186.684292 -354.626949)
			(xy 186.699656 -354.574621) (xy 186.722312 -354.525012) (xy 186.751796 -354.479133) (xy 186.78751 -354.437916)
			(xy 186.828726 -354.402201) (xy 186.874605 -354.372716) (xy 186.924214 -354.350059) (xy 186.976542 -354.334693)
			(xy 187.030523 -354.326931) (xy 187.057792 -354.326444) (xy 187.921392 -354.326444) (xy 187.948664 -354.326895)
			(xy 188.002652 -354.334656) (xy 188.054987 -354.350022) (xy 188.104602 -354.37268) (xy 188.150487 -354.402167)
			(xy 188.191709 -354.437885) (xy 188.227428 -354.479106) (xy 188.256917 -354.524991) (xy 188.279575 -354.574606)
			(xy 188.294942 -354.62694) (xy 188.302704 -354.680928) (xy 188.302704 -354.735472) (xy 188.299268 -354.759369)
			(xy 270.624806 -354.759369) (xy 270.624806 -354.704831) (xy 270.632567 -354.650848) (xy 270.647932 -354.598519)
			(xy 270.670586 -354.548909) (xy 270.70007 -354.503028) (xy 270.735783 -354.46181) (xy 270.776998 -354.426093)
			(xy 270.822876 -354.396604) (xy 270.872484 -354.373945) (xy 270.924811 -354.358575) (xy 270.978793 -354.350809)
			(xy 271.006062 -354.35032) (xy 271.869662 -354.35032) (xy 271.896933 -354.350817) (xy 271.950922 -354.358574)
			(xy 272.003257 -354.373936) (xy 272.052872 -354.396591) (xy 272.098759 -354.426076) (xy 272.139981 -354.461792)
			(xy 272.175701 -354.503011) (xy 272.205191 -354.548894) (xy 272.22785 -354.598508) (xy 272.243218 -354.650841)
			(xy 272.25098 -354.704829) (xy 272.25098 -354.759371) (xy 272.25098 -354.759373) (xy 273.733684 -354.759373)
			(xy 273.733684 -354.704827) (xy 273.741447 -354.650835) (xy 273.756815 -354.598498) (xy 273.779475 -354.548882)
			(xy 273.808966 -354.502995) (xy 273.844688 -354.461772) (xy 273.885912 -354.426053) (xy 273.931801 -354.396564)
			(xy 273.981419 -354.373907) (xy 274.033757 -354.358542) (xy 274.087749 -354.350782) (xy 274.115022 -354.35032)
			(xy 274.978622 -354.35032) (xy 275.005889 -354.350844) (xy 275.059868 -354.358608) (xy 275.112192 -354.373974)
			(xy 275.161797 -354.396631) (xy 275.207673 -354.426116) (xy 275.248886 -354.461829) (xy 275.284597 -354.503044)
			(xy 275.31408 -354.548922) (xy 275.336733 -354.598528) (xy 275.352097 -354.650854) (xy 275.359858 -354.704833)
			(xy 275.359858 -354.759367) (xy 275.359858 -354.75937) (xy 276.842706 -354.75937) (xy 276.842706 -354.70483)
			(xy 276.850468 -354.650846) (xy 276.865833 -354.598515) (xy 276.888489 -354.548904) (xy 276.917975 -354.503022)
			(xy 276.95369 -354.461802) (xy 276.994907 -354.426085) (xy 277.040788 -354.396598) (xy 277.090398 -354.373939)
			(xy 277.142728 -354.358572) (xy 277.196712 -354.350808) (xy 277.223982 -354.35032) (xy 278.087582 -354.35032)
			(xy 278.114853 -354.350818) (xy 278.168839 -354.358578) (xy 278.221171 -354.373942) (xy 278.270784 -354.396597)
			(xy 278.316668 -354.426083) (xy 278.357888 -354.461799) (xy 278.393606 -354.503018) (xy 278.423094 -354.5489)
			(xy 278.445752 -354.598512) (xy 278.461118 -354.650844) (xy 278.468881 -354.704829) (xy 278.468881 -354.759371)
			(xy 278.468881 -354.759374) (xy 279.951584 -354.759374) (xy 279.951584 -354.704826) (xy 279.959347 -354.650833)
			(xy 279.974716 -354.598494) (xy 279.997378 -354.548876) (xy 280.026871 -354.502988) (xy 280.062595 -354.461765)
			(xy 280.103822 -354.426046) (xy 280.149713 -354.396558) (xy 280.199334 -354.373902) (xy 280.251674 -354.358538)
			(xy 280.305668 -354.350781) (xy 280.332942 -354.35032) (xy 281.196542 -354.35032) (xy 281.223808 -354.350845)
			(xy 281.277785 -354.358611) (xy 281.330107 -354.37398) (xy 281.379709 -354.396637) (xy 281.425583 -354.426123)
			(xy 281.466793 -354.461836) (xy 281.502502 -354.503051) (xy 281.531983 -354.548928) (xy 281.554635 -354.598533)
			(xy 281.569998 -354.650856) (xy 281.577758 -354.704834) (xy 281.577758 -354.759366) (xy 281.577757 -354.759372)
			(xy 283.060584 -354.759372) (xy 283.060584 -354.704828) (xy 283.068346 -354.650838) (xy 283.083713 -354.598503)
			(xy 283.106372 -354.548887) (xy 283.135861 -354.503001) (xy 283.171581 -354.461779) (xy 283.212803 -354.42606)
			(xy 283.258689 -354.396571) (xy 283.308305 -354.373912) (xy 283.36064 -354.358546) (xy 283.41463 -354.350783)
			(xy 283.441902 -354.35032) (xy 284.305502 -354.35032) (xy 284.33277 -354.350843) (xy 284.386751 -354.358604)
			(xy 284.439078 -354.373969) (xy 284.488685 -354.396624) (xy 284.534564 -354.426109) (xy 284.575779 -354.461822)
			(xy 284.611493 -354.503038) (xy 284.640977 -354.548917) (xy 284.663632 -354.598524) (xy 284.678996 -354.650851)
			(xy 284.686758 -354.704832) (xy 284.686758 -354.759368) (xy 284.686758 -354.759369) (xy 286.169606 -354.759369)
			(xy 286.169606 -354.704831) (xy 286.177367 -354.650848) (xy 286.192732 -354.598519) (xy 286.215386 -354.548909)
			(xy 286.24487 -354.503028) (xy 286.280583 -354.46181) (xy 286.321798 -354.426093) (xy 286.367676 -354.396604)
			(xy 286.417284 -354.373945) (xy 286.469611 -354.358575) (xy 286.523593 -354.350809) (xy 286.550862 -354.35032)
			(xy 287.414462 -354.35032) (xy 287.441733 -354.350817) (xy 287.495722 -354.358574) (xy 287.548057 -354.373936)
			(xy 287.597672 -354.396591) (xy 287.643559 -354.426076) (xy 287.684781 -354.461792) (xy 287.720501 -354.503011)
			(xy 287.749991 -354.548894) (xy 287.77265 -354.598508) (xy 287.788018 -354.650841) (xy 287.79578 -354.704829)
			(xy 287.79578 -354.759371) (xy 287.79578 -354.759373) (xy 289.278484 -354.759373) (xy 289.278484 -354.704827)
			(xy 289.286247 -354.650835) (xy 289.301615 -354.598498) (xy 289.324275 -354.548882) (xy 289.353766 -354.502995)
			(xy 289.389488 -354.461772) (xy 289.430712 -354.426053) (xy 289.476601 -354.396564) (xy 289.526219 -354.373907)
			(xy 289.578557 -354.358542) (xy 289.632549 -354.350782) (xy 289.659822 -354.35032) (xy 290.523422 -354.35032)
			(xy 290.550689 -354.350844) (xy 290.604668 -354.358608) (xy 290.656992 -354.373974) (xy 290.706597 -354.396631)
			(xy 290.752473 -354.426116) (xy 290.793686 -354.461829) (xy 290.829397 -354.503044) (xy 290.85888 -354.548922)
			(xy 290.881533 -354.598528) (xy 290.896897 -354.650854) (xy 290.904658 -354.704833) (xy 290.904658 -354.759367)
			(xy 290.904658 -354.75937) (xy 292.387506 -354.75937) (xy 292.387506 -354.70483) (xy 292.395268 -354.650846)
			(xy 292.410633 -354.598515) (xy 292.433289 -354.548904) (xy 292.462775 -354.503022) (xy 292.49849 -354.461802)
			(xy 292.539707 -354.426085) (xy 292.585588 -354.396598) (xy 292.635198 -354.373939) (xy 292.687528 -354.358572)
			(xy 292.741512 -354.350808) (xy 292.768782 -354.35032) (xy 293.632382 -354.35032) (xy 293.659653 -354.350818)
			(xy 293.713639 -354.358578) (xy 293.765971 -354.373942) (xy 293.815584 -354.396597) (xy 293.861468 -354.426083)
			(xy 293.902688 -354.461799) (xy 293.938406 -354.503018) (xy 293.967894 -354.5489) (xy 293.990552 -354.598512)
			(xy 294.005918 -354.650844) (xy 294.013681 -354.704829) (xy 294.013681 -354.759371) (xy 294.013681 -354.759374)
			(xy 295.496384 -354.759374) (xy 295.496384 -354.704826) (xy 295.504147 -354.650833) (xy 295.519516 -354.598494)
			(xy 295.542178 -354.548876) (xy 295.571671 -354.502988) (xy 295.607395 -354.461765) (xy 295.648622 -354.426046)
			(xy 295.694513 -354.396558) (xy 295.744134 -354.373902) (xy 295.796474 -354.358538) (xy 295.850468 -354.350781)
			(xy 295.877742 -354.35032) (xy 296.741342 -354.35032) (xy 296.768608 -354.350845) (xy 296.822585 -354.358611)
			(xy 296.874907 -354.37398) (xy 296.924509 -354.396637) (xy 296.970383 -354.426123) (xy 297.011593 -354.461836)
			(xy 297.047302 -354.503051) (xy 297.076783 -354.548928) (xy 297.099435 -354.598533) (xy 297.114798 -354.650856)
			(xy 297.122558 -354.704834) (xy 297.122558 -354.759366) (xy 297.122557 -354.759372) (xy 298.605384 -354.759372)
			(xy 298.605384 -354.704828) (xy 298.613146 -354.650838) (xy 298.628513 -354.598503) (xy 298.651172 -354.548887)
			(xy 298.680661 -354.503001) (xy 298.716381 -354.461779) (xy 298.757603 -354.42606) (xy 298.803489 -354.396571)
			(xy 298.853105 -354.373912) (xy 298.90544 -354.358546) (xy 298.95943 -354.350783) (xy 298.986702 -354.35032)
			(xy 299.850302 -354.35032) (xy 299.87757 -354.350843) (xy 299.931551 -354.358604) (xy 299.983878 -354.373969)
			(xy 300.033485 -354.396624) (xy 300.079364 -354.426109) (xy 300.120579 -354.461822) (xy 300.156293 -354.503038)
			(xy 300.185777 -354.548917) (xy 300.208432 -354.598524) (xy 300.223796 -354.650851) (xy 300.231558 -354.704832)
			(xy 300.231558 -354.759368) (xy 300.231558 -354.759369) (xy 315.230506 -354.759369) (xy 315.230506 -354.704831)
			(xy 315.238267 -354.650848) (xy 315.253632 -354.598519) (xy 315.276286 -354.548909) (xy 315.30577 -354.503027)
			(xy 315.341483 -354.461809) (xy 315.382699 -354.426092) (xy 315.428577 -354.396604) (xy 315.478185 -354.373944)
			(xy 315.530513 -354.358575) (xy 315.584495 -354.350809) (xy 315.611764 -354.35032) (xy 316.475364 -354.35032)
			(xy 316.502635 -354.350817) (xy 316.556624 -354.358575) (xy 316.608958 -354.373937) (xy 316.658574 -354.396591)
			(xy 316.70446 -354.426077) (xy 316.745682 -354.461793) (xy 316.781402 -354.503012) (xy 316.810891 -354.548895)
			(xy 316.83355 -354.598508) (xy 316.848918 -354.650841) (xy 316.85668 -354.704829) (xy 316.85668 -354.759371)
			(xy 316.85668 -354.759373) (xy 318.339384 -354.759373) (xy 318.339384 -354.704827) (xy 318.347147 -354.650835)
			(xy 318.362515 -354.598498) (xy 318.385175 -354.548881) (xy 318.414667 -354.502994) (xy 318.450388 -354.461771)
			(xy 318.491613 -354.426052) (xy 318.537502 -354.396564) (xy 318.587121 -354.373907) (xy 318.639459 -354.358542)
			(xy 318.693451 -354.350782) (xy 318.720724 -354.35032) (xy 319.584324 -354.35032) (xy 319.611591 -354.350844)
			(xy 319.665569 -354.358608) (xy 319.717894 -354.373975) (xy 319.767498 -354.396631) (xy 319.813374 -354.426116)
			(xy 319.854587 -354.46183) (xy 319.890298 -354.503045) (xy 319.91978 -354.548923) (xy 319.942434 -354.598529)
			(xy 319.957797 -354.650854) (xy 319.965558 -354.704833) (xy 319.965558 -354.759367) (xy 319.965558 -354.75937)
			(xy 321.448406 -354.75937) (xy 321.448406 -354.70483) (xy 321.456168 -354.650845) (xy 321.471533 -354.598515)
			(xy 321.494189 -354.548903) (xy 321.523675 -354.503021) (xy 321.55939 -354.461802) (xy 321.600608 -354.426085)
			(xy 321.646489 -354.396597) (xy 321.6961 -354.373939) (xy 321.74843 -354.358571) (xy 321.802414 -354.350808)
			(xy 321.829684 -354.35032) (xy 322.693284 -354.35032) (xy 322.720554 -354.350818) (xy 322.774541 -354.358578)
			(xy 322.826873 -354.373942) (xy 322.876485 -354.396598) (xy 322.922369 -354.426084) (xy 322.963589 -354.4618)
			(xy 322.999307 -354.503018) (xy 323.028794 -354.5489) (xy 323.051452 -354.598512) (xy 323.066818 -354.650844)
			(xy 323.074581 -354.70483) (xy 323.074581 -354.75937) (xy 323.07458 -354.759374) (xy 324.557284 -354.759374)
			(xy 324.557284 -354.704826) (xy 324.565047 -354.650832) (xy 324.580417 -354.598494) (xy 324.603078 -354.548875)
			(xy 324.632571 -354.502987) (xy 324.668295 -354.461764) (xy 324.709523 -354.426045) (xy 324.755414 -354.396557)
			(xy 324.805035 -354.373901) (xy 324.857375 -354.358538) (xy 324.91137 -354.350781) (xy 324.938644 -354.35032)
			(xy 325.802244 -354.35032) (xy 325.82951 -354.350845) (xy 325.883486 -354.358612) (xy 325.935808 -354.37398)
			(xy 325.98541 -354.396638) (xy 326.031284 -354.426124) (xy 326.072494 -354.461837) (xy 326.108203 -354.503052)
			(xy 326.137683 -354.548928) (xy 326.160335 -354.598533) (xy 326.175698 -354.650857) (xy 326.183458 -354.704834)
			(xy 326.183458 -354.759366) (xy 326.183457 -354.759372) (xy 327.666284 -354.759372) (xy 327.666284 -354.704828)
			(xy 327.674046 -354.650838) (xy 327.689413 -354.598502) (xy 327.712072 -354.548887) (xy 327.741562 -354.503001)
			(xy 327.777281 -354.461778) (xy 327.818504 -354.426059) (xy 327.86439 -354.39657) (xy 327.914006 -354.373912)
			(xy 327.966342 -354.358545) (xy 328.020332 -354.350783) (xy 328.047604 -354.35032) (xy 328.911204 -354.35032)
			(xy 328.938472 -354.350843) (xy 328.992453 -354.358604) (xy 329.044779 -354.373969) (xy 329.094386 -354.396625)
			(xy 329.140265 -354.426109) (xy 329.18148 -354.461823) (xy 329.217193 -354.503039) (xy 329.246677 -354.548917)
			(xy 329.269332 -354.598525) (xy 329.284696 -354.650851) (xy 329.292458 -354.704832) (xy 329.292458 -354.759368)
			(xy 329.292458 -354.759369) (xy 330.775306 -354.759369) (xy 330.775306 -354.704831) (xy 330.783067 -354.650848)
			(xy 330.798432 -354.598519) (xy 330.821086 -354.548909) (xy 330.85057 -354.503027) (xy 330.886283 -354.461809)
			(xy 330.927499 -354.426092) (xy 330.973377 -354.396604) (xy 331.022985 -354.373944) (xy 331.075313 -354.358575)
			(xy 331.129295 -354.350809) (xy 331.156564 -354.35032) (xy 332.020164 -354.35032) (xy 332.047435 -354.350817)
			(xy 332.101424 -354.358575) (xy 332.153758 -354.373937) (xy 332.203374 -354.396591) (xy 332.24926 -354.426077)
			(xy 332.290482 -354.461793) (xy 332.326202 -354.503012) (xy 332.355691 -354.548895) (xy 332.37835 -354.598508)
			(xy 332.393718 -354.650841) (xy 332.40148 -354.704829) (xy 332.40148 -354.759371) (xy 332.40148 -354.759373)
			(xy 333.884184 -354.759373) (xy 333.884184 -354.704827) (xy 333.891947 -354.650835) (xy 333.907315 -354.598498)
			(xy 333.929975 -354.548881) (xy 333.959467 -354.502994) (xy 333.995188 -354.461771) (xy 334.036413 -354.426052)
			(xy 334.082302 -354.396564) (xy 334.131921 -354.373907) (xy 334.184259 -354.358542) (xy 334.238251 -354.350782)
			(xy 334.265524 -354.35032) (xy 335.129124 -354.35032) (xy 335.156391 -354.350844) (xy 335.210369 -354.358608)
			(xy 335.262694 -354.373975) (xy 335.312298 -354.396631) (xy 335.358174 -354.426116) (xy 335.399387 -354.46183)
			(xy 335.435098 -354.503045) (xy 335.46458 -354.548923) (xy 335.487234 -354.598529) (xy 335.502597 -354.650854)
			(xy 335.510358 -354.704833) (xy 335.510358 -354.759367) (xy 335.510358 -354.75937) (xy 336.993206 -354.75937)
			(xy 336.993206 -354.70483) (xy 337.000968 -354.650845) (xy 337.016333 -354.598515) (xy 337.038989 -354.548903)
			(xy 337.068475 -354.503021) (xy 337.10419 -354.461802) (xy 337.145408 -354.426085) (xy 337.191289 -354.396597)
			(xy 337.2409 -354.373939) (xy 337.29323 -354.358571) (xy 337.347214 -354.350808) (xy 337.374484 -354.35032)
			(xy 338.238084 -354.35032) (xy 338.265354 -354.350818) (xy 338.319341 -354.358578) (xy 338.371673 -354.373942)
			(xy 338.421285 -354.396598) (xy 338.467169 -354.426084) (xy 338.508389 -354.4618) (xy 338.544107 -354.503018)
			(xy 338.573594 -354.5489) (xy 338.596252 -354.598512) (xy 338.611618 -354.650844) (xy 338.619381 -354.70483)
			(xy 338.619381 -354.75937) (xy 338.61938 -354.759374) (xy 340.102084 -354.759374) (xy 340.102084 -354.704826)
			(xy 340.109847 -354.650832) (xy 340.125217 -354.598494) (xy 340.147878 -354.548875) (xy 340.177371 -354.502987)
			(xy 340.213095 -354.461764) (xy 340.254323 -354.426045) (xy 340.300214 -354.396557) (xy 340.349835 -354.373901)
			(xy 340.402175 -354.358538) (xy 340.45617 -354.350781) (xy 340.483444 -354.35032) (xy 341.347044 -354.35032)
			(xy 341.37431 -354.350845) (xy 341.428286 -354.358612) (xy 341.480608 -354.37398) (xy 341.53021 -354.396638)
			(xy 341.576084 -354.426124) (xy 341.617294 -354.461837) (xy 341.653003 -354.503052) (xy 341.682483 -354.548928)
			(xy 341.705135 -354.598533) (xy 341.720498 -354.650857) (xy 341.728258 -354.704834) (xy 341.728258 -354.759366)
			(xy 341.728257 -354.759372) (xy 343.211084 -354.759372) (xy 343.211084 -354.704828) (xy 343.218846 -354.650838)
			(xy 343.234213 -354.598502) (xy 343.256872 -354.548887) (xy 343.286362 -354.503001) (xy 343.322081 -354.461778)
			(xy 343.363304 -354.426059) (xy 343.40919 -354.39657) (xy 343.458806 -354.373912) (xy 343.511142 -354.358545)
			(xy 343.565132 -354.350783) (xy 343.592404 -354.35032) (xy 344.456004 -354.35032) (xy 344.483272 -354.350843)
			(xy 344.537253 -354.358604) (xy 344.589579 -354.373969) (xy 344.639186 -354.396625) (xy 344.685065 -354.426109)
			(xy 344.72628 -354.461823) (xy 344.761993 -354.503039) (xy 344.791477 -354.548917) (xy 344.814132 -354.598525)
			(xy 344.829496 -354.650851) (xy 344.837258 -354.704832) (xy 344.837258 -354.759368) (xy 344.837257 -354.759374)
			(xy 373.915584 -354.759374) (xy 373.915584 -354.704826) (xy 373.923347 -354.650833) (xy 373.938716 -354.598495)
			(xy 373.961378 -354.548876) (xy 373.990871 -354.502989) (xy 374.026594 -354.461766) (xy 374.067821 -354.426047)
			(xy 374.113712 -354.396559) (xy 374.163332 -354.373902) (xy 374.215672 -354.358539) (xy 374.269666 -354.350781)
			(xy 374.29694 -354.35032) (xy 375.16054 -354.35032) (xy 375.187806 -354.350845) (xy 375.241783 -354.358611)
			(xy 375.294105 -354.373979) (xy 375.343708 -354.396637) (xy 375.389582 -354.426122) (xy 375.430793 -354.461836)
			(xy 375.466502 -354.50305) (xy 375.495983 -354.548927) (xy 375.518635 -354.598532) (xy 375.533997 -354.650856)
			(xy 375.541758 -354.704834) (xy 375.541758 -354.759366) (xy 375.541757 -354.759371) (xy 377.024606 -354.759371)
			(xy 377.024606 -354.704829) (xy 377.032369 -354.650843) (xy 377.047735 -354.598511) (xy 377.070392 -354.548899)
			(xy 377.099879 -354.503016) (xy 377.135596 -354.461796) (xy 377.176816 -354.426079) (xy 377.222699 -354.396592)
			(xy 377.272311 -354.373935) (xy 377.324643 -354.358569) (xy 377.378629 -354.350806) (xy 377.4059 -354.35032)
			(xy 378.2695 -354.35032) (xy 378.296768 -354.350842) (xy 378.350749 -354.358604) (xy 378.403076 -354.373968)
			(xy 378.452684 -354.396623) (xy 378.498563 -354.426108) (xy 378.539778 -354.461822) (xy 378.575492 -354.503037)
			(xy 378.604977 -354.548916) (xy 378.627632 -354.598524) (xy 378.642996 -354.650851) (xy 378.650758 -354.704832)
			(xy 378.650758 -354.759368) (xy 378.650758 -354.759369) (xy 380.133606 -354.759369) (xy 380.133606 -354.704831)
			(xy 380.141367 -354.650849) (xy 380.156731 -354.59852) (xy 380.179386 -354.54891) (xy 380.208869 -354.503029)
			(xy 380.244582 -354.46181) (xy 380.285797 -354.426093) (xy 380.331675 -354.396605) (xy 380.381282 -354.373945)
			(xy 380.433609 -354.358576) (xy 380.487591 -354.350809) (xy 380.51486 -354.35032) (xy 381.37846 -354.35032)
			(xy 381.405732 -354.350817) (xy 381.45972 -354.358574) (xy 381.512055 -354.373936) (xy 381.561671 -354.39659)
			(xy 381.607558 -354.426075) (xy 381.648781 -354.461791) (xy 381.684501 -354.50301) (xy 381.713991 -354.548894)
			(xy 381.73665 -354.598507) (xy 381.752018 -354.650841) (xy 381.75978 -354.704828) (xy 381.75978 -354.759372)
			(xy 381.75978 -354.759373) (xy 383.242484 -354.759373) (xy 383.242484 -354.704827) (xy 383.250247 -354.650836)
			(xy 383.265615 -354.598499) (xy 383.288275 -354.548882) (xy 383.317766 -354.502995) (xy 383.353487 -354.461773)
			(xy 383.394711 -354.426054) (xy 383.4406 -354.396565) (xy 383.490218 -354.373908) (xy 383.542555 -354.358542)
			(xy 383.596547 -354.350782) (xy 383.62382 -354.35032) (xy 384.48742 -354.35032) (xy 384.514687 -354.350844)
			(xy 384.568666 -354.358607) (xy 384.620991 -354.373974) (xy 384.670596 -354.39663) (xy 384.716472 -354.426115)
			(xy 384.757686 -354.461829) (xy 384.793397 -354.503044) (xy 384.82288 -354.548922) (xy 384.845533 -354.598528)
			(xy 384.860897 -354.650854) (xy 384.868658 -354.704833) (xy 384.868658 -354.759367) (xy 384.868658 -354.75937)
			(xy 386.351506 -354.75937) (xy 386.351506 -354.70483) (xy 386.359268 -354.650846) (xy 386.374633 -354.598515)
			(xy 386.397289 -354.548904) (xy 386.426774 -354.503022) (xy 386.462489 -354.461803) (xy 386.503706 -354.426086)
			(xy 386.549587 -354.396598) (xy 386.599197 -354.37394) (xy 386.651526 -354.358572) (xy 386.70551 -354.350808)
			(xy 386.73278 -354.35032) (xy 387.59638 -354.35032) (xy 387.623651 -354.350818) (xy 387.677637 -354.358578)
			(xy 387.72997 -354.373941) (xy 387.779583 -354.396597) (xy 387.825467 -354.426082) (xy 387.866688 -354.461798)
			(xy 387.902406 -354.503017) (xy 387.931894 -354.548899) (xy 387.954552 -354.598511) (xy 387.969918 -354.650843)
			(xy 387.97768 -354.704829) (xy 387.97768 -354.759371) (xy 387.97768 -354.759374) (xy 389.460384 -354.759374)
			(xy 389.460384 -354.704826) (xy 389.468147 -354.650833) (xy 389.483516 -354.598495) (xy 389.506178 -354.548876)
			(xy 389.535671 -354.502989) (xy 389.571394 -354.461766) (xy 389.612621 -354.426047) (xy 389.658512 -354.396559)
			(xy 389.708132 -354.373902) (xy 389.760472 -354.358539) (xy 389.814466 -354.350781) (xy 389.84174 -354.35032)
			(xy 390.70534 -354.35032) (xy 390.732606 -354.350845) (xy 390.786583 -354.358611) (xy 390.838905 -354.373979)
			(xy 390.888508 -354.396637) (xy 390.934382 -354.426122) (xy 390.975593 -354.461836) (xy 391.011302 -354.50305)
			(xy 391.040783 -354.548927) (xy 391.063435 -354.598532) (xy 391.078797 -354.650856) (xy 391.086558 -354.704834)
			(xy 391.086558 -354.759366) (xy 391.086557 -354.759371) (xy 392.569406 -354.759371) (xy 392.569406 -354.704829)
			(xy 392.577169 -354.650843) (xy 392.592535 -354.598511) (xy 392.615192 -354.548899) (xy 392.644679 -354.503016)
			(xy 392.680396 -354.461796) (xy 392.721616 -354.426079) (xy 392.767499 -354.396592) (xy 392.817111 -354.373935)
			(xy 392.869443 -354.358569) (xy 392.923429 -354.350806) (xy 392.9507 -354.35032) (xy 393.8143 -354.35032)
			(xy 393.841568 -354.350842) (xy 393.895549 -354.358604) (xy 393.947876 -354.373968) (xy 393.997484 -354.396623)
			(xy 394.043363 -354.426108) (xy 394.084578 -354.461822) (xy 394.120292 -354.503037) (xy 394.149777 -354.548916)
			(xy 394.172432 -354.598524) (xy 394.187796 -354.650851) (xy 394.195558 -354.704832) (xy 394.195558 -354.759368)
			(xy 394.195558 -354.759369) (xy 395.678406 -354.759369) (xy 395.678406 -354.704831) (xy 395.686167 -354.650849)
			(xy 395.701531 -354.59852) (xy 395.724186 -354.54891) (xy 395.753669 -354.503029) (xy 395.789382 -354.46181)
			(xy 395.830597 -354.426093) (xy 395.876475 -354.396605) (xy 395.926082 -354.373945) (xy 395.978409 -354.358576)
			(xy 396.032391 -354.350809) (xy 396.05966 -354.35032) (xy 396.92326 -354.35032) (xy 396.950532 -354.350817)
			(xy 397.00452 -354.358574) (xy 397.056855 -354.373936) (xy 397.106471 -354.39659) (xy 397.152358 -354.426075)
			(xy 397.193581 -354.461791) (xy 397.229301 -354.50301) (xy 397.258791 -354.548894) (xy 397.28145 -354.598507)
			(xy 397.296818 -354.650841) (xy 397.30458 -354.704828) (xy 397.30458 -354.759372) (xy 397.30458 -354.759373)
			(xy 398.787284 -354.759373) (xy 398.787284 -354.704827) (xy 398.795047 -354.650836) (xy 398.810415 -354.598499)
			(xy 398.833075 -354.548882) (xy 398.862566 -354.502995) (xy 398.898287 -354.461773) (xy 398.939511 -354.426054)
			(xy 398.9854 -354.396565) (xy 399.035018 -354.373908) (xy 399.087355 -354.358542) (xy 399.141347 -354.350782)
			(xy 399.16862 -354.35032) (xy 400.03222 -354.35032) (xy 400.059487 -354.350844) (xy 400.113466 -354.358607)
			(xy 400.165791 -354.373974) (xy 400.215396 -354.39663) (xy 400.261272 -354.426115) (xy 400.302486 -354.461829)
			(xy 400.338197 -354.503044) (xy 400.36768 -354.548922) (xy 400.390333 -354.598528) (xy 400.405697 -354.650854)
			(xy 400.413458 -354.704833) (xy 400.413458 -354.759367) (xy 400.413458 -354.75937) (xy 401.896306 -354.75937)
			(xy 401.896306 -354.70483) (xy 401.904068 -354.650846) (xy 401.919433 -354.598515) (xy 401.942089 -354.548904)
			(xy 401.971574 -354.503022) (xy 402.007289 -354.461803) (xy 402.048506 -354.426086) (xy 402.094387 -354.396598)
			(xy 402.143997 -354.37394) (xy 402.196326 -354.358572) (xy 402.25031 -354.350808) (xy 402.27758 -354.35032)
			(xy 403.14118 -354.35032) (xy 403.168451 -354.350818) (xy 403.222437 -354.358578) (xy 403.27477 -354.373941)
			(xy 403.324383 -354.396597) (xy 403.370267 -354.426082) (xy 403.411488 -354.461798) (xy 403.447206 -354.503017)
			(xy 403.476694 -354.548899) (xy 403.499352 -354.598511) (xy 403.514718 -354.650843) (xy 403.52248 -354.704829)
			(xy 403.52248 -354.759368) (xy 412.022806 -354.759368) (xy 412.022806 -354.704832) (xy 412.030567 -354.65085)
			(xy 412.045931 -354.598521) (xy 412.068585 -354.548912) (xy 412.098067 -354.503031) (xy 412.133779 -354.461813)
			(xy 412.174993 -354.426096) (xy 412.22087 -354.396608) (xy 412.270476 -354.373948) (xy 412.322803 -354.358577)
			(xy 412.376784 -354.35081) (xy 412.404052 -354.35032) (xy 413.267652 -354.35032) (xy 413.294924 -354.350816)
			(xy 413.348913 -354.358572) (xy 413.401249 -354.373934) (xy 413.450866 -354.396588) (xy 413.496754 -354.426072)
			(xy 413.537978 -354.461788) (xy 413.573699 -354.503008) (xy 413.603189 -354.548891) (xy 413.625849 -354.598506)
			(xy 413.641217 -354.65084) (xy 413.64898 -354.704828) (xy 413.64898 -354.759372) (xy 413.64898 -354.759373)
			(xy 415.131684 -354.759373) (xy 415.131684 -354.704827) (xy 415.139446 -354.650837) (xy 415.154814 -354.598501)
			(xy 415.177473 -354.548884) (xy 415.206964 -354.502998) (xy 415.242684 -354.461776) (xy 415.283908 -354.426056)
			(xy 415.329795 -354.396568) (xy 415.379412 -354.37391) (xy 415.431748 -354.358544) (xy 415.485739 -354.350783)
			(xy 415.513012 -354.35032) (xy 416.376612 -354.35032) (xy 416.40388 -354.350843) (xy 416.457859 -354.358606)
			(xy 416.510185 -354.373972) (xy 416.559791 -354.396627) (xy 416.605668 -354.426112) (xy 416.646883 -354.461826)
			(xy 416.682595 -354.503041) (xy 416.712078 -354.548919) (xy 416.734733 -354.598526) (xy 416.750097 -354.650852)
			(xy 416.757858 -354.704832) (xy 416.757858 -354.759368) (xy 416.757858 -354.759369) (xy 418.240706 -354.759369)
			(xy 418.240706 -354.704831) (xy 418.248468 -354.650847) (xy 418.263832 -354.598517) (xy 418.286488 -354.548907)
			(xy 418.315972 -354.503025) (xy 418.351686 -354.461806) (xy 418.392902 -354.426089) (xy 418.438782 -354.396601)
			(xy 418.488391 -354.373942) (xy 418.54072 -354.358574) (xy 418.594703 -354.350808) (xy 418.621972 -354.35032)
			(xy 419.485572 -354.35032) (xy 419.512843 -354.350818) (xy 419.56683 -354.358576) (xy 419.619164 -354.373939)
			(xy 419.668778 -354.396594) (xy 419.714663 -354.42608) (xy 419.755885 -354.461795) (xy 419.791604 -354.503014)
			(xy 419.821092 -354.548897) (xy 419.843751 -354.59851) (xy 419.859118 -354.650842) (xy 419.86688 -354.704829)
			(xy 419.86688 -354.759371) (xy 419.86688 -354.759374) (xy 421.349584 -354.759374) (xy 421.349584 -354.704826)
			(xy 421.357347 -354.650834) (xy 421.372716 -354.598496) (xy 421.395377 -354.548879) (xy 421.424869 -354.502991)
			(xy 421.460591 -354.461768) (xy 421.501817 -354.426049) (xy 421.547707 -354.396561) (xy 421.597326 -354.373904)
			(xy 421.649665 -354.35854) (xy 421.703658 -354.350781) (xy 421.730932 -354.35032) (xy 422.594532 -354.35032)
			(xy 422.621799 -354.350845) (xy 422.675776 -354.35861) (xy 422.728099 -354.373977) (xy 422.777703 -354.396634)
			(xy 422.823578 -354.426119) (xy 422.86479 -354.461833) (xy 422.9005 -354.503048) (xy 422.929981 -354.548925)
			(xy 422.952634 -354.598531) (xy 422.967997 -354.650855) (xy 422.975758 -354.704833) (xy 422.975758 -354.759367)
			(xy 422.975758 -354.75937) (xy 424.458606 -354.75937) (xy 424.458606 -354.70483) (xy 424.466368 -354.650844)
			(xy 424.481734 -354.598513) (xy 424.504391 -354.548901) (xy 424.533877 -354.503018) (xy 424.569593 -354.461799)
			(xy 424.610812 -354.426082) (xy 424.656694 -354.396594) (xy 424.706305 -354.373937) (xy 424.758636 -354.35857)
			(xy 424.812622 -354.350807) (xy 424.839892 -354.35032) (xy 425.703492 -354.35032) (xy 425.730762 -354.350819)
			(xy 425.784747 -354.35858) (xy 425.837078 -354.373945) (xy 425.88669 -354.396601) (xy 425.932573 -354.426087)
			(xy 425.973792 -354.461802) (xy 426.009509 -354.503021) (xy 426.038996 -354.548903) (xy 426.061653 -354.598514)
			(xy 426.077019 -354.650845) (xy 426.084781 -354.70483) (xy 426.084781 -354.759368) (xy 427.567606 -354.759368)
			(xy 427.567606 -354.704832) (xy 427.575367 -354.65085) (xy 427.590731 -354.598521) (xy 427.613385 -354.548912)
			(xy 427.642867 -354.503031) (xy 427.678579 -354.461813) (xy 427.719793 -354.426096) (xy 427.76567 -354.396608)
			(xy 427.815276 -354.373948) (xy 427.867603 -354.358577) (xy 427.921584 -354.35081) (xy 427.948852 -354.35032)
			(xy 428.812452 -354.35032) (xy 428.839724 -354.350816) (xy 428.893713 -354.358572) (xy 428.946049 -354.373934)
			(xy 428.995666 -354.396588) (xy 429.041554 -354.426072) (xy 429.082778 -354.461788) (xy 429.118499 -354.503008)
			(xy 429.147989 -354.548891) (xy 429.170649 -354.598506) (xy 429.186017 -354.65084) (xy 429.19378 -354.704828)
			(xy 429.19378 -354.759372) (xy 429.19378 -354.759373) (xy 430.676484 -354.759373) (xy 430.676484 -354.704827)
			(xy 430.684246 -354.650837) (xy 430.699614 -354.598501) (xy 430.722273 -354.548884) (xy 430.751764 -354.502998)
			(xy 430.787484 -354.461776) (xy 430.828708 -354.426056) (xy 430.874595 -354.396568) (xy 430.924212 -354.37391)
			(xy 430.976548 -354.358544) (xy 431.030539 -354.350783) (xy 431.057812 -354.35032) (xy 431.921412 -354.35032)
			(xy 431.94868 -354.350843) (xy 432.002659 -354.358606) (xy 432.054985 -354.373972) (xy 432.104591 -354.396627)
			(xy 432.150468 -354.426112) (xy 432.191683 -354.461826) (xy 432.227395 -354.503041) (xy 432.256878 -354.548919)
			(xy 432.279533 -354.598526) (xy 432.294897 -354.650852) (xy 432.302658 -354.704832) (xy 432.302658 -354.759368)
			(xy 432.302658 -354.759369) (xy 433.785506 -354.759369) (xy 433.785506 -354.704831) (xy 433.793268 -354.650847)
			(xy 433.808632 -354.598517) (xy 433.831288 -354.548907) (xy 433.860772 -354.503025) (xy 433.896486 -354.461806)
			(xy 433.937702 -354.426089) (xy 433.983582 -354.396601) (xy 434.033191 -354.373942) (xy 434.08552 -354.358574)
			(xy 434.139503 -354.350808) (xy 434.166772 -354.35032) (xy 435.030372 -354.35032) (xy 435.057643 -354.350818)
			(xy 435.11163 -354.358576) (xy 435.163964 -354.373939) (xy 435.213578 -354.396594) (xy 435.259463 -354.42608)
			(xy 435.300685 -354.461795) (xy 435.336404 -354.503014) (xy 435.365892 -354.548897) (xy 435.388551 -354.59851)
			(xy 435.403918 -354.650842) (xy 435.41168 -354.704829) (xy 435.41168 -354.759371) (xy 435.41168 -354.759374)
			(xy 436.894384 -354.759374) (xy 436.894384 -354.704826) (xy 436.902147 -354.650834) (xy 436.917516 -354.598496)
			(xy 436.940177 -354.548879) (xy 436.969669 -354.502991) (xy 437.005391 -354.461768) (xy 437.046617 -354.426049)
			(xy 437.092507 -354.396561) (xy 437.142126 -354.373904) (xy 437.194465 -354.35854) (xy 437.248458 -354.350781)
			(xy 437.275732 -354.35032) (xy 438.139332 -354.35032) (xy 438.166599 -354.350845) (xy 438.220576 -354.35861)
			(xy 438.272899 -354.373977) (xy 438.322503 -354.396634) (xy 438.368378 -354.426119) (xy 438.40959 -354.461833)
			(xy 438.4453 -354.503048) (xy 438.474781 -354.548925) (xy 438.497434 -354.598531) (xy 438.512797 -354.650855)
			(xy 438.520558 -354.704833) (xy 438.520558 -354.759367) (xy 438.520558 -354.75937) (xy 440.003406 -354.75937)
			(xy 440.003406 -354.70483) (xy 440.011168 -354.650844) (xy 440.026534 -354.598513) (xy 440.049191 -354.548901)
			(xy 440.078677 -354.503018) (xy 440.114393 -354.461799) (xy 440.155612 -354.426082) (xy 440.201494 -354.396594)
			(xy 440.251105 -354.373937) (xy 440.303436 -354.35857) (xy 440.357422 -354.350807) (xy 440.384692 -354.35032)
			(xy 441.248292 -354.35032) (xy 441.275562 -354.350819) (xy 441.329547 -354.35858) (xy 441.381878 -354.373945)
			(xy 441.43149 -354.396601) (xy 441.477373 -354.426087) (xy 441.518592 -354.461802) (xy 441.554309 -354.503021)
			(xy 441.583796 -354.548903) (xy 441.606453 -354.598514) (xy 441.621819 -354.650845) (xy 441.629581 -354.70483)
			(xy 441.629581 -354.75937) (xy 441.621819 -354.813355) (xy 441.606453 -354.865686) (xy 441.583796 -354.915297)
			(xy 441.554309 -354.961179) (xy 441.518592 -355.002398) (xy 441.477373 -355.038113) (xy 441.43149 -355.067599)
			(xy 441.381878 -355.090255) (xy 441.329547 -355.10562) (xy 441.275562 -355.113381) (xy 441.248292 -355.113844)
			(xy 440.384692 -355.113844) (xy 440.357422 -355.113393) (xy 440.303436 -355.10563) (xy 440.251105 -355.090263)
			(xy 440.201494 -355.067606) (xy 440.155612 -355.038118) (xy 440.114393 -355.002401) (xy 440.078677 -354.961182)
			(xy 440.049191 -354.915299) (xy 440.026534 -354.865687) (xy 440.011168 -354.813356) (xy 440.003406 -354.75937)
			(xy 438.520558 -354.75937) (xy 438.512797 -354.813345) (xy 438.497434 -354.865669) (xy 438.474781 -354.915275)
			(xy 438.4453 -354.961152) (xy 438.40959 -355.002367) (xy 438.368378 -355.038081) (xy 438.322503 -355.067566)
			(xy 438.272899 -355.090223) (xy 438.220576 -355.10559) (xy 438.166599 -355.113355) (xy 438.139332 -355.113844)
			(xy 437.275732 -355.113844) (xy 437.248458 -355.113419) (xy 437.194465 -355.10566) (xy 437.142126 -355.090296)
			(xy 437.092507 -355.067639) (xy 437.046617 -355.038151) (xy 437.005391 -355.002432) (xy 436.969669 -354.961209)
			(xy 436.940177 -354.915321) (xy 436.917516 -354.865704) (xy 436.902147 -354.813366) (xy 436.894384 -354.759374)
			(xy 435.41168 -354.759374) (xy 435.403918 -354.813358) (xy 435.388551 -354.86569) (xy 435.365892 -354.915303)
			(xy 435.336404 -354.961186) (xy 435.300685 -355.002405) (xy 435.259463 -355.03812) (xy 435.213578 -355.067606)
			(xy 435.163964 -355.090261) (xy 435.11163 -355.105624) (xy 435.057643 -355.113382) (xy 435.030372 -355.113844)
			(xy 434.166772 -355.113844) (xy 434.139503 -355.113392) (xy 434.08552 -355.105626) (xy 434.033191 -355.090258)
			(xy 433.983582 -355.067599) (xy 433.937702 -355.038111) (xy 433.896486 -355.002394) (xy 433.860772 -354.961175)
			(xy 433.831288 -354.915293) (xy 433.808632 -354.865683) (xy 433.793268 -354.813353) (xy 433.785506 -354.759369)
			(xy 432.302658 -354.759369) (xy 432.294897 -354.813348) (xy 432.279533 -354.865674) (xy 432.256878 -354.915281)
			(xy 432.227395 -354.961159) (xy 432.191683 -355.002374) (xy 432.150468 -355.038088) (xy 432.104591 -355.067573)
			(xy 432.054985 -355.090228) (xy 432.002659 -355.105594) (xy 431.94868 -355.113357) (xy 431.921412 -355.113844)
			(xy 431.057812 -355.113844) (xy 431.030539 -355.113417) (xy 430.976548 -355.105656) (xy 430.924212 -355.09029)
			(xy 430.874595 -355.067632) (xy 430.828708 -355.038144) (xy 430.787484 -355.002424) (xy 430.751764 -354.961202)
			(xy 430.722273 -354.915316) (xy 430.699614 -354.865699) (xy 430.684246 -354.813363) (xy 430.676484 -354.759373)
			(xy 429.19378 -354.759373) (xy 429.186017 -354.81336) (xy 429.170649 -354.865694) (xy 429.147989 -354.915309)
			(xy 429.118499 -354.961192) (xy 429.082778 -355.002412) (xy 429.041554 -355.038128) (xy 428.995666 -355.067612)
			(xy 428.946049 -355.090266) (xy 428.893713 -355.105628) (xy 428.839724 -355.113384) (xy 428.812452 -355.113844)
			(xy 427.948852 -355.113844) (xy 427.921584 -355.11339) (xy 427.867603 -355.105623) (xy 427.815276 -355.090252)
			(xy 427.76567 -355.067592) (xy 427.719793 -355.038104) (xy 427.678579 -355.002387) (xy 427.642867 -354.961169)
			(xy 427.613385 -354.915288) (xy 427.590731 -354.865679) (xy 427.575367 -354.81335) (xy 427.567606 -354.759368)
			(xy 426.084781 -354.759368) (xy 426.084781 -354.75937) (xy 426.077019 -354.813355) (xy 426.061653 -354.865686)
			(xy 426.038996 -354.915297) (xy 426.009509 -354.961179) (xy 425.973792 -355.002398) (xy 425.932573 -355.038113)
			(xy 425.88669 -355.067599) (xy 425.837078 -355.090255) (xy 425.784747 -355.10562) (xy 425.730762 -355.113381)
			(xy 425.703492 -355.113844) (xy 424.839892 -355.113844) (xy 424.812622 -355.113393) (xy 424.758636 -355.10563)
			(xy 424.706305 -355.090263) (xy 424.656694 -355.067606) (xy 424.610812 -355.038118) (xy 424.569593 -355.002401)
			(xy 424.533877 -354.961182) (xy 424.504391 -354.915299) (xy 424.481734 -354.865687) (xy 424.466368 -354.813356)
			(xy 424.458606 -354.75937) (xy 422.975758 -354.75937) (xy 422.967997 -354.813345) (xy 422.952634 -354.865669)
			(xy 422.929981 -354.915275) (xy 422.9005 -354.961152) (xy 422.86479 -355.002367) (xy 422.823578 -355.038081)
			(xy 422.777703 -355.067566) (xy 422.728099 -355.090223) (xy 422.675776 -355.10559) (xy 422.621799 -355.113355)
			(xy 422.594532 -355.113844) (xy 421.730932 -355.113844) (xy 421.703658 -355.113419) (xy 421.649665 -355.10566)
			(xy 421.597326 -355.090296) (xy 421.547707 -355.067639) (xy 421.501817 -355.038151) (xy 421.460591 -355.002432)
			(xy 421.424869 -354.961209) (xy 421.395377 -354.915321) (xy 421.372716 -354.865704) (xy 421.357347 -354.813366)
			(xy 421.349584 -354.759374) (xy 419.86688 -354.759374) (xy 419.859118 -354.813358) (xy 419.843751 -354.86569)
			(xy 419.821092 -354.915303) (xy 419.791604 -354.961186) (xy 419.755885 -355.002405) (xy 419.714663 -355.03812)
			(xy 419.668778 -355.067606) (xy 419.619164 -355.090261) (xy 419.56683 -355.105624) (xy 419.512843 -355.113382)
			(xy 419.485572 -355.113844) (xy 418.621972 -355.113844) (xy 418.594703 -355.113392) (xy 418.54072 -355.105626)
			(xy 418.488391 -355.090258) (xy 418.438782 -355.067599) (xy 418.392902 -355.038111) (xy 418.351686 -355.002394)
			(xy 418.315972 -354.961175) (xy 418.286488 -354.915293) (xy 418.263832 -354.865683) (xy 418.248468 -354.813353)
			(xy 418.240706 -354.759369) (xy 416.757858 -354.759369) (xy 416.750097 -354.813348) (xy 416.734733 -354.865674)
			(xy 416.712078 -354.915281) (xy 416.682595 -354.961159) (xy 416.646883 -355.002374) (xy 416.605668 -355.038088)
			(xy 416.559791 -355.067573) (xy 416.510185 -355.090228) (xy 416.457859 -355.105594) (xy 416.40388 -355.113357)
			(xy 416.376612 -355.113844) (xy 415.513012 -355.113844) (xy 415.485739 -355.113417) (xy 415.431748 -355.105656)
			(xy 415.379412 -355.09029) (xy 415.329795 -355.067632) (xy 415.283908 -355.038144) (xy 415.242684 -355.002424)
			(xy 415.206964 -354.961202) (xy 415.177473 -354.915316) (xy 415.154814 -354.865699) (xy 415.139446 -354.813363)
			(xy 415.131684 -354.759373) (xy 413.64898 -354.759373) (xy 413.641217 -354.81336) (xy 413.625849 -354.865694)
			(xy 413.603189 -354.915309) (xy 413.573699 -354.961192) (xy 413.537978 -355.002412) (xy 413.496754 -355.038128)
			(xy 413.450866 -355.067612) (xy 413.401249 -355.090266) (xy 413.348913 -355.105628) (xy 413.294924 -355.113384)
			(xy 413.267652 -355.113844) (xy 412.404052 -355.113844) (xy 412.376784 -355.11339) (xy 412.322803 -355.105623)
			(xy 412.270476 -355.090252) (xy 412.22087 -355.067592) (xy 412.174993 -355.038104) (xy 412.133779 -355.002387)
			(xy 412.098067 -354.961169) (xy 412.068585 -354.915288) (xy 412.045931 -354.865679) (xy 412.030567 -354.81335)
			(xy 412.022806 -354.759368) (xy 403.52248 -354.759368) (xy 403.52248 -354.759371) (xy 403.514718 -354.813357)
			(xy 403.499352 -354.865689) (xy 403.476694 -354.915301) (xy 403.447206 -354.961183) (xy 403.411488 -355.002402)
			(xy 403.370267 -355.038118) (xy 403.324383 -355.067603) (xy 403.27477 -355.090259) (xy 403.222437 -355.105622)
			(xy 403.168451 -355.113382) (xy 403.14118 -355.113844) (xy 402.27758 -355.113844) (xy 402.25031 -355.113392)
			(xy 402.196326 -355.105628) (xy 402.143997 -355.09026) (xy 402.094387 -355.067602) (xy 402.048506 -355.038114)
			(xy 402.007289 -355.002397) (xy 401.971574 -354.961178) (xy 401.942089 -354.915296) (xy 401.919433 -354.865685)
			(xy 401.904068 -354.813354) (xy 401.896306 -354.75937) (xy 400.413458 -354.75937) (xy 400.405697 -354.813346)
			(xy 400.390333 -354.865672) (xy 400.36768 -354.915278) (xy 400.338197 -354.961156) (xy 400.302486 -355.002371)
			(xy 400.261272 -355.038085) (xy 400.215396 -355.06757) (xy 400.165791 -355.090226) (xy 400.113466 -355.105593)
			(xy 400.059487 -355.113356) (xy 400.03222 -355.113844) (xy 399.16862 -355.113844) (xy 399.141347 -355.113418)
			(xy 399.087355 -355.105658) (xy 399.035018 -355.090292) (xy 398.9854 -355.067635) (xy 398.939511 -355.038146)
			(xy 398.898287 -355.002427) (xy 398.862566 -354.961205) (xy 398.833075 -354.915318) (xy 398.810415 -354.865701)
			(xy 398.795047 -354.813364) (xy 398.787284 -354.759373) (xy 397.30458 -354.759373) (xy 397.296818 -354.813359)
			(xy 397.28145 -354.865693) (xy 397.258791 -354.915306) (xy 397.229301 -354.96119) (xy 397.193581 -355.002409)
			(xy 397.152358 -355.038125) (xy 397.106471 -355.06761) (xy 397.056855 -355.090264) (xy 397.00452 -355.105626)
			(xy 396.950532 -355.113383) (xy 396.92326 -355.113844) (xy 396.05966 -355.113844) (xy 396.032391 -355.113391)
			(xy 395.978409 -355.105624) (xy 395.926082 -355.090255) (xy 395.876475 -355.067595) (xy 395.830597 -355.038107)
			(xy 395.789382 -355.00239) (xy 395.753669 -354.961171) (xy 395.724186 -354.91529) (xy 395.701531 -354.86568)
			(xy 395.686167 -354.813351) (xy 395.678406 -354.759369) (xy 394.195558 -354.759369) (xy 394.187796 -354.813349)
			(xy 394.172432 -354.865676) (xy 394.149777 -354.915284) (xy 394.120292 -354.961163) (xy 394.084578 -355.002378)
			(xy 394.043363 -355.038092) (xy 393.997484 -355.067577) (xy 393.947876 -355.090232) (xy 393.895549 -355.105596)
			(xy 393.841568 -355.113358) (xy 393.8143 -355.113844) (xy 392.9507 -355.113844) (xy 392.923429 -355.113394)
			(xy 392.869443 -355.105631) (xy 392.817111 -355.090265) (xy 392.767499 -355.067608) (xy 392.721616 -355.038121)
			(xy 392.680396 -355.002404) (xy 392.644679 -354.961184) (xy 392.615192 -354.915301) (xy 392.592535 -354.865689)
			(xy 392.577169 -354.813357) (xy 392.569406 -354.759371) (xy 391.086557 -354.759371) (xy 391.078797 -354.813344)
			(xy 391.063435 -354.865668) (xy 391.040783 -354.915273) (xy 391.011302 -354.96115) (xy 390.975593 -355.002364)
			(xy 390.934382 -355.038078) (xy 390.888508 -355.067563) (xy 390.838905 -355.090221) (xy 390.786583 -355.105589)
			(xy 390.732606 -355.113355) (xy 390.70534 -355.113844) (xy 389.84174 -355.113844) (xy 389.814466 -355.113419)
			(xy 389.760472 -355.105661) (xy 389.708132 -355.090298) (xy 389.658512 -355.067641) (xy 389.612621 -355.038153)
			(xy 389.571394 -355.002434) (xy 389.535671 -354.961211) (xy 389.506178 -354.915324) (xy 389.483516 -354.865705)
			(xy 389.468147 -354.813367) (xy 389.460384 -354.759374) (xy 387.97768 -354.759374) (xy 387.969918 -354.813357)
			(xy 387.954552 -354.865689) (xy 387.931894 -354.915301) (xy 387.902406 -354.961183) (xy 387.866688 -355.002402)
			(xy 387.825467 -355.038118) (xy 387.779583 -355.067603) (xy 387.72997 -355.090259) (xy 387.677637 -355.105622)
			(xy 387.623651 -355.113382) (xy 387.59638 -355.113844) (xy 386.73278 -355.113844) (xy 386.70551 -355.113392)
			(xy 386.651526 -355.105628) (xy 386.599197 -355.09026) (xy 386.549587 -355.067602) (xy 386.503706 -355.038114)
			(xy 386.462489 -355.002397) (xy 386.426774 -354.961178) (xy 386.397289 -354.915296) (xy 386.374633 -354.865685)
			(xy 386.359268 -354.813354) (xy 386.351506 -354.75937) (xy 384.868658 -354.75937) (xy 384.860897 -354.813346)
			(xy 384.845533 -354.865672) (xy 384.82288 -354.915278) (xy 384.793397 -354.961156) (xy 384.757686 -355.002371)
			(xy 384.716472 -355.038085) (xy 384.670596 -355.06757) (xy 384.620991 -355.090226) (xy 384.568666 -355.105593)
			(xy 384.514687 -355.113356) (xy 384.48742 -355.113844) (xy 383.62382 -355.113844) (xy 383.596547 -355.113418)
			(xy 383.542555 -355.105658) (xy 383.490218 -355.090292) (xy 383.4406 -355.067635) (xy 383.394711 -355.038146)
			(xy 383.353487 -355.002427) (xy 383.317766 -354.961205) (xy 383.288275 -354.915318) (xy 383.265615 -354.865701)
			(xy 383.250247 -354.813364) (xy 383.242484 -354.759373) (xy 381.75978 -354.759373) (xy 381.752018 -354.813359)
			(xy 381.73665 -354.865693) (xy 381.713991 -354.915306) (xy 381.684501 -354.96119) (xy 381.648781 -355.002409)
			(xy 381.607558 -355.038125) (xy 381.561671 -355.06761) (xy 381.512055 -355.090264) (xy 381.45972 -355.105626)
			(xy 381.405732 -355.113383) (xy 381.37846 -355.113844) (xy 380.51486 -355.113844) (xy 380.487591 -355.113391)
			(xy 380.433609 -355.105624) (xy 380.381282 -355.090255) (xy 380.331675 -355.067595) (xy 380.285797 -355.038107)
			(xy 380.244582 -355.00239) (xy 380.208869 -354.961171) (xy 380.179386 -354.91529) (xy 380.156731 -354.86568)
			(xy 380.141367 -354.813351) (xy 380.133606 -354.759369) (xy 378.650758 -354.759369) (xy 378.642996 -354.813349)
			(xy 378.627632 -354.865676) (xy 378.604977 -354.915284) (xy 378.575492 -354.961163) (xy 378.539778 -355.002378)
			(xy 378.498563 -355.038092) (xy 378.452684 -355.067577) (xy 378.403076 -355.090232) (xy 378.350749 -355.105596)
			(xy 378.296768 -355.113358) (xy 378.2695 -355.113844) (xy 377.4059 -355.113844) (xy 377.378629 -355.113394)
			(xy 377.324643 -355.105631) (xy 377.272311 -355.090265) (xy 377.222699 -355.067608) (xy 377.176816 -355.038121)
			(xy 377.135596 -355.002404) (xy 377.099879 -354.961184) (xy 377.070392 -354.915301) (xy 377.047735 -354.865689)
			(xy 377.032369 -354.813357) (xy 377.024606 -354.759371) (xy 375.541757 -354.759371) (xy 375.533997 -354.813344)
			(xy 375.518635 -354.865668) (xy 375.495983 -354.915273) (xy 375.466502 -354.96115) (xy 375.430793 -355.002364)
			(xy 375.389582 -355.038078) (xy 375.343708 -355.067563) (xy 375.294105 -355.090221) (xy 375.241783 -355.105589)
			(xy 375.187806 -355.113355) (xy 375.16054 -355.113844) (xy 374.29694 -355.113844) (xy 374.269666 -355.113419)
			(xy 374.215672 -355.105661) (xy 374.163332 -355.090298) (xy 374.113712 -355.067641) (xy 374.067821 -355.038153)
			(xy 374.026594 -355.002434) (xy 373.990871 -354.961211) (xy 373.961378 -354.915324) (xy 373.938716 -354.865705)
			(xy 373.923347 -354.813367) (xy 373.915584 -354.759374) (xy 344.837257 -354.759374) (xy 344.829496 -354.813349)
			(xy 344.814132 -354.865675) (xy 344.791477 -354.915283) (xy 344.761993 -354.961161) (xy 344.72628 -355.002377)
			(xy 344.685065 -355.038091) (xy 344.639186 -355.067575) (xy 344.589579 -355.090231) (xy 344.537253 -355.105596)
			(xy 344.483272 -355.113357) (xy 344.456004 -355.113844) (xy 343.592404 -355.113844) (xy 343.565132 -355.113417)
			(xy 343.511142 -355.105655) (xy 343.458806 -355.090288) (xy 343.40919 -355.06763) (xy 343.363304 -355.038141)
			(xy 343.322081 -355.002422) (xy 343.286362 -354.961199) (xy 343.256872 -354.915313) (xy 343.234213 -354.865698)
			(xy 343.218846 -354.813362) (xy 343.211084 -354.759372) (xy 341.728257 -354.759372) (xy 341.720498 -354.813343)
			(xy 341.705135 -354.865667) (xy 341.682483 -354.915272) (xy 341.653003 -354.961148) (xy 341.617294 -355.002363)
			(xy 341.576084 -355.038076) (xy 341.53021 -355.067562) (xy 341.480608 -355.09022) (xy 341.428286 -355.105588)
			(xy 341.37431 -355.113355) (xy 341.347044 -355.113844) (xy 340.483444 -355.113844) (xy 340.45617 -355.113419)
			(xy 340.402175 -355.105662) (xy 340.349835 -355.090299) (xy 340.300214 -355.067643) (xy 340.254323 -355.038155)
			(xy 340.213095 -355.002436) (xy 340.177371 -354.961213) (xy 340.147878 -354.915325) (xy 340.125217 -354.865706)
			(xy 340.109847 -354.813368) (xy 340.102084 -354.759374) (xy 338.61938 -354.759374) (xy 338.611618 -354.813356)
			(xy 338.596252 -354.865688) (xy 338.573594 -354.9153) (xy 338.544107 -354.961182) (xy 338.508389 -355.0024)
			(xy 338.467169 -355.038116) (xy 338.421285 -355.067602) (xy 338.371673 -355.090258) (xy 338.319341 -355.105622)
			(xy 338.265354 -355.113382) (xy 338.238084 -355.113844) (xy 337.374484 -355.113844) (xy 337.347214 -355.113392)
			(xy 337.29323 -355.105629) (xy 337.2409 -355.090261) (xy 337.191289 -355.067603) (xy 337.145408 -355.038115)
			(xy 337.10419 -355.002398) (xy 337.068475 -354.961179) (xy 337.038989 -354.915297) (xy 337.016333 -354.865685)
			(xy 337.000968 -354.813355) (xy 336.993206 -354.75937) (xy 335.510358 -354.75937) (xy 335.502597 -354.813346)
			(xy 335.487234 -354.865671) (xy 335.46458 -354.915277) (xy 335.435098 -354.961155) (xy 335.399387 -355.00237)
			(xy 335.358174 -355.038084) (xy 335.312298 -355.067569) (xy 335.262694 -355.090225) (xy 335.210369 -355.105592)
			(xy 335.156391 -355.113356) (xy 335.129124 -355.113844) (xy 334.265524 -355.113844) (xy 334.238251 -355.113418)
			(xy 334.184259 -355.105658) (xy 334.131921 -355.090293) (xy 334.082302 -355.067636) (xy 334.036413 -355.038148)
			(xy 333.995188 -355.002429) (xy 333.959467 -354.961206) (xy 333.929975 -354.915319) (xy 333.907315 -354.865702)
			(xy 333.891947 -354.813365) (xy 333.884184 -354.759373) (xy 332.40148 -354.759373) (xy 332.393718 -354.813359)
			(xy 332.37835 -354.865692) (xy 332.355691 -354.915305) (xy 332.326202 -354.961188) (xy 332.290482 -355.002407)
			(xy 332.24926 -355.038123) (xy 332.203374 -355.067609) (xy 332.153758 -355.090263) (xy 332.101424 -355.105625)
			(xy 332.047435 -355.113383) (xy 332.020164 -355.113844) (xy 331.156564 -355.113844) (xy 331.129295 -355.113391)
			(xy 331.075313 -355.105625) (xy 331.022985 -355.090256) (xy 330.973377 -355.067596) (xy 330.927499 -355.038108)
			(xy 330.886283 -355.002391) (xy 330.85057 -354.961173) (xy 330.821086 -354.915291) (xy 330.798432 -354.865681)
			(xy 330.783067 -354.813352) (xy 330.775306 -354.759369) (xy 329.292458 -354.759369) (xy 329.284696 -354.813349)
			(xy 329.269332 -354.865675) (xy 329.246677 -354.915283) (xy 329.217193 -354.961161) (xy 329.18148 -355.002377)
			(xy 329.140265 -355.038091) (xy 329.094386 -355.067575) (xy 329.044779 -355.090231) (xy 328.992453 -355.105596)
			(xy 328.938472 -355.113357) (xy 328.911204 -355.113844) (xy 328.047604 -355.113844) (xy 328.020332 -355.113417)
			(xy 327.966342 -355.105655) (xy 327.914006 -355.090288) (xy 327.86439 -355.06763) (xy 327.818504 -355.038141)
			(xy 327.777281 -355.002422) (xy 327.741562 -354.961199) (xy 327.712072 -354.915313) (xy 327.689413 -354.865698)
			(xy 327.674046 -354.813362) (xy 327.666284 -354.759372) (xy 326.183457 -354.759372) (xy 326.175698 -354.813343)
			(xy 326.160335 -354.865667) (xy 326.137683 -354.915272) (xy 326.108203 -354.961148) (xy 326.072494 -355.002363)
			(xy 326.031284 -355.038076) (xy 325.98541 -355.067562) (xy 325.935808 -355.09022) (xy 325.883486 -355.105588)
			(xy 325.82951 -355.113355) (xy 325.802244 -355.113844) (xy 324.938644 -355.113844) (xy 324.91137 -355.113419)
			(xy 324.857375 -355.105662) (xy 324.805035 -355.090299) (xy 324.755414 -355.067643) (xy 324.709523 -355.038155)
			(xy 324.668295 -355.002436) (xy 324.632571 -354.961213) (xy 324.603078 -354.915325) (xy 324.580417 -354.865706)
			(xy 324.565047 -354.813368) (xy 324.557284 -354.759374) (xy 323.07458 -354.759374) (xy 323.066818 -354.813356)
			(xy 323.051452 -354.865688) (xy 323.028794 -354.9153) (xy 322.999307 -354.961182) (xy 322.963589 -355.0024)
			(xy 322.922369 -355.038116) (xy 322.876485 -355.067602) (xy 322.826873 -355.090258) (xy 322.774541 -355.105622)
			(xy 322.720554 -355.113382) (xy 322.693284 -355.113844) (xy 321.829684 -355.113844) (xy 321.802414 -355.113392)
			(xy 321.74843 -355.105629) (xy 321.6961 -355.090261) (xy 321.646489 -355.067603) (xy 321.600608 -355.038115)
			(xy 321.55939 -355.002398) (xy 321.523675 -354.961179) (xy 321.494189 -354.915297) (xy 321.471533 -354.865685)
			(xy 321.456168 -354.813355) (xy 321.448406 -354.75937) (xy 319.965558 -354.75937) (xy 319.957797 -354.813346)
			(xy 319.942434 -354.865671) (xy 319.91978 -354.915277) (xy 319.890298 -354.961155) (xy 319.854587 -355.00237)
			(xy 319.813374 -355.038084) (xy 319.767498 -355.067569) (xy 319.717894 -355.090225) (xy 319.665569 -355.105592)
			(xy 319.611591 -355.113356) (xy 319.584324 -355.113844) (xy 318.720724 -355.113844) (xy 318.693451 -355.113418)
			(xy 318.639459 -355.105658) (xy 318.587121 -355.090293) (xy 318.537502 -355.067636) (xy 318.491613 -355.038148)
			(xy 318.450388 -355.002429) (xy 318.414667 -354.961206) (xy 318.385175 -354.915319) (xy 318.362515 -354.865702)
			(xy 318.347147 -354.813365) (xy 318.339384 -354.759373) (xy 316.85668 -354.759373) (xy 316.848918 -354.813359)
			(xy 316.83355 -354.865692) (xy 316.810891 -354.915305) (xy 316.781402 -354.961188) (xy 316.745682 -355.002407)
			(xy 316.70446 -355.038123) (xy 316.658574 -355.067609) (xy 316.608958 -355.090263) (xy 316.556624 -355.105625)
			(xy 316.502635 -355.113383) (xy 316.475364 -355.113844) (xy 315.611764 -355.113844) (xy 315.584495 -355.113391)
			(xy 315.530513 -355.105625) (xy 315.478185 -355.090256) (xy 315.428577 -355.067596) (xy 315.382699 -355.038108)
			(xy 315.341483 -355.002391) (xy 315.30577 -354.961173) (xy 315.276286 -354.915291) (xy 315.253632 -354.865681)
			(xy 315.238267 -354.813352) (xy 315.230506 -354.759369) (xy 300.231558 -354.759369) (xy 300.223796 -354.813349)
			(xy 300.208432 -354.865676) (xy 300.185777 -354.915283) (xy 300.156293 -354.961162) (xy 300.120579 -355.002378)
			(xy 300.079364 -355.038091) (xy 300.033485 -355.067576) (xy 299.983878 -355.090231) (xy 299.931551 -355.105596)
			(xy 299.87757 -355.113357) (xy 299.850302 -355.113844) (xy 298.986702 -355.113844) (xy 298.95943 -355.113417)
			(xy 298.90544 -355.105654) (xy 298.853105 -355.090288) (xy 298.803489 -355.067629) (xy 298.757603 -355.03814)
			(xy 298.716381 -355.002421) (xy 298.680661 -354.961199) (xy 298.651172 -354.915313) (xy 298.628513 -354.865697)
			(xy 298.613146 -354.813362) (xy 298.605384 -354.759372) (xy 297.122557 -354.759372) (xy 297.114798 -354.813344)
			(xy 297.099435 -354.865667) (xy 297.076783 -354.915272) (xy 297.047302 -354.961149) (xy 297.011593 -355.002364)
			(xy 296.970383 -355.038077) (xy 296.924509 -355.067563) (xy 296.874907 -355.09022) (xy 296.822585 -355.105589)
			(xy 296.768608 -355.113355) (xy 296.741342 -355.113844) (xy 295.877742 -355.113844) (xy 295.850468 -355.113419)
			(xy 295.796474 -355.105662) (xy 295.744134 -355.090298) (xy 295.694513 -355.067642) (xy 295.648622 -355.038154)
			(xy 295.607395 -355.002435) (xy 295.571671 -354.961212) (xy 295.542178 -354.915324) (xy 295.519516 -354.865706)
			(xy 295.504147 -354.813367) (xy 295.496384 -354.759374) (xy 294.013681 -354.759374) (xy 294.005918 -354.813356)
			(xy 293.990552 -354.865688) (xy 293.967894 -354.9153) (xy 293.938406 -354.961182) (xy 293.902688 -355.002401)
			(xy 293.861468 -355.038117) (xy 293.815584 -355.067603) (xy 293.765971 -355.090258) (xy 293.713639 -355.105622)
			(xy 293.659653 -355.113382) (xy 293.632382 -355.113844) (xy 292.768782 -355.113844) (xy 292.741512 -355.113392)
			(xy 292.687528 -355.105628) (xy 292.635198 -355.090261) (xy 292.585588 -355.067602) (xy 292.539707 -355.038115)
			(xy 292.49849 -355.002398) (xy 292.462775 -354.961178) (xy 292.433289 -354.915296) (xy 292.410633 -354.865685)
			(xy 292.395268 -354.813354) (xy 292.387506 -354.75937) (xy 290.904658 -354.75937) (xy 290.896897 -354.813346)
			(xy 290.881533 -354.865672) (xy 290.85888 -354.915278) (xy 290.829397 -354.961156) (xy 290.793686 -355.002371)
			(xy 290.752473 -355.038084) (xy 290.706597 -355.067569) (xy 290.656992 -355.090226) (xy 290.604668 -355.105592)
			(xy 290.550689 -355.113356) (xy 290.523422 -355.113844) (xy 289.659822 -355.113844) (xy 289.632549 -355.113418)
			(xy 289.578557 -355.105658) (xy 289.526219 -355.090293) (xy 289.476601 -355.067636) (xy 289.430712 -355.038147)
			(xy 289.389488 -355.002428) (xy 289.353766 -354.961205) (xy 289.324275 -354.915318) (xy 289.301615 -354.865702)
			(xy 289.286247 -354.813365) (xy 289.278484 -354.759373) (xy 287.79578 -354.759373) (xy 287.788018 -354.813359)
			(xy 287.77265 -354.865692) (xy 287.749991 -354.915306) (xy 287.720501 -354.961189) (xy 287.684781 -355.002408)
			(xy 287.643559 -355.038124) (xy 287.597672 -355.067609) (xy 287.548057 -355.090264) (xy 287.495722 -355.105626)
			(xy 287.441733 -355.113383) (xy 287.414462 -355.113844) (xy 286.550862 -355.113844) (xy 286.523593 -355.113391)
			(xy 286.469611 -355.105625) (xy 286.417284 -355.090255) (xy 286.367676 -355.067596) (xy 286.321798 -355.038107)
			(xy 286.280583 -355.00239) (xy 286.24487 -354.961172) (xy 286.215386 -354.915291) (xy 286.192732 -354.865681)
			(xy 286.177367 -354.813352) (xy 286.169606 -354.759369) (xy 284.686758 -354.759369) (xy 284.678996 -354.813349)
			(xy 284.663632 -354.865676) (xy 284.640977 -354.915283) (xy 284.611493 -354.961162) (xy 284.575779 -355.002378)
			(xy 284.534564 -355.038091) (xy 284.488685 -355.067576) (xy 284.439078 -355.090231) (xy 284.386751 -355.105596)
			(xy 284.33277 -355.113357) (xy 284.305502 -355.113844) (xy 283.441902 -355.113844) (xy 283.41463 -355.113417)
			(xy 283.36064 -355.105654) (xy 283.308305 -355.090288) (xy 283.258689 -355.067629) (xy 283.212803 -355.03814)
			(xy 283.171581 -355.002421) (xy 283.135861 -354.961199) (xy 283.106372 -354.915313) (xy 283.083713 -354.865697)
			(xy 283.068346 -354.813362) (xy 283.060584 -354.759372) (xy 281.577757 -354.759372) (xy 281.569998 -354.813344)
			(xy 281.554635 -354.865667) (xy 281.531983 -354.915272) (xy 281.502502 -354.961149) (xy 281.466793 -355.002364)
			(xy 281.425583 -355.038077) (xy 281.379709 -355.067563) (xy 281.330107 -355.09022) (xy 281.277785 -355.105589)
			(xy 281.223808 -355.113355) (xy 281.196542 -355.113844) (xy 280.332942 -355.113844) (xy 280.305668 -355.113419)
			(xy 280.251674 -355.105662) (xy 280.199334 -355.090298) (xy 280.149713 -355.067642) (xy 280.103822 -355.038154)
			(xy 280.062595 -355.002435) (xy 280.026871 -354.961212) (xy 279.997378 -354.915324) (xy 279.974716 -354.865706)
			(xy 279.959347 -354.813367) (xy 279.951584 -354.759374) (xy 278.468881 -354.759374) (xy 278.461118 -354.813356)
			(xy 278.445752 -354.865688) (xy 278.423094 -354.9153) (xy 278.393606 -354.961182) (xy 278.357888 -355.002401)
			(xy 278.316668 -355.038117) (xy 278.270784 -355.067603) (xy 278.221171 -355.090258) (xy 278.168839 -355.105622)
			(xy 278.114853 -355.113382) (xy 278.087582 -355.113844) (xy 277.223982 -355.113844) (xy 277.196712 -355.113392)
			(xy 277.142728 -355.105628) (xy 277.090398 -355.090261) (xy 277.040788 -355.067602) (xy 276.994907 -355.038115)
			(xy 276.95369 -355.002398) (xy 276.917975 -354.961178) (xy 276.888489 -354.915296) (xy 276.865833 -354.865685)
			(xy 276.850468 -354.813354) (xy 276.842706 -354.75937) (xy 275.359858 -354.75937) (xy 275.352097 -354.813346)
			(xy 275.336733 -354.865672) (xy 275.31408 -354.915278) (xy 275.284597 -354.961156) (xy 275.248886 -355.002371)
			(xy 275.207673 -355.038084) (xy 275.161797 -355.067569) (xy 275.112192 -355.090226) (xy 275.059868 -355.105592)
			(xy 275.005889 -355.113356) (xy 274.978622 -355.113844) (xy 274.115022 -355.113844) (xy 274.087749 -355.113418)
			(xy 274.033757 -355.105658) (xy 273.981419 -355.090293) (xy 273.931801 -355.067636) (xy 273.885912 -355.038147)
			(xy 273.844688 -355.002428) (xy 273.808966 -354.961205) (xy 273.779475 -354.915318) (xy 273.756815 -354.865702)
			(xy 273.741447 -354.813365) (xy 273.733684 -354.759373) (xy 272.25098 -354.759373) (xy 272.243218 -354.813359)
			(xy 272.22785 -354.865692) (xy 272.205191 -354.915306) (xy 272.175701 -354.961189) (xy 272.139981 -355.002408)
			(xy 272.098759 -355.038124) (xy 272.052872 -355.067609) (xy 272.003257 -355.090264) (xy 271.950922 -355.105626)
			(xy 271.896933 -355.113383) (xy 271.869662 -355.113844) (xy 271.006062 -355.113844) (xy 270.978793 -355.113391)
			(xy 270.924811 -355.105625) (xy 270.872484 -355.090255) (xy 270.822876 -355.067596) (xy 270.776998 -355.038107)
			(xy 270.735783 -355.00239) (xy 270.70007 -354.961172) (xy 270.670586 -354.915291) (xy 270.647932 -354.865681)
			(xy 270.632567 -354.813352) (xy 270.624806 -354.759369) (xy 188.299268 -354.759369) (xy 188.294942 -354.78946)
			(xy 188.279575 -354.841794) (xy 188.256917 -354.891409) (xy 188.227428 -354.937294) (xy 188.191709 -354.978515)
			(xy 188.150487 -355.014233) (xy 188.104602 -355.04372) (xy 188.054987 -355.066378) (xy 188.002652 -355.081744)
			(xy 187.948664 -355.089505) (xy 187.921392 -355.089968) (xy 187.057792 -355.089968) (xy 187.030523 -355.089469)
			(xy 186.976542 -355.081707) (xy 186.924214 -355.066341) (xy 186.874605 -355.043684) (xy 186.828726 -355.014199)
			(xy 186.78751 -354.978484) (xy 186.751796 -354.937267) (xy 186.722312 -354.891388) (xy 186.699656 -354.841779)
			(xy 186.684292 -354.789451) (xy 186.67653 -354.735469) (xy 185.193682 -354.735469) (xy 185.185921 -354.78945)
			(xy 185.170557 -354.841778) (xy 185.147903 -354.891387) (xy 185.118419 -354.937267) (xy 185.082707 -354.978484)
			(xy 185.041492 -355.0142) (xy 184.995615 -355.043687) (xy 184.946008 -355.066346) (xy 184.893681 -355.081714)
			(xy 184.8397 -355.089479) (xy 184.812432 -355.089968) (xy 183.948832 -355.089968) (xy 183.92156 -355.089495)
			(xy 183.86757 -355.081736) (xy 183.815235 -355.066373) (xy 183.765618 -355.043718) (xy 183.719731 -355.014231)
			(xy 183.678508 -354.978515) (xy 183.642788 -354.937294) (xy 183.613298 -354.89141) (xy 183.590638 -354.841795)
			(xy 183.57527 -354.789461) (xy 183.567508 -354.735472) (xy 182.08478 -354.735472) (xy 182.08478 -354.759371)
			(xy 182.077018 -354.813358) (xy 182.061651 -354.86569) (xy 182.038992 -354.915303) (xy 182.009504 -354.961186)
			(xy 181.973785 -355.002405) (xy 181.932563 -355.03812) (xy 181.886678 -355.067606) (xy 181.837064 -355.090261)
			(xy 181.78473 -355.105624) (xy 181.730743 -355.113382) (xy 181.703472 -355.113844) (xy 180.839872 -355.113844)
			(xy 180.812603 -355.113392) (xy 180.75862 -355.105626) (xy 180.706291 -355.090258) (xy 180.656682 -355.067599)
			(xy 180.610802 -355.038111) (xy 180.569586 -355.002394) (xy 180.533872 -354.961175) (xy 180.504388 -354.915293)
			(xy 180.481732 -354.865683) (xy 180.466368 -354.813353) (xy 180.458606 -354.759369) (xy 178.975758 -354.759369)
			(xy 178.967997 -354.813348) (xy 178.952633 -354.865674) (xy 178.929978 -354.915281) (xy 178.900495 -354.961159)
			(xy 178.864783 -355.002374) (xy 178.823568 -355.038088) (xy 178.777691 -355.067573) (xy 178.728085 -355.090228)
			(xy 178.675759 -355.105594) (xy 178.62178 -355.113357) (xy 178.594512 -355.113844) (xy 177.730912 -355.113844)
			(xy 177.703639 -355.113417) (xy 177.649648 -355.105656) (xy 177.597312 -355.09029) (xy 177.547695 -355.067632)
			(xy 177.501808 -355.038144) (xy 177.460584 -355.002424) (xy 177.424864 -354.961202) (xy 177.395373 -354.915316)
			(xy 177.372714 -354.865699) (xy 177.357346 -354.813363) (xy 177.349584 -354.759373) (xy 175.86688 -354.759373)
			(xy 175.859117 -354.81336) (xy 175.843749 -354.865694) (xy 175.821089 -354.915309) (xy 175.791599 -354.961192)
			(xy 175.755878 -355.002412) (xy 175.714654 -355.038128) (xy 175.668766 -355.067612) (xy 175.619149 -355.090266)
			(xy 175.566813 -355.105628) (xy 175.512824 -355.113384) (xy 175.485552 -355.113844) (xy 174.621952 -355.113844)
			(xy 174.594684 -355.11339) (xy 174.540703 -355.105623) (xy 174.488376 -355.090252) (xy 174.43877 -355.067592)
			(xy 174.392893 -355.038104) (xy 174.351679 -355.002387) (xy 174.315967 -354.961169) (xy 174.286485 -354.915288)
			(xy 174.263831 -354.865679) (xy 174.248467 -354.81335) (xy 174.240706 -354.759368) (xy 172.757881 -354.759368)
			(xy 172.757881 -354.75937) (xy 172.750119 -354.813355) (xy 172.734753 -354.865686) (xy 172.712096 -354.915297)
			(xy 172.682609 -354.961179) (xy 172.646892 -355.002398) (xy 172.605673 -355.038113) (xy 172.55979 -355.067599)
			(xy 172.510178 -355.090255) (xy 172.457847 -355.10562) (xy 172.403862 -355.113381) (xy 172.376592 -355.113844)
			(xy 171.512992 -355.113844) (xy 171.485722 -355.113393) (xy 171.431736 -355.10563) (xy 171.379405 -355.090263)
			(xy 171.329794 -355.067606) (xy 171.283912 -355.038118) (xy 171.242693 -355.002401) (xy 171.206977 -354.961182)
			(xy 171.177491 -354.915299) (xy 171.154834 -354.865687) (xy 171.139468 -354.813356) (xy 171.131706 -354.75937)
			(xy 169.648858 -354.75937) (xy 169.641097 -354.813345) (xy 169.625734 -354.865669) (xy 169.603081 -354.915275)
			(xy 169.5736 -354.961152) (xy 169.53789 -355.002367) (xy 169.496678 -355.038081) (xy 169.450803 -355.067566)
			(xy 169.401199 -355.090223) (xy 169.348876 -355.10559) (xy 169.294899 -355.113355) (xy 169.267632 -355.113844)
			(xy 168.404032 -355.113844) (xy 168.376758 -355.113419) (xy 168.322765 -355.10566) (xy 168.270426 -355.090296)
			(xy 168.220807 -355.067639) (xy 168.174917 -355.038151) (xy 168.133691 -355.002432) (xy 168.097969 -354.961209)
			(xy 168.068477 -354.915321) (xy 168.045816 -354.865704) (xy 168.030447 -354.813366) (xy 168.022684 -354.759374)
			(xy 166.53998 -354.759374) (xy 166.532218 -354.813358) (xy 166.516851 -354.86569) (xy 166.494192 -354.915303)
			(xy 166.464704 -354.961186) (xy 166.428985 -355.002405) (xy 166.387763 -355.03812) (xy 166.341878 -355.067606)
			(xy 166.292264 -355.090261) (xy 166.23993 -355.105624) (xy 166.185943 -355.113382) (xy 166.158672 -355.113844)
			(xy 165.295072 -355.113844) (xy 165.267803 -355.113392) (xy 165.21382 -355.105626) (xy 165.161491 -355.090258)
			(xy 165.111882 -355.067599) (xy 165.066002 -355.038111) (xy 165.024786 -355.002394) (xy 164.989072 -354.961175)
			(xy 164.959588 -354.915293) (xy 164.936932 -354.865683) (xy 164.921568 -354.813353) (xy 164.913806 -354.759369)
			(xy 163.430958 -354.759369) (xy 163.423197 -354.813348) (xy 163.407833 -354.865674) (xy 163.385178 -354.915281)
			(xy 163.355695 -354.961159) (xy 163.319983 -355.002374) (xy 163.278768 -355.038088) (xy 163.232891 -355.067573)
			(xy 163.183285 -355.090228) (xy 163.130959 -355.105594) (xy 163.07698 -355.113357) (xy 163.049712 -355.113844)
			(xy 162.186112 -355.113844) (xy 162.158839 -355.113417) (xy 162.104848 -355.105656) (xy 162.052512 -355.09029)
			(xy 162.002895 -355.067632) (xy 161.957008 -355.038144) (xy 161.915784 -355.002424) (xy 161.880064 -354.961202)
			(xy 161.850573 -354.915316) (xy 161.827914 -354.865699) (xy 161.812546 -354.813363) (xy 161.804784 -354.759373)
			(xy 160.32208 -354.759373) (xy 160.314317 -354.81336) (xy 160.298949 -354.865694) (xy 160.276289 -354.915309)
			(xy 160.246799 -354.961192) (xy 160.211078 -355.002412) (xy 160.169854 -355.038128) (xy 160.123966 -355.067612)
			(xy 160.074349 -355.090266) (xy 160.022013 -355.105628) (xy 159.968024 -355.113384) (xy 159.940752 -355.113844)
			(xy 159.077152 -355.113844) (xy 159.049884 -355.11339) (xy 158.995903 -355.105623) (xy 158.943576 -355.090252)
			(xy 158.89397 -355.067592) (xy 158.848093 -355.038104) (xy 158.806879 -355.002387) (xy 158.771167 -354.961169)
			(xy 158.741685 -354.915288) (xy 158.719031 -354.865679) (xy 158.703667 -354.81335) (xy 158.695906 -354.759368)
			(xy 144.196558 -354.759368) (xy 144.188797 -354.813348) (xy 144.173432 -354.865675) (xy 144.150778 -354.915282)
			(xy 144.121294 -354.96116) (xy 144.085581 -355.002376) (xy 144.044367 -355.038089) (xy 143.998489 -355.067574)
			(xy 143.948882 -355.09023) (xy 143.896556 -355.105595) (xy 143.842576 -355.113357) (xy 143.815308 -355.113844)
			(xy 142.951708 -355.113844) (xy 142.924435 -355.113417) (xy 142.870445 -355.105655) (xy 142.818109 -355.090289)
			(xy 142.768492 -355.067631) (xy 142.722606 -355.038142) (xy 142.681383 -355.002423) (xy 142.645663 -354.961201)
			(xy 142.616173 -354.915315) (xy 142.593514 -354.865699) (xy 142.578146 -354.813363) (xy 142.570384 -354.759373)
			(xy 141.087557 -354.759373) (xy 141.079798 -354.813343) (xy 141.064436 -354.865666) (xy 141.041784 -354.915271)
			(xy 141.012304 -354.961147) (xy 140.976595 -355.002361) (xy 140.935386 -355.038075) (xy 140.889513 -355.067561)
			(xy 140.839911 -355.090219) (xy 140.78759 -355.105587) (xy 140.733614 -355.113354) (xy 140.706348 -355.113844)
			(xy 139.842748 -355.113844) (xy 139.815473 -355.11342) (xy 139.761479 -355.105663) (xy 139.709138 -355.0903)
			(xy 139.659516 -355.067644) (xy 139.613625 -355.038156) (xy 139.572397 -355.002437) (xy 139.536672 -354.961214)
			(xy 139.507179 -354.915326) (xy 139.484517 -354.865707) (xy 139.469147 -354.813368) (xy 139.461384 -354.759374)
			(xy 137.97868 -354.759374) (xy 137.970918 -354.813356) (xy 137.955552 -354.865687) (xy 137.932895 -354.915298)
			(xy 137.903408 -354.961181) (xy 137.867691 -355.002399) (xy 137.826471 -355.038115) (xy 137.780588 -355.067601)
			(xy 137.730976 -355.090256) (xy 137.678644 -355.105621) (xy 137.624658 -355.113381) (xy 137.597388 -355.113844)
			(xy 136.733788 -355.113844) (xy 136.706518 -355.113393) (xy 136.652533 -355.105629) (xy 136.600203 -355.090262)
			(xy 136.550591 -355.067604) (xy 136.50471 -355.038117) (xy 136.463492 -355.0024) (xy 136.427776 -354.96118)
			(xy 136.39829 -354.915298) (xy 136.375634 -354.865686) (xy 136.360268 -354.813355) (xy 136.352506 -354.75937)
			(xy 134.869658 -354.75937) (xy 134.861897 -354.813345) (xy 134.846534 -354.86567) (xy 134.823881 -354.915276)
			(xy 134.794399 -354.961154) (xy 134.758688 -355.002369) (xy 134.717476 -355.038082) (xy 134.671601 -355.067567)
			(xy 134.621997 -355.090224) (xy 134.569673 -355.105591) (xy 134.515695 -355.113356) (xy 134.488428 -355.113844)
			(xy 133.624828 -355.113844) (xy 133.597554 -355.113418) (xy 133.543562 -355.105659) (xy 133.491223 -355.090295)
			(xy 133.441604 -355.067638) (xy 133.395715 -355.038149) (xy 133.35449 -355.00243) (xy 133.318768 -354.961207)
			(xy 133.289276 -354.91532) (xy 133.266615 -354.865703) (xy 133.251247 -354.813365) (xy 133.243484 -354.759374)
			(xy 131.76078 -354.759374) (xy 131.753018 -354.813358) (xy 131.737651 -354.865691) (xy 131.714992 -354.915304)
			(xy 131.685503 -354.961187) (xy 131.649783 -355.002406) (xy 131.608561 -355.038122) (xy 131.562676 -355.067607)
			(xy 131.513061 -355.090262) (xy 131.460727 -355.105625) (xy 131.406739 -355.113383) (xy 131.379468 -355.113844)
			(xy 130.515868 -355.113844) (xy 130.488599 -355.113391) (xy 130.434616 -355.105626) (xy 130.382288 -355.090257)
			(xy 130.33268 -355.067598) (xy 130.2868 -355.03811) (xy 130.245585 -355.002393) (xy 130.209871 -354.961174)
			(xy 130.180387 -354.915292) (xy 130.157732 -354.865682) (xy 130.142368 -354.813353) (xy 130.134606 -354.759369)
			(xy 128.651758 -354.759369) (xy 128.643997 -354.813348) (xy 128.628632 -354.865675) (xy 128.605978 -354.915282)
			(xy 128.576494 -354.96116) (xy 128.540781 -355.002376) (xy 128.499567 -355.038089) (xy 128.453689 -355.067574)
			(xy 128.404082 -355.09023) (xy 128.351756 -355.105595) (xy 128.297776 -355.113357) (xy 128.270508 -355.113844)
			(xy 127.406908 -355.113844) (xy 127.379635 -355.113417) (xy 127.325645 -355.105655) (xy 127.273309 -355.090289)
			(xy 127.223692 -355.067631) (xy 127.177806 -355.038142) (xy 127.136583 -355.002423) (xy 127.100863 -354.961201)
			(xy 127.071373 -354.915315) (xy 127.048714 -354.865699) (xy 127.033346 -354.813363) (xy 127.025584 -354.759373)
			(xy 125.542757 -354.759373) (xy 125.534998 -354.813343) (xy 125.519636 -354.865666) (xy 125.496984 -354.915271)
			(xy 125.467504 -354.961147) (xy 125.431795 -355.002361) (xy 125.390586 -355.038075) (xy 125.344713 -355.067561)
			(xy 125.295111 -355.090219) (xy 125.24279 -355.105587) (xy 125.188814 -355.113354) (xy 125.161548 -355.113844)
			(xy 124.297948 -355.113844) (xy 124.270673 -355.11342) (xy 124.216679 -355.105663) (xy 124.164338 -355.0903)
			(xy 124.114716 -355.067644) (xy 124.068825 -355.038156) (xy 124.027597 -355.002437) (xy 123.991872 -354.961214)
			(xy 123.962379 -354.915326) (xy 123.939717 -354.865707) (xy 123.924347 -354.813368) (xy 123.916584 -354.759374)
			(xy 122.43388 -354.759374) (xy 122.426118 -354.813356) (xy 122.410752 -354.865687) (xy 122.388095 -354.915298)
			(xy 122.358608 -354.961181) (xy 122.322891 -355.002399) (xy 122.281671 -355.038115) (xy 122.235788 -355.067601)
			(xy 122.186176 -355.090256) (xy 122.133844 -355.105621) (xy 122.079858 -355.113381) (xy 122.052588 -355.113844)
			(xy 121.188988 -355.113844) (xy 121.161718 -355.113393) (xy 121.107733 -355.105629) (xy 121.055403 -355.090262)
			(xy 121.005791 -355.067604) (xy 120.95991 -355.038117) (xy 120.918692 -355.0024) (xy 120.882976 -354.96118)
			(xy 120.85349 -354.915298) (xy 120.830834 -354.865686) (xy 120.815468 -354.813355) (xy 120.807706 -354.75937)
			(xy 119.324858 -354.75937) (xy 119.317097 -354.813345) (xy 119.301734 -354.86567) (xy 119.279081 -354.915276)
			(xy 119.249599 -354.961154) (xy 119.213888 -355.002369) (xy 119.172676 -355.038082) (xy 119.126801 -355.067567)
			(xy 119.077197 -355.090224) (xy 119.024873 -355.105591) (xy 118.970895 -355.113356) (xy 118.943628 -355.113844)
			(xy 118.080028 -355.113844) (xy 118.052754 -355.113418) (xy 117.998762 -355.105659) (xy 117.946423 -355.090295)
			(xy 117.896804 -355.067638) (xy 117.850915 -355.038149) (xy 117.80969 -355.00243) (xy 117.773968 -354.961207)
			(xy 117.744476 -354.91532) (xy 117.721815 -354.865703) (xy 117.706447 -354.813365) (xy 117.698684 -354.759374)
			(xy 116.21598 -354.759374) (xy 116.208218 -354.813358) (xy 116.192851 -354.865691) (xy 116.170192 -354.915304)
			(xy 116.140703 -354.961187) (xy 116.104983 -355.002406) (xy 116.063761 -355.038122) (xy 116.017876 -355.067607)
			(xy 115.968261 -355.090262) (xy 115.915927 -355.105625) (xy 115.861939 -355.113383) (xy 115.834668 -355.113844)
			(xy 114.971068 -355.113844) (xy 114.943799 -355.113391) (xy 114.889816 -355.105626) (xy 114.837488 -355.090257)
			(xy 114.78788 -355.067598) (xy 114.742 -355.03811) (xy 114.700785 -355.002393) (xy 114.665071 -354.961174)
			(xy 114.635587 -354.915292) (xy 114.612932 -354.865682) (xy 114.597568 -354.813353) (xy 114.589806 -354.759369)
			(xy 93.706658 -354.759369) (xy 93.698898 -354.813344) (xy 93.683535 -354.865667) (xy 93.660883 -354.915272)
			(xy 93.631402 -354.961149) (xy 93.595693 -355.002364) (xy 93.554483 -355.038077) (xy 93.508609 -355.067563)
			(xy 93.459007 -355.09022) (xy 93.406685 -355.105589) (xy 93.352708 -355.113355) (xy 93.325442 -355.113844)
			(xy 92.461842 -355.113844) (xy 92.434568 -355.113419) (xy 92.380574 -355.105662) (xy 92.328234 -355.090298)
			(xy 92.278613 -355.067642) (xy 92.232722 -355.038154) (xy 92.191495 -355.002435) (xy 92.155771 -354.961212)
			(xy 92.126278 -354.915324) (xy 92.103616 -354.865706) (xy 92.088247 -354.813367) (xy 92.080484 -354.759374)
			(xy 90.597781 -354.759374) (xy 90.590018 -354.813356) (xy 90.574652 -354.865688) (xy 90.551994 -354.9153)
			(xy 90.522506 -354.961182) (xy 90.486788 -355.002401) (xy 90.445568 -355.038117) (xy 90.399684 -355.067603)
			(xy 90.350071 -355.090258) (xy 90.297739 -355.105622) (xy 90.243753 -355.113382) (xy 90.216482 -355.113844)
			(xy 89.352882 -355.113844) (xy 89.325612 -355.113392) (xy 89.271628 -355.105628) (xy 89.219298 -355.090261)
			(xy 89.169688 -355.067602) (xy 89.123807 -355.038115) (xy 89.08259 -355.002398) (xy 89.046875 -354.961178)
			(xy 89.017389 -354.915296) (xy 88.994733 -354.865685) (xy 88.979368 -354.813354) (xy 88.971606 -354.75937)
			(xy 87.488758 -354.75937) (xy 87.480997 -354.813346) (xy 87.465633 -354.865672) (xy 87.44298 -354.915278)
			(xy 87.413497 -354.961156) (xy 87.377786 -355.002371) (xy 87.336573 -355.038084) (xy 87.290697 -355.067569)
			(xy 87.241092 -355.090226) (xy 87.188768 -355.105592) (xy 87.134789 -355.113356) (xy 87.107522 -355.113844)
			(xy 86.243922 -355.113844) (xy 86.216649 -355.113418) (xy 86.162657 -355.105658) (xy 86.110319 -355.090293)
			(xy 86.060701 -355.067636) (xy 86.014812 -355.038147) (xy 85.973588 -355.002428) (xy 85.937866 -354.961205)
			(xy 85.908375 -354.915318) (xy 85.885715 -354.865702) (xy 85.870347 -354.813365) (xy 85.862584 -354.759373)
			(xy 84.37988 -354.759373) (xy 84.372118 -354.813359) (xy 84.35675 -354.865692) (xy 84.334091 -354.915306)
			(xy 84.304601 -354.961189) (xy 84.268881 -355.002408) (xy 84.227659 -355.038124) (xy 84.181772 -355.067609)
			(xy 84.132157 -355.090264) (xy 84.079822 -355.105626) (xy 84.025833 -355.113383) (xy 83.998562 -355.113844)
			(xy 83.134962 -355.113844) (xy 83.107693 -355.113391) (xy 83.053711 -355.105625) (xy 83.001384 -355.090255)
			(xy 82.951776 -355.067596) (xy 82.905898 -355.038107) (xy 82.864683 -355.00239) (xy 82.82897 -354.961172)
			(xy 82.799486 -354.915291) (xy 82.776832 -354.865681) (xy 82.761467 -354.813352) (xy 82.753706 -354.759369)
			(xy 81.270858 -354.759369) (xy 81.263096 -354.813349) (xy 81.247732 -354.865676) (xy 81.225077 -354.915283)
			(xy 81.195593 -354.961162) (xy 81.159879 -355.002378) (xy 81.118664 -355.038091) (xy 81.072785 -355.067576)
			(xy 81.023178 -355.090231) (xy 80.970851 -355.105596) (xy 80.91687 -355.113357) (xy 80.889602 -355.113844)
			(xy 80.026002 -355.113844) (xy 79.99873 -355.113417) (xy 79.94474 -355.105654) (xy 79.892405 -355.090288)
			(xy 79.842789 -355.067629) (xy 79.796903 -355.03814) (xy 79.755681 -355.002421) (xy 79.719961 -354.961199)
			(xy 79.690472 -354.915313) (xy 79.667813 -354.865697) (xy 79.652446 -354.813362) (xy 79.644684 -354.759372)
			(xy 78.161857 -354.759372) (xy 78.154098 -354.813344) (xy 78.138735 -354.865667) (xy 78.116083 -354.915272)
			(xy 78.086602 -354.961149) (xy 78.050893 -355.002364) (xy 78.009683 -355.038077) (xy 77.963809 -355.067563)
			(xy 77.914207 -355.09022) (xy 77.861885 -355.105589) (xy 77.807908 -355.113355) (xy 77.780642 -355.113844)
			(xy 76.917042 -355.113844) (xy 76.889768 -355.113419) (xy 76.835774 -355.105662) (xy 76.783434 -355.090298)
			(xy 76.733813 -355.067642) (xy 76.687922 -355.038154) (xy 76.646695 -355.002435) (xy 76.610971 -354.961212)
			(xy 76.581478 -354.915324) (xy 76.558816 -354.865706) (xy 76.543447 -354.813367) (xy 76.535684 -354.759374)
			(xy 75.052981 -354.759374) (xy 75.045218 -354.813356) (xy 75.029852 -354.865688) (xy 75.007194 -354.9153)
			(xy 74.977706 -354.961182) (xy 74.941988 -355.002401) (xy 74.900768 -355.038117) (xy 74.854884 -355.067603)
			(xy 74.805271 -355.090258) (xy 74.752939 -355.105622) (xy 74.698953 -355.113382) (xy 74.671682 -355.113844)
			(xy 73.808082 -355.113844) (xy 73.780812 -355.113392) (xy 73.726828 -355.105628) (xy 73.674498 -355.090261)
			(xy 73.624888 -355.067602) (xy 73.579007 -355.038115) (xy 73.53779 -355.002398) (xy 73.502075 -354.961178)
			(xy 73.472589 -354.915296) (xy 73.449933 -354.865685) (xy 73.434568 -354.813354) (xy 73.426806 -354.75937)
			(xy 71.943958 -354.75937) (xy 71.936197 -354.813346) (xy 71.920833 -354.865672) (xy 71.89818 -354.915278)
			(xy 71.868697 -354.961156) (xy 71.832986 -355.002371) (xy 71.791773 -355.038084) (xy 71.745897 -355.067569)
			(xy 71.696292 -355.090226) (xy 71.643968 -355.105592) (xy 71.589989 -355.113356) (xy 71.562722 -355.113844)
			(xy 70.699122 -355.113844) (xy 70.671849 -355.113418) (xy 70.617857 -355.105658) (xy 70.565519 -355.090293)
			(xy 70.515901 -355.067636) (xy 70.470012 -355.038147) (xy 70.428788 -355.002428) (xy 70.393066 -354.961205)
			(xy 70.363575 -354.915318) (xy 70.340915 -354.865702) (xy 70.325547 -354.813365) (xy 70.317784 -354.759373)
			(xy 68.83508 -354.759373) (xy 68.827318 -354.813359) (xy 68.81195 -354.865692) (xy 68.789291 -354.915306)
			(xy 68.759801 -354.961189) (xy 68.724081 -355.002408) (xy 68.682859 -355.038124) (xy 68.636972 -355.067609)
			(xy 68.587357 -355.090264) (xy 68.535022 -355.105626) (xy 68.481033 -355.113383) (xy 68.453762 -355.113844)
			(xy 67.590162 -355.113844) (xy 67.562893 -355.113391) (xy 67.508911 -355.105625) (xy 67.456584 -355.090255)
			(xy 67.406976 -355.067596) (xy 67.361098 -355.038107) (xy 67.319883 -355.00239) (xy 67.28417 -354.961172)
			(xy 67.254686 -354.915291) (xy 67.232032 -354.865681) (xy 67.216667 -354.813352) (xy 67.208906 -354.759369)
			(xy 65.726058 -354.759369) (xy 65.718296 -354.813349) (xy 65.702932 -354.865676) (xy 65.680277 -354.915283)
			(xy 65.650793 -354.961162) (xy 65.615079 -355.002378) (xy 65.573864 -355.038091) (xy 65.527985 -355.067576)
			(xy 65.478378 -355.090231) (xy 65.426051 -355.105596) (xy 65.37207 -355.113357) (xy 65.344802 -355.113844)
			(xy 64.481202 -355.113844) (xy 64.45393 -355.113417) (xy 64.39994 -355.105654) (xy 64.347605 -355.090288)
			(xy 64.297989 -355.067629) (xy 64.252103 -355.03814) (xy 64.210881 -355.002421) (xy 64.175161 -354.961199)
			(xy 64.145672 -354.915313) (xy 64.123013 -354.865697) (xy 64.107646 -354.813362) (xy 64.099884 -354.759372)
			(xy 51.666857 -354.759372) (xy 51.659098 -354.813343) (xy 51.643736 -354.865666) (xy 51.621084 -354.915271)
			(xy 51.591604 -354.961147) (xy 51.555895 -355.002361) (xy 51.514686 -355.038075) (xy 51.468813 -355.067561)
			(xy 51.419211 -355.090219) (xy 51.36689 -355.105587) (xy 51.312914 -355.113354) (xy 51.285648 -355.113844)
			(xy 50.422048 -355.113844) (xy 50.394773 -355.11342) (xy 50.340779 -355.105663) (xy 50.288438 -355.0903)
			(xy 50.238816 -355.067644) (xy 50.192925 -355.038156) (xy 50.151697 -355.002437) (xy 50.115972 -354.961214)
			(xy 50.086479 -354.915326) (xy 50.063817 -354.865707) (xy 50.048447 -354.813368) (xy 50.040684 -354.759374)
			(xy 48.55798 -354.759374) (xy 48.550218 -354.813356) (xy 48.534852 -354.865687) (xy 48.512195 -354.915298)
			(xy 48.482708 -354.961181) (xy 48.446991 -355.002399) (xy 48.405771 -355.038115) (xy 48.359888 -355.067601)
			(xy 48.310276 -355.090256) (xy 48.257944 -355.105621) (xy 48.203958 -355.113381) (xy 48.176688 -355.113844)
			(xy 47.313088 -355.113844) (xy 47.285818 -355.113393) (xy 47.231833 -355.105629) (xy 47.179503 -355.090262)
			(xy 47.129891 -355.067604) (xy 47.08401 -355.038117) (xy 47.042792 -355.0024) (xy 47.007076 -354.96118)
			(xy 46.97759 -354.915298) (xy 46.954934 -354.865686) (xy 46.939568 -354.813355) (xy 46.931806 -354.75937)
			(xy 45.448958 -354.75937) (xy 45.441197 -354.813345) (xy 45.425834 -354.86567) (xy 45.403181 -354.915276)
			(xy 45.373699 -354.961154) (xy 45.337988 -355.002369) (xy 45.296776 -355.038082) (xy 45.250901 -355.067567)
			(xy 45.201297 -355.090224) (xy 45.148973 -355.105591) (xy 45.094995 -355.113356) (xy 45.067728 -355.113844)
			(xy 44.204128 -355.113844) (xy 44.176854 -355.113418) (xy 44.122862 -355.105659) (xy 44.070523 -355.090295)
			(xy 44.020904 -355.067638) (xy 43.975015 -355.038149) (xy 43.93379 -355.00243) (xy 43.898068 -354.961207)
			(xy 43.868576 -354.91532) (xy 43.845915 -354.865703) (xy 43.830547 -354.813365) (xy 43.822784 -354.759374)
			(xy 42.34008 -354.759374) (xy 42.332318 -354.813358) (xy 42.316951 -354.865691) (xy 42.294292 -354.915304)
			(xy 42.264803 -354.961187) (xy 42.229083 -355.002406) (xy 42.187861 -355.038122) (xy 42.141976 -355.067607)
			(xy 42.092361 -355.090262) (xy 42.040027 -355.105625) (xy 41.986039 -355.113383) (xy 41.958768 -355.113844)
			(xy 41.095168 -355.113844) (xy 41.067899 -355.113391) (xy 41.013916 -355.105626) (xy 40.961588 -355.090257)
			(xy 40.91198 -355.067598) (xy 40.8661 -355.03811) (xy 40.824885 -355.002393) (xy 40.789171 -354.961174)
			(xy 40.759687 -354.915292) (xy 40.737032 -354.865682) (xy 40.721668 -354.813353) (xy 40.713906 -354.759369)
			(xy 39.231058 -354.759369) (xy 39.223297 -354.813348) (xy 39.207932 -354.865675) (xy 39.185278 -354.915282)
			(xy 39.155794 -354.96116) (xy 39.120081 -355.002376) (xy 39.078867 -355.038089) (xy 39.032989 -355.067574)
			(xy 38.983382 -355.09023) (xy 38.931056 -355.105595) (xy 38.877076 -355.113357) (xy 38.849808 -355.113844)
			(xy 37.986208 -355.113844) (xy 37.958935 -355.113417) (xy 37.904945 -355.105655) (xy 37.852609 -355.090289)
			(xy 37.802992 -355.067631) (xy 37.757106 -355.038142) (xy 37.715883 -355.002423) (xy 37.680163 -354.961201)
			(xy 37.650673 -354.915315) (xy 37.628014 -354.865699) (xy 37.612646 -354.813363) (xy 37.604884 -354.759373)
			(xy 36.122057 -354.759373) (xy 36.114298 -354.813343) (xy 36.098936 -354.865666) (xy 36.076284 -354.915271)
			(xy 36.046804 -354.961147) (xy 36.011095 -355.002361) (xy 35.969886 -355.038075) (xy 35.924013 -355.067561)
			(xy 35.874411 -355.090219) (xy 35.82209 -355.105587) (xy 35.768114 -355.113354) (xy 35.740848 -355.113844)
			(xy 34.877248 -355.113844) (xy 34.849973 -355.11342) (xy 34.795979 -355.105663) (xy 34.743638 -355.0903)
			(xy 34.694016 -355.067644) (xy 34.648125 -355.038156) (xy 34.606897 -355.002437) (xy 34.571172 -354.961214)
			(xy 34.541679 -354.915326) (xy 34.519017 -354.865707) (xy 34.503647 -354.813368) (xy 34.495884 -354.759374)
			(xy 33.01318 -354.759374) (xy 33.005418 -354.813356) (xy 32.990052 -354.865687) (xy 32.967395 -354.915298)
			(xy 32.937908 -354.961181) (xy 32.902191 -355.002399) (xy 32.860971 -355.038115) (xy 32.815088 -355.067601)
			(xy 32.765476 -355.090256) (xy 32.713144 -355.105621) (xy 32.659158 -355.113381) (xy 32.631888 -355.113844)
			(xy 31.768288 -355.113844) (xy 31.741018 -355.113393) (xy 31.687033 -355.105629) (xy 31.634703 -355.090262)
			(xy 31.585091 -355.067604) (xy 31.53921 -355.038117) (xy 31.497992 -355.0024) (xy 31.462276 -354.96118)
			(xy 31.43279 -354.915298) (xy 31.410134 -354.865686) (xy 31.394768 -354.813355) (xy 31.387006 -354.75937)
			(xy 29.904158 -354.75937) (xy 29.896397 -354.813345) (xy 29.881034 -354.86567) (xy 29.858381 -354.915276)
			(xy 29.828899 -354.961154) (xy 29.793188 -355.002369) (xy 29.751976 -355.038082) (xy 29.706101 -355.067567)
			(xy 29.656497 -355.090224) (xy 29.604173 -355.105591) (xy 29.550195 -355.113356) (xy 29.522928 -355.113844)
			(xy 28.659328 -355.113844) (xy 28.632054 -355.113418) (xy 28.578062 -355.105659) (xy 28.525723 -355.090295)
			(xy 28.476104 -355.067638) (xy 28.430215 -355.038149) (xy 28.38899 -355.00243) (xy 28.353268 -354.961207)
			(xy 28.323776 -354.91532) (xy 28.301115 -354.865703) (xy 28.285747 -354.813365) (xy 28.277984 -354.759374)
			(xy 26.79528 -354.759374) (xy 26.787518 -354.813358) (xy 26.772151 -354.865691) (xy 26.749492 -354.915304)
			(xy 26.720003 -354.961187) (xy 26.684283 -355.002406) (xy 26.643061 -355.038122) (xy 26.597176 -355.067607)
			(xy 26.547561 -355.090262) (xy 26.495227 -355.105625) (xy 26.441239 -355.113383) (xy 26.413968 -355.113844)
			(xy 25.550368 -355.113844) (xy 25.523099 -355.113391) (xy 25.469116 -355.105626) (xy 25.416788 -355.090257)
			(xy 25.36718 -355.067598) (xy 25.3213 -355.03811) (xy 25.280085 -355.002393) (xy 25.244371 -354.961174)
			(xy 25.214887 -354.915292) (xy 25.192232 -354.865682) (xy 25.176868 -354.813353) (xy 25.169106 -354.759369)
			(xy 23.686258 -354.759369) (xy 23.678497 -354.813348) (xy 23.663132 -354.865675) (xy 23.640478 -354.915282)
			(xy 23.610994 -354.96116) (xy 23.575281 -355.002376) (xy 23.534067 -355.038089) (xy 23.488189 -355.067574)
			(xy 23.438582 -355.09023) (xy 23.386256 -355.105595) (xy 23.332276 -355.113357) (xy 23.305008 -355.113844)
			(xy 22.441408 -355.113844) (xy 22.414135 -355.113417) (xy 22.360145 -355.105655) (xy 22.307809 -355.090289)
			(xy 22.258192 -355.067631) (xy 22.212306 -355.038142) (xy 22.171083 -355.002423) (xy 22.135363 -354.961201)
			(xy 22.105873 -354.915315) (xy 22.083214 -354.865699) (xy 22.067846 -354.813363) (xy 22.060084 -354.759373)
			(xy 0.509016 -354.759373) (xy 0.509016 -356.613206) (xy 22.224492 -356.613206) (xy 22.224492 -355.876606)
			(xy 22.225037 -355.866454) (xy 22.232801 -355.847694) (xy 22.24715 -355.83333) (xy 22.265903 -355.825547)
			(xy 22.276054 -355.825044) (xy 22.518878 -355.825044) (xy 22.84857 -356.041198) (xy 22.859618 -356.046673)
			(xy 22.884238 -356.04735) (xy 22.89556 -356.042468) (xy 23.21052 -355.837236) (xy 23.21687 -355.833172)
			(xy 23.217378 -355.832664) (xy 23.22957 -355.825044) (xy 23.472394 -355.825044) (xy 23.482566 -355.825469)
			(xy 23.501362 -355.833253) (xy 23.515747 -355.847638) (xy 23.523531 -355.866434) (xy 23.523956 -355.876606)
			(xy 23.523956 -356.613206) (xy 25.333452 -356.613206) (xy 25.333452 -355.876606) (xy 25.333869 -355.866433)
			(xy 25.341655 -355.847636) (xy 25.356042 -355.83325) (xy 25.374841 -355.825467) (xy 25.385014 -355.825044)
			(xy 25.627838 -355.825044) (xy 25.95753 -356.041198) (xy 25.968563 -356.046713) (xy 25.993197 -356.047364)
			(xy 26.00452 -356.042468) (xy 26.31948 -355.837236) (xy 26.32583 -355.833172) (xy 26.326338 -355.832664)
			(xy 26.33853 -355.825044) (xy 26.581354 -355.825044) (xy 26.591523 -355.825502) (xy 26.610318 -355.833273)
			(xy 26.624705 -355.847648) (xy 26.63249 -355.866437) (xy 26.632916 -355.876606) (xy 26.632916 -356.613206)
			(xy 28.442412 -356.613206) (xy 28.442412 -355.876606) (xy 28.442938 -355.866452) (xy 28.450705 -355.847688)
			(xy 28.465061 -355.833323) (xy 28.48382 -355.825544) (xy 28.493974 -355.825044) (xy 28.736798 -355.825044)
			(xy 29.06649 -356.041198) (xy 29.077533 -356.046686) (xy 29.102158 -356.047354) (xy 29.11348 -356.042468)
			(xy 29.42844 -355.837236) (xy 29.43479 -355.833172) (xy 29.435298 -355.832664) (xy 29.44749 -355.825044)
			(xy 29.690314 -355.825044) (xy 29.700473 -355.825522) (xy 29.719244 -355.833302) (xy 29.733609 -355.847673)
			(xy 29.741382 -355.866446) (xy 29.741876 -355.876606) (xy 29.741876 -356.613206) (xy 31.551372 -356.613206)
			(xy 31.551372 -355.876606) (xy 31.551769 -355.866431) (xy 31.559559 -355.847629) (xy 31.573953 -355.833243)
			(xy 31.592758 -355.825464) (xy 31.602934 -355.825044) (xy 31.845758 -355.825044) (xy 32.17545 -356.041198)
			(xy 32.186504 -356.046659) (xy 32.211118 -356.047344) (xy 32.22244 -356.042468) (xy 32.5374 -355.837236)
			(xy 32.54375 -355.833172) (xy 32.544258 -355.832664) (xy 32.55645 -355.825044) (xy 32.799274 -355.825044)
			(xy 32.809445 -355.825485) (xy 32.82824 -355.833263) (xy 32.842626 -355.847643) (xy 32.850411 -355.866436)
			(xy 32.850836 -355.876606) (xy 32.850836 -356.613206) (xy 34.660332 -356.613206) (xy 34.660332 -355.876606)
			(xy 34.660838 -355.866449) (xy 34.668609 -355.847681) (xy 34.682971 -355.833316) (xy 34.701737 -355.825541)
			(xy 34.711894 -355.825044) (xy 34.954718 -355.825044) (xy 35.28441 -356.041198) (xy 35.295448 -356.046699)
			(xy 35.320077 -356.047359) (xy 35.3314 -356.042468) (xy 35.64636 -355.837236) (xy 35.65271 -355.833172)
			(xy 35.653218 -355.832664) (xy 35.66541 -355.825044) (xy 35.908234 -355.825044) (xy 35.918395 -355.825506)
			(xy 35.937166 -355.833292) (xy 35.95153 -355.847668) (xy 35.959302 -355.866445) (xy 35.959796 -355.876606)
			(xy 35.959796 -356.613206) (xy 37.769292 -356.613206) (xy 37.769292 -355.876606) (xy 37.769837 -355.866454)
			(xy 37.777601 -355.847694) (xy 37.79195 -355.83333) (xy 37.810703 -355.825547) (xy 37.820854 -355.825044)
			(xy 38.063678 -355.825044) (xy 38.39337 -356.041198) (xy 38.404418 -356.046673) (xy 38.429038 -356.04735)
			(xy 38.44036 -356.042468) (xy 38.75532 -355.837236) (xy 38.76167 -355.833172) (xy 38.762178 -355.832664)
			(xy 38.77437 -355.825044) (xy 39.017194 -355.825044) (xy 39.027366 -355.825469) (xy 39.046162 -355.833253)
			(xy 39.060547 -355.847638) (xy 39.068331 -355.866434) (xy 39.068756 -355.876606) (xy 39.068756 -356.613206)
			(xy 40.878252 -356.613206) (xy 40.878252 -355.876606) (xy 40.878669 -355.866433) (xy 40.886455 -355.847636)
			(xy 40.900842 -355.83325) (xy 40.919641 -355.825467) (xy 40.929814 -355.825044) (xy 41.172638 -355.825044)
			(xy 41.50233 -356.041198) (xy 41.513363 -356.046713) (xy 41.537997 -356.047364) (xy 41.54932 -356.042468)
			(xy 41.86428 -355.837236) (xy 41.87063 -355.833172) (xy 41.871138 -355.832664) (xy 41.88333 -355.825044)
			(xy 42.126154 -355.825044) (xy 42.136323 -355.825502) (xy 42.155118 -355.833273) (xy 42.169505 -355.847648)
			(xy 42.17729 -355.866437) (xy 42.177716 -355.876606) (xy 42.177716 -356.613206) (xy 43.987212 -356.613206)
			(xy 43.987212 -355.876606) (xy 43.987738 -355.866452) (xy 43.995505 -355.847688) (xy 44.009861 -355.833323)
			(xy 44.02862 -355.825544) (xy 44.038774 -355.825044) (xy 44.281598 -355.825044) (xy 44.61129 -356.041198)
			(xy 44.622333 -356.046686) (xy 44.646958 -356.047354) (xy 44.65828 -356.042468) (xy 44.97324 -355.837236)
			(xy 44.97959 -355.833172) (xy 44.980098 -355.832664) (xy 44.99229 -355.825044) (xy 45.235114 -355.825044)
			(xy 45.245273 -355.825522) (xy 45.264044 -355.833302) (xy 45.278409 -355.847673) (xy 45.286182 -355.866446)
			(xy 45.286676 -355.876606) (xy 45.286676 -356.613206) (xy 47.096172 -356.613206) (xy 47.096172 -355.876606)
			(xy 47.096569 -355.866431) (xy 47.104359 -355.847629) (xy 47.118753 -355.833243) (xy 47.137558 -355.825464)
			(xy 47.147734 -355.825044) (xy 47.390558 -355.825044) (xy 47.72025 -356.041198) (xy 47.731304 -356.046659)
			(xy 47.755918 -356.047344) (xy 47.76724 -356.042468) (xy 48.0822 -355.837236) (xy 48.08855 -355.833172)
			(xy 48.089058 -355.832664) (xy 48.10125 -355.825044) (xy 48.344074 -355.825044) (xy 48.354245 -355.825485)
			(xy 48.37304 -355.833263) (xy 48.387426 -355.847643) (xy 48.395211 -355.866436) (xy 48.395636 -355.876606)
			(xy 48.395636 -356.613206) (xy 50.205132 -356.613206) (xy 50.205132 -355.876606) (xy 50.205638 -355.866449)
			(xy 50.213409 -355.847681) (xy 50.227771 -355.833316) (xy 50.246537 -355.825541) (xy 50.256694 -355.825044)
			(xy 50.499518 -355.825044) (xy 50.82921 -356.041198) (xy 50.840248 -356.046699) (xy 50.864877 -356.047359)
			(xy 50.8762 -356.042468) (xy 51.19116 -355.837236) (xy 51.19751 -355.833172) (xy 51.198018 -355.832664)
			(xy 51.21021 -355.825044) (xy 51.453034 -355.825044) (xy 51.463195 -355.825506) (xy 51.481966 -355.833292)
			(xy 51.49633 -355.847668) (xy 51.504102 -355.866445) (xy 51.504596 -355.876606) (xy 51.504596 -356.613206)
			(xy 64.264032 -356.613206) (xy 64.264032 -355.876606) (xy 64.264474 -355.866404) (xy 64.272304 -355.847562)
			(xy 64.286765 -355.833168) (xy 64.305644 -355.825427) (xy 64.315848 -355.825044) (xy 64.558672 -355.825044)
			(xy 64.888364 -356.041198) (xy 64.899414 -356.046669) (xy 64.924032 -356.047348) (xy 64.935354 -356.042468)
			(xy 65.250314 -355.837236) (xy 65.256664 -355.833172) (xy 65.257172 -355.832664) (xy 65.269364 -355.825044)
			(xy 65.512188 -355.825044) (xy 65.522359 -355.825584) (xy 65.541164 -355.833338) (xy 65.55559 -355.847679)
			(xy 65.563456 -355.866438) (xy 65.564004 -355.876606) (xy 65.564004 -356.613206) (xy 67.372992 -356.613206)
			(xy 67.372992 -355.876606) (xy 67.373473 -355.866409) (xy 67.381295 -355.847574) (xy 67.395744 -355.833182)
			(xy 67.414609 -355.825434) (xy 67.424808 -355.825044) (xy 67.667632 -355.825044) (xy 67.997324 -356.041198)
			(xy 68.008359 -356.046709) (xy 68.032991 -356.047362) (xy 68.044314 -356.042468) (xy 68.359274 -355.837236)
			(xy 68.365624 -355.833172) (xy 68.366132 -355.832664) (xy 68.378324 -355.825044) (xy 68.621148 -355.825044)
			(xy 68.631323 -355.825535) (xy 68.650129 -355.833309) (xy 68.664553 -355.847664) (xy 68.672416 -355.866434)
			(xy 68.672964 -355.876606) (xy 68.672964 -356.613206) (xy 70.481952 -356.613206) (xy 70.481952 -355.876606)
			(xy 70.482375 -355.866401) (xy 70.490208 -355.847555) (xy 70.504676 -355.833161) (xy 70.523561 -355.825423)
			(xy 70.533768 -355.825044) (xy 70.776592 -355.825044) (xy 71.106284 -356.041198) (xy 71.117329 -356.046682)
			(xy 71.141952 -356.047353) (xy 71.153274 -356.042468) (xy 71.468234 -355.837236) (xy 71.474584 -355.833172)
			(xy 71.475092 -355.832664) (xy 71.487284 -355.825044) (xy 71.730108 -355.825044) (xy 71.74028 -355.825567)
			(xy 71.759086 -355.833328) (xy 71.773511 -355.847674) (xy 71.781376 -355.866437) (xy 71.781924 -355.876606)
			(xy 71.781924 -356.613206) (xy 73.590912 -356.613206) (xy 73.590912 -355.876606) (xy 73.591374 -355.866406)
			(xy 73.599199 -355.847568) (xy 73.613655 -355.833175) (xy 73.632527 -355.82543) (xy 73.642728 -355.825044)
			(xy 73.885552 -355.825044) (xy 74.215244 -356.041198) (xy 74.226273 -356.046722) (xy 74.250911 -356.047368)
			(xy 74.262234 -356.042468) (xy 74.577194 -355.837236) (xy 74.583544 -355.833172) (xy 74.584052 -355.832664)
			(xy 74.596244 -355.825044) (xy 74.839068 -355.825044) (xy 74.849238 -355.8256) (xy 74.868043 -355.833348)
			(xy 74.882469 -355.847684) (xy 74.890335 -355.86644) (xy 74.890884 -355.876606) (xy 74.890884 -356.613206)
			(xy 76.699872 -356.613206) (xy 76.699872 -355.876606) (xy 76.700275 -355.866399) (xy 76.708112 -355.847549)
			(xy 76.722586 -355.833154) (xy 76.741479 -355.82542) (xy 76.751688 -355.825044) (xy 76.994512 -355.825044)
			(xy 77.324204 -356.041198) (xy 77.335244 -356.046695) (xy 77.359872 -356.047358) (xy 77.371194 -356.042468)
			(xy 77.686154 -355.837236) (xy 77.692504 -355.833172) (xy 77.693012 -355.832664) (xy 77.705204 -355.825044)
			(xy 77.948028 -355.825044) (xy 77.958201 -355.825551) (xy 77.977008 -355.833318) (xy 77.991432 -355.847669)
			(xy 77.999296 -355.866435) (xy 77.999844 -355.876606) (xy 77.999844 -356.613206) (xy 79.808832 -356.613206)
			(xy 79.808832 -355.876606) (xy 79.809274 -355.866404) (xy 79.817104 -355.847562) (xy 79.831565 -355.833168)
			(xy 79.850444 -355.825427) (xy 79.860648 -355.825044) (xy 80.103472 -355.825044) (xy 80.433164 -356.041198)
			(xy 80.444214 -356.046669) (xy 80.468832 -356.047348) (xy 80.480154 -356.042468) (xy 80.795114 -355.837236)
			(xy 80.801464 -355.833172) (xy 80.801972 -355.832664) (xy 80.814164 -355.825044) (xy 81.056988 -355.825044)
			(xy 81.067159 -355.825584) (xy 81.085964 -355.833338) (xy 81.10039 -355.847679) (xy 81.108256 -355.866438)
			(xy 81.108804 -355.876606) (xy 81.108804 -356.613206) (xy 82.917792 -356.613206) (xy 82.917792 -355.876606)
			(xy 82.918273 -355.866409) (xy 82.926095 -355.847574) (xy 82.940544 -355.833182) (xy 82.959409 -355.825434)
			(xy 82.969608 -355.825044) (xy 83.212432 -355.825044) (xy 83.542124 -356.041198) (xy 83.553159 -356.046709)
			(xy 83.577791 -356.047362) (xy 83.589114 -356.042468) (xy 83.904074 -355.837236) (xy 83.910424 -355.833172)
			(xy 83.910932 -355.832664) (xy 83.923124 -355.825044) (xy 84.165948 -355.825044) (xy 84.176123 -355.825535)
			(xy 84.194929 -355.833309) (xy 84.209353 -355.847664) (xy 84.217216 -355.866434) (xy 84.217764 -355.876606)
			(xy 84.217764 -356.613206) (xy 86.026752 -356.613206) (xy 86.026752 -355.876606) (xy 86.027175 -355.866401)
			(xy 86.035008 -355.847555) (xy 86.049476 -355.833161) (xy 86.068361 -355.825423) (xy 86.078568 -355.825044)
			(xy 86.321392 -355.825044) (xy 86.651084 -356.041198) (xy 86.662129 -356.046682) (xy 86.686752 -356.047353)
			(xy 86.698074 -356.042468) (xy 87.013034 -355.837236) (xy 87.019384 -355.833172) (xy 87.019892 -355.832664)
			(xy 87.032084 -355.825044) (xy 87.274908 -355.825044) (xy 87.28508 -355.825567) (xy 87.303886 -355.833328)
			(xy 87.318311 -355.847674) (xy 87.326176 -355.866437) (xy 87.326724 -355.876606) (xy 87.326724 -356.613206)
			(xy 89.135712 -356.613206) (xy 89.135712 -355.876606) (xy 89.136174 -355.866406) (xy 89.143999 -355.847568)
			(xy 89.158455 -355.833175) (xy 89.177327 -355.82543) (xy 89.187528 -355.825044) (xy 89.430352 -355.825044)
			(xy 89.760044 -356.041198) (xy 89.771073 -356.046722) (xy 89.795711 -356.047368) (xy 89.807034 -356.042468)
			(xy 90.121994 -355.837236) (xy 90.128344 -355.833172) (xy 90.128852 -355.832664) (xy 90.141044 -355.825044)
			(xy 90.383868 -355.825044) (xy 90.394038 -355.8256) (xy 90.412843 -355.833348) (xy 90.427269 -355.847684)
			(xy 90.435135 -355.86644) (xy 90.435684 -355.876606) (xy 90.435684 -356.613206) (xy 92.244672 -356.613206)
			(xy 92.244672 -355.876606) (xy 92.245075 -355.866399) (xy 92.252912 -355.847549) (xy 92.267386 -355.833154)
			(xy 92.286279 -355.82542) (xy 92.296488 -355.825044) (xy 92.539312 -355.825044) (xy 92.869004 -356.041198)
			(xy 92.880044 -356.046695) (xy 92.904672 -356.047358) (xy 92.915994 -356.042468) (xy 93.230954 -355.837236)
			(xy 93.237304 -355.833172) (xy 93.237812 -355.832664) (xy 93.250004 -355.825044) (xy 93.492828 -355.825044)
			(xy 93.503001 -355.825551) (xy 93.521808 -355.833318) (xy 93.536232 -355.847669) (xy 93.544096 -355.866435)
			(xy 93.544644 -355.876606) (xy 93.544644 -356.613206) (xy 114.754152 -356.613206) (xy 114.754152 -355.876606)
			(xy 114.754569 -355.866433) (xy 114.762355 -355.847636) (xy 114.776742 -355.83325) (xy 114.795541 -355.825467)
			(xy 114.805714 -355.825044) (xy 115.048538 -355.825044) (xy 115.37823 -356.041198) (xy 115.389263 -356.046713)
			(xy 115.413897 -356.047364) (xy 115.42522 -356.042468) (xy 115.74018 -355.837236) (xy 115.74653 -355.833172)
			(xy 115.747038 -355.832664) (xy 115.75923 -355.825044) (xy 116.002054 -355.825044) (xy 116.012223 -355.825502)
			(xy 116.031018 -355.833273) (xy 116.045405 -355.847648) (xy 116.05319 -355.866437) (xy 116.053616 -355.876606)
			(xy 116.053616 -356.613206) (xy 117.863112 -356.613206) (xy 117.863112 -355.876606) (xy 117.863638 -355.866452)
			(xy 117.871405 -355.847688) (xy 117.885761 -355.833323) (xy 117.90452 -355.825544) (xy 117.914674 -355.825044)
			(xy 118.157498 -355.825044) (xy 118.48719 -356.041198) (xy 118.498233 -356.046686) (xy 118.522858 -356.047354)
			(xy 118.53418 -356.042468) (xy 118.84914 -355.837236) (xy 118.85549 -355.833172) (xy 118.855998 -355.832664)
			(xy 118.86819 -355.825044) (xy 119.111014 -355.825044) (xy 119.121173 -355.825522) (xy 119.139944 -355.833302)
			(xy 119.154309 -355.847673) (xy 119.162082 -355.866446) (xy 119.162576 -355.876606) (xy 119.162576 -356.613206)
			(xy 120.972072 -356.613206) (xy 120.972072 -355.876606) (xy 120.972469 -355.866431) (xy 120.980259 -355.847629)
			(xy 120.994653 -355.833243) (xy 121.013458 -355.825464) (xy 121.023634 -355.825044) (xy 121.266458 -355.825044)
			(xy 121.59615 -356.041198) (xy 121.607204 -356.046659) (xy 121.631818 -356.047344) (xy 121.64314 -356.042468)
			(xy 121.9581 -355.837236) (xy 121.96445 -355.833172) (xy 121.964958 -355.832664) (xy 121.97715 -355.825044)
			(xy 122.219974 -355.825044) (xy 122.230145 -355.825485) (xy 122.24894 -355.833263) (xy 122.263326 -355.847643)
			(xy 122.271111 -355.866436) (xy 122.271536 -355.876606) (xy 122.271536 -356.613206) (xy 124.081032 -356.613206)
			(xy 124.081032 -355.876606) (xy 124.081538 -355.866449) (xy 124.089309 -355.847681) (xy 124.103671 -355.833316)
			(xy 124.122437 -355.825541) (xy 124.132594 -355.825044) (xy 124.375418 -355.825044) (xy 124.70511 -356.041198)
			(xy 124.716148 -356.046699) (xy 124.740777 -356.047359) (xy 124.7521 -356.042468) (xy 125.06706 -355.837236)
			(xy 125.07341 -355.833172) (xy 125.073918 -355.832664) (xy 125.08611 -355.825044) (xy 125.328934 -355.825044)
			(xy 125.339095 -355.825506) (xy 125.357866 -355.833292) (xy 125.37223 -355.847668) (xy 125.380002 -355.866445)
			(xy 125.380496 -355.876606) (xy 125.380496 -356.613206) (xy 127.189992 -356.613206) (xy 127.189992 -355.876606)
			(xy 127.190537 -355.866454) (xy 127.198301 -355.847694) (xy 127.21265 -355.83333) (xy 127.231403 -355.825547)
			(xy 127.241554 -355.825044) (xy 127.484378 -355.825044) (xy 127.81407 -356.041198) (xy 127.825118 -356.046673)
			(xy 127.849738 -356.04735) (xy 127.86106 -356.042468) (xy 128.17602 -355.837236) (xy 128.18237 -355.833172)
			(xy 128.182878 -355.832664) (xy 128.19507 -355.825044) (xy 128.437894 -355.825044) (xy 128.448066 -355.825469)
			(xy 128.466862 -355.833253) (xy 128.481247 -355.847638) (xy 128.489031 -355.866434) (xy 128.489456 -355.876606)
			(xy 128.489456 -356.613206) (xy 130.298952 -356.613206) (xy 130.298952 -355.876606) (xy 130.299369 -355.866433)
			(xy 130.307155 -355.847636) (xy 130.321542 -355.83325) (xy 130.340341 -355.825467) (xy 130.350514 -355.825044)
			(xy 130.593338 -355.825044) (xy 130.92303 -356.041198) (xy 130.934063 -356.046713) (xy 130.958697 -356.047364)
			(xy 130.97002 -356.042468) (xy 131.28498 -355.837236) (xy 131.29133 -355.833172) (xy 131.291838 -355.832664)
			(xy 131.30403 -355.825044) (xy 131.546854 -355.825044) (xy 131.557023 -355.825502) (xy 131.575818 -355.833273)
			(xy 131.590205 -355.847648) (xy 131.59799 -355.866437) (xy 131.598416 -355.876606) (xy 131.598416 -356.613206)
			(xy 133.407912 -356.613206) (xy 133.407912 -355.876606) (xy 133.408438 -355.866452) (xy 133.416205 -355.847688)
			(xy 133.430561 -355.833323) (xy 133.44932 -355.825544) (xy 133.459474 -355.825044) (xy 133.702298 -355.825044)
			(xy 134.03199 -356.041198) (xy 134.043033 -356.046686) (xy 134.067658 -356.047354) (xy 134.07898 -356.042468)
			(xy 134.39394 -355.837236) (xy 134.40029 -355.833172) (xy 134.400798 -355.832664) (xy 134.41299 -355.825044)
			(xy 134.655814 -355.825044) (xy 134.665973 -355.825522) (xy 134.684744 -355.833302) (xy 134.699109 -355.847673)
			(xy 134.706882 -355.866446) (xy 134.707376 -355.876606) (xy 134.707376 -356.613206) (xy 136.516872 -356.613206)
			(xy 136.516872 -355.876606) (xy 136.517269 -355.866431) (xy 136.525059 -355.847629) (xy 136.539453 -355.833243)
			(xy 136.558258 -355.825464) (xy 136.568434 -355.825044) (xy 136.811258 -355.825044) (xy 137.14095 -356.041198)
			(xy 137.152004 -356.046659) (xy 137.176618 -356.047344) (xy 137.18794 -356.042468) (xy 137.5029 -355.837236)
			(xy 137.50925 -355.833172) (xy 137.509758 -355.832664) (xy 137.52195 -355.825044) (xy 137.764774 -355.825044)
			(xy 137.774945 -355.825485) (xy 137.79374 -355.833263) (xy 137.808126 -355.847643) (xy 137.815911 -355.866436)
			(xy 137.816336 -355.876606) (xy 137.816336 -356.613206) (xy 139.625832 -356.613206) (xy 139.625832 -355.876606)
			(xy 139.626338 -355.866449) (xy 139.634109 -355.847681) (xy 139.648471 -355.833316) (xy 139.667237 -355.825541)
			(xy 139.677394 -355.825044) (xy 139.920218 -355.825044) (xy 140.24991 -356.041198) (xy 140.260948 -356.046699)
			(xy 140.285577 -356.047359) (xy 140.2969 -356.042468) (xy 140.61186 -355.837236) (xy 140.61821 -355.833172)
			(xy 140.618718 -355.832664) (xy 140.63091 -355.825044) (xy 140.873734 -355.825044) (xy 140.883895 -355.825506)
			(xy 140.902666 -355.833292) (xy 140.91703 -355.847668) (xy 140.924802 -355.866445) (xy 140.925296 -355.876606)
			(xy 140.925296 -356.613206) (xy 142.734792 -356.613206) (xy 142.734792 -355.876606) (xy 142.735337 -355.866454)
			(xy 142.743101 -355.847694) (xy 142.75745 -355.83333) (xy 142.776203 -355.825547) (xy 142.786354 -355.825044)
			(xy 143.029178 -355.825044) (xy 143.35887 -356.041198) (xy 143.369918 -356.046673) (xy 143.394538 -356.04735)
			(xy 143.40586 -356.042468) (xy 143.72082 -355.837236) (xy 143.72717 -355.833172) (xy 143.727678 -355.832664)
			(xy 143.73987 -355.825044) (xy 143.982694 -355.825044) (xy 143.992866 -355.825469) (xy 144.011662 -355.833253)
			(xy 144.026047 -355.847638) (xy 144.033831 -355.866434) (xy 144.034256 -355.876606) (xy 144.034256 -356.613206)
			(xy 158.860236 -356.613206) (xy 158.860236 -355.876606) (xy 158.860669 -355.866435) (xy 158.868451 -355.847641)
			(xy 158.882834 -355.833256) (xy 158.901627 -355.82547) (xy 158.911798 -355.825044) (xy 159.154622 -355.825044)
			(xy 159.484314 -356.041198) (xy 159.495351 -356.046702) (xy 159.519981 -356.04736) (xy 159.531304 -356.042468)
			(xy 159.846264 -355.837236) (xy 159.852614 -355.833172) (xy 159.853122 -355.832664) (xy 159.865314 -355.825044)
			(xy 160.108138 -355.825044) (xy 160.118299 -355.825502) (xy 160.13707 -355.83329) (xy 160.151434 -355.847667)
			(xy 160.159206 -355.866445) (xy 160.1597 -355.876606) (xy 160.1597 -356.613206) (xy 161.969196 -356.613206)
			(xy 161.969196 -355.876606) (xy 161.969737 -355.866454) (xy 161.977502 -355.847693) (xy 161.991853 -355.833329)
			(xy 162.010606 -355.825547) (xy 162.020758 -355.825044) (xy 162.263582 -355.825044) (xy 162.593274 -356.041198)
			(xy 162.604321 -356.046676) (xy 162.628942 -356.047351) (xy 162.640264 -356.042468) (xy 162.955224 -355.837236)
			(xy 162.961574 -355.833172) (xy 162.962082 -355.832664) (xy 162.974274 -355.825044) (xy 163.217098 -355.825044)
			(xy 163.22727 -355.825466) (xy 163.246066 -355.833251) (xy 163.260451 -355.847637) (xy 163.268235 -355.866434)
			(xy 163.26866 -355.876606) (xy 163.26866 -356.613206) (xy 165.078156 -356.613206) (xy 165.078156 -355.876606)
			(xy 165.078569 -355.866433) (xy 165.086356 -355.847634) (xy 165.100745 -355.833249) (xy 165.119544 -355.825467)
			(xy 165.129718 -355.825044) (xy 165.372542 -355.825044) (xy 165.702234 -356.041198) (xy 165.713266 -356.046716)
			(xy 165.737901 -356.047365) (xy 165.749224 -356.042468) (xy 166.064184 -355.837236) (xy 166.070534 -355.833172)
			(xy 166.071042 -355.832664) (xy 166.083234 -355.825044) (xy 166.326058 -355.825044) (xy 166.336228 -355.825498)
			(xy 166.355023 -355.833271) (xy 166.369409 -355.847647) (xy 166.377195 -355.866437) (xy 166.37762 -355.876606)
			(xy 166.37762 -356.613206) (xy 168.187116 -356.613206) (xy 168.187116 -355.876606) (xy 168.187638 -355.866451)
			(xy 168.195406 -355.847687) (xy 168.209763 -355.833322) (xy 168.228524 -355.825543) (xy 168.238678 -355.825044)
			(xy 168.481502 -355.825044) (xy 168.811194 -356.041198) (xy 168.822236 -356.046689) (xy 168.846862 -356.047355)
			(xy 168.858184 -356.042468) (xy 169.173144 -355.837236) (xy 169.179494 -355.833172) (xy 169.180002 -355.832664)
			(xy 169.192194 -355.825044) (xy 169.435018 -355.825044) (xy 169.445178 -355.825519) (xy 169.463948 -355.8333)
			(xy 169.478313 -355.847672) (xy 169.486086 -355.866446) (xy 169.48658 -355.876606) (xy 169.48658 -356.613206)
			(xy 171.296076 -356.613206) (xy 171.296076 -355.876606) (xy 171.29647 -355.86643) (xy 171.30426 -355.847628)
			(xy 171.318655 -355.833242) (xy 171.337462 -355.825463) (xy 171.347638 -355.825044) (xy 171.590462 -355.825044)
			(xy 171.920154 -356.041198) (xy 171.931207 -356.046662) (xy 171.955822 -356.047345) (xy 171.967144 -356.042468)
			(xy 172.282104 -355.837236) (xy 172.288454 -355.833172) (xy 172.288962 -355.832664) (xy 172.301154 -355.825044)
			(xy 172.543978 -355.825044) (xy 172.554149 -355.825482) (xy 172.572944 -355.833261) (xy 172.58733 -355.847642)
			(xy 172.595115 -355.866435) (xy 172.59554 -355.876606) (xy 172.59554 -356.613206) (xy 174.405036 -356.613206)
			(xy 174.405036 -355.876606) (xy 174.405469 -355.866435) (xy 174.413251 -355.847641) (xy 174.427634 -355.833256)
			(xy 174.446427 -355.82547) (xy 174.456598 -355.825044) (xy 174.699422 -355.825044) (xy 175.029114 -356.041198)
			(xy 175.040151 -356.046702) (xy 175.064781 -356.04736) (xy 175.076104 -356.042468) (xy 175.391064 -355.837236)
			(xy 175.397414 -355.833172) (xy 175.397922 -355.832664) (xy 175.410114 -355.825044) (xy 175.652938 -355.825044)
			(xy 175.663099 -355.825502) (xy 175.68187 -355.83329) (xy 175.696234 -355.847667) (xy 175.704006 -355.866445)
			(xy 175.7045 -355.876606) (xy 175.7045 -356.613206) (xy 177.513996 -356.613206) (xy 177.513996 -355.876606)
			(xy 177.514537 -355.866454) (xy 177.522302 -355.847693) (xy 177.536653 -355.833329) (xy 177.555406 -355.825547)
			(xy 177.565558 -355.825044) (xy 177.808382 -355.825044) (xy 178.138074 -356.041198) (xy 178.149121 -356.046676)
			(xy 178.173742 -356.047351) (xy 178.185064 -356.042468) (xy 178.500024 -355.837236) (xy 178.506374 -355.833172)
			(xy 178.506882 -355.832664) (xy 178.519074 -355.825044) (xy 178.761898 -355.825044) (xy 178.77207 -355.825466)
			(xy 178.790866 -355.833251) (xy 178.805251 -355.847637) (xy 178.813035 -355.866434) (xy 178.81346 -355.876606)
			(xy 178.81346 -356.613206) (xy 180.622956 -356.613206) (xy 180.622956 -355.876606) (xy 180.623369 -355.866433)
			(xy 180.631156 -355.847634) (xy 180.645545 -355.833249) (xy 180.664344 -355.825467) (xy 180.674518 -355.825044)
			(xy 180.917342 -355.825044) (xy 181.247034 -356.041198) (xy 181.258066 -356.046716) (xy 181.282701 -356.047365)
			(xy 181.294024 -356.042468) (xy 181.608984 -355.837236) (xy 181.615334 -355.833172) (xy 181.615842 -355.832664)
			(xy 181.628034 -355.825044) (xy 181.870858 -355.825044) (xy 181.881028 -355.825498) (xy 181.899823 -355.833271)
			(xy 181.914209 -355.847647) (xy 181.921995 -355.866437) (xy 181.92242 -355.876606) (xy 181.92242 -356.58933)
			(xy 183.731916 -356.58933) (xy 183.731916 -355.85273) (xy 183.732388 -355.842563) (xy 183.740159 -355.823773)
			(xy 183.75453 -355.809388) (xy 183.773312 -355.801598) (xy 183.783478 -355.801168) (xy 184.026302 -355.801168)
			(xy 184.355994 -356.017322) (xy 184.367036 -356.022812) (xy 184.391661 -356.023478) (xy 184.402984 -356.018592)
			(xy 184.717944 -355.81336) (xy 184.724294 -355.809296) (xy 184.724802 -355.808788) (xy 184.736994 -355.801168)
			(xy 184.979818 -355.801168) (xy 184.989994 -355.80155) (xy 185.008795 -355.809347) (xy 185.02318 -355.823745)
			(xy 185.030959 -355.842553) (xy 185.03138 -355.85273) (xy 185.03138 -356.58933) (xy 186.840876 -356.58933)
			(xy 186.840876 -355.85273) (xy 186.841289 -355.842556) (xy 186.849072 -355.823754) (xy 186.863461 -355.809367)
			(xy 186.882264 -355.801588) (xy 186.892438 -355.801168) (xy 187.135262 -355.801168) (xy 187.464954 -356.017322)
			(xy 187.476007 -356.022785) (xy 187.500622 -356.023468) (xy 187.511944 -356.018592) (xy 187.826904 -355.81336)
			(xy 187.833254 -355.809296) (xy 187.833762 -355.808788) (xy 187.845954 -355.801168) (xy 188.088778 -355.801168)
			(xy 188.098952 -355.801583) (xy 188.117752 -355.809366) (xy 188.132138 -355.823755) (xy 188.139919 -355.842556)
			(xy 188.14034 -355.85273) (xy 188.14034 -356.58933) (xy 188.139891 -356.599492) (xy 188.134202 -356.613206)
			(xy 270.788892 -356.613206) (xy 270.788892 -355.876606) (xy 270.789373 -355.866409) (xy 270.797195 -355.847574)
			(xy 270.811644 -355.833182) (xy 270.830509 -355.825434) (xy 270.840708 -355.825044) (xy 271.083532 -355.825044)
			(xy 271.413224 -356.041198) (xy 271.424259 -356.046709) (xy 271.448891 -356.047362) (xy 271.460214 -356.042468)
			(xy 271.775174 -355.837236) (xy 271.781524 -355.833172) (xy 271.782032 -355.832664) (xy 271.794224 -355.825044)
			(xy 272.037048 -355.825044) (xy 272.047223 -355.825535) (xy 272.066029 -355.833309) (xy 272.080453 -355.847664)
			(xy 272.088316 -355.866434) (xy 272.088864 -355.876606) (xy 272.088864 -356.613206) (xy 273.897852 -356.613206)
			(xy 273.897852 -355.876606) (xy 273.898275 -355.866401) (xy 273.906108 -355.847555) (xy 273.920576 -355.833161)
			(xy 273.939461 -355.825423) (xy 273.949668 -355.825044) (xy 274.192492 -355.825044) (xy 274.522184 -356.041198)
			(xy 274.533229 -356.046682) (xy 274.557852 -356.047353) (xy 274.569174 -356.042468) (xy 274.884134 -355.837236)
			(xy 274.890484 -355.833172) (xy 274.890992 -355.832664) (xy 274.903184 -355.825044) (xy 275.146008 -355.825044)
			(xy 275.15618 -355.825567) (xy 275.174986 -355.833328) (xy 275.189411 -355.847674) (xy 275.197276 -355.866437)
			(xy 275.197824 -355.876606) (xy 275.197824 -356.613206) (xy 277.006812 -356.613206) (xy 277.006812 -355.876606)
			(xy 277.007274 -355.866406) (xy 277.015099 -355.847568) (xy 277.029555 -355.833175) (xy 277.048427 -355.82543)
			(xy 277.058628 -355.825044) (xy 277.301452 -355.825044) (xy 277.631144 -356.041198) (xy 277.642173 -356.046722)
			(xy 277.666811 -356.047368) (xy 277.678134 -356.042468) (xy 277.993094 -355.837236) (xy 277.999444 -355.833172)
			(xy 277.999952 -355.832664) (xy 278.012144 -355.825044) (xy 278.254968 -355.825044) (xy 278.265138 -355.8256)
			(xy 278.283943 -355.833348) (xy 278.298369 -355.847684) (xy 278.306235 -355.86644) (xy 278.306784 -355.876606)
			(xy 278.306784 -356.613206) (xy 280.115772 -356.613206) (xy 280.115772 -355.876606) (xy 280.116175 -355.866399)
			(xy 280.124012 -355.847549) (xy 280.138486 -355.833154) (xy 280.157379 -355.82542) (xy 280.167588 -355.825044)
			(xy 280.410412 -355.825044) (xy 280.740104 -356.041198) (xy 280.751144 -356.046695) (xy 280.775772 -356.047358)
			(xy 280.787094 -356.042468) (xy 281.102054 -355.837236) (xy 281.108404 -355.833172) (xy 281.108912 -355.832664)
			(xy 281.121104 -355.825044) (xy 281.363928 -355.825044) (xy 281.374101 -355.825551) (xy 281.392908 -355.833318)
			(xy 281.407332 -355.847669) (xy 281.415196 -355.866435) (xy 281.415744 -355.876606) (xy 281.415744 -356.613206)
			(xy 283.224732 -356.613206) (xy 283.224732 -355.876606) (xy 283.225174 -355.866404) (xy 283.233004 -355.847562)
			(xy 283.247465 -355.833168) (xy 283.266344 -355.825427) (xy 283.276548 -355.825044) (xy 283.519372 -355.825044)
			(xy 283.849064 -356.041198) (xy 283.860114 -356.046669) (xy 283.884732 -356.047348) (xy 283.896054 -356.042468)
			(xy 284.211014 -355.837236) (xy 284.217364 -355.833172) (xy 284.217872 -355.832664) (xy 284.230064 -355.825044)
			(xy 284.472888 -355.825044) (xy 284.483059 -355.825584) (xy 284.501864 -355.833338) (xy 284.51629 -355.847679)
			(xy 284.524156 -355.866438) (xy 284.524704 -355.876606) (xy 284.524704 -356.613206) (xy 286.333692 -356.613206)
			(xy 286.333692 -355.876606) (xy 286.334173 -355.866409) (xy 286.341995 -355.847574) (xy 286.356444 -355.833182)
			(xy 286.375309 -355.825434) (xy 286.385508 -355.825044) (xy 286.628332 -355.825044) (xy 286.958024 -356.041198)
			(xy 286.969059 -356.046709) (xy 286.993691 -356.047362) (xy 287.005014 -356.042468) (xy 287.319974 -355.837236)
			(xy 287.326324 -355.833172) (xy 287.326832 -355.832664) (xy 287.339024 -355.825044) (xy 287.581848 -355.825044)
			(xy 287.592023 -355.825535) (xy 287.610829 -355.833309) (xy 287.625253 -355.847664) (xy 287.633116 -355.866434)
			(xy 287.633664 -355.876606) (xy 287.633664 -356.613206) (xy 289.442652 -356.613206) (xy 289.442652 -355.876606)
			(xy 289.443075 -355.866401) (xy 289.450908 -355.847555) (xy 289.465376 -355.833161) (xy 289.484261 -355.825423)
			(xy 289.494468 -355.825044) (xy 289.737292 -355.825044) (xy 290.066984 -356.041198) (xy 290.078029 -356.046682)
			(xy 290.102652 -356.047353) (xy 290.113974 -356.042468) (xy 290.428934 -355.837236) (xy 290.435284 -355.833172)
			(xy 290.435792 -355.832664) (xy 290.447984 -355.825044) (xy 290.690808 -355.825044) (xy 290.70098 -355.825567)
			(xy 290.719786 -355.833328) (xy 290.734211 -355.847674) (xy 290.742076 -355.866437) (xy 290.742624 -355.876606)
			(xy 290.742624 -356.613206) (xy 292.551612 -356.613206) (xy 292.551612 -355.876606) (xy 292.552074 -355.866406)
			(xy 292.559899 -355.847568) (xy 292.574355 -355.833175) (xy 292.593227 -355.82543) (xy 292.603428 -355.825044)
			(xy 292.846252 -355.825044) (xy 293.175944 -356.041198) (xy 293.186973 -356.046722) (xy 293.211611 -356.047368)
			(xy 293.222934 -356.042468) (xy 293.537894 -355.837236) (xy 293.544244 -355.833172) (xy 293.544752 -355.832664)
			(xy 293.556944 -355.825044) (xy 293.799768 -355.825044) (xy 293.809938 -355.8256) (xy 293.828743 -355.833348)
			(xy 293.843169 -355.847684) (xy 293.851035 -355.86644) (xy 293.851584 -355.876606) (xy 293.851584 -356.613206)
			(xy 295.660572 -356.613206) (xy 295.660572 -355.876606) (xy 295.660975 -355.866399) (xy 295.668812 -355.847549)
			(xy 295.683286 -355.833154) (xy 295.702179 -355.82542) (xy 295.712388 -355.825044) (xy 295.955212 -355.825044)
			(xy 296.284904 -356.041198) (xy 296.295944 -356.046695) (xy 296.320572 -356.047358) (xy 296.331894 -356.042468)
			(xy 296.646854 -355.837236) (xy 296.653204 -355.833172) (xy 296.653712 -355.832664) (xy 296.665904 -355.825044)
			(xy 296.908728 -355.825044) (xy 296.918901 -355.825551) (xy 296.937708 -355.833318) (xy 296.952132 -355.847669)
			(xy 296.959996 -355.866435) (xy 296.960544 -355.876606) (xy 296.960544 -356.613206) (xy 298.769532 -356.613206)
			(xy 298.769532 -355.876606) (xy 298.769974 -355.866404) (xy 298.777804 -355.847562) (xy 298.792265 -355.833168)
			(xy 298.811144 -355.825427) (xy 298.821348 -355.825044) (xy 299.064172 -355.825044) (xy 299.393864 -356.041198)
			(xy 299.404914 -356.046669) (xy 299.429532 -356.047348) (xy 299.440854 -356.042468) (xy 299.755814 -355.837236)
			(xy 299.762164 -355.833172) (xy 299.762672 -355.832664) (xy 299.774864 -355.825044) (xy 300.017688 -355.825044)
			(xy 300.027859 -355.825584) (xy 300.046664 -355.833338) (xy 300.06109 -355.847679) (xy 300.068956 -355.866438)
			(xy 300.069504 -355.876606) (xy 300.069504 -356.613206) (xy 315.394848 -356.613206) (xy 315.394848 -355.876606)
			(xy 315.395269 -355.866434) (xy 315.403054 -355.847637) (xy 315.41744 -355.833252) (xy 315.436237 -355.825468)
			(xy 315.44641 -355.825044) (xy 315.689234 -355.825044) (xy 316.018926 -356.041198) (xy 316.02996 -356.046711)
			(xy 316.054593 -356.047363) (xy 316.065916 -356.042468) (xy 316.380876 -355.837236) (xy 316.387226 -355.833172)
			(xy 316.387734 -355.832664) (xy 316.399926 -355.825044) (xy 316.64275 -355.825044) (xy 316.652919 -355.825505)
			(xy 316.671714 -355.833275) (xy 316.686101 -355.847649) (xy 316.693886 -355.866437) (xy 316.694312 -355.876606)
			(xy 316.694312 -356.613206) (xy 318.503808 -356.613206) (xy 318.503808 -355.876606) (xy 318.504338 -355.866452)
			(xy 318.512104 -355.847689) (xy 318.526459 -355.833325) (xy 318.545217 -355.825545) (xy 318.55537 -355.825044)
			(xy 318.798194 -355.825044) (xy 319.127886 -356.041198) (xy 319.13893 -356.046684) (xy 319.163554 -356.047353)
			(xy 319.174876 -356.042468) (xy 319.489836 -355.837236) (xy 319.496186 -355.833172) (xy 319.496694 -355.832664)
			(xy 319.508886 -355.825044) (xy 319.75171 -355.825044) (xy 319.761869 -355.825526) (xy 319.78064 -355.833304)
			(xy 319.795005 -355.847674) (xy 319.802778 -355.866447) (xy 319.803272 -355.876606) (xy 319.803272 -356.613206)
			(xy 321.612768 -356.613206) (xy 321.612768 -355.876606) (xy 321.613169 -355.866431) (xy 321.620958 -355.847631)
			(xy 321.635351 -355.833245) (xy 321.654155 -355.825465) (xy 321.66433 -355.825044) (xy 321.907154 -355.825044)
			(xy 322.236846 -356.041198) (xy 322.247901 -356.046657) (xy 322.272515 -356.047343) (xy 322.283836 -356.042468)
			(xy 322.598796 -355.837236) (xy 322.605146 -355.833172) (xy 322.605654 -355.832664) (xy 322.617846 -355.825044)
			(xy 322.86067 -355.825044) (xy 322.87084 -355.825489) (xy 322.889636 -355.833265) (xy 322.904022 -355.847644)
			(xy 322.911807 -355.866436) (xy 322.912232 -355.876606) (xy 322.912232 -356.613206) (xy 324.721728 -356.613206)
			(xy 324.721728 -355.876606) (xy 324.722238 -355.86645) (xy 324.730009 -355.847683) (xy 324.744369 -355.833318)
			(xy 324.763134 -355.825541) (xy 324.77329 -355.825044) (xy 325.016114 -355.825044) (xy 325.345806 -356.041198)
			(xy 325.356845 -356.046697) (xy 325.381473 -356.047358) (xy 325.392796 -356.042468) (xy 325.707756 -355.837236)
			(xy 325.714106 -355.833172) (xy 325.714614 -355.832664) (xy 325.726806 -355.825044) (xy 325.96963 -355.825044)
			(xy 325.97979 -355.825509) (xy 325.998561 -355.833294) (xy 326.012926 -355.847669) (xy 326.020698 -355.866445)
			(xy 326.021192 -355.876606) (xy 326.021192 -356.613206) (xy 327.830688 -356.613206) (xy 327.830688 -355.876606)
			(xy 327.83107 -355.866429) (xy 327.838862 -355.847624) (xy 327.853261 -355.833238) (xy 327.872072 -355.825461)
			(xy 327.88225 -355.825044) (xy 328.125074 -355.825044) (xy 328.454766 -356.041198) (xy 328.465815 -356.04667)
			(xy 328.490434 -356.047349) (xy 328.501756 -356.042468) (xy 328.816716 -355.837236) (xy 328.823066 -355.833172)
			(xy 328.823574 -355.832664) (xy 328.835766 -355.825044) (xy 329.07859 -355.825044) (xy 329.088762 -355.825472)
			(xy 329.107557 -355.833255) (xy 329.121943 -355.847639) (xy 329.129727 -355.866434) (xy 329.130152 -355.876606)
			(xy 329.130152 -356.613206) (xy 330.939648 -356.613206) (xy 330.939648 -355.876606) (xy 330.940069 -355.866434)
			(xy 330.947854 -355.847637) (xy 330.96224 -355.833252) (xy 330.981037 -355.825468) (xy 330.99121 -355.825044)
			(xy 331.234034 -355.825044) (xy 331.563726 -356.041198) (xy 331.57476 -356.046711) (xy 331.599393 -356.047363)
			(xy 331.610716 -356.042468) (xy 331.925676 -355.837236) (xy 331.932026 -355.833172) (xy 331.932534 -355.832664)
			(xy 331.944726 -355.825044) (xy 332.18755 -355.825044) (xy 332.197719 -355.825505) (xy 332.216514 -355.833275)
			(xy 332.230901 -355.847649) (xy 332.238686 -355.866437) (xy 332.239112 -355.876606) (xy 332.239112 -356.613206)
			(xy 334.048608 -356.613206) (xy 334.048608 -355.876606) (xy 334.049138 -355.866452) (xy 334.056904 -355.847689)
			(xy 334.071259 -355.833325) (xy 334.090017 -355.825545) (xy 334.10017 -355.825044) (xy 334.342994 -355.825044)
			(xy 334.672686 -356.041198) (xy 334.68373 -356.046684) (xy 334.708354 -356.047353) (xy 334.719676 -356.042468)
			(xy 335.034636 -355.837236) (xy 335.040986 -355.833172) (xy 335.041494 -355.832664) (xy 335.053686 -355.825044)
			(xy 335.29651 -355.825044) (xy 335.306669 -355.825526) (xy 335.32544 -355.833304) (xy 335.339805 -355.847674)
			(xy 335.347578 -355.866447) (xy 335.348072 -355.876606) (xy 335.348072 -356.613206) (xy 337.157568 -356.613206)
			(xy 337.157568 -355.876606) (xy 337.157969 -355.866431) (xy 337.165758 -355.847631) (xy 337.180151 -355.833245)
			(xy 337.198955 -355.825465) (xy 337.20913 -355.825044) (xy 337.451954 -355.825044) (xy 337.781646 -356.041198)
			(xy 337.792701 -356.046657) (xy 337.817315 -356.047343) (xy 337.828636 -356.042468) (xy 338.143596 -355.837236)
			(xy 338.149946 -355.833172) (xy 338.150454 -355.832664) (xy 338.162646 -355.825044) (xy 338.40547 -355.825044)
			(xy 338.41564 -355.825489) (xy 338.434436 -355.833265) (xy 338.448822 -355.847644) (xy 338.456607 -355.866436)
			(xy 338.457032 -355.876606) (xy 338.457032 -356.613206) (xy 340.266528 -356.613206) (xy 340.266528 -355.876606)
			(xy 340.267038 -355.86645) (xy 340.274809 -355.847683) (xy 340.289169 -355.833318) (xy 340.307934 -355.825541)
			(xy 340.31809 -355.825044) (xy 340.560914 -355.825044) (xy 340.890606 -356.041198) (xy 340.901645 -356.046697)
			(xy 340.926273 -356.047358) (xy 340.937596 -356.042468) (xy 341.252556 -355.837236) (xy 341.258906 -355.833172)
			(xy 341.259414 -355.832664) (xy 341.271606 -355.825044) (xy 341.51443 -355.825044) (xy 341.52459 -355.825509)
			(xy 341.543361 -355.833294) (xy 341.557726 -355.847669) (xy 341.565498 -355.866445) (xy 341.565992 -355.876606)
			(xy 341.565992 -356.613206) (xy 343.375488 -356.613206) (xy 343.375488 -355.876606) (xy 343.37587 -355.866429)
			(xy 343.383662 -355.847624) (xy 343.398061 -355.833238) (xy 343.416872 -355.825461) (xy 343.42705 -355.825044)
			(xy 343.669874 -355.825044) (xy 343.999566 -356.041198) (xy 344.010615 -356.04667) (xy 344.035234 -356.047349)
			(xy 344.046556 -356.042468) (xy 344.361516 -355.837236) (xy 344.367866 -355.833172) (xy 344.368374 -355.832664)
			(xy 344.380566 -355.825044) (xy 344.62339 -355.825044) (xy 344.633562 -355.825472) (xy 344.652357 -355.833255)
			(xy 344.666743 -355.847639) (xy 344.674527 -355.866434) (xy 344.674952 -355.876606) (xy 344.674952 -356.613206)
			(xy 374.080024 -356.613206) (xy 374.080024 -355.876606) (xy 374.080538 -355.86645) (xy 374.088308 -355.847684)
			(xy 374.102667 -355.833319) (xy 374.121431 -355.825542) (xy 374.131586 -355.825044) (xy 374.37441 -355.825044)
			(xy 374.704102 -356.041198) (xy 374.715142 -356.046694) (xy 374.73977 -356.047357) (xy 374.751092 -356.042468)
			(xy 375.066052 -355.837236) (xy 375.072402 -355.833172) (xy 375.07291 -355.832664) (xy 375.085102 -355.825044)
			(xy 375.327926 -355.825044) (xy 375.338086 -355.825512) (xy 375.356857 -355.833296) (xy 375.371222 -355.84767)
			(xy 375.378994 -355.866445) (xy 375.379488 -355.876606) (xy 375.379488 -356.613206) (xy 377.188984 -356.613206)
			(xy 377.188984 -355.876606) (xy 377.18937 -355.866429) (xy 377.197161 -355.847626) (xy 377.211559 -355.833239)
			(xy 377.230369 -355.825462) (xy 377.240546 -355.825044) (xy 377.48337 -355.825044) (xy 377.813062 -356.041198)
			(xy 377.824112 -356.046668) (xy 377.84873 -356.047348) (xy 377.860052 -356.042468) (xy 378.175012 -355.837236)
			(xy 378.181362 -355.833172) (xy 378.18187 -355.832664) (xy 378.194062 -355.825044) (xy 378.436886 -355.825044)
			(xy 378.447057 -355.825475) (xy 378.465853 -355.833257) (xy 378.480239 -355.84764) (xy 378.488023 -355.866435)
			(xy 378.488448 -355.876606) (xy 378.488448 -356.613206) (xy 380.297944 -356.613206) (xy 380.297944 -355.876606)
			(xy 380.298369 -355.866434) (xy 380.306153 -355.847638) (xy 380.320538 -355.833253) (xy 380.339334 -355.825469)
			(xy 380.349506 -355.825044) (xy 380.59233 -355.825044) (xy 380.922022 -356.041198) (xy 380.933057 -356.046707)
			(xy 380.957689 -356.047362) (xy 380.969012 -356.042468) (xy 381.283972 -355.837236) (xy 381.290322 -355.833172)
			(xy 381.29083 -355.832664) (xy 381.303022 -355.825044) (xy 381.545846 -355.825044) (xy 381.556007 -355.825496)
			(xy 381.574779 -355.833287) (xy 381.589143 -355.847665) (xy 381.596914 -355.866444) (xy 381.597408 -355.876606)
			(xy 381.597408 -356.613206) (xy 383.406904 -356.613206) (xy 383.406904 -355.876606) (xy 383.407437 -355.866453)
			(xy 383.415204 -355.84769) (xy 383.429557 -355.833326) (xy 383.448313 -355.825545) (xy 383.458466 -355.825044)
			(xy 383.70129 -355.825044) (xy 384.030982 -356.041198) (xy 384.042027 -356.046681) (xy 384.06665 -356.047352)
			(xy 384.077972 -356.042468) (xy 384.392932 -355.837236) (xy 384.399282 -355.833172) (xy 384.39979 -355.832664)
			(xy 384.411982 -355.825044) (xy 384.654806 -355.825044) (xy 384.664965 -355.825529) (xy 384.683735 -355.833306)
			(xy 384.6981 -355.847675) (xy 384.705874 -355.866447) (xy 384.706368 -355.876606) (xy 384.706368 -356.613206)
			(xy 386.515864 -356.613206) (xy 386.515864 -355.876606) (xy 386.516269 -355.866432) (xy 386.524057 -355.847632)
			(xy 386.538449 -355.833246) (xy 386.557251 -355.825465) (xy 386.567426 -355.825044) (xy 386.81025 -355.825044)
			(xy 387.139942 -356.041198) (xy 387.150972 -356.046721) (xy 387.175609 -356.047367) (xy 387.186932 -356.042468)
			(xy 387.501892 -355.837236) (xy 387.508242 -355.833172) (xy 387.50875 -355.832664) (xy 387.520942 -355.825044)
			(xy 387.763766 -355.825044) (xy 387.773936 -355.825492) (xy 387.792731 -355.833267) (xy 387.807117 -355.847645)
			(xy 387.814903 -355.866436) (xy 387.815328 -355.876606) (xy 387.815328 -356.613206) (xy 389.624824 -356.613206)
			(xy 389.624824 -355.876606) (xy 389.625338 -355.86645) (xy 389.633108 -355.847684) (xy 389.647467 -355.833319)
			(xy 389.666231 -355.825542) (xy 389.676386 -355.825044) (xy 389.91921 -355.825044) (xy 390.248902 -356.041198)
			(xy 390.259942 -356.046694) (xy 390.28457 -356.047357) (xy 390.295892 -356.042468) (xy 390.610852 -355.837236)
			(xy 390.617202 -355.833172) (xy 390.61771 -355.832664) (xy 390.629902 -355.825044) (xy 390.872726 -355.825044)
			(xy 390.882886 -355.825512) (xy 390.901657 -355.833296) (xy 390.916022 -355.84767) (xy 390.923794 -355.866445)
			(xy 390.924288 -355.876606) (xy 390.924288 -356.613206) (xy 392.733784 -356.613206) (xy 392.733784 -355.876606)
			(xy 392.73417 -355.866429) (xy 392.741961 -355.847626) (xy 392.756359 -355.833239) (xy 392.775169 -355.825462)
			(xy 392.785346 -355.825044) (xy 393.02817 -355.825044) (xy 393.357862 -356.041198) (xy 393.368912 -356.046668)
			(xy 393.39353 -356.047348) (xy 393.404852 -356.042468) (xy 393.719812 -355.837236) (xy 393.726162 -355.833172)
			(xy 393.72667 -355.832664) (xy 393.738862 -355.825044) (xy 393.981686 -355.825044) (xy 393.991857 -355.825475)
			(xy 394.010653 -355.833257) (xy 394.025039 -355.84764) (xy 394.032823 -355.866435) (xy 394.033248 -355.876606)
			(xy 394.033248 -356.613206) (xy 395.842744 -356.613206) (xy 395.842744 -355.876606) (xy 395.843169 -355.866434)
			(xy 395.850953 -355.847638) (xy 395.865338 -355.833253) (xy 395.884134 -355.825469) (xy 395.894306 -355.825044)
			(xy 396.13713 -355.825044) (xy 396.466822 -356.041198) (xy 396.477857 -356.046707) (xy 396.502489 -356.047362)
			(xy 396.513812 -356.042468) (xy 396.828772 -355.837236) (xy 396.835122 -355.833172) (xy 396.83563 -355.832664)
			(xy 396.847822 -355.825044) (xy 397.090646 -355.825044) (xy 397.100807 -355.825496) (xy 397.119579 -355.833287)
			(xy 397.133943 -355.847665) (xy 397.141714 -355.866444) (xy 397.142208 -355.876606) (xy 397.142208 -356.613206)
			(xy 398.951704 -356.613206) (xy 398.951704 -355.876606) (xy 398.952237 -355.866453) (xy 398.960004 -355.84769)
			(xy 398.974357 -355.833326) (xy 398.993113 -355.825545) (xy 399.003266 -355.825044) (xy 399.24609 -355.825044)
			(xy 399.575782 -356.041198) (xy 399.586827 -356.046681) (xy 399.61145 -356.047352) (xy 399.622772 -356.042468)
			(xy 399.937732 -355.837236) (xy 399.944082 -355.833172) (xy 399.94459 -355.832664) (xy 399.956782 -355.825044)
			(xy 400.199606 -355.825044) (xy 400.209765 -355.825529) (xy 400.228535 -355.833306) (xy 400.2429 -355.847675)
			(xy 400.250674 -355.866447) (xy 400.251168 -355.876606) (xy 400.251168 -356.613206) (xy 402.060664 -356.613206)
			(xy 402.060664 -355.876606) (xy 402.061069 -355.866432) (xy 402.068857 -355.847632) (xy 402.083249 -355.833246)
			(xy 402.102051 -355.825465) (xy 402.112226 -355.825044) (xy 402.35505 -355.825044) (xy 402.684742 -356.041198)
			(xy 402.695772 -356.046721) (xy 402.720409 -356.047367) (xy 402.731732 -356.042468) (xy 403.046692 -355.837236)
			(xy 403.053042 -355.833172) (xy 403.05355 -355.832664) (xy 403.065742 -355.825044) (xy 403.308566 -355.825044)
			(xy 403.318736 -355.825492) (xy 403.337531 -355.833267) (xy 403.351917 -355.847645) (xy 403.359703 -355.866436)
			(xy 403.360128 -355.876606) (xy 403.360128 -356.613206) (xy 412.187136 -356.613206) (xy 412.187136 -355.876606)
			(xy 412.187569 -355.866435) (xy 412.195351 -355.847641) (xy 412.209734 -355.833256) (xy 412.228527 -355.82547)
			(xy 412.238698 -355.825044) (xy 412.481522 -355.825044) (xy 412.811214 -356.041198) (xy 412.822251 -356.046702)
			(xy 412.846881 -356.04736) (xy 412.858204 -356.042468) (xy 413.173164 -355.837236) (xy 413.179514 -355.833172)
			(xy 413.180022 -355.832664) (xy 413.192214 -355.825044) (xy 413.435038 -355.825044) (xy 413.445199 -355.825502)
			(xy 413.46397 -355.83329) (xy 413.478334 -355.847667) (xy 413.486106 -355.866445) (xy 413.4866 -355.876606)
			(xy 413.4866 -356.613206) (xy 415.296096 -356.613206) (xy 415.296096 -355.876606) (xy 415.296637 -355.866454)
			(xy 415.304402 -355.847693) (xy 415.318753 -355.833329) (xy 415.337506 -355.825547) (xy 415.347658 -355.825044)
			(xy 415.590482 -355.825044) (xy 415.920174 -356.041198) (xy 415.931221 -356.046676) (xy 415.955842 -356.047351)
			(xy 415.967164 -356.042468) (xy 416.282124 -355.837236) (xy 416.288474 -355.833172) (xy 416.288982 -355.832664)
			(xy 416.301174 -355.825044) (xy 416.543998 -355.825044) (xy 416.55417 -355.825466) (xy 416.572966 -355.833251)
			(xy 416.587351 -355.847637) (xy 416.595135 -355.866434) (xy 416.59556 -355.876606) (xy 416.59556 -356.613206)
			(xy 418.405056 -356.613206) (xy 418.405056 -355.876606) (xy 418.405469 -355.866433) (xy 418.413256 -355.847634)
			(xy 418.427645 -355.833249) (xy 418.446444 -355.825467) (xy 418.456618 -355.825044) (xy 418.699442 -355.825044)
			(xy 419.029134 -356.041198) (xy 419.040166 -356.046716) (xy 419.064801 -356.047365) (xy 419.076124 -356.042468)
			(xy 419.391084 -355.837236) (xy 419.397434 -355.833172) (xy 419.397942 -355.832664) (xy 419.410134 -355.825044)
			(xy 419.652958 -355.825044) (xy 419.663128 -355.825498) (xy 419.681923 -355.833271) (xy 419.696309 -355.847647)
			(xy 419.704095 -355.866437) (xy 419.70452 -355.876606) (xy 419.70452 -356.613206) (xy 421.514016 -356.613206)
			(xy 421.514016 -355.876606) (xy 421.514538 -355.866451) (xy 421.522306 -355.847687) (xy 421.536663 -355.833322)
			(xy 421.555424 -355.825543) (xy 421.565578 -355.825044) (xy 421.808402 -355.825044) (xy 422.138094 -356.041198)
			(xy 422.149136 -356.046689) (xy 422.173762 -356.047355) (xy 422.185084 -356.042468) (xy 422.500044 -355.837236)
			(xy 422.506394 -355.833172) (xy 422.506902 -355.832664) (xy 422.519094 -355.825044) (xy 422.761918 -355.825044)
			(xy 422.772078 -355.825519) (xy 422.790848 -355.8333) (xy 422.805213 -355.847672) (xy 422.812986 -355.866446)
			(xy 422.81348 -355.876606) (xy 422.81348 -356.613206) (xy 424.622976 -356.613206) (xy 424.622976 -355.876606)
			(xy 424.62337 -355.86643) (xy 424.63116 -355.847628) (xy 424.645555 -355.833242) (xy 424.664362 -355.825463)
			(xy 424.674538 -355.825044) (xy 424.917362 -355.825044) (xy 425.247054 -356.041198) (xy 425.258107 -356.046662)
			(xy 425.282722 -356.047345) (xy 425.294044 -356.042468) (xy 425.609004 -355.837236) (xy 425.615354 -355.833172)
			(xy 425.615862 -355.832664) (xy 425.628054 -355.825044) (xy 425.870878 -355.825044) (xy 425.881049 -355.825482)
			(xy 425.899844 -355.833261) (xy 425.91423 -355.847642) (xy 425.922015 -355.866435) (xy 425.92244 -355.876606)
			(xy 425.92244 -356.613206) (xy 427.731936 -356.613206) (xy 427.731936 -355.876606) (xy 427.732369 -355.866435)
			(xy 427.740151 -355.847641) (xy 427.754534 -355.833256) (xy 427.773327 -355.82547) (xy 427.783498 -355.825044)
			(xy 428.026322 -355.825044) (xy 428.356014 -356.041198) (xy 428.367051 -356.046702) (xy 428.391681 -356.04736)
			(xy 428.403004 -356.042468) (xy 428.717964 -355.837236) (xy 428.724314 -355.833172) (xy 428.724822 -355.832664)
			(xy 428.737014 -355.825044) (xy 428.979838 -355.825044) (xy 428.989999 -355.825502) (xy 429.00877 -355.83329)
			(xy 429.023134 -355.847667) (xy 429.030906 -355.866445) (xy 429.0314 -355.876606) (xy 429.0314 -356.613206)
			(xy 430.840896 -356.613206) (xy 430.840896 -355.876606) (xy 430.841437 -355.866454) (xy 430.849202 -355.847693)
			(xy 430.863553 -355.833329) (xy 430.882306 -355.825547) (xy 430.892458 -355.825044) (xy 431.135282 -355.825044)
			(xy 431.464974 -356.041198) (xy 431.476021 -356.046676) (xy 431.500642 -356.047351) (xy 431.511964 -356.042468)
			(xy 431.826924 -355.837236) (xy 431.833274 -355.833172) (xy 431.833782 -355.832664) (xy 431.845974 -355.825044)
			(xy 432.088798 -355.825044) (xy 432.09897 -355.825466) (xy 432.117766 -355.833251) (xy 432.132151 -355.847637)
			(xy 432.139935 -355.866434) (xy 432.14036 -355.876606) (xy 432.14036 -356.613206) (xy 433.949856 -356.613206)
			(xy 433.949856 -355.876606) (xy 433.950269 -355.866433) (xy 433.958056 -355.847634) (xy 433.972445 -355.833249)
			(xy 433.991244 -355.825467) (xy 434.001418 -355.825044) (xy 434.244242 -355.825044) (xy 434.573934 -356.041198)
			(xy 434.584966 -356.046716) (xy 434.609601 -356.047365) (xy 434.620924 -356.042468) (xy 434.935884 -355.837236)
			(xy 434.942234 -355.833172) (xy 434.942742 -355.832664) (xy 434.954934 -355.825044) (xy 435.197758 -355.825044)
			(xy 435.207928 -355.825498) (xy 435.226723 -355.833271) (xy 435.241109 -355.847647) (xy 435.248895 -355.866437)
			(xy 435.24932 -355.876606) (xy 435.24932 -356.613206) (xy 437.058816 -356.613206) (xy 437.058816 -355.876606)
			(xy 437.059338 -355.866451) (xy 437.067106 -355.847687) (xy 437.081463 -355.833322) (xy 437.100224 -355.825543)
			(xy 437.110378 -355.825044) (xy 437.353202 -355.825044) (xy 437.682894 -356.041198) (xy 437.693936 -356.046689)
			(xy 437.718562 -356.047355) (xy 437.729884 -356.042468) (xy 438.044844 -355.837236) (xy 438.051194 -355.833172)
			(xy 438.051702 -355.832664) (xy 438.063894 -355.825044) (xy 438.306718 -355.825044) (xy 438.316878 -355.825519)
			(xy 438.335648 -355.8333) (xy 438.350013 -355.847672) (xy 438.357786 -355.866446) (xy 438.35828 -355.876606)
			(xy 438.35828 -356.613206) (xy 440.167776 -356.613206) (xy 440.167776 -355.876606) (xy 440.16817 -355.86643)
			(xy 440.17596 -355.847628) (xy 440.190355 -355.833242) (xy 440.209162 -355.825463) (xy 440.219338 -355.825044)
			(xy 440.462162 -355.825044) (xy 440.791854 -356.041198) (xy 440.802907 -356.046662) (xy 440.827522 -356.047345)
			(xy 440.838844 -356.042468) (xy 441.153804 -355.837236) (xy 441.160154 -355.833172) (xy 441.160662 -355.832664)
			(xy 441.172854 -355.825044) (xy 441.415678 -355.825044) (xy 441.425849 -355.825482) (xy 441.444644 -355.833261)
			(xy 441.45903 -355.847642) (xy 441.466815 -355.866435) (xy 441.46724 -355.876606) (xy 441.46724 -356.613206)
			(xy 441.46684 -356.623381) (xy 441.459049 -356.64218) (xy 441.444656 -356.656565) (xy 441.425853 -356.664346)
			(xy 441.415678 -356.664768) (xy 441.172854 -356.664768) (xy 440.84113 -356.448106) (xy 440.829991 -356.443069)
			(xy 440.805583 -356.442929) (xy 440.794394 -356.447852) (xy 440.463432 -356.664768) (xy 440.219338 -356.664768)
			(xy 440.20917 -356.664305) (xy 440.190377 -356.656534) (xy 440.175991 -356.64216) (xy 440.168204 -356.623374)
			(xy 440.167776 -356.613206) (xy 438.35828 -356.613206) (xy 438.357772 -356.623362) (xy 438.349999 -356.642128)
			(xy 438.335638 -356.656492) (xy 438.316874 -356.664269) (xy 438.306718 -356.664768) (xy 438.063894 -356.664768)
			(xy 437.73217 -356.448106) (xy 437.721045 -356.443029) (xy 437.696624 -356.442915) (xy 437.685434 -356.447852)
			(xy 437.354472 -356.664768) (xy 437.110378 -356.664768) (xy 437.10022 -356.664285) (xy 437.081451 -356.656504)
			(xy 437.067087 -356.642136) (xy 437.059312 -356.623365) (xy 437.058816 -356.613206) (xy 435.24932 -356.613206)
			(xy 435.24894 -356.623383) (xy 435.241145 -356.642186) (xy 435.226746 -356.656572) (xy 435.207936 -356.664349)
			(xy 435.197758 -356.664768) (xy 434.954934 -356.664768) (xy 434.62321 -356.448106) (xy 434.612075 -356.443056)
			(xy 434.587664 -356.442924) (xy 434.576474 -356.447852) (xy 434.245512 -356.664768) (xy 434.001418 -356.664768)
			(xy 433.991248 -356.664322) (xy 433.972455 -356.656544) (xy 433.95807 -356.642165) (xy 433.950283 -356.623376)
			(xy 433.949856 -356.613206) (xy 432.14036 -356.613206) (xy 432.139871 -356.623364) (xy 432.132095 -356.642134)
			(xy 432.117727 -356.656499) (xy 432.098956 -356.664273) (xy 432.088798 -356.664768) (xy 431.845974 -356.664768)
			(xy 431.51425 -356.448106) (xy 431.503106 -356.443083) (xy 431.478703 -356.442934) (xy 431.467514 -356.447852)
			(xy 431.136552 -356.664768) (xy 430.892458 -356.664768) (xy 430.882298 -356.664301) (xy 430.863529 -356.656514)
			(xy 430.849166 -356.64214) (xy 430.841392 -356.623366) (xy 430.840896 -356.613206) (xy 429.0314 -356.613206)
			(xy 429.030872 -356.623359) (xy 429.023103 -356.642121) (xy 429.008748 -356.656485) (xy 428.989991 -356.664266)
			(xy 428.979838 -356.664768) (xy 428.737014 -356.664768) (xy 428.40529 -356.448106) (xy 428.39416 -356.443043)
			(xy 428.369744 -356.44292) (xy 428.358554 -356.447852) (xy 428.027592 -356.664768) (xy 427.783498 -356.664768)
			(xy 427.773341 -356.664268) (xy 427.754573 -356.656494) (xy 427.740208 -356.642131) (xy 427.732432 -356.623363)
			(xy 427.731936 -356.613206) (xy 425.92244 -356.613206) (xy 425.92204 -356.623381) (xy 425.914249 -356.64218)
			(xy 425.899856 -356.656565) (xy 425.881053 -356.664346) (xy 425.870878 -356.664768) (xy 425.628054 -356.664768)
			(xy 425.29633 -356.448106) (xy 425.285191 -356.443069) (xy 425.260783 -356.442929) (xy 425.249594 -356.447852)
			(xy 424.918632 -356.664768) (xy 424.674538 -356.664768) (xy 424.66437 -356.664305) (xy 424.645577 -356.656534)
			(xy 424.631191 -356.64216) (xy 424.623404 -356.623374) (xy 424.622976 -356.613206) (xy 422.81348 -356.613206)
			(xy 422.812972 -356.623362) (xy 422.805199 -356.642128) (xy 422.790838 -356.656492) (xy 422.772074 -356.664269)
			(xy 422.761918 -356.664768) (xy 422.519094 -356.664768) (xy 422.18737 -356.448106) (xy 422.176245 -356.443029)
			(xy 422.151824 -356.442915) (xy 422.140634 -356.447852) (xy 421.809672 -356.664768) (xy 421.565578 -356.664768)
			(xy 421.55542 -356.664285) (xy 421.536651 -356.656504) (xy 421.522287 -356.642136) (xy 421.514512 -356.623365)
			(xy 421.514016 -356.613206) (xy 419.70452 -356.613206) (xy 419.70414 -356.623383) (xy 419.696345 -356.642186)
			(xy 419.681946 -356.656572) (xy 419.663136 -356.664349) (xy 419.652958 -356.664768) (xy 419.410134 -356.664768)
			(xy 419.07841 -356.448106) (xy 419.067275 -356.443056) (xy 419.042864 -356.442924) (xy 419.031674 -356.447852)
			(xy 418.700712 -356.664768) (xy 418.456618 -356.664768) (xy 418.446448 -356.664322) (xy 418.427655 -356.656544)
			(xy 418.41327 -356.642165) (xy 418.405483 -356.623376) (xy 418.405056 -356.613206) (xy 416.59556 -356.613206)
			(xy 416.595071 -356.623364) (xy 416.587295 -356.642134) (xy 416.572927 -356.656499) (xy 416.554156 -356.664273)
			(xy 416.543998 -356.664768) (xy 416.301174 -356.664768) (xy 415.96945 -356.448106) (xy 415.958306 -356.443083)
			(xy 415.933903 -356.442934) (xy 415.922714 -356.447852) (xy 415.591752 -356.664768) (xy 415.347658 -356.664768)
			(xy 415.337498 -356.664301) (xy 415.318729 -356.656514) (xy 415.304366 -356.64214) (xy 415.296592 -356.623366)
			(xy 415.296096 -356.613206) (xy 413.4866 -356.613206) (xy 413.486072 -356.623359) (xy 413.478303 -356.642121)
			(xy 413.463948 -356.656485) (xy 413.445191 -356.664266) (xy 413.435038 -356.664768) (xy 413.192214 -356.664768)
			(xy 412.86049 -356.448106) (xy 412.84936 -356.443043) (xy 412.824944 -356.44292) (xy 412.813754 -356.447852)
			(xy 412.482792 -356.664768) (xy 412.238698 -356.664768) (xy 412.228541 -356.664268) (xy 412.209773 -356.656494)
			(xy 412.195408 -356.642131) (xy 412.187632 -356.623363) (xy 412.187136 -356.613206) (xy 403.360128 -356.613206)
			(xy 403.35974 -356.623382) (xy 403.351947 -356.642184) (xy 403.33755 -356.656569) (xy 403.318743 -356.664348)
			(xy 403.308566 -356.664768) (xy 403.065742 -356.664768) (xy 402.734018 -356.448106) (xy 402.722882 -356.443061)
			(xy 402.698471 -356.442926) (xy 402.687282 -356.447852) (xy 402.35632 -356.664768) (xy 402.112226 -356.664768)
			(xy 402.102057 -356.664315) (xy 402.083264 -356.65654) (xy 402.068878 -356.642163) (xy 402.061091 -356.623375)
			(xy 402.060664 -356.613206) (xy 400.251168 -356.613206) (xy 400.250672 -356.623363) (xy 400.242896 -356.642131)
			(xy 400.228531 -356.656496) (xy 400.209763 -356.664272) (xy 400.199606 -356.664768) (xy 399.956782 -356.664768)
			(xy 399.625058 -356.448106) (xy 399.613912 -356.443088) (xy 399.589511 -356.442936) (xy 399.578322 -356.447852)
			(xy 399.24736 -356.664768) (xy 399.003266 -356.664768) (xy 398.993107 -356.664295) (xy 398.974338 -356.65651)
			(xy 398.959974 -356.642138) (xy 398.9522 -356.623365) (xy 398.951704 -356.613206) (xy 397.142208 -356.613206)
			(xy 397.141673 -356.623358) (xy 397.133905 -356.642119) (xy 397.119552 -356.656482) (xy 397.100798 -356.664265)
			(xy 397.090646 -356.664768) (xy 396.847822 -356.664768) (xy 396.516098 -356.448106) (xy 396.504966 -356.443048)
			(xy 396.480552 -356.442922) (xy 396.469362 -356.447852) (xy 396.1384 -356.664768) (xy 395.894306 -356.664768)
			(xy 395.884149 -356.664262) (xy 395.865381 -356.656491) (xy 395.851016 -356.642129) (xy 395.843241 -356.623363)
			(xy 395.842744 -356.613206) (xy 394.033248 -356.613206) (xy 394.032841 -356.62338) (xy 394.025051 -356.642177)
			(xy 394.01066 -356.656562) (xy 393.99186 -356.664345) (xy 393.981686 -356.664768) (xy 393.738862 -356.664768)
			(xy 393.407138 -356.448106) (xy 393.395997 -356.443075) (xy 393.371591 -356.442932) (xy 393.360402 -356.447852)
			(xy 393.02944 -356.664768) (xy 392.785346 -356.664768) (xy 392.775178 -356.664299) (xy 392.756386 -356.65653)
			(xy 392.741999 -356.642158) (xy 392.734212 -356.623373) (xy 392.733784 -356.613206) (xy 390.924288 -356.613206)
			(xy 390.923772 -356.623361) (xy 390.916 -356.642125) (xy 390.901642 -356.656489) (xy 390.882881 -356.664268)
			(xy 390.872726 -356.664768) (xy 390.629902 -356.664768) (xy 390.298178 -356.448106) (xy 390.287051 -356.443035)
			(xy 390.262632 -356.442917) (xy 390.251442 -356.447852) (xy 389.92048 -356.664768) (xy 389.676386 -356.664768)
			(xy 389.666228 -356.664278) (xy 389.64746 -356.6565) (xy 389.633095 -356.642133) (xy 389.62532 -356.623364)
			(xy 389.624824 -356.613206) (xy 387.815328 -356.613206) (xy 387.81494 -356.623382) (xy 387.807147 -356.642184)
			(xy 387.79275 -356.656569) (xy 387.773943 -356.664348) (xy 387.763766 -356.664768) (xy 387.520942 -356.664768)
			(xy 387.189218 -356.448106) (xy 387.178082 -356.443061) (xy 387.153671 -356.442926) (xy 387.142482 -356.447852)
			(xy 386.81152 -356.664768) (xy 386.567426 -356.664768) (xy 386.557257 -356.664315) (xy 386.538464 -356.65654)
			(xy 386.524078 -356.642163) (xy 386.516291 -356.623375) (xy 386.515864 -356.613206) (xy 384.706368 -356.613206)
			(xy 384.705872 -356.623363) (xy 384.698096 -356.642131) (xy 384.683731 -356.656496) (xy 384.664963 -356.664272)
			(xy 384.654806 -356.664768) (xy 384.411982 -356.664768) (xy 384.080258 -356.448106) (xy 384.069112 -356.443088)
			(xy 384.044711 -356.442936) (xy 384.033522 -356.447852) (xy 383.70256 -356.664768) (xy 383.458466 -356.664768)
			(xy 383.448307 -356.664295) (xy 383.429538 -356.65651) (xy 383.415174 -356.642138) (xy 383.4074 -356.623365)
			(xy 383.406904 -356.613206) (xy 381.597408 -356.613206) (xy 381.596873 -356.623358) (xy 381.589105 -356.642119)
			(xy 381.574752 -356.656482) (xy 381.555998 -356.664265) (xy 381.545846 -356.664768) (xy 381.303022 -356.664768)
			(xy 380.971298 -356.448106) (xy 380.960166 -356.443048) (xy 380.935752 -356.442922) (xy 380.924562 -356.447852)
			(xy 380.5936 -356.664768) (xy 380.349506 -356.664768) (xy 380.339349 -356.664262) (xy 380.320581 -356.656491)
			(xy 380.306216 -356.642129) (xy 380.298441 -356.623363) (xy 380.297944 -356.613206) (xy 378.488448 -356.613206)
			(xy 378.488041 -356.62338) (xy 378.480251 -356.642177) (xy 378.46586 -356.656562) (xy 378.44706 -356.664345)
			(xy 378.436886 -356.664768) (xy 378.194062 -356.664768) (xy 377.862338 -356.448106) (xy 377.851197 -356.443075)
			(xy 377.826791 -356.442932) (xy 377.815602 -356.447852) (xy 377.48464 -356.664768) (xy 377.240546 -356.664768)
			(xy 377.230378 -356.664299) (xy 377.211586 -356.65653) (xy 377.197199 -356.642158) (xy 377.189412 -356.623373)
			(xy 377.188984 -356.613206) (xy 375.379488 -356.613206) (xy 375.378972 -356.623361) (xy 375.3712 -356.642125)
			(xy 375.356842 -356.656489) (xy 375.338081 -356.664268) (xy 375.327926 -356.664768) (xy 375.085102 -356.664768)
			(xy 374.753378 -356.448106) (xy 374.742251 -356.443035) (xy 374.717832 -356.442917) (xy 374.706642 -356.447852)
			(xy 374.37568 -356.664768) (xy 374.131586 -356.664768) (xy 374.121428 -356.664278) (xy 374.10266 -356.6565)
			(xy 374.088295 -356.642133) (xy 374.08052 -356.623364) (xy 374.080024 -356.613206) (xy 344.674952 -356.613206)
			(xy 344.674541 -356.623379) (xy 344.666752 -356.642176) (xy 344.652363 -356.656561) (xy 344.633563 -356.664344)
			(xy 344.62339 -356.664768) (xy 344.380566 -356.664768) (xy 344.048842 -356.448106) (xy 344.0377 -356.443077)
			(xy 344.013295 -356.442932) (xy 344.002106 -356.447852) (xy 343.671144 -356.664768) (xy 343.42705 -356.664768)
			(xy 343.416882 -356.664295) (xy 343.39809 -356.656528) (xy 343.383703 -356.642157) (xy 343.375916 -356.623373)
			(xy 343.375488 -356.613206) (xy 341.565992 -356.613206) (xy 341.565472 -356.62336) (xy 341.557701 -356.642124)
			(xy 341.543344 -356.656488) (xy 341.524584 -356.664267) (xy 341.51443 -356.664768) (xy 341.271606 -356.664768)
			(xy 340.939882 -356.448106) (xy 340.928754 -356.443037) (xy 340.904336 -356.442918) (xy 340.893146 -356.447852)
			(xy 340.562184 -356.664768) (xy 340.31809 -356.664768) (xy 340.307932 -356.664275) (xy 340.289164 -356.656498)
			(xy 340.2748 -356.642132) (xy 340.267024 -356.623364) (xy 340.266528 -356.613206) (xy 338.457032 -356.613206)
			(xy 338.45664 -356.623382) (xy 338.448848 -356.642182) (xy 338.434452 -356.656568) (xy 338.415646 -356.664347)
			(xy 338.40547 -356.664768) (xy 338.162646 -356.664768) (xy 337.830922 -356.448106) (xy 337.819785 -356.443064)
			(xy 337.795375 -356.442927) (xy 337.784186 -356.447852) (xy 337.453224 -356.664768) (xy 337.20913 -356.664768)
			(xy 337.198961 -356.664312) (xy 337.180168 -356.656538) (xy 337.165783 -356.642162) (xy 337.157996 -356.623375)
			(xy 337.157568 -356.613206) (xy 335.348072 -356.613206) (xy 335.347572 -356.623363) (xy 335.339797 -356.64213)
			(xy 335.325434 -356.656495) (xy 335.306667 -356.664271) (xy 335.29651 -356.664768) (xy 335.053686 -356.664768)
			(xy 334.721962 -356.448106) (xy 334.710815 -356.443091) (xy 334.686415 -356.442937) (xy 334.675226 -356.447852)
			(xy 334.344264 -356.664768) (xy 334.10017 -356.664768) (xy 334.090011 -356.664291) (xy 334.071242 -356.656508)
			(xy 334.056878 -356.642138) (xy 334.049104 -356.623365) (xy 334.048608 -356.613206) (xy 332.239112 -356.613206)
			(xy 332.23874 -356.623384) (xy 332.230944 -356.642189) (xy 332.216541 -356.656575) (xy 332.197729 -356.664351)
			(xy 332.18755 -356.664768) (xy 331.944726 -356.664768) (xy 331.613002 -356.448106) (xy 331.601869 -356.443051)
			(xy 331.577456 -356.442923) (xy 331.566266 -356.447852) (xy 331.235304 -356.664768) (xy 330.99121 -356.664768)
			(xy 330.98104 -356.664328) (xy 330.962246 -356.656548) (xy 330.947861 -356.642167) (xy 330.940075 -356.623376)
			(xy 330.939648 -356.613206) (xy 329.130152 -356.613206) (xy 329.129741 -356.623379) (xy 329.121952 -356.642176)
			(xy 329.107563 -356.656561) (xy 329.088763 -356.664344) (xy 329.07859 -356.664768) (xy 328.835766 -356.664768)
			(xy 328.504042 -356.448106) (xy 328.4929 -356.443077) (xy 328.468495 -356.442932) (xy 328.457306 -356.447852)
			(xy 328.126344 -356.664768) (xy 327.88225 -356.664768) (xy 327.872082 -356.664295) (xy 327.85329 -356.656528)
			(xy 327.838903 -356.642157) (xy 327.831116 -356.623373) (xy 327.830688 -356.613206) (xy 326.021192 -356.613206)
			(xy 326.020672 -356.62336) (xy 326.012901 -356.642124) (xy 325.998544 -356.656488) (xy 325.979784 -356.664267)
			(xy 325.96963 -356.664768) (xy 325.726806 -356.664768) (xy 325.395082 -356.448106) (xy 325.383954 -356.443037)
			(xy 325.359536 -356.442918) (xy 325.348346 -356.447852) (xy 325.017384 -356.664768) (xy 324.77329 -356.664768)
			(xy 324.763132 -356.664275) (xy 324.744364 -356.656498) (xy 324.73 -356.642132) (xy 324.722224 -356.623364)
			(xy 324.721728 -356.613206) (xy 322.912232 -356.613206) (xy 322.91184 -356.623382) (xy 322.904048 -356.642182)
			(xy 322.889652 -356.656568) (xy 322.870846 -356.664347) (xy 322.86067 -356.664768) (xy 322.617846 -356.664768)
			(xy 322.286122 -356.448106) (xy 322.274985 -356.443064) (xy 322.250575 -356.442927) (xy 322.239386 -356.447852)
			(xy 321.908424 -356.664768) (xy 321.66433 -356.664768) (xy 321.654161 -356.664312) (xy 321.635368 -356.656538)
			(xy 321.620983 -356.642162) (xy 321.613196 -356.623375) (xy 321.612768 -356.613206) (xy 319.803272 -356.613206)
			(xy 319.802772 -356.623363) (xy 319.794997 -356.64213) (xy 319.780634 -356.656495) (xy 319.761867 -356.664271)
			(xy 319.75171 -356.664768) (xy 319.508886 -356.664768) (xy 319.177162 -356.448106) (xy 319.166015 -356.443091)
			(xy 319.141615 -356.442937) (xy 319.130426 -356.447852) (xy 318.799464 -356.664768) (xy 318.55537 -356.664768)
			(xy 318.545211 -356.664291) (xy 318.526442 -356.656508) (xy 318.512078 -356.642138) (xy 318.504304 -356.623365)
			(xy 318.503808 -356.613206) (xy 316.694312 -356.613206) (xy 316.69394 -356.623384) (xy 316.686144 -356.642189)
			(xy 316.671741 -356.656575) (xy 316.652929 -356.664351) (xy 316.64275 -356.664768) (xy 316.399926 -356.664768)
			(xy 316.068202 -356.448106) (xy 316.057069 -356.443051) (xy 316.032656 -356.442923) (xy 316.021466 -356.447852)
			(xy 315.690504 -356.664768) (xy 315.44641 -356.664768) (xy 315.43624 -356.664328) (xy 315.417446 -356.656548)
			(xy 315.403061 -356.642167) (xy 315.395275 -356.623376) (xy 315.394848 -356.613206) (xy 300.069504 -356.613206)
			(xy 300.069036 -356.623404) (xy 300.06121 -356.64224) (xy 300.046757 -356.656632) (xy 300.027888 -356.664379)
			(xy 300.017688 -356.664768) (xy 299.774864 -356.664768) (xy 299.44314 -356.448106) (xy 299.431998 -356.443076)
			(xy 299.407593 -356.442932) (xy 299.396404 -356.447852) (xy 299.065442 -356.664768) (xy 298.821348 -356.664768)
			(xy 298.811169 -356.664284) (xy 298.792347 -356.656525) (xy 298.777917 -356.642166) (xy 298.770066 -356.623383)
			(xy 298.769532 -356.613206) (xy 296.960544 -356.613206) (xy 296.960135 -356.623412) (xy 296.952297 -356.642259)
			(xy 296.937825 -356.656653) (xy 296.918936 -356.664389) (xy 296.908728 -356.664768) (xy 296.665904 -356.664768)
			(xy 296.33418 -356.448106) (xy 296.323053 -356.443036) (xy 296.298634 -356.442917) (xy 296.287444 -356.447852)
			(xy 295.956482 -356.664768) (xy 295.712388 -356.664768) (xy 295.702205 -356.664333) (xy 295.683382 -356.656555)
			(xy 295.668954 -356.642181) (xy 295.661105 -356.623387) (xy 295.660572 -356.613206) (xy 293.851584 -356.613206)
			(xy 293.851136 -356.623407) (xy 293.843306 -356.642246) (xy 293.828846 -356.656639) (xy 293.809971 -356.664382)
			(xy 293.799768 -356.664768) (xy 293.556944 -356.664768) (xy 293.22522 -356.448106) (xy 293.214083 -356.443062)
			(xy 293.189673 -356.442927) (xy 293.178484 -356.447852) (xy 292.847522 -356.664768) (xy 292.603428 -356.664768)
			(xy 292.593247 -356.664301) (xy 292.574426 -356.656536) (xy 292.559996 -356.642171) (xy 292.552145 -356.623384)
			(xy 292.551612 -356.613206) (xy 290.742624 -356.613206) (xy 290.742235 -356.623414) (xy 290.734393 -356.642265)
			(xy 290.719915 -356.65666) (xy 290.701019 -356.664393) (xy 290.690808 -356.664768) (xy 290.447984 -356.664768)
			(xy 290.11626 -356.448106) (xy 290.105113 -356.443089) (xy 290.080713 -356.442937) (xy 290.069524 -356.447852)
			(xy 289.738562 -356.664768) (xy 289.494468 -356.664768) (xy 289.484283 -356.66435) (xy 289.46546 -356.656565)
			(xy 289.451033 -356.642186) (xy 289.443185 -356.623389) (xy 289.442652 -356.613206) (xy 287.633664 -356.613206)
			(xy 287.633235 -356.623409) (xy 287.625401 -356.642253) (xy 287.610936 -356.656646) (xy 287.592053 -356.664386)
			(xy 287.581848 -356.664768) (xy 287.339024 -356.664768) (xy 287.0073 -356.448106) (xy 286.996168 -356.443049)
			(xy 286.971754 -356.442922) (xy 286.960564 -356.447852) (xy 286.629602 -356.664768) (xy 286.385508 -356.664768)
			(xy 286.375326 -356.664317) (xy 286.356504 -356.656545) (xy 286.342075 -356.642176) (xy 286.334225 -356.623386)
			(xy 286.333692 -356.613206) (xy 284.524704 -356.613206) (xy 284.524236 -356.623404) (xy 284.51641 -356.64224)
			(xy 284.501957 -356.656632) (xy 284.483088 -356.664379) (xy 284.472888 -356.664768) (xy 284.230064 -356.664768)
			(xy 283.89834 -356.448106) (xy 283.887198 -356.443076) (xy 283.862793 -356.442932) (xy 283.851604 -356.447852)
			(xy 283.520642 -356.664768) (xy 283.276548 -356.664768) (xy 283.266369 -356.664284) (xy 283.247547 -356.656525)
			(xy 283.233117 -356.642166) (xy 283.225266 -356.623383) (xy 283.224732 -356.613206) (xy 281.415744 -356.613206)
			(xy 281.415335 -356.623412) (xy 281.407497 -356.642259) (xy 281.393025 -356.656653) (xy 281.374136 -356.664389)
			(xy 281.363928 -356.664768) (xy 281.121104 -356.664768) (xy 280.78938 -356.448106) (xy 280.778253 -356.443036)
			(xy 280.753834 -356.442917) (xy 280.742644 -356.447852) (xy 280.411682 -356.664768) (xy 280.167588 -356.664768)
			(xy 280.157405 -356.664333) (xy 280.138582 -356.656555) (xy 280.124154 -356.642181) (xy 280.116305 -356.623387)
			(xy 280.115772 -356.613206) (xy 278.306784 -356.613206) (xy 278.306336 -356.623407) (xy 278.298506 -356.642246)
			(xy 278.284046 -356.656639) (xy 278.265171 -356.664382) (xy 278.254968 -356.664768) (xy 278.012144 -356.664768)
			(xy 277.68042 -356.448106) (xy 277.669283 -356.443062) (xy 277.644873 -356.442927) (xy 277.633684 -356.447852)
			(xy 277.302722 -356.664768) (xy 277.058628 -356.664768) (xy 277.048447 -356.664301) (xy 277.029626 -356.656536)
			(xy 277.015196 -356.642171) (xy 277.007345 -356.623384) (xy 277.006812 -356.613206) (xy 275.197824 -356.613206)
			(xy 275.197435 -356.623414) (xy 275.189593 -356.642265) (xy 275.175115 -356.65666) (xy 275.156219 -356.664393)
			(xy 275.146008 -356.664768) (xy 274.903184 -356.664768) (xy 274.57146 -356.448106) (xy 274.560313 -356.443089)
			(xy 274.535913 -356.442937) (xy 274.524724 -356.447852) (xy 274.193762 -356.664768) (xy 273.949668 -356.664768)
			(xy 273.939483 -356.66435) (xy 273.92066 -356.656565) (xy 273.906233 -356.642186) (xy 273.898385 -356.623389)
			(xy 273.897852 -356.613206) (xy 272.088864 -356.613206) (xy 272.088435 -356.623409) (xy 272.080601 -356.642253)
			(xy 272.066136 -356.656646) (xy 272.047253 -356.664386) (xy 272.037048 -356.664768) (xy 271.794224 -356.664768)
			(xy 271.4625 -356.448106) (xy 271.451368 -356.443049) (xy 271.426954 -356.442922) (xy 271.415764 -356.447852)
			(xy 271.084802 -356.664768) (xy 270.840708 -356.664768) (xy 270.830526 -356.664317) (xy 270.811704 -356.656545)
			(xy 270.797275 -356.642176) (xy 270.789425 -356.623386) (xy 270.788892 -356.613206) (xy 188.134202 -356.613206)
			(xy 188.132102 -356.618267) (xy 188.117723 -356.632632) (xy 188.098941 -356.640401) (xy 188.088778 -356.640892)
			(xy 187.845954 -356.640892) (xy 187.51423 -356.42423) (xy 187.503091 -356.419192) (xy 187.478683 -356.419052)
			(xy 187.467494 -356.423976) (xy 187.136532 -356.640892) (xy 186.892438 -356.640892) (xy 186.882273 -356.640406)
			(xy 186.863484 -356.632639) (xy 186.849099 -356.618273) (xy 186.841308 -356.599495) (xy 186.840876 -356.58933)
			(xy 185.03138 -356.58933) (xy 185.030892 -356.599487) (xy 185.023111 -356.618254) (xy 185.008744 -356.632617)
			(xy 184.989976 -356.640394) (xy 184.979818 -356.640892) (xy 184.736994 -356.640892) (xy 184.40527 -356.42423)
			(xy 184.394145 -356.419152) (xy 184.369724 -356.419037) (xy 184.358534 -356.423976) (xy 184.027572 -356.640892)
			(xy 183.783478 -356.640892) (xy 183.773322 -356.640386) (xy 183.754559 -356.632609) (xy 183.740195 -356.618248)
			(xy 183.732416 -356.599485) (xy 183.731916 -356.58933) (xy 181.92242 -356.58933) (xy 181.92242 -356.613206)
			(xy 181.92204 -356.623383) (xy 181.914245 -356.642186) (xy 181.899846 -356.656572) (xy 181.881036 -356.664349)
			(xy 181.870858 -356.664768) (xy 181.628034 -356.664768) (xy 181.29631 -356.448106) (xy 181.285175 -356.443056)
			(xy 181.260764 -356.442924) (xy 181.249574 -356.447852) (xy 180.918612 -356.664768) (xy 180.674518 -356.664768)
			(xy 180.664348 -356.664322) (xy 180.645555 -356.656544) (xy 180.63117 -356.642165) (xy 180.623383 -356.623376)
			(xy 180.622956 -356.613206) (xy 178.81346 -356.613206) (xy 178.812971 -356.623364) (xy 178.805195 -356.642134)
			(xy 178.790827 -356.656499) (xy 178.772056 -356.664273) (xy 178.761898 -356.664768) (xy 178.519074 -356.664768)
			(xy 178.18735 -356.448106) (xy 178.176206 -356.443083) (xy 178.151803 -356.442934) (xy 178.140614 -356.447852)
			(xy 177.809652 -356.664768) (xy 177.565558 -356.664768) (xy 177.555398 -356.664301) (xy 177.536629 -356.656514)
			(xy 177.522266 -356.64214) (xy 177.514492 -356.623366) (xy 177.513996 -356.613206) (xy 175.7045 -356.613206)
			(xy 175.703972 -356.623359) (xy 175.696203 -356.642121) (xy 175.681848 -356.656485) (xy 175.663091 -356.664266)
			(xy 175.652938 -356.664768) (xy 175.410114 -356.664768) (xy 175.07839 -356.448106) (xy 175.06726 -356.443043)
			(xy 175.042844 -356.44292) (xy 175.031654 -356.447852) (xy 174.700692 -356.664768) (xy 174.456598 -356.664768)
			(xy 174.446441 -356.664268) (xy 174.427673 -356.656494) (xy 174.413308 -356.642131) (xy 174.405532 -356.623363)
			(xy 174.405036 -356.613206) (xy 172.59554 -356.613206) (xy 172.59514 -356.623381) (xy 172.587349 -356.64218)
			(xy 172.572956 -356.656565) (xy 172.554153 -356.664346) (xy 172.543978 -356.664768) (xy 172.301154 -356.664768)
			(xy 171.96943 -356.448106) (xy 171.958291 -356.443069) (xy 171.933883 -356.442929) (xy 171.922694 -356.447852)
			(xy 171.591732 -356.664768) (xy 171.347638 -356.664768) (xy 171.33747 -356.664305) (xy 171.318677 -356.656534)
			(xy 171.304291 -356.64216) (xy 171.296504 -356.623374) (xy 171.296076 -356.613206) (xy 169.48658 -356.613206)
			(xy 169.486072 -356.623362) (xy 169.478299 -356.642128) (xy 169.463938 -356.656492) (xy 169.445174 -356.664269)
			(xy 169.435018 -356.664768) (xy 169.192194 -356.664768) (xy 168.86047 -356.448106) (xy 168.849345 -356.443029)
			(xy 168.824924 -356.442915) (xy 168.813734 -356.447852) (xy 168.482772 -356.664768) (xy 168.238678 -356.664768)
			(xy 168.22852 -356.664285) (xy 168.209751 -356.656504) (xy 168.195387 -356.642136) (xy 168.187612 -356.623365)
			(xy 168.187116 -356.613206) (xy 166.37762 -356.613206) (xy 166.37724 -356.623383) (xy 166.369445 -356.642186)
			(xy 166.355046 -356.656572) (xy 166.336236 -356.664349) (xy 166.326058 -356.664768) (xy 166.083234 -356.664768)
			(xy 165.75151 -356.448106) (xy 165.740375 -356.443056) (xy 165.715964 -356.442924) (xy 165.704774 -356.447852)
			(xy 165.373812 -356.664768) (xy 165.129718 -356.664768) (xy 165.119548 -356.664322) (xy 165.100755 -356.656544)
			(xy 165.08637 -356.642165) (xy 165.078583 -356.623376) (xy 165.078156 -356.613206) (xy 163.26866 -356.613206)
			(xy 163.268171 -356.623364) (xy 163.260395 -356.642134) (xy 163.246027 -356.656499) (xy 163.227256 -356.664273)
			(xy 163.217098 -356.664768) (xy 162.974274 -356.664768) (xy 162.64255 -356.448106) (xy 162.631406 -356.443083)
			(xy 162.607003 -356.442934) (xy 162.595814 -356.447852) (xy 162.264852 -356.664768) (xy 162.020758 -356.664768)
			(xy 162.010598 -356.664301) (xy 161.991829 -356.656514) (xy 161.977466 -356.64214) (xy 161.969692 -356.623366)
			(xy 161.969196 -356.613206) (xy 160.1597 -356.613206) (xy 160.159172 -356.623359) (xy 160.151403 -356.642121)
			(xy 160.137048 -356.656485) (xy 160.118291 -356.664266) (xy 160.108138 -356.664768) (xy 159.865314 -356.664768)
			(xy 159.53359 -356.448106) (xy 159.52246 -356.443043) (xy 159.498044 -356.44292) (xy 159.486854 -356.447852)
			(xy 159.155892 -356.664768) (xy 158.911798 -356.664768) (xy 158.901641 -356.664268) (xy 158.882873 -356.656494)
			(xy 158.868508 -356.642131) (xy 158.860732 -356.623363) (xy 158.860236 -356.613206) (xy 144.034256 -356.613206)
			(xy 144.033771 -356.623365) (xy 144.025994 -356.642135) (xy 144.011625 -356.6565) (xy 143.992853 -356.664274)
			(xy 143.982694 -356.664768) (xy 143.73987 -356.664768) (xy 143.408146 -356.448106) (xy 143.397003 -356.44308)
			(xy 143.372599 -356.442933) (xy 143.36141 -356.447852) (xy 143.030448 -356.664768) (xy 142.786354 -356.664768)
			(xy 142.776194 -356.664304) (xy 142.757425 -356.656516) (xy 142.743062 -356.642141) (xy 142.735288 -356.623366)
			(xy 142.734792 -356.613206) (xy 140.925296 -356.613206) (xy 140.924772 -356.62336) (xy 140.917002 -356.642123)
			(xy 140.902646 -356.656486) (xy 140.883888 -356.664267) (xy 140.873734 -356.664768) (xy 140.63091 -356.664768)
			(xy 140.299186 -356.448106) (xy 140.288057 -356.44304) (xy 140.26364 -356.442919) (xy 140.25245 -356.447852)
			(xy 139.921488 -356.664768) (xy 139.677394 -356.664768) (xy 139.667237 -356.664272) (xy 139.648469 -356.656496)
			(xy 139.634104 -356.642131) (xy 139.626328 -356.623363) (xy 139.625832 -356.613206) (xy 137.816336 -356.613206)
			(xy 137.81594 -356.623381) (xy 137.808149 -356.642181) (xy 137.793754 -356.656567) (xy 137.774949 -356.664347)
			(xy 137.764774 -356.664768) (xy 137.52195 -356.664768) (xy 137.190226 -356.448106) (xy 137.179088 -356.443066)
			(xy 137.154679 -356.442928) (xy 137.14349 -356.447852) (xy 136.812528 -356.664768) (xy 136.568434 -356.664768)
			(xy 136.558265 -356.664308) (xy 136.539473 -356.656536) (xy 136.525087 -356.642161) (xy 136.5173 -356.623374)
			(xy 136.516872 -356.613206) (xy 134.707376 -356.613206) (xy 134.706872 -356.623362) (xy 134.699098 -356.642129)
			(xy 134.684736 -356.656493) (xy 134.66597 -356.66427) (xy 134.655814 -356.664768) (xy 134.41299 -356.664768)
			(xy 134.081266 -356.448106) (xy 134.070142 -356.443027) (xy 134.04572 -356.442914) (xy 134.03453 -356.447852)
			(xy 133.703568 -356.664768) (xy 133.459474 -356.664768) (xy 133.449315 -356.664288) (xy 133.430547 -356.656506)
			(xy 133.416182 -356.642137) (xy 133.408408 -356.623365) (xy 133.407912 -356.613206) (xy 131.598416 -356.613206)
			(xy 131.59804 -356.623384) (xy 131.590244 -356.642187) (xy 131.575844 -356.656574) (xy 131.557032 -356.66435)
			(xy 131.546854 -356.664768) (xy 131.30403 -356.664768) (xy 130.972306 -356.448106) (xy 130.961172 -356.443053)
			(xy 130.93676 -356.442924) (xy 130.92557 -356.447852) (xy 130.594608 -356.664768) (xy 130.350514 -356.664768)
			(xy 130.340344 -356.664325) (xy 130.321551 -356.656546) (xy 130.307166 -356.642166) (xy 130.299379 -356.623376)
			(xy 130.298952 -356.613206) (xy 128.489456 -356.613206) (xy 128.488971 -356.623365) (xy 128.481194 -356.642135)
			(xy 128.466825 -356.6565) (xy 128.448053 -356.664274) (xy 128.437894 -356.664768) (xy 128.19507 -356.664768)
			(xy 127.863346 -356.448106) (xy 127.852203 -356.44308) (xy 127.827799 -356.442933) (xy 127.81661 -356.447852)
			(xy 127.485648 -356.664768) (xy 127.241554 -356.664768) (xy 127.231394 -356.664304) (xy 127.212625 -356.656516)
			(xy 127.198262 -356.642141) (xy 127.190488 -356.623366) (xy 127.189992 -356.613206) (xy 125.380496 -356.613206)
			(xy 125.379972 -356.62336) (xy 125.372202 -356.642123) (xy 125.357846 -356.656486) (xy 125.339088 -356.664267)
			(xy 125.328934 -356.664768) (xy 125.08611 -356.664768) (xy 124.754386 -356.448106) (xy 124.743257 -356.44304)
			(xy 124.71884 -356.442919) (xy 124.70765 -356.447852) (xy 124.376688 -356.664768) (xy 124.132594 -356.664768)
			(xy 124.122437 -356.664272) (xy 124.103669 -356.656496) (xy 124.089304 -356.642131) (xy 124.081528 -356.623363)
			(xy 124.081032 -356.613206) (xy 122.271536 -356.613206) (xy 122.27114 -356.623381) (xy 122.263349 -356.642181)
			(xy 122.248954 -356.656567) (xy 122.230149 -356.664347) (xy 122.219974 -356.664768) (xy 121.97715 -356.664768)
			(xy 121.645426 -356.448106) (xy 121.634288 -356.443066) (xy 121.609879 -356.442928) (xy 121.59869 -356.447852)
			(xy 121.267728 -356.664768) (xy 121.023634 -356.664768) (xy 121.013465 -356.664308) (xy 120.994673 -356.656536)
			(xy 120.980287 -356.642161) (xy 120.9725 -356.623374) (xy 120.972072 -356.613206) (xy 119.162576 -356.613206)
			(xy 119.162072 -356.623362) (xy 119.154298 -356.642129) (xy 119.139936 -356.656493) (xy 119.12117 -356.66427)
			(xy 119.111014 -356.664768) (xy 118.86819 -356.664768) (xy 118.536466 -356.448106) (xy 118.525342 -356.443027)
			(xy 118.50092 -356.442914) (xy 118.48973 -356.447852) (xy 118.158768 -356.664768) (xy 117.914674 -356.664768)
			(xy 117.904515 -356.664288) (xy 117.885747 -356.656506) (xy 117.871382 -356.642137) (xy 117.863608 -356.623365)
			(xy 117.863112 -356.613206) (xy 116.053616 -356.613206) (xy 116.05324 -356.623384) (xy 116.045444 -356.642187)
			(xy 116.031044 -356.656574) (xy 116.012232 -356.66435) (xy 116.002054 -356.664768) (xy 115.75923 -356.664768)
			(xy 115.427506 -356.448106) (xy 115.416372 -356.443053) (xy 115.39196 -356.442924) (xy 115.38077 -356.447852)
			(xy 115.049808 -356.664768) (xy 114.805714 -356.664768) (xy 114.795544 -356.664325) (xy 114.776751 -356.656546)
			(xy 114.762366 -356.642166) (xy 114.754579 -356.623376) (xy 114.754152 -356.613206) (xy 93.544644 -356.613206)
			(xy 93.544235 -356.623412) (xy 93.536397 -356.642259) (xy 93.521925 -356.656653) (xy 93.503036 -356.664389)
			(xy 93.492828 -356.664768) (xy 93.250004 -356.664768) (xy 92.91828 -356.448106) (xy 92.907153 -356.443036)
			(xy 92.882734 -356.442917) (xy 92.871544 -356.447852) (xy 92.540582 -356.664768) (xy 92.296488 -356.664768)
			(xy 92.286305 -356.664333) (xy 92.267482 -356.656555) (xy 92.253054 -356.642181) (xy 92.245205 -356.623387)
			(xy 92.244672 -356.613206) (xy 90.435684 -356.613206) (xy 90.435236 -356.623407) (xy 90.427406 -356.642246)
			(xy 90.412946 -356.656639) (xy 90.394071 -356.664382) (xy 90.383868 -356.664768) (xy 90.141044 -356.664768)
			(xy 89.80932 -356.448106) (xy 89.798183 -356.443062) (xy 89.773773 -356.442927) (xy 89.762584 -356.447852)
			(xy 89.431622 -356.664768) (xy 89.187528 -356.664768) (xy 89.177347 -356.664301) (xy 89.158526 -356.656536)
			(xy 89.144096 -356.642171) (xy 89.136245 -356.623384) (xy 89.135712 -356.613206) (xy 87.326724 -356.613206)
			(xy 87.326335 -356.623414) (xy 87.318493 -356.642265) (xy 87.304015 -356.65666) (xy 87.285119 -356.664393)
			(xy 87.274908 -356.664768) (xy 87.032084 -356.664768) (xy 86.70036 -356.448106) (xy 86.689213 -356.443089)
			(xy 86.664813 -356.442937) (xy 86.653624 -356.447852) (xy 86.322662 -356.664768) (xy 86.078568 -356.664768)
			(xy 86.068383 -356.66435) (xy 86.04956 -356.656565) (xy 86.035133 -356.642186) (xy 86.027285 -356.623389)
			(xy 86.026752 -356.613206) (xy 84.217764 -356.613206) (xy 84.217335 -356.623409) (xy 84.209501 -356.642253)
			(xy 84.195036 -356.656646) (xy 84.176153 -356.664386) (xy 84.165948 -356.664768) (xy 83.923124 -356.664768)
			(xy 83.5914 -356.448106) (xy 83.580268 -356.443049) (xy 83.555854 -356.442922) (xy 83.544664 -356.447852)
			(xy 83.213702 -356.664768) (xy 82.969608 -356.664768) (xy 82.959426 -356.664317) (xy 82.940604 -356.656545)
			(xy 82.926175 -356.642176) (xy 82.918325 -356.623386) (xy 82.917792 -356.613206) (xy 81.108804 -356.613206)
			(xy 81.108336 -356.623404) (xy 81.10051 -356.64224) (xy 81.086057 -356.656632) (xy 81.067188 -356.664379)
			(xy 81.056988 -356.664768) (xy 80.814164 -356.664768) (xy 80.48244 -356.448106) (xy 80.471298 -356.443076)
			(xy 80.446893 -356.442932) (xy 80.435704 -356.447852) (xy 80.104742 -356.664768) (xy 79.860648 -356.664768)
			(xy 79.850469 -356.664284) (xy 79.831647 -356.656525) (xy 79.817217 -356.642166) (xy 79.809366 -356.623383)
			(xy 79.808832 -356.613206) (xy 77.999844 -356.613206) (xy 77.999435 -356.623412) (xy 77.991597 -356.642259)
			(xy 77.977125 -356.656653) (xy 77.958236 -356.664389) (xy 77.948028 -356.664768) (xy 77.705204 -356.664768)
			(xy 77.37348 -356.448106) (xy 77.362353 -356.443036) (xy 77.337934 -356.442917) (xy 77.326744 -356.447852)
			(xy 76.995782 -356.664768) (xy 76.751688 -356.664768) (xy 76.741505 -356.664333) (xy 76.722682 -356.656555)
			(xy 76.708254 -356.642181) (xy 76.700405 -356.623387) (xy 76.699872 -356.613206) (xy 74.890884 -356.613206)
			(xy 74.890436 -356.623407) (xy 74.882606 -356.642246) (xy 74.868146 -356.656639) (xy 74.849271 -356.664382)
			(xy 74.839068 -356.664768) (xy 74.596244 -356.664768) (xy 74.26452 -356.448106) (xy 74.253383 -356.443062)
			(xy 74.228973 -356.442927) (xy 74.217784 -356.447852) (xy 73.886822 -356.664768) (xy 73.642728 -356.664768)
			(xy 73.632547 -356.664301) (xy 73.613726 -356.656536) (xy 73.599296 -356.642171) (xy 73.591445 -356.623384)
			(xy 73.590912 -356.613206) (xy 71.781924 -356.613206) (xy 71.781535 -356.623414) (xy 71.773693 -356.642265)
			(xy 71.759215 -356.65666) (xy 71.740319 -356.664393) (xy 71.730108 -356.664768) (xy 71.487284 -356.664768)
			(xy 71.15556 -356.448106) (xy 71.144413 -356.443089) (xy 71.120013 -356.442937) (xy 71.108824 -356.447852)
			(xy 70.777862 -356.664768) (xy 70.533768 -356.664768) (xy 70.523583 -356.66435) (xy 70.50476 -356.656565)
			(xy 70.490333 -356.642186) (xy 70.482485 -356.623389) (xy 70.481952 -356.613206) (xy 68.672964 -356.613206)
			(xy 68.672535 -356.623409) (xy 68.664701 -356.642253) (xy 68.650236 -356.656646) (xy 68.631353 -356.664386)
			(xy 68.621148 -356.664768) (xy 68.378324 -356.664768) (xy 68.0466 -356.448106) (xy 68.035468 -356.443049)
			(xy 68.011054 -356.442922) (xy 67.999864 -356.447852) (xy 67.668902 -356.664768) (xy 67.424808 -356.664768)
			(xy 67.414626 -356.664317) (xy 67.395804 -356.656545) (xy 67.381375 -356.642176) (xy 67.373525 -356.623386)
			(xy 67.372992 -356.613206) (xy 65.564004 -356.613206) (xy 65.563536 -356.623404) (xy 65.55571 -356.64224)
			(xy 65.541257 -356.656632) (xy 65.522388 -356.664379) (xy 65.512188 -356.664768) (xy 65.269364 -356.664768)
			(xy 64.93764 -356.448106) (xy 64.926498 -356.443076) (xy 64.902093 -356.442932) (xy 64.890904 -356.447852)
			(xy 64.559942 -356.664768) (xy 64.315848 -356.664768) (xy 64.305669 -356.664284) (xy 64.286847 -356.656525)
			(xy 64.272417 -356.642166) (xy 64.264566 -356.623383) (xy 64.264032 -356.613206) (xy 51.504596 -356.613206)
			(xy 51.504072 -356.62336) (xy 51.496302 -356.642123) (xy 51.481946 -356.656486) (xy 51.463188 -356.664267)
			(xy 51.453034 -356.664768) (xy 51.21021 -356.664768) (xy 50.878486 -356.448106) (xy 50.867357 -356.44304)
			(xy 50.84294 -356.442919) (xy 50.83175 -356.447852) (xy 50.500788 -356.664768) (xy 50.256694 -356.664768)
			(xy 50.246537 -356.664272) (xy 50.227769 -356.656496) (xy 50.213404 -356.642131) (xy 50.205628 -356.623363)
			(xy 50.205132 -356.613206) (xy 48.395636 -356.613206) (xy 48.39524 -356.623381) (xy 48.387449 -356.642181)
			(xy 48.373054 -356.656567) (xy 48.354249 -356.664347) (xy 48.344074 -356.664768) (xy 48.10125 -356.664768)
			(xy 47.769526 -356.448106) (xy 47.758388 -356.443066) (xy 47.733979 -356.442928) (xy 47.72279 -356.447852)
			(xy 47.391828 -356.664768) (xy 47.147734 -356.664768) (xy 47.137565 -356.664308) (xy 47.118773 -356.656536)
			(xy 47.104387 -356.642161) (xy 47.0966 -356.623374) (xy 47.096172 -356.613206) (xy 45.286676 -356.613206)
			(xy 45.286172 -356.623362) (xy 45.278398 -356.642129) (xy 45.264036 -356.656493) (xy 45.24527 -356.66427)
			(xy 45.235114 -356.664768) (xy 44.99229 -356.664768) (xy 44.660566 -356.448106) (xy 44.649442 -356.443027)
			(xy 44.62502 -356.442914) (xy 44.61383 -356.447852) (xy 44.282868 -356.664768) (xy 44.038774 -356.664768)
			(xy 44.028615 -356.664288) (xy 44.009847 -356.656506) (xy 43.995482 -356.642137) (xy 43.987708 -356.623365)
			(xy 43.987212 -356.613206) (xy 42.177716 -356.613206) (xy 42.17734 -356.623384) (xy 42.169544 -356.642187)
			(xy 42.155144 -356.656574) (xy 42.136332 -356.66435) (xy 42.126154 -356.664768) (xy 41.88333 -356.664768)
			(xy 41.551606 -356.448106) (xy 41.540472 -356.443053) (xy 41.51606 -356.442924) (xy 41.50487 -356.447852)
			(xy 41.173908 -356.664768) (xy 40.929814 -356.664768) (xy 40.919644 -356.664325) (xy 40.900851 -356.656546)
			(xy 40.886466 -356.642166) (xy 40.878679 -356.623376) (xy 40.878252 -356.613206) (xy 39.068756 -356.613206)
			(xy 39.068271 -356.623365) (xy 39.060494 -356.642135) (xy 39.046125 -356.6565) (xy 39.027353 -356.664274)
			(xy 39.017194 -356.664768) (xy 38.77437 -356.664768) (xy 38.442646 -356.448106) (xy 38.431503 -356.44308)
			(xy 38.407099 -356.442933) (xy 38.39591 -356.447852) (xy 38.064948 -356.664768) (xy 37.820854 -356.664768)
			(xy 37.810694 -356.664304) (xy 37.791925 -356.656516) (xy 37.777562 -356.642141) (xy 37.769788 -356.623366)
			(xy 37.769292 -356.613206) (xy 35.959796 -356.613206) (xy 35.959272 -356.62336) (xy 35.951502 -356.642123)
			(xy 35.937146 -356.656486) (xy 35.918388 -356.664267) (xy 35.908234 -356.664768) (xy 35.66541 -356.664768)
			(xy 35.333686 -356.448106) (xy 35.322557 -356.44304) (xy 35.29814 -356.442919) (xy 35.28695 -356.447852)
			(xy 34.955988 -356.664768) (xy 34.711894 -356.664768) (xy 34.701737 -356.664272) (xy 34.682969 -356.656496)
			(xy 34.668604 -356.642131) (xy 34.660828 -356.623363) (xy 34.660332 -356.613206) (xy 32.850836 -356.613206)
			(xy 32.85044 -356.623381) (xy 32.842649 -356.642181) (xy 32.828254 -356.656567) (xy 32.809449 -356.664347)
			(xy 32.799274 -356.664768) (xy 32.55645 -356.664768) (xy 32.224726 -356.448106) (xy 32.213588 -356.443066)
			(xy 32.189179 -356.442928) (xy 32.17799 -356.447852) (xy 31.847028 -356.664768) (xy 31.602934 -356.664768)
			(xy 31.592765 -356.664308) (xy 31.573973 -356.656536) (xy 31.559587 -356.642161) (xy 31.5518 -356.623374)
			(xy 31.551372 -356.613206) (xy 29.741876 -356.613206) (xy 29.741372 -356.623362) (xy 29.733598 -356.642129)
			(xy 29.719236 -356.656493) (xy 29.70047 -356.66427) (xy 29.690314 -356.664768) (xy 29.44749 -356.664768)
			(xy 29.115766 -356.448106) (xy 29.104642 -356.443027) (xy 29.08022 -356.442914) (xy 29.06903 -356.447852)
			(xy 28.738068 -356.664768) (xy 28.493974 -356.664768) (xy 28.483815 -356.664288) (xy 28.465047 -356.656506)
			(xy 28.450682 -356.642137) (xy 28.442908 -356.623365) (xy 28.442412 -356.613206) (xy 26.632916 -356.613206)
			(xy 26.63254 -356.623384) (xy 26.624744 -356.642187) (xy 26.610344 -356.656574) (xy 26.591532 -356.66435)
			(xy 26.581354 -356.664768) (xy 26.33853 -356.664768) (xy 26.006806 -356.448106) (xy 25.995672 -356.443053)
			(xy 25.97126 -356.442924) (xy 25.96007 -356.447852) (xy 25.629108 -356.664768) (xy 25.385014 -356.664768)
			(xy 25.374844 -356.664325) (xy 25.356051 -356.656546) (xy 25.341666 -356.642166) (xy 25.333879 -356.623376)
			(xy 25.333452 -356.613206) (xy 23.523956 -356.613206) (xy 23.523471 -356.623365) (xy 23.515694 -356.642135)
			(xy 23.501325 -356.6565) (xy 23.482553 -356.664274) (xy 23.472394 -356.664768) (xy 23.22957 -356.664768)
			(xy 22.897846 -356.448106) (xy 22.886703 -356.44308) (xy 22.862299 -356.442933) (xy 22.85111 -356.447852)
			(xy 22.520148 -356.664768) (xy 22.276054 -356.664768) (xy 22.265894 -356.664304) (xy 22.247125 -356.656516)
			(xy 22.232762 -356.642141) (xy 22.224988 -356.623366) (xy 22.224492 -356.613206) (xy 0.509016 -356.613206)
			(xy 0.509016 -357.784969) (xy 22.060131 -357.784969) (xy 22.060131 -357.730431) (xy 22.067893 -357.676447)
			(xy 22.083259 -357.624118) (xy 22.105915 -357.574508) (xy 22.135401 -357.528628) (xy 22.171117 -357.487411)
			(xy 22.212334 -357.451696) (xy 22.258215 -357.422211) (xy 22.307826 -357.399556) (xy 22.360155 -357.384191)
			(xy 22.414139 -357.376431) (xy 22.441408 -357.375968) (xy 23.305008 -357.375968) (xy 23.332279 -357.376395)
			(xy 23.386266 -357.384158) (xy 23.438599 -357.399525) (xy 23.488212 -357.422184) (xy 23.534095 -357.451672)
			(xy 23.575315 -357.48739) (xy 23.611032 -357.528611) (xy 23.64052 -357.574495) (xy 23.663177 -357.624109)
			(xy 23.678543 -357.676442) (xy 23.686306 -357.730429) (xy 23.686306 -357.784966) (xy 25.169154 -357.784966)
			(xy 25.169154 -357.730434) (xy 25.176914 -357.676458) (xy 25.192277 -357.624135) (xy 25.214929 -357.574531)
			(xy 25.24441 -357.528655) (xy 25.280119 -357.487441) (xy 25.321329 -357.451729) (xy 25.367203 -357.422244)
			(xy 25.416805 -357.399588) (xy 25.469126 -357.384221) (xy 25.523102 -357.376457) (xy 25.550368 -357.375968)
			(xy 26.413968 -357.375968) (xy 26.441243 -357.376369) (xy 26.495237 -357.384128) (xy 26.547578 -357.399493)
			(xy 26.597199 -357.422151) (xy 26.64309 -357.45164) (xy 26.684317 -357.48736) (xy 26.720041 -357.528584)
			(xy 26.749534 -357.574473) (xy 26.772196 -357.624092) (xy 26.787565 -357.676431) (xy 26.795328 -357.730425)
			(xy 26.795328 -357.78497) (xy 28.278031 -357.78497) (xy 28.278032 -357.73043) (xy 28.285794 -357.676445)
			(xy 28.30116 -357.624114) (xy 28.323818 -357.574503) (xy 28.353306 -357.528621) (xy 28.389024 -357.487404)
			(xy 28.430244 -357.451689) (xy 28.476127 -357.422205) (xy 28.52574 -357.39955) (xy 28.578072 -357.384188)
			(xy 28.632058 -357.37643) (xy 28.659328 -357.375968) (xy 29.522928 -357.375968) (xy 29.550198 -357.376396)
			(xy 29.604183 -357.384162) (xy 29.656513 -357.399531) (xy 29.706124 -357.42219) (xy 29.752005 -357.451679)
			(xy 29.793222 -357.487397) (xy 29.828937 -357.528618) (xy 29.858423 -357.574501) (xy 29.881079 -357.624113)
			(xy 29.896444 -357.676444) (xy 29.904206 -357.73043) (xy 29.904206 -357.784967) (xy 31.387054 -357.784967)
			(xy 31.387054 -357.730433) (xy 31.394815 -357.676455) (xy 31.410179 -357.624131) (xy 31.432832 -357.574525)
			(xy 31.462315 -357.528648) (xy 31.498026 -357.487434) (xy 31.539239 -357.451722) (xy 31.585115 -357.422238)
			(xy 31.634719 -357.399583) (xy 31.687043 -357.384218) (xy 31.741021 -357.376455) (xy 31.768288 -357.375968)
			(xy 32.631888 -357.375968) (xy 32.659162 -357.376371) (xy 32.713154 -357.384132) (xy 32.765492 -357.399499)
			(xy 32.815111 -357.422157) (xy 32.861 -357.451647) (xy 32.902224 -357.487367) (xy 32.937946 -357.528591)
			(xy 32.967437 -357.574479) (xy 32.990097 -357.624096) (xy 33.005465 -357.676434) (xy 33.013228 -357.730426)
			(xy 33.013228 -357.784971) (xy 34.495932 -357.784971) (xy 34.495932 -357.730429) (xy 34.503694 -357.676442)
			(xy 34.519062 -357.62411) (xy 34.541721 -357.574497) (xy 34.571211 -357.528615) (xy 34.606931 -357.487397)
			(xy 34.648153 -357.451682) (xy 34.694039 -357.422198) (xy 34.743655 -357.399545) (xy 34.795989 -357.384184)
			(xy 34.849977 -357.376428) (xy 34.877248 -357.375968) (xy 35.740848 -357.375968) (xy 35.768117 -357.376398)
			(xy 35.8221 -357.384166) (xy 35.874428 -357.399536) (xy 35.924036 -357.422197) (xy 35.969914 -357.451687)
			(xy 36.011129 -357.487405) (xy 36.046842 -357.528624) (xy 36.076326 -357.574506) (xy 36.09898 -357.624117)
			(xy 36.114345 -357.676447) (xy 36.122106 -357.730431) (xy 36.122106 -357.784969) (xy 37.604931 -357.784969)
			(xy 37.604931 -357.730431) (xy 37.612693 -357.676447) (xy 37.628059 -357.624118) (xy 37.650715 -357.574508)
			(xy 37.680201 -357.528628) (xy 37.715917 -357.487411) (xy 37.757134 -357.451696) (xy 37.803015 -357.422211)
			(xy 37.852626 -357.399556) (xy 37.904955 -357.384191) (xy 37.958939 -357.376431) (xy 37.986208 -357.375968)
			(xy 38.849808 -357.375968) (xy 38.877079 -357.376395) (xy 38.931066 -357.384158) (xy 38.983399 -357.399525)
			(xy 39.033012 -357.422184) (xy 39.078895 -357.451672) (xy 39.120115 -357.48739) (xy 39.155832 -357.528611)
			(xy 39.18532 -357.574495) (xy 39.207977 -357.624109) (xy 39.223343 -357.676442) (xy 39.231106 -357.730429)
			(xy 39.231106 -357.784966) (xy 40.713954 -357.784966) (xy 40.713954 -357.730434) (xy 40.721714 -357.676458)
			(xy 40.737077 -357.624135) (xy 40.759729 -357.574531) (xy 40.78921 -357.528655) (xy 40.824919 -357.487441)
			(xy 40.866129 -357.451729) (xy 40.912003 -357.422244) (xy 40.961605 -357.399588) (xy 41.013926 -357.384221)
			(xy 41.067902 -357.376457) (xy 41.095168 -357.375968) (xy 41.958768 -357.375968) (xy 41.986043 -357.376369)
			(xy 42.040037 -357.384128) (xy 42.092378 -357.399493) (xy 42.141999 -357.422151) (xy 42.18789 -357.45164)
			(xy 42.229117 -357.48736) (xy 42.264841 -357.528584) (xy 42.294334 -357.574473) (xy 42.316996 -357.624092)
			(xy 42.332365 -357.676431) (xy 42.340128 -357.730425) (xy 42.340128 -357.78497) (xy 43.822831 -357.78497)
			(xy 43.822832 -357.73043) (xy 43.830594 -357.676445) (xy 43.84596 -357.624114) (xy 43.868618 -357.574503)
			(xy 43.898106 -357.528621) (xy 43.933824 -357.487404) (xy 43.975044 -357.451689) (xy 44.020927 -357.422205)
			(xy 44.07054 -357.39955) (xy 44.122872 -357.384188) (xy 44.176858 -357.37643) (xy 44.204128 -357.375968)
			(xy 45.067728 -357.375968) (xy 45.094998 -357.376396) (xy 45.148983 -357.384162) (xy 45.201313 -357.399531)
			(xy 45.250924 -357.42219) (xy 45.296805 -357.451679) (xy 45.338022 -357.487397) (xy 45.373737 -357.528618)
			(xy 45.403223 -357.574501) (xy 45.425879 -357.624113) (xy 45.441244 -357.676444) (xy 45.449006 -357.73043)
			(xy 45.449006 -357.784967) (xy 46.931854 -357.784967) (xy 46.931854 -357.730433) (xy 46.939615 -357.676455)
			(xy 46.954979 -357.624131) (xy 46.977632 -357.574525) (xy 47.007115 -357.528648) (xy 47.042826 -357.487434)
			(xy 47.084039 -357.451722) (xy 47.129915 -357.422238) (xy 47.179519 -357.399583) (xy 47.231843 -357.384218)
			(xy 47.285821 -357.376455) (xy 47.313088 -357.375968) (xy 48.176688 -357.375968) (xy 48.203962 -357.376371)
			(xy 48.257954 -357.384132) (xy 48.310292 -357.399499) (xy 48.359911 -357.422157) (xy 48.4058 -357.451647)
			(xy 48.447024 -357.487367) (xy 48.482746 -357.528591) (xy 48.512237 -357.574479) (xy 48.534897 -357.624096)
			(xy 48.550265 -357.676434) (xy 48.558028 -357.730426) (xy 48.558028 -357.784971) (xy 50.040732 -357.784971)
			(xy 50.040732 -357.730429) (xy 50.048494 -357.676442) (xy 50.063862 -357.62411) (xy 50.086521 -357.574497)
			(xy 50.116011 -357.528615) (xy 50.151731 -357.487397) (xy 50.192953 -357.451682) (xy 50.238839 -357.422198)
			(xy 50.288455 -357.399545) (xy 50.340789 -357.384184) (xy 50.394777 -357.376428) (xy 50.422048 -357.375968)
			(xy 51.285648 -357.375968) (xy 51.312917 -357.376398) (xy 51.3669 -357.384166) (xy 51.419228 -357.399536)
			(xy 51.468836 -357.422197) (xy 51.514714 -357.451687) (xy 51.555929 -357.487405) (xy 51.591642 -357.528624)
			(xy 51.621126 -357.574506) (xy 51.64378 -357.624117) (xy 51.659145 -357.676447) (xy 51.666906 -357.730431)
			(xy 51.666906 -357.784969) (xy 64.099931 -357.784969) (xy 64.099931 -357.730431) (xy 64.107693 -357.676448)
			(xy 64.123058 -357.62412) (xy 64.145714 -357.57451) (xy 64.1752 -357.52863) (xy 64.210914 -357.487413)
			(xy 64.252132 -357.451698) (xy 64.298012 -357.422213) (xy 64.347621 -357.399557) (xy 64.39995 -357.384193)
			(xy 64.453933 -357.376431) (xy 64.481202 -357.375968) (xy 65.344802 -357.375968) (xy 65.372073 -357.376395)
			(xy 65.426061 -357.384157) (xy 65.478394 -357.399524) (xy 65.528008 -357.422182) (xy 65.573893 -357.45167)
			(xy 65.615113 -357.487388) (xy 65.650831 -357.528609) (xy 65.680319 -357.574493) (xy 65.702977 -357.624107)
			(xy 65.718343 -357.676441) (xy 65.726106 -357.730429) (xy 65.726106 -357.784966) (xy 67.208954 -357.784966)
			(xy 67.208954 -357.730435) (xy 67.216714 -357.676458) (xy 67.232077 -357.624136) (xy 67.254728 -357.574532)
			(xy 67.284208 -357.528657) (xy 67.319917 -357.487443) (xy 67.361126 -357.451731) (xy 67.406999 -357.422246)
			(xy 67.4566 -357.39959) (xy 67.508921 -357.384222) (xy 67.562897 -357.376457) (xy 67.590162 -357.375968)
			(xy 68.453762 -357.375968) (xy 68.481037 -357.376369) (xy 68.535032 -357.384127) (xy 68.587373 -357.399491)
			(xy 68.636995 -357.422149) (xy 68.682887 -357.451638) (xy 68.724115 -357.487358) (xy 68.75984 -357.528582)
			(xy 68.789333 -357.574471) (xy 68.811995 -357.624091) (xy 68.827365 -357.676431) (xy 68.835128 -357.730425)
			(xy 68.835128 -357.78497) (xy 70.317831 -357.78497) (xy 70.317831 -357.73043) (xy 70.325594 -357.676446)
			(xy 70.34096 -357.624115) (xy 70.363617 -357.574505) (xy 70.393105 -357.528623) (xy 70.428822 -357.487406)
			(xy 70.470041 -357.451691) (xy 70.515924 -357.422207) (xy 70.565536 -357.399552) (xy 70.617867 -357.384189)
			(xy 70.671852 -357.37643) (xy 70.699122 -357.375968) (xy 71.562722 -357.375968) (xy 71.589992 -357.376396)
			(xy 71.643978 -357.384161) (xy 71.696309 -357.399529) (xy 71.74592 -357.422189) (xy 71.791802 -357.451677)
			(xy 71.83302 -357.487395) (xy 71.868736 -357.528616) (xy 71.898222 -357.574499) (xy 71.920878 -357.624112)
			(xy 71.936244 -357.676444) (xy 71.944006 -357.730429) (xy 71.944006 -357.784966) (xy 73.426854 -357.784966)
			(xy 73.426854 -357.730434) (xy 73.434615 -357.676456) (xy 73.449978 -357.624132) (xy 73.472631 -357.574527)
			(xy 73.502113 -357.52865) (xy 73.537824 -357.487436) (xy 73.579036 -357.451724) (xy 73.624911 -357.42224)
			(xy 73.674515 -357.399584) (xy 73.726838 -357.384219) (xy 73.780816 -357.376456) (xy 73.808082 -357.375968)
			(xy 74.671682 -357.375968) (xy 74.698956 -357.37637) (xy 74.752949 -357.384131) (xy 74.805288 -357.399497)
			(xy 74.854907 -357.422155) (xy 74.900797 -357.451645) (xy 74.942022 -357.487365) (xy 74.977744 -357.528589)
			(xy 75.007236 -357.574477) (xy 75.029897 -357.624095) (xy 75.045265 -357.676433) (xy 75.053028 -357.730426)
			(xy 75.053028 -357.784971) (xy 76.535732 -357.784971) (xy 76.535732 -357.730429) (xy 76.543494 -357.676443)
			(xy 76.558861 -357.624111) (xy 76.58152 -357.574499) (xy 76.611009 -357.528617) (xy 76.646729 -357.487399)
			(xy 76.687951 -357.451684) (xy 76.733836 -357.4222) (xy 76.78345 -357.399547) (xy 76.835784 -357.384185)
			(xy 76.889771 -357.376429) (xy 76.917042 -357.375968) (xy 77.780642 -357.375968) (xy 77.807912 -357.376397)
			(xy 77.861895 -357.384165) (xy 77.914223 -357.399535) (xy 77.963832 -357.422195) (xy 78.009711 -357.451684)
			(xy 78.050927 -357.487402) (xy 78.086641 -357.528622) (xy 78.116125 -357.574505) (xy 78.13878 -357.624116)
			(xy 78.154144 -357.676446) (xy 78.161906 -357.73043) (xy 78.161906 -357.784969) (xy 79.644731 -357.784969)
			(xy 79.644731 -357.730431) (xy 79.652493 -357.676448) (xy 79.667858 -357.62412) (xy 79.690514 -357.57451)
			(xy 79.72 -357.52863) (xy 79.755714 -357.487413) (xy 79.796932 -357.451698) (xy 79.842812 -357.422213)
			(xy 79.892421 -357.399557) (xy 79.94475 -357.384193) (xy 79.998733 -357.376431) (xy 80.026002 -357.375968)
			(xy 80.889602 -357.375968) (xy 80.916873 -357.376395) (xy 80.970861 -357.384157) (xy 81.023194 -357.399524)
			(xy 81.072808 -357.422182) (xy 81.118693 -357.45167) (xy 81.159913 -357.487388) (xy 81.195631 -357.528609)
			(xy 81.225119 -357.574493) (xy 81.247777 -357.624107) (xy 81.263143 -357.676441) (xy 81.270906 -357.730429)
			(xy 81.270906 -357.784966) (xy 82.753754 -357.784966) (xy 82.753754 -357.730435) (xy 82.761514 -357.676458)
			(xy 82.776877 -357.624136) (xy 82.799528 -357.574532) (xy 82.829008 -357.528657) (xy 82.864717 -357.487443)
			(xy 82.905926 -357.451731) (xy 82.951799 -357.422246) (xy 83.0014 -357.39959) (xy 83.053721 -357.384222)
			(xy 83.107697 -357.376457) (xy 83.134962 -357.375968) (xy 83.998562 -357.375968) (xy 84.025837 -357.376369)
			(xy 84.079832 -357.384127) (xy 84.132173 -357.399491) (xy 84.181795 -357.422149) (xy 84.227687 -357.451638)
			(xy 84.268915 -357.487358) (xy 84.30464 -357.528582) (xy 84.334133 -357.574471) (xy 84.356795 -357.624091)
			(xy 84.372165 -357.676431) (xy 84.379928 -357.730425) (xy 84.379928 -357.78497) (xy 85.862631 -357.78497)
			(xy 85.862631 -357.73043) (xy 85.870394 -357.676446) (xy 85.88576 -357.624115) (xy 85.908417 -357.574505)
			(xy 85.937905 -357.528623) (xy 85.973622 -357.487406) (xy 86.014841 -357.451691) (xy 86.060724 -357.422207)
			(xy 86.110336 -357.399552) (xy 86.162667 -357.384189) (xy 86.216652 -357.37643) (xy 86.243922 -357.375968)
			(xy 87.107522 -357.375968) (xy 87.134792 -357.376396) (xy 87.188778 -357.384161) (xy 87.241109 -357.399529)
			(xy 87.29072 -357.422189) (xy 87.336602 -357.451677) (xy 87.37782 -357.487395) (xy 87.413536 -357.528616)
			(xy 87.443022 -357.574499) (xy 87.465678 -357.624112) (xy 87.481044 -357.676444) (xy 87.488806 -357.730429)
			(xy 87.488806 -357.784966) (xy 88.971654 -357.784966) (xy 88.971654 -357.730434) (xy 88.979415 -357.676456)
			(xy 88.994778 -357.624132) (xy 89.017431 -357.574527) (xy 89.046913 -357.52865) (xy 89.082624 -357.487436)
			(xy 89.123836 -357.451724) (xy 89.169711 -357.42224) (xy 89.219315 -357.399584) (xy 89.271638 -357.384219)
			(xy 89.325616 -357.376456) (xy 89.352882 -357.375968) (xy 90.216482 -357.375968) (xy 90.243756 -357.37637)
			(xy 90.297749 -357.384131) (xy 90.350088 -357.399497) (xy 90.399707 -357.422155) (xy 90.445597 -357.451645)
			(xy 90.486822 -357.487365) (xy 90.522544 -357.528589) (xy 90.552036 -357.574477) (xy 90.574697 -357.624095)
			(xy 90.590065 -357.676433) (xy 90.597828 -357.730426) (xy 90.597828 -357.784971) (xy 92.080532 -357.784971)
			(xy 92.080532 -357.730429) (xy 92.088294 -357.676443) (xy 92.103661 -357.624111) (xy 92.12632 -357.574499)
			(xy 92.155809 -357.528617) (xy 92.191529 -357.487399) (xy 92.232751 -357.451684) (xy 92.278636 -357.4222)
			(xy 92.32825 -357.399547) (xy 92.380584 -357.384185) (xy 92.434571 -357.376429) (xy 92.461842 -357.375968)
			(xy 93.325442 -357.375968) (xy 93.352712 -357.376397) (xy 93.406695 -357.384165) (xy 93.459023 -357.399535)
			(xy 93.508632 -357.422195) (xy 93.554511 -357.451684) (xy 93.595727 -357.487402) (xy 93.631441 -357.528622)
			(xy 93.660925 -357.574505) (xy 93.68358 -357.624116) (xy 93.698944 -357.676446) (xy 93.706706 -357.73043)
			(xy 93.706706 -357.784966) (xy 114.589854 -357.784966) (xy 114.589854 -357.730434) (xy 114.597614 -357.676458)
			(xy 114.612977 -357.624135) (xy 114.635629 -357.574531) (xy 114.66511 -357.528655) (xy 114.700819 -357.487441)
			(xy 114.742029 -357.451729) (xy 114.787903 -357.422244) (xy 114.837505 -357.399588) (xy 114.889826 -357.384221)
			(xy 114.943802 -357.376457) (xy 114.971068 -357.375968) (xy 115.834668 -357.375968) (xy 115.861943 -357.376369)
			(xy 115.915937 -357.384128) (xy 115.968278 -357.399493) (xy 116.017899 -357.422151) (xy 116.06379 -357.45164)
			(xy 116.105017 -357.48736) (xy 116.140741 -357.528584) (xy 116.170234 -357.574473) (xy 116.192896 -357.624092)
			(xy 116.208265 -357.676431) (xy 116.216028 -357.730425) (xy 116.216028 -357.78497) (xy 117.698731 -357.78497)
			(xy 117.698732 -357.73043) (xy 117.706494 -357.676445) (xy 117.72186 -357.624114) (xy 117.744518 -357.574503)
			(xy 117.774006 -357.528621) (xy 117.809724 -357.487404) (xy 117.850944 -357.451689) (xy 117.896827 -357.422205)
			(xy 117.94644 -357.39955) (xy 117.998772 -357.384188) (xy 118.052758 -357.37643) (xy 118.080028 -357.375968)
			(xy 118.943628 -357.375968) (xy 118.970898 -357.376396) (xy 119.024883 -357.384162) (xy 119.077213 -357.399531)
			(xy 119.126824 -357.42219) (xy 119.172705 -357.451679) (xy 119.213922 -357.487397) (xy 119.249637 -357.528618)
			(xy 119.279123 -357.574501) (xy 119.301779 -357.624113) (xy 119.317144 -357.676444) (xy 119.324906 -357.73043)
			(xy 119.324906 -357.784967) (xy 120.807754 -357.784967) (xy 120.807754 -357.730433) (xy 120.815515 -357.676455)
			(xy 120.830879 -357.624131) (xy 120.853532 -357.574525) (xy 120.883015 -357.528648) (xy 120.918726 -357.487434)
			(xy 120.959939 -357.451722) (xy 121.005815 -357.422238) (xy 121.055419 -357.399583) (xy 121.107743 -357.384218)
			(xy 121.161721 -357.376455) (xy 121.188988 -357.375968) (xy 122.052588 -357.375968) (xy 122.079862 -357.376371)
			(xy 122.133854 -357.384132) (xy 122.186192 -357.399499) (xy 122.235811 -357.422157) (xy 122.2817 -357.451647)
			(xy 122.322924 -357.487367) (xy 122.358646 -357.528591) (xy 122.388137 -357.574479) (xy 122.410797 -357.624096)
			(xy 122.426165 -357.676434) (xy 122.433928 -357.730426) (xy 122.433928 -357.784971) (xy 123.916632 -357.784971)
			(xy 123.916632 -357.730429) (xy 123.924394 -357.676442) (xy 123.939762 -357.62411) (xy 123.962421 -357.574497)
			(xy 123.991911 -357.528615) (xy 124.027631 -357.487397) (xy 124.068853 -357.451682) (xy 124.114739 -357.422198)
			(xy 124.164355 -357.399545) (xy 124.216689 -357.384184) (xy 124.270677 -357.376428) (xy 124.297948 -357.375968)
			(xy 125.161548 -357.375968) (xy 125.188817 -357.376398) (xy 125.2428 -357.384166) (xy 125.295128 -357.399536)
			(xy 125.344736 -357.422197) (xy 125.390614 -357.451687) (xy 125.431829 -357.487405) (xy 125.467542 -357.528624)
			(xy 125.497026 -357.574506) (xy 125.51968 -357.624117) (xy 125.535045 -357.676447) (xy 125.542806 -357.730431)
			(xy 125.542806 -357.784969) (xy 127.025631 -357.784969) (xy 127.025631 -357.730431) (xy 127.033393 -357.676447)
			(xy 127.048759 -357.624118) (xy 127.071415 -357.574508) (xy 127.100901 -357.528628) (xy 127.136617 -357.487411)
			(xy 127.177834 -357.451696) (xy 127.223715 -357.422211) (xy 127.273326 -357.399556) (xy 127.325655 -357.384191)
			(xy 127.379639 -357.376431) (xy 127.406908 -357.375968) (xy 128.270508 -357.375968) (xy 128.297779 -357.376395)
			(xy 128.351766 -357.384158) (xy 128.404099 -357.399525) (xy 128.453712 -357.422184) (xy 128.499595 -357.451672)
			(xy 128.540815 -357.48739) (xy 128.576532 -357.528611) (xy 128.60602 -357.574495) (xy 128.628677 -357.624109)
			(xy 128.644043 -357.676442) (xy 128.651806 -357.730429) (xy 128.651806 -357.784966) (xy 130.134654 -357.784966)
			(xy 130.134654 -357.730434) (xy 130.142414 -357.676458) (xy 130.157777 -357.624135) (xy 130.180429 -357.574531)
			(xy 130.20991 -357.528655) (xy 130.245619 -357.487441) (xy 130.286829 -357.451729) (xy 130.332703 -357.422244)
			(xy 130.382305 -357.399588) (xy 130.434626 -357.384221) (xy 130.488602 -357.376457) (xy 130.515868 -357.375968)
			(xy 131.379468 -357.375968) (xy 131.406743 -357.376369) (xy 131.460737 -357.384128) (xy 131.513078 -357.399493)
			(xy 131.562699 -357.422151) (xy 131.60859 -357.45164) (xy 131.649817 -357.48736) (xy 131.685541 -357.528584)
			(xy 131.715034 -357.574473) (xy 131.737696 -357.624092) (xy 131.753065 -357.676431) (xy 131.760828 -357.730425)
			(xy 131.760828 -357.78497) (xy 133.243531 -357.78497) (xy 133.243532 -357.73043) (xy 133.251294 -357.676445)
			(xy 133.26666 -357.624114) (xy 133.289318 -357.574503) (xy 133.318806 -357.528621) (xy 133.354524 -357.487404)
			(xy 133.395744 -357.451689) (xy 133.441627 -357.422205) (xy 133.49124 -357.39955) (xy 133.543572 -357.384188)
			(xy 133.597558 -357.37643) (xy 133.624828 -357.375968) (xy 134.488428 -357.375968) (xy 134.515698 -357.376396)
			(xy 134.569683 -357.384162) (xy 134.622013 -357.399531) (xy 134.671624 -357.42219) (xy 134.717505 -357.451679)
			(xy 134.758722 -357.487397) (xy 134.794437 -357.528618) (xy 134.823923 -357.574501) (xy 134.846579 -357.624113)
			(xy 134.861944 -357.676444) (xy 134.869706 -357.73043) (xy 134.869706 -357.784967) (xy 136.352554 -357.784967)
			(xy 136.352554 -357.730433) (xy 136.360315 -357.676455) (xy 136.375679 -357.624131) (xy 136.398332 -357.574525)
			(xy 136.427815 -357.528648) (xy 136.463526 -357.487434) (xy 136.504739 -357.451722) (xy 136.550615 -357.422238)
			(xy 136.600219 -357.399583) (xy 136.652543 -357.384218) (xy 136.706521 -357.376455) (xy 136.733788 -357.375968)
			(xy 137.597388 -357.375968) (xy 137.624662 -357.376371) (xy 137.678654 -357.384132) (xy 137.730992 -357.399499)
			(xy 137.780611 -357.422157) (xy 137.8265 -357.451647) (xy 137.867724 -357.487367) (xy 137.903446 -357.528591)
			(xy 137.932937 -357.574479) (xy 137.955597 -357.624096) (xy 137.970965 -357.676434) (xy 137.978728 -357.730426)
			(xy 137.978728 -357.784971) (xy 139.461432 -357.784971) (xy 139.461432 -357.730429) (xy 139.469194 -357.676442)
			(xy 139.484562 -357.62411) (xy 139.507221 -357.574497) (xy 139.536711 -357.528615) (xy 139.572431 -357.487397)
			(xy 139.613653 -357.451682) (xy 139.659539 -357.422198) (xy 139.709155 -357.399545) (xy 139.761489 -357.384184)
			(xy 139.815477 -357.376428) (xy 139.842748 -357.375968) (xy 140.706348 -357.375968) (xy 140.733617 -357.376398)
			(xy 140.7876 -357.384166) (xy 140.839928 -357.399536) (xy 140.889536 -357.422197) (xy 140.935414 -357.451687)
			(xy 140.976629 -357.487405) (xy 141.012342 -357.528624) (xy 141.041826 -357.574506) (xy 141.06448 -357.624117)
			(xy 141.079845 -357.676447) (xy 141.087606 -357.730431) (xy 141.087606 -357.784969) (xy 142.570431 -357.784969)
			(xy 142.570431 -357.730431) (xy 142.578193 -357.676447) (xy 142.593559 -357.624118) (xy 142.616215 -357.574508)
			(xy 142.645701 -357.528628) (xy 142.681417 -357.487411) (xy 142.722634 -357.451696) (xy 142.768515 -357.422211)
			(xy 142.818126 -357.399556) (xy 142.870455 -357.384191) (xy 142.924439 -357.376431) (xy 142.951708 -357.375968)
			(xy 143.815308 -357.375968) (xy 143.842579 -357.376395) (xy 143.896566 -357.384158) (xy 143.948899 -357.399525)
			(xy 143.998512 -357.422184) (xy 144.044395 -357.451672) (xy 144.085615 -357.48739) (xy 144.121332 -357.528611)
			(xy 144.15082 -357.574495) (xy 144.173477 -357.624109) (xy 144.188843 -357.676442) (xy 144.196606 -357.730429)
			(xy 144.196606 -357.784965) (xy 158.695954 -357.784965) (xy 158.695954 -357.730435) (xy 158.703714 -357.67646)
			(xy 158.719076 -357.624138) (xy 158.741727 -357.574535) (xy 158.771206 -357.52866) (xy 158.806913 -357.487447)
			(xy 158.848122 -357.451735) (xy 158.893993 -357.42225) (xy 158.943593 -357.399593) (xy 158.995913 -357.384224)
			(xy 159.049887 -357.376458) (xy 159.077152 -357.375968) (xy 159.940752 -357.375968) (xy 159.968027 -357.376368)
			(xy 160.022024 -357.384125) (xy 160.074366 -357.399489) (xy 160.123989 -357.422145) (xy 160.169883 -357.451634)
			(xy 160.211112 -357.487354) (xy 160.246837 -357.528579) (xy 160.276332 -357.574468) (xy 160.298994 -357.624089)
			(xy 160.314364 -357.676429) (xy 160.322128 -357.730425) (xy 160.322128 -357.784969) (xy 161.804831 -357.784969)
			(xy 161.804831 -357.730431) (xy 161.812593 -357.676447) (xy 161.827959 -357.624117) (xy 161.850616 -357.574507)
			(xy 161.880102 -357.528627) (xy 161.915818 -357.487409) (xy 161.957036 -357.451695) (xy 162.002918 -357.42221)
			(xy 162.052529 -357.399555) (xy 162.104859 -357.384191) (xy 162.158843 -357.376431) (xy 162.186112 -357.375968)
			(xy 163.049712 -357.375968) (xy 163.076983 -357.376395) (xy 163.130969 -357.384159) (xy 163.183302 -357.399527)
			(xy 163.232914 -357.422185) (xy 163.278797 -357.451674) (xy 163.320017 -357.487392) (xy 163.355733 -357.528612)
			(xy 163.385221 -357.574496) (xy 163.407878 -357.62411) (xy 163.423244 -357.676442) (xy 163.431006 -357.730429)
			(xy 163.431006 -357.784966) (xy 164.913854 -357.784966) (xy 164.913854 -357.730434) (xy 164.921615 -357.676457)
			(xy 164.936977 -357.624134) (xy 164.95963 -357.57453) (xy 164.989111 -357.528654) (xy 165.02482 -357.48744)
			(xy 165.066031 -357.451727) (xy 165.111905 -357.422243) (xy 165.161508 -357.399587) (xy 165.21383 -357.384221)
			(xy 165.267806 -357.376456) (xy 165.295072 -357.375968) (xy 166.158672 -357.375968) (xy 166.185946 -357.37637)
			(xy 166.239941 -357.384129) (xy 166.292281 -357.399494) (xy 166.341901 -357.422152) (xy 166.387792 -357.451641)
			(xy 166.429019 -357.487361) (xy 166.464742 -357.528585) (xy 166.494235 -357.574474) (xy 166.516896 -357.624093)
			(xy 166.532265 -357.676432) (xy 166.540028 -357.730426) (xy 166.540028 -357.78497) (xy 168.022732 -357.78497)
			(xy 168.022732 -357.73043) (xy 168.030494 -357.676444) (xy 168.045861 -357.624113) (xy 168.068519 -357.574502)
			(xy 168.098007 -357.52862) (xy 168.133725 -357.487402) (xy 168.174946 -357.451688) (xy 168.22083 -357.422203)
			(xy 168.270443 -357.399549) (xy 168.322776 -357.384187) (xy 168.376762 -357.376429) (xy 168.404032 -357.375968)
			(xy 169.267632 -357.375968) (xy 169.294902 -357.376397) (xy 169.348886 -357.384163) (xy 169.401216 -357.399532)
			(xy 169.450826 -357.422192) (xy 169.496707 -357.451681) (xy 169.537924 -357.487399) (xy 169.573638 -357.528619)
			(xy 169.603124 -357.574502) (xy 169.625779 -357.624114) (xy 169.641144 -357.676445) (xy 169.648906 -357.73043)
			(xy 169.648906 -357.784967) (xy 171.131754 -357.784967) (xy 171.131754 -357.730433) (xy 171.139515 -357.676454)
			(xy 171.154879 -357.62413) (xy 171.177533 -357.574524) (xy 171.207016 -357.528647) (xy 171.242727 -357.487433)
			(xy 171.283941 -357.45172) (xy 171.329817 -357.422237) (xy 171.379422 -357.399582) (xy 171.431747 -357.384217)
			(xy 171.485725 -357.376455) (xy 171.512992 -357.375968) (xy 172.376592 -357.375968) (xy 172.403866 -357.376371)
			(xy 172.457857 -357.384133) (xy 172.510195 -357.3995) (xy 172.559813 -357.422159) (xy 172.605702 -357.451648)
			(xy 172.646926 -357.487368) (xy 172.682647 -357.528592) (xy 172.712138 -357.57448) (xy 172.734798 -357.624097)
			(xy 172.750165 -357.676435) (xy 172.757928 -357.730426) (xy 172.757928 -357.784965) (xy 174.240754 -357.784965)
			(xy 174.240754 -357.730435) (xy 174.248514 -357.67646) (xy 174.263876 -357.624138) (xy 174.286527 -357.574535)
			(xy 174.316006 -357.52866) (xy 174.351713 -357.487447) (xy 174.392922 -357.451735) (xy 174.438793 -357.42225)
			(xy 174.488393 -357.399593) (xy 174.540713 -357.384224) (xy 174.594687 -357.376458) (xy 174.621952 -357.375968)
			(xy 175.485552 -357.375968) (xy 175.512827 -357.376368) (xy 175.566824 -357.384125) (xy 175.619166 -357.399489)
			(xy 175.668789 -357.422145) (xy 175.714683 -357.451634) (xy 175.755912 -357.487354) (xy 175.791637 -357.528579)
			(xy 175.821132 -357.574468) (xy 175.843794 -357.624089) (xy 175.859164 -357.676429) (xy 175.866928 -357.730425)
			(xy 175.866928 -357.784969) (xy 177.349631 -357.784969) (xy 177.349631 -357.730431) (xy 177.357393 -357.676447)
			(xy 177.372759 -357.624117) (xy 177.395416 -357.574507) (xy 177.424902 -357.528627) (xy 177.460618 -357.487409)
			(xy 177.501836 -357.451695) (xy 177.547718 -357.42221) (xy 177.597329 -357.399555) (xy 177.649659 -357.384191)
			(xy 177.703643 -357.376431) (xy 177.730912 -357.375968) (xy 178.594512 -357.375968) (xy 178.621783 -357.376395)
			(xy 178.675769 -357.384159) (xy 178.728102 -357.399527) (xy 178.777714 -357.422185) (xy 178.823597 -357.451674)
			(xy 178.864817 -357.487392) (xy 178.900533 -357.528612) (xy 178.930021 -357.574496) (xy 178.952678 -357.62411)
			(xy 178.968044 -357.676442) (xy 178.975806 -357.730429) (xy 178.975806 -357.784966) (xy 180.458654 -357.784966)
			(xy 180.458654 -357.730434) (xy 180.466415 -357.676457) (xy 180.481777 -357.624134) (xy 180.50443 -357.57453)
			(xy 180.533911 -357.528654) (xy 180.56962 -357.48744) (xy 180.610831 -357.451727) (xy 180.656705 -357.422243)
			(xy 180.706308 -357.399587) (xy 180.75863 -357.384221) (xy 180.812606 -357.376456) (xy 180.839872 -357.375968)
			(xy 181.703472 -357.375968) (xy 181.730746 -357.37637) (xy 181.784741 -357.384129) (xy 181.837081 -357.399494)
			(xy 181.886701 -357.422152) (xy 181.932592 -357.451641) (xy 181.973819 -357.487361) (xy 182.009542 -357.528585)
			(xy 182.039035 -357.574474) (xy 182.061696 -357.624093) (xy 182.077065 -357.676432) (xy 182.084828 -357.730426)
			(xy 182.084828 -357.761176) (xy 183.567456 -357.761176) (xy 183.567456 -357.706624) (xy 183.57522 -357.652628)
			(xy 183.590589 -357.600287) (xy 183.613252 -357.550665) (xy 183.642746 -357.504775) (xy 183.678471 -357.463549)
			(xy 183.7197 -357.427827) (xy 183.765593 -357.398337) (xy 183.815217 -357.375678) (xy 183.867559 -357.360313)
			(xy 183.921556 -357.352553) (xy 183.948832 -357.352092) (xy 184.812432 -357.352092) (xy 184.839697 -357.352672)
			(xy 184.89367 -357.360437) (xy 184.94599 -357.375803) (xy 184.99559 -357.398458) (xy 185.041461 -357.427942)
			(xy 185.08267 -357.463653) (xy 185.118378 -357.504864) (xy 185.147857 -357.550738) (xy 185.170508 -357.60034)
			(xy 185.18587 -357.652661) (xy 185.19363 -357.706635) (xy 185.19363 -357.761165) (xy 185.193629 -357.761172)
			(xy 186.676479 -357.761172) (xy 186.676479 -357.706628) (xy 186.684241 -357.652638) (xy 186.699608 -357.600303)
			(xy 186.722266 -357.550688) (xy 186.751755 -357.504801) (xy 186.787473 -357.463579) (xy 186.828695 -357.42786)
			(xy 186.87458 -357.39837) (xy 186.924196 -357.37571) (xy 186.97653 -357.360343) (xy 187.03052 -357.352579)
			(xy 187.057792 -357.352092) (xy 187.921392 -357.352092) (xy 187.94866 -357.352647) (xy 188.002641 -357.360407)
			(xy 188.054969 -357.375771) (xy 188.104577 -357.398425) (xy 188.150456 -357.427909) (xy 188.191672 -357.463622)
			(xy 188.227386 -357.504838) (xy 188.256871 -357.550716) (xy 188.279526 -357.600324) (xy 188.294891 -357.652651)
			(xy 188.302653 -357.706632) (xy 188.302653 -357.761168) (xy 188.294891 -357.815149) (xy 188.279526 -357.867476)
			(xy 188.256871 -357.917084) (xy 188.227386 -357.962962) (xy 188.223925 -357.966956) (xy 245.50903 -357.966956)
			(xy 245.50903 -357.88226) (xy 245.517081 -357.797946) (xy 245.53311 -357.71478) (xy 245.556971 -357.633513)
			(xy 245.58845 -357.554883) (xy 245.627261 -357.479602) (xy 245.673051 -357.40835) (xy 245.725407 -357.341774)
			(xy 245.783855 -357.280476) (xy 245.847865 -357.225011) (xy 245.916857 -357.175882) (xy 245.990207 -357.133533)
			(xy 246.06725 -357.098349) (xy 246.147289 -357.070647) (xy 246.229598 -357.050679) (xy 246.313433 -357.038626)
			(xy 246.398034 -357.034596) (xy 246.482635 -357.038626) (xy 246.56647 -357.050679) (xy 246.648779 -357.070647)
			(xy 246.728818 -357.098349) (xy 246.805861 -357.133533) (xy 246.879211 -357.175882) (xy 246.948203 -357.225011)
			(xy 247.012213 -357.280476) (xy 247.070661 -357.341774) (xy 247.123017 -357.40835) (xy 247.168807 -357.479602)
			(xy 247.207618 -357.554883) (xy 247.239097 -357.633513) (xy 247.262958 -357.71478) (xy 247.276485 -357.784966)
			(xy 270.624854 -357.784966) (xy 270.624854 -357.730435) (xy 270.632614 -357.676458) (xy 270.647977 -357.624136)
			(xy 270.670628 -357.574532) (xy 270.700108 -357.528657) (xy 270.735817 -357.487443) (xy 270.777026 -357.451731)
			(xy 270.822899 -357.422246) (xy 270.8725 -357.39959) (xy 270.924821 -357.384222) (xy 270.978797 -357.376457)
			(xy 271.006062 -357.375968) (xy 271.869662 -357.375968) (xy 271.896937 -357.376369) (xy 271.950932 -357.384127)
			(xy 272.003273 -357.399491) (xy 272.052895 -357.422149) (xy 272.098787 -357.451638) (xy 272.140015 -357.487358)
			(xy 272.17574 -357.528582) (xy 272.205233 -357.574471) (xy 272.227895 -357.624091) (xy 272.243265 -357.676431)
			(xy 272.251028 -357.730425) (xy 272.251028 -357.78497) (xy 273.733731 -357.78497) (xy 273.733731 -357.73043)
			(xy 273.741494 -357.676446) (xy 273.75686 -357.624115) (xy 273.779517 -357.574505) (xy 273.809005 -357.528623)
			(xy 273.844722 -357.487406) (xy 273.885941 -357.451691) (xy 273.931824 -357.422207) (xy 273.981436 -357.399552)
			(xy 274.033767 -357.384189) (xy 274.087752 -357.37643) (xy 274.115022 -357.375968) (xy 274.978622 -357.375968)
			(xy 275.005892 -357.376396) (xy 275.059878 -357.384161) (xy 275.112209 -357.399529) (xy 275.16182 -357.422189)
			(xy 275.207702 -357.451677) (xy 275.24892 -357.487395) (xy 275.284636 -357.528616) (xy 275.314122 -357.574499)
			(xy 275.336778 -357.624112) (xy 275.352144 -357.676444) (xy 275.359906 -357.730429) (xy 275.359906 -357.784966)
			(xy 276.842754 -357.784966) (xy 276.842754 -357.730434) (xy 276.850515 -357.676456) (xy 276.865878 -357.624132)
			(xy 276.888531 -357.574527) (xy 276.918013 -357.52865) (xy 276.953724 -357.487436) (xy 276.994936 -357.451724)
			(xy 277.040811 -357.42224) (xy 277.090415 -357.399584) (xy 277.142738 -357.384219) (xy 277.196716 -357.376456)
			(xy 277.223982 -357.375968) (xy 278.087582 -357.375968) (xy 278.114856 -357.37637) (xy 278.168849 -357.384131)
			(xy 278.221188 -357.399497) (xy 278.270807 -357.422155) (xy 278.316697 -357.451645) (xy 278.357922 -357.487365)
			(xy 278.393644 -357.528589) (xy 278.423136 -357.574477) (xy 278.445797 -357.624095) (xy 278.461165 -357.676433)
			(xy 278.468928 -357.730426) (xy 278.468928 -357.784971) (xy 279.951632 -357.784971) (xy 279.951632 -357.730429)
			(xy 279.959394 -357.676443) (xy 279.974761 -357.624111) (xy 279.99742 -357.574499) (xy 280.026909 -357.528617)
			(xy 280.062629 -357.487399) (xy 280.103851 -357.451684) (xy 280.149736 -357.4222) (xy 280.19935 -357.399547)
			(xy 280.251684 -357.384185) (xy 280.305671 -357.376429) (xy 280.332942 -357.375968) (xy 281.196542 -357.375968)
			(xy 281.223812 -357.376397) (xy 281.277795 -357.384165) (xy 281.330123 -357.399535) (xy 281.379732 -357.422195)
			(xy 281.425611 -357.451684) (xy 281.466827 -357.487402) (xy 281.502541 -357.528622) (xy 281.532025 -357.574505)
			(xy 281.55468 -357.624116) (xy 281.570044 -357.676446) (xy 281.577806 -357.73043) (xy 281.577806 -357.784969)
			(xy 283.060631 -357.784969) (xy 283.060631 -357.730431) (xy 283.068393 -357.676448) (xy 283.083758 -357.62412)
			(xy 283.106414 -357.57451) (xy 283.1359 -357.52863) (xy 283.171614 -357.487413) (xy 283.212832 -357.451698)
			(xy 283.258712 -357.422213) (xy 283.308321 -357.399557) (xy 283.36065 -357.384193) (xy 283.414633 -357.376431)
			(xy 283.441902 -357.375968) (xy 284.305502 -357.375968) (xy 284.332773 -357.376395) (xy 284.386761 -357.384157)
			(xy 284.439094 -357.399524) (xy 284.488708 -357.422182) (xy 284.534593 -357.45167) (xy 284.575813 -357.487388)
			(xy 284.611531 -357.528609) (xy 284.641019 -357.574493) (xy 284.663677 -357.624107) (xy 284.679043 -357.676441)
			(xy 284.686806 -357.730429) (xy 284.686806 -357.784966) (xy 286.169654 -357.784966) (xy 286.169654 -357.730435)
			(xy 286.177414 -357.676458) (xy 286.192777 -357.624136) (xy 286.215428 -357.574532) (xy 286.244908 -357.528657)
			(xy 286.280617 -357.487443) (xy 286.321826 -357.451731) (xy 286.367699 -357.422246) (xy 286.4173 -357.39959)
			(xy 286.469621 -357.384222) (xy 286.523597 -357.376457) (xy 286.550862 -357.375968) (xy 287.414462 -357.375968)
			(xy 287.441737 -357.376369) (xy 287.495732 -357.384127) (xy 287.548073 -357.399491) (xy 287.597695 -357.422149)
			(xy 287.643587 -357.451638) (xy 287.684815 -357.487358) (xy 287.72054 -357.528582) (xy 287.750033 -357.574471)
			(xy 287.772695 -357.624091) (xy 287.788065 -357.676431) (xy 287.795828 -357.730425) (xy 287.795828 -357.78497)
			(xy 289.278531 -357.78497) (xy 289.278531 -357.73043) (xy 289.286294 -357.676446) (xy 289.30166 -357.624115)
			(xy 289.324317 -357.574505) (xy 289.353805 -357.528623) (xy 289.389522 -357.487406) (xy 289.430741 -357.451691)
			(xy 289.476624 -357.422207) (xy 289.526236 -357.399552) (xy 289.578567 -357.384189) (xy 289.632552 -357.37643)
			(xy 289.659822 -357.375968) (xy 290.523422 -357.375968) (xy 290.550692 -357.376396) (xy 290.604678 -357.384161)
			(xy 290.657009 -357.399529) (xy 290.70662 -357.422189) (xy 290.752502 -357.451677) (xy 290.79372 -357.487395)
			(xy 290.829436 -357.528616) (xy 290.858922 -357.574499) (xy 290.881578 -357.624112) (xy 290.896944 -357.676444)
			(xy 290.904706 -357.730429) (xy 290.904706 -357.784966) (xy 292.387554 -357.784966) (xy 292.387554 -357.730434)
			(xy 292.395315 -357.676456) (xy 292.410678 -357.624132) (xy 292.433331 -357.574527) (xy 292.462813 -357.52865)
			(xy 292.498524 -357.487436) (xy 292.539736 -357.451724) (xy 292.585611 -357.42224) (xy 292.635215 -357.399584)
			(xy 292.687538 -357.384219) (xy 292.741516 -357.376456) (xy 292.768782 -357.375968) (xy 293.632382 -357.375968)
			(xy 293.659656 -357.37637) (xy 293.713649 -357.384131) (xy 293.765988 -357.399497) (xy 293.815607 -357.422155)
			(xy 293.861497 -357.451645) (xy 293.902722 -357.487365) (xy 293.938444 -357.528589) (xy 293.967936 -357.574477)
			(xy 293.990597 -357.624095) (xy 294.005965 -357.676433) (xy 294.013728 -357.730426) (xy 294.013728 -357.784971)
			(xy 295.496432 -357.784971) (xy 295.496432 -357.730429) (xy 295.504194 -357.676443) (xy 295.519561 -357.624111)
			(xy 295.54222 -357.574499) (xy 295.571709 -357.528617) (xy 295.607429 -357.487399) (xy 295.648651 -357.451684)
			(xy 295.694536 -357.4222) (xy 295.74415 -357.399547) (xy 295.796484 -357.384185) (xy 295.850471 -357.376429)
			(xy 295.877742 -357.375968) (xy 296.741342 -357.375968) (xy 296.768612 -357.376397) (xy 296.822595 -357.384165)
			(xy 296.874923 -357.399535) (xy 296.924532 -357.422195) (xy 296.970411 -357.451684) (xy 297.011627 -357.487402)
			(xy 297.047341 -357.528622) (xy 297.076825 -357.574505) (xy 297.09948 -357.624116) (xy 297.114844 -357.676446)
			(xy 297.122606 -357.73043) (xy 297.122606 -357.784969) (xy 298.605431 -357.784969) (xy 298.605431 -357.730431)
			(xy 298.613193 -357.676448) (xy 298.628558 -357.62412) (xy 298.651214 -357.57451) (xy 298.6807 -357.52863)
			(xy 298.716414 -357.487413) (xy 298.757632 -357.451698) (xy 298.803512 -357.422213) (xy 298.853121 -357.399557)
			(xy 298.90545 -357.384193) (xy 298.959433 -357.376431) (xy 298.986702 -357.375968) (xy 299.850302 -357.375968)
			(xy 299.877573 -357.376395) (xy 299.931561 -357.384157) (xy 299.983894 -357.399524) (xy 300.033508 -357.422182)
			(xy 300.079393 -357.45167) (xy 300.120613 -357.487388) (xy 300.156331 -357.528609) (xy 300.185819 -357.574493)
			(xy 300.208477 -357.624107) (xy 300.223843 -357.676441) (xy 300.231606 -357.730429) (xy 300.231606 -357.784966)
			(xy 315.230554 -357.784966) (xy 315.230554 -357.730434) (xy 315.238314 -357.676458) (xy 315.253677 -357.624136)
			(xy 315.276328 -357.574532) (xy 315.305809 -357.528656) (xy 315.341517 -357.487443) (xy 315.382727 -357.45173)
			(xy 315.4286 -357.422246) (xy 315.478202 -357.399589) (xy 315.530523 -357.384222) (xy 315.584498 -357.376457)
			(xy 315.611764 -357.375968) (xy 316.475364 -357.375968) (xy 316.502639 -357.376369) (xy 316.556634 -357.384128)
			(xy 316.608975 -357.399492) (xy 316.658597 -357.422149) (xy 316.704488 -357.451638) (xy 316.745716 -357.487359)
			(xy 316.78144 -357.528583) (xy 316.810933 -357.574472) (xy 316.833595 -357.624091) (xy 316.848965 -357.676431)
			(xy 316.856728 -357.730425) (xy 316.856728 -357.78497) (xy 318.339431 -357.78497) (xy 318.339431 -357.73043)
			(xy 318.347194 -357.676445) (xy 318.36256 -357.624115) (xy 318.385217 -357.574504) (xy 318.414705 -357.528623)
			(xy 318.450422 -357.487405) (xy 318.491642 -357.451691) (xy 318.537525 -357.422206) (xy 318.587137 -357.399552)
			(xy 318.639469 -357.384189) (xy 318.693454 -357.37643) (xy 318.720724 -357.375968) (xy 319.584324 -357.375968)
			(xy 319.611594 -357.376396) (xy 319.66558 -357.384161) (xy 319.71791 -357.39953) (xy 319.767521 -357.422189)
			(xy 319.813403 -357.451678) (xy 319.854621 -357.487396) (xy 319.890336 -357.528616) (xy 319.919822 -357.5745)
			(xy 319.942479 -357.624112) (xy 319.957844 -357.676444) (xy 319.965606 -357.73043) (xy 319.965606 -357.784967)
			(xy 321.448454 -357.784967) (xy 321.448454 -357.730434) (xy 321.456215 -357.676456) (xy 321.471578 -357.624131)
			(xy 321.494232 -357.574526) (xy 321.523714 -357.52865) (xy 321.559424 -357.487436) (xy 321.600637 -357.451723)
			(xy 321.646512 -357.422239) (xy 321.696116 -357.399584) (xy 321.74844 -357.384218) (xy 321.802418 -357.376455)
			(xy 321.829684 -357.375968) (xy 322.693284 -357.375968) (xy 322.720558 -357.37637) (xy 322.774551 -357.384131)
			(xy 322.826889 -357.399497) (xy 322.876508 -357.422156) (xy 322.922398 -357.451645) (xy 322.963623 -357.487366)
			(xy 322.999345 -357.528589) (xy 323.028836 -357.574477) (xy 323.051497 -357.624096) (xy 323.066865 -357.676434)
			(xy 323.074628 -357.730426) (xy 323.074628 -357.784971) (xy 324.557332 -357.784971) (xy 324.557332 -357.730429)
			(xy 324.565094 -357.676443) (xy 324.580461 -357.624111) (xy 324.603121 -357.574498) (xy 324.63261 -357.528616)
			(xy 324.668329 -357.487398) (xy 324.709551 -357.451684) (xy 324.755437 -357.422199) (xy 324.805052 -357.399546)
			(xy 324.857386 -357.384185) (xy 324.911373 -357.376428) (xy 324.938644 -357.375968) (xy 325.802244 -357.375968)
			(xy 325.829513 -357.376398) (xy 325.883497 -357.384165) (xy 325.935825 -357.399535) (xy 325.985433 -357.422196)
			(xy 326.031312 -357.451685) (xy 326.072528 -357.487403) (xy 326.108241 -357.528623) (xy 326.137725 -357.574505)
			(xy 326.16038 -357.624116) (xy 326.175744 -357.676447) (xy 326.183506 -357.73043) (xy 326.183506 -357.784969)
			(xy 327.666331 -357.784969) (xy 327.666331 -357.730431) (xy 327.674093 -357.676448) (xy 327.689458 -357.624119)
			(xy 327.712114 -357.57451) (xy 327.7416 -357.528629) (xy 327.777315 -357.487412) (xy 327.818533 -357.451698)
			(xy 327.864413 -357.422212) (xy 327.914023 -357.399557) (xy 327.966352 -357.384192) (xy 328.020335 -357.376431)
			(xy 328.047604 -357.375968) (xy 328.911204 -357.375968) (xy 328.938475 -357.376395) (xy 328.992463 -357.384158)
			(xy 329.044796 -357.399524) (xy 329.094409 -357.422183) (xy 329.140293 -357.451671) (xy 329.181514 -357.487389)
			(xy 329.217231 -357.52861) (xy 329.246719 -357.574494) (xy 329.269377 -357.624108) (xy 329.284743 -357.676441)
			(xy 329.292506 -357.730429) (xy 329.292506 -357.784966) (xy 330.775354 -357.784966) (xy 330.775354 -357.730434)
			(xy 330.783114 -357.676458) (xy 330.798477 -357.624136) (xy 330.821128 -357.574532) (xy 330.850609 -357.528656)
			(xy 330.886317 -357.487443) (xy 330.927527 -357.45173) (xy 330.9734 -357.422246) (xy 331.023002 -357.399589)
			(xy 331.075323 -357.384222) (xy 331.129298 -357.376457) (xy 331.156564 -357.375968) (xy 332.020164 -357.375968)
			(xy 332.047439 -357.376369) (xy 332.101434 -357.384128) (xy 332.153775 -357.399492) (xy 332.203397 -357.422149)
			(xy 332.249288 -357.451638) (xy 332.290516 -357.487359) (xy 332.32624 -357.528583) (xy 332.355733 -357.574472)
			(xy 332.378395 -357.624091) (xy 332.393765 -357.676431) (xy 332.401528 -357.730425) (xy 332.401528 -357.78497)
			(xy 333.884231 -357.78497) (xy 333.884231 -357.73043) (xy 333.891994 -357.676445) (xy 333.90736 -357.624115)
			(xy 333.930017 -357.574504) (xy 333.959505 -357.528623) (xy 333.995222 -357.487405) (xy 334.036442 -357.451691)
			(xy 334.082325 -357.422206) (xy 334.131937 -357.399552) (xy 334.184269 -357.384189) (xy 334.238254 -357.37643)
			(xy 334.265524 -357.375968) (xy 335.129124 -357.375968) (xy 335.156394 -357.376396) (xy 335.21038 -357.384161)
			(xy 335.26271 -357.39953) (xy 335.312321 -357.422189) (xy 335.358203 -357.451678) (xy 335.399421 -357.487396)
			(xy 335.435136 -357.528616) (xy 335.464622 -357.5745) (xy 335.487279 -357.624112) (xy 335.502644 -357.676444)
			(xy 335.510406 -357.73043) (xy 335.510406 -357.784967) (xy 336.993254 -357.784967) (xy 336.993254 -357.730434)
			(xy 337.001015 -357.676456) (xy 337.016378 -357.624131) (xy 337.039032 -357.574526) (xy 337.068514 -357.52865)
			(xy 337.104224 -357.487436) (xy 337.145437 -357.451723) (xy 337.191312 -357.422239) (xy 337.240916 -357.399584)
			(xy 337.29324 -357.384218) (xy 337.347218 -357.376455) (xy 337.374484 -357.375968) (xy 338.238084 -357.375968)
			(xy 338.265358 -357.37637) (xy 338.319351 -357.384131) (xy 338.371689 -357.399497) (xy 338.421308 -357.422156)
			(xy 338.467198 -357.451645) (xy 338.508423 -357.487366) (xy 338.544145 -357.528589) (xy 338.573636 -357.574477)
			(xy 338.596297 -357.624096) (xy 338.611665 -357.676434) (xy 338.619428 -357.730426) (xy 338.619428 -357.784971)
			(xy 340.102132 -357.784971) (xy 340.102132 -357.730429) (xy 340.109894 -357.676443) (xy 340.125261 -357.624111)
			(xy 340.147921 -357.574498) (xy 340.17741 -357.528616) (xy 340.213129 -357.487398) (xy 340.254351 -357.451684)
			(xy 340.300237 -357.422199) (xy 340.349852 -357.399546) (xy 340.402186 -357.384185) (xy 340.456173 -357.376428)
			(xy 340.483444 -357.375968) (xy 341.347044 -357.375968) (xy 341.374313 -357.376398) (xy 341.428297 -357.384165)
			(xy 341.480625 -357.399535) (xy 341.530233 -357.422196) (xy 341.576112 -357.451685) (xy 341.617328 -357.487403)
			(xy 341.653041 -357.528623) (xy 341.682525 -357.574505) (xy 341.70518 -357.624116) (xy 341.720544 -357.676447)
			(xy 341.728306 -357.73043) (xy 341.728306 -357.784969) (xy 343.211131 -357.784969) (xy 343.211131 -357.730431)
			(xy 343.218893 -357.676448) (xy 343.234258 -357.624119) (xy 343.256914 -357.57451) (xy 343.2864 -357.528629)
			(xy 343.322115 -357.487412) (xy 343.363333 -357.451698) (xy 343.409213 -357.422212) (xy 343.458823 -357.399557)
			(xy 343.511152 -357.384192) (xy 343.565135 -357.376431) (xy 343.592404 -357.375968) (xy 344.456004 -357.375968)
			(xy 344.483275 -357.376395) (xy 344.537263 -357.384158) (xy 344.589596 -357.399524) (xy 344.639209 -357.422183)
			(xy 344.685093 -357.451671) (xy 344.726314 -357.487389) (xy 344.762031 -357.52861) (xy 344.791519 -357.574494)
			(xy 344.814177 -357.624108) (xy 344.829543 -357.676441) (xy 344.837306 -357.730429) (xy 344.837306 -357.784971)
			(xy 373.915632 -357.784971) (xy 373.915632 -357.730429) (xy 373.923394 -357.676443) (xy 373.938761 -357.624111)
			(xy 373.96142 -357.574499) (xy 373.990909 -357.528617) (xy 374.026628 -357.4874) (xy 374.06785 -357.451685)
			(xy 374.113735 -357.422201) (xy 374.163349 -357.399547) (xy 374.215682 -357.384186) (xy 374.269669 -357.376429)
			(xy 374.29694 -357.375968) (xy 375.16054 -357.375968) (xy 375.18781 -357.376397) (xy 375.241793 -357.384164)
			(xy 375.294122 -357.399534) (xy 375.343731 -357.422194) (xy 375.389611 -357.451684) (xy 375.430827 -357.487402)
			(xy 375.46654 -357.528622) (xy 375.496025 -357.574504) (xy 375.51868 -357.624116) (xy 375.534044 -357.676446)
			(xy 375.541806 -357.73043) (xy 375.541806 -357.784967) (xy 377.024654 -357.784967) (xy 377.024654 -357.730433)
			(xy 377.032415 -357.676453) (xy 377.04778 -357.624128) (xy 377.070434 -357.574522) (xy 377.099918 -357.528644)
			(xy 377.13563 -357.48743) (xy 377.176844 -357.451718) (xy 377.222722 -357.422234) (xy 377.272328 -357.39958)
			(xy 377.324653 -357.384215) (xy 377.378633 -357.376454) (xy 377.4059 -357.375968) (xy 378.2695 -357.375968)
			(xy 378.296772 -357.376395) (xy 378.350759 -357.384157) (xy 378.403093 -357.399523) (xy 378.452707 -357.422181)
			(xy 378.498592 -357.451669) (xy 378.539812 -357.487388) (xy 378.575531 -357.528608) (xy 378.605019 -357.574493)
			(xy 378.627677 -357.624107) (xy 378.643043 -357.676441) (xy 378.650805 -357.730428) (xy 378.650805 -357.784965)
			(xy 380.133654 -357.784965) (xy 380.133654 -357.730435) (xy 380.141414 -357.676459) (xy 380.156776 -357.624137)
			(xy 380.179428 -357.574533) (xy 380.208908 -357.528658) (xy 380.244616 -357.487444) (xy 380.285825 -357.451732)
			(xy 380.331698 -357.422247) (xy 380.381299 -357.39959) (xy 380.43362 -357.384223) (xy 380.487595 -357.376457)
			(xy 380.51486 -357.375968) (xy 381.37846 -357.375968) (xy 381.405735 -357.376369) (xy 381.45973 -357.384127)
			(xy 381.512072 -357.399491) (xy 381.561694 -357.422148) (xy 381.607586 -357.451637) (xy 381.648815 -357.487357)
			(xy 381.684539 -357.528582) (xy 381.714033 -357.574471) (xy 381.736695 -357.62409) (xy 381.752065 -357.67643)
			(xy 381.759828 -357.730425) (xy 381.759828 -357.78497) (xy 383.242531 -357.78497) (xy 383.242531 -357.73043)
			(xy 383.250294 -357.676446) (xy 383.26566 -357.624116) (xy 383.288317 -357.574505) (xy 383.317804 -357.528624)
			(xy 383.353521 -357.487407) (xy 383.39474 -357.451692) (xy 383.440623 -357.422207) (xy 383.490234 -357.399553)
			(xy 383.542565 -357.384189) (xy 383.59655 -357.37643) (xy 383.62382 -357.375968) (xy 384.48742 -357.375968)
			(xy 384.514691 -357.376396) (xy 384.568676 -357.38416) (xy 384.621007 -357.399529) (xy 384.670619 -357.422188)
			(xy 384.716501 -357.451677) (xy 384.75772 -357.487395) (xy 384.793435 -357.528615) (xy 384.822922 -357.574499)
			(xy 384.845578 -357.624111) (xy 384.860944 -357.676443) (xy 384.868706 -357.730429) (xy 384.868706 -357.784966)
			(xy 386.351554 -357.784966) (xy 386.351554 -357.730434) (xy 386.359315 -357.676456) (xy 386.374678 -357.624132)
			(xy 386.397331 -357.574527) (xy 386.426813 -357.528651) (xy 386.462523 -357.487437) (xy 386.503735 -357.451725)
			(xy 386.54961 -357.422241) (xy 386.599213 -357.399585) (xy 386.651537 -357.384219) (xy 386.705514 -357.376456)
			(xy 386.73278 -357.375968) (xy 387.59638 -357.375968) (xy 387.623654 -357.37637) (xy 387.677647 -357.384131)
			(xy 387.729987 -357.399496) (xy 387.779606 -357.422155) (xy 387.825496 -357.451644) (xy 387.866722 -357.487364)
			(xy 387.902444 -357.528588) (xy 387.931936 -357.574476) (xy 387.954597 -357.624095) (xy 387.969965 -357.676433)
			(xy 387.977728 -357.730426) (xy 387.977728 -357.784971) (xy 389.460432 -357.784971) (xy 389.460432 -357.730429)
			(xy 389.468194 -357.676443) (xy 389.483561 -357.624111) (xy 389.50622 -357.574499) (xy 389.535709 -357.528617)
			(xy 389.571428 -357.4874) (xy 389.61265 -357.451685) (xy 389.658535 -357.422201) (xy 389.708149 -357.399547)
			(xy 389.760482 -357.384186) (xy 389.814469 -357.376429) (xy 389.84174 -357.375968) (xy 390.70534 -357.375968)
			(xy 390.73261 -357.376397) (xy 390.786593 -357.384164) (xy 390.838922 -357.399534) (xy 390.888531 -357.422194)
			(xy 390.934411 -357.451684) (xy 390.975627 -357.487402) (xy 391.01134 -357.528622) (xy 391.040825 -357.574504)
			(xy 391.06348 -357.624116) (xy 391.078844 -357.676446) (xy 391.086606 -357.73043) (xy 391.086606 -357.784967)
			(xy 392.569454 -357.784967) (xy 392.569454 -357.730433) (xy 392.577215 -357.676453) (xy 392.59258 -357.624128)
			(xy 392.615234 -357.574522) (xy 392.644718 -357.528644) (xy 392.68043 -357.48743) (xy 392.721644 -357.451718)
			(xy 392.767522 -357.422234) (xy 392.817128 -357.39958) (xy 392.869453 -357.384215) (xy 392.923433 -357.376454)
			(xy 392.9507 -357.375968) (xy 393.8143 -357.375968) (xy 393.841572 -357.376395) (xy 393.895559 -357.384157)
			(xy 393.947893 -357.399523) (xy 393.997507 -357.422181) (xy 394.043392 -357.451669) (xy 394.084612 -357.487388)
			(xy 394.120331 -357.528608) (xy 394.149819 -357.574493) (xy 394.172477 -357.624107) (xy 394.187843 -357.676441)
			(xy 394.195605 -357.730428) (xy 394.195605 -357.784965) (xy 395.678454 -357.784965) (xy 395.678454 -357.730435)
			(xy 395.686214 -357.676459) (xy 395.701576 -357.624137) (xy 395.724228 -357.574533) (xy 395.753708 -357.528658)
			(xy 395.789416 -357.487444) (xy 395.830625 -357.451732) (xy 395.876498 -357.422247) (xy 395.926099 -357.39959)
			(xy 395.97842 -357.384223) (xy 396.032395 -357.376457) (xy 396.05966 -357.375968) (xy 396.92326 -357.375968)
			(xy 396.950535 -357.376369) (xy 397.00453 -357.384127) (xy 397.056872 -357.399491) (xy 397.106494 -357.422148)
			(xy 397.152386 -357.451637) (xy 397.193615 -357.487357) (xy 397.229339 -357.528582) (xy 397.258833 -357.574471)
			(xy 397.281495 -357.62409) (xy 397.296865 -357.67643) (xy 397.304628 -357.730425) (xy 397.304628 -357.78497)
			(xy 398.787331 -357.78497) (xy 398.787331 -357.73043) (xy 398.795094 -357.676446) (xy 398.81046 -357.624116)
			(xy 398.833117 -357.574505) (xy 398.862604 -357.528624) (xy 398.898321 -357.487407) (xy 398.93954 -357.451692)
			(xy 398.985423 -357.422207) (xy 399.035034 -357.399553) (xy 399.087365 -357.384189) (xy 399.14135 -357.37643)
			(xy 399.16862 -357.375968) (xy 400.03222 -357.375968) (xy 400.059491 -357.376396) (xy 400.113476 -357.38416)
			(xy 400.165807 -357.399529) (xy 400.215419 -357.422188) (xy 400.261301 -357.451677) (xy 400.30252 -357.487395)
			(xy 400.338235 -357.528615) (xy 400.367722 -357.574499) (xy 400.390378 -357.624111) (xy 400.405744 -357.676443)
			(xy 400.413506 -357.730429) (xy 400.413506 -357.784966) (xy 401.896354 -357.784966) (xy 401.896354 -357.730434)
			(xy 401.904115 -357.676456) (xy 401.919478 -357.624132) (xy 401.942131 -357.574527) (xy 401.971613 -357.528651)
			(xy 402.007323 -357.487437) (xy 402.048535 -357.451725) (xy 402.09441 -357.422241) (xy 402.144013 -357.399585)
			(xy 402.196337 -357.384219) (xy 402.250314 -357.376456) (xy 402.27758 -357.375968) (xy 403.14118 -357.375968)
			(xy 403.168454 -357.37637) (xy 403.222447 -357.384131) (xy 403.274787 -357.399496) (xy 403.324406 -357.422155)
			(xy 403.370296 -357.451644) (xy 403.411522 -357.487364) (xy 403.447244 -357.528588) (xy 403.476736 -357.574476)
			(xy 403.499397 -357.624095) (xy 403.514765 -357.676433) (xy 403.522528 -357.730426) (xy 403.522528 -357.784965)
			(xy 412.022854 -357.784965) (xy 412.022854 -357.730435) (xy 412.030614 -357.67646) (xy 412.045976 -357.624138)
			(xy 412.068627 -357.574535) (xy 412.098106 -357.52866) (xy 412.133813 -357.487447) (xy 412.175022 -357.451735)
			(xy 412.220893 -357.42225) (xy 412.270493 -357.399593) (xy 412.322813 -357.384224) (xy 412.376787 -357.376458)
			(xy 412.404052 -357.375968) (xy 413.267652 -357.375968) (xy 413.294927 -357.376368) (xy 413.348924 -357.384125)
			(xy 413.401266 -357.399489) (xy 413.450889 -357.422145) (xy 413.496783 -357.451634) (xy 413.538012 -357.487354)
			(xy 413.573737 -357.528579) (xy 413.603232 -357.574468) (xy 413.625894 -357.624089) (xy 413.641264 -357.676429)
			(xy 413.649028 -357.730425) (xy 413.649028 -357.784969) (xy 415.131731 -357.784969) (xy 415.131731 -357.730431)
			(xy 415.139493 -357.676447) (xy 415.154859 -357.624117) (xy 415.177516 -357.574507) (xy 415.207002 -357.528627)
			(xy 415.242718 -357.487409) (xy 415.283936 -357.451695) (xy 415.329818 -357.42221) (xy 415.379429 -357.399555)
			(xy 415.431759 -357.384191) (xy 415.485743 -357.376431) (xy 415.513012 -357.375968) (xy 416.376612 -357.375968)
			(xy 416.403883 -357.376395) (xy 416.457869 -357.384159) (xy 416.510202 -357.399527) (xy 416.559814 -357.422185)
			(xy 416.605697 -357.451674) (xy 416.646917 -357.487392) (xy 416.682633 -357.528612) (xy 416.712121 -357.574496)
			(xy 416.734778 -357.62411) (xy 416.750144 -357.676442) (xy 416.757906 -357.730429) (xy 416.757906 -357.784966)
			(xy 418.240754 -357.784966) (xy 418.240754 -357.730434) (xy 418.248515 -357.676457) (xy 418.263877 -357.624134)
			(xy 418.28653 -357.57453) (xy 418.316011 -357.528654) (xy 418.35172 -357.48744) (xy 418.392931 -357.451727)
			(xy 418.438805 -357.422243) (xy 418.488408 -357.399587) (xy 418.54073 -357.384221) (xy 418.594706 -357.376456)
			(xy 418.621972 -357.375968) (xy 419.485572 -357.375968) (xy 419.512846 -357.37637) (xy 419.566841 -357.384129)
			(xy 419.619181 -357.399494) (xy 419.668801 -357.422152) (xy 419.714692 -357.451641) (xy 419.755919 -357.487361)
			(xy 419.791642 -357.528585) (xy 419.821135 -357.574474) (xy 419.843796 -357.624093) (xy 419.859165 -357.676432)
			(xy 419.866928 -357.730426) (xy 419.866928 -357.78497) (xy 421.349632 -357.78497) (xy 421.349632 -357.73043)
			(xy 421.357394 -357.676444) (xy 421.372761 -357.624113) (xy 421.395419 -357.574502) (xy 421.424907 -357.52862)
			(xy 421.460625 -357.487402) (xy 421.501846 -357.451688) (xy 421.54773 -357.422203) (xy 421.597343 -357.399549)
			(xy 421.649676 -357.384187) (xy 421.703662 -357.376429) (xy 421.730932 -357.375968) (xy 422.594532 -357.375968)
			(xy 422.621802 -357.376397) (xy 422.675786 -357.384163) (xy 422.728116 -357.399532) (xy 422.777726 -357.422192)
			(xy 422.823607 -357.451681) (xy 422.864824 -357.487399) (xy 422.900538 -357.528619) (xy 422.930024 -357.574502)
			(xy 422.952679 -357.624114) (xy 422.968044 -357.676445) (xy 422.975806 -357.73043) (xy 422.975806 -357.784967)
			(xy 424.458654 -357.784967) (xy 424.458654 -357.730433) (xy 424.466415 -357.676454) (xy 424.481779 -357.62413)
			(xy 424.504433 -357.574524) (xy 424.533916 -357.528647) (xy 424.569627 -357.487433) (xy 424.610841 -357.45172)
			(xy 424.656717 -357.422237) (xy 424.706322 -357.399582) (xy 424.758647 -357.384217) (xy 424.812625 -357.376455)
			(xy 424.839892 -357.375968) (xy 425.703492 -357.375968) (xy 425.730766 -357.376371) (xy 425.784757 -357.384133)
			(xy 425.837095 -357.3995) (xy 425.886713 -357.422159) (xy 425.932602 -357.451648) (xy 425.973826 -357.487368)
			(xy 426.009547 -357.528592) (xy 426.039038 -357.57448) (xy 426.061698 -357.624097) (xy 426.077065 -357.676435)
			(xy 426.084828 -357.730426) (xy 426.084828 -357.784965) (xy 427.567654 -357.784965) (xy 427.567654 -357.730435)
			(xy 427.575414 -357.67646) (xy 427.590776 -357.624138) (xy 427.613427 -357.574535) (xy 427.642906 -357.52866)
			(xy 427.678613 -357.487447) (xy 427.719822 -357.451735) (xy 427.765693 -357.42225) (xy 427.815293 -357.399593)
			(xy 427.867613 -357.384224) (xy 427.921587 -357.376458) (xy 427.948852 -357.375968) (xy 428.812452 -357.375968)
			(xy 428.839727 -357.376368) (xy 428.893724 -357.384125) (xy 428.946066 -357.399489) (xy 428.995689 -357.422145)
			(xy 429.041583 -357.451634) (xy 429.082812 -357.487354) (xy 429.118537 -357.528579) (xy 429.148032 -357.574468)
			(xy 429.170694 -357.624089) (xy 429.186064 -357.676429) (xy 429.193828 -357.730425) (xy 429.193828 -357.784969)
			(xy 430.676531 -357.784969) (xy 430.676531 -357.730431) (xy 430.684293 -357.676447) (xy 430.699659 -357.624117)
			(xy 430.722316 -357.574507) (xy 430.751802 -357.528627) (xy 430.787518 -357.487409) (xy 430.828736 -357.451695)
			(xy 430.874618 -357.42221) (xy 430.924229 -357.399555) (xy 430.976559 -357.384191) (xy 431.030543 -357.376431)
			(xy 431.057812 -357.375968) (xy 431.921412 -357.375968) (xy 431.948683 -357.376395) (xy 432.002669 -357.384159)
			(xy 432.055002 -357.399527) (xy 432.104614 -357.422185) (xy 432.150497 -357.451674) (xy 432.191717 -357.487392)
			(xy 432.227433 -357.528612) (xy 432.256921 -357.574496) (xy 432.279578 -357.62411) (xy 432.294944 -357.676442)
			(xy 432.302706 -357.730429) (xy 432.302706 -357.784966) (xy 433.785554 -357.784966) (xy 433.785554 -357.730434)
			(xy 433.793315 -357.676457) (xy 433.808677 -357.624134) (xy 433.83133 -357.57453) (xy 433.860811 -357.528654)
			(xy 433.89652 -357.48744) (xy 433.937731 -357.451727) (xy 433.983605 -357.422243) (xy 434.033208 -357.399587)
			(xy 434.08553 -357.384221) (xy 434.139506 -357.376456) (xy 434.166772 -357.375968) (xy 435.030372 -357.375968)
			(xy 435.057646 -357.37637) (xy 435.111641 -357.384129) (xy 435.163981 -357.399494) (xy 435.213601 -357.422152)
			(xy 435.259492 -357.451641) (xy 435.300719 -357.487361) (xy 435.336442 -357.528585) (xy 435.365935 -357.574474)
			(xy 435.388596 -357.624093) (xy 435.403965 -357.676432) (xy 435.411728 -357.730426) (xy 435.411728 -357.78497)
			(xy 436.894432 -357.78497) (xy 436.894432 -357.73043) (xy 436.902194 -357.676444) (xy 436.917561 -357.624113)
			(xy 436.940219 -357.574502) (xy 436.969707 -357.52862) (xy 437.005425 -357.487402) (xy 437.046646 -357.451688)
			(xy 437.09253 -357.422203) (xy 437.142143 -357.399549) (xy 437.194476 -357.384187) (xy 437.248462 -357.376429)
			(xy 437.275732 -357.375968) (xy 438.139332 -357.375968) (xy 438.166602 -357.376397) (xy 438.220586 -357.384163)
			(xy 438.272916 -357.399532) (xy 438.322526 -357.422192) (xy 438.368407 -357.451681) (xy 438.409624 -357.487399)
			(xy 438.445338 -357.528619) (xy 438.474824 -357.574502) (xy 438.497479 -357.624114) (xy 438.512844 -357.676445)
			(xy 438.520606 -357.73043) (xy 438.520606 -357.784967) (xy 440.003454 -357.784967) (xy 440.003454 -357.730433)
			(xy 440.011215 -357.676454) (xy 440.026579 -357.62413) (xy 440.049233 -357.574524) (xy 440.078716 -357.528647)
			(xy 440.114427 -357.487433) (xy 440.155641 -357.45172) (xy 440.201517 -357.422237) (xy 440.251122 -357.399582)
			(xy 440.303447 -357.384217) (xy 440.357425 -357.376455) (xy 440.384692 -357.375968) (xy 441.248292 -357.375968)
			(xy 441.275566 -357.376371) (xy 441.329557 -357.384133) (xy 441.381895 -357.3995) (xy 441.431513 -357.422159)
			(xy 441.477402 -357.451648) (xy 441.518626 -357.487368) (xy 441.554347 -357.528592) (xy 441.583838 -357.57448)
			(xy 441.606498 -357.624097) (xy 441.621865 -357.676435) (xy 441.629628 -357.730426) (xy 441.629628 -357.784974)
			(xy 441.621865 -357.838965) (xy 441.606498 -357.891303) (xy 441.583838 -357.94092) (xy 441.554347 -357.986808)
			(xy 441.518626 -358.028032) (xy 441.477402 -358.063752) (xy 441.431513 -358.093241) (xy 441.381895 -358.1159)
			(xy 441.329557 -358.131267) (xy 441.275566 -358.139029) (xy 441.248292 -358.139492) (xy 440.384692 -358.139492)
			(xy 440.357425 -358.138945) (xy 440.303447 -358.131183) (xy 440.251122 -358.115818) (xy 440.201517 -358.093163)
			(xy 440.155641 -358.06368) (xy 440.114427 -358.027967) (xy 440.078716 -357.986753) (xy 440.049233 -357.940876)
			(xy 440.026579 -357.89127) (xy 440.011215 -357.838946) (xy 440.003454 -357.784967) (xy 438.520606 -357.784967)
			(xy 438.520606 -357.78497) (xy 438.512844 -357.838955) (xy 438.497479 -357.891286) (xy 438.474824 -357.940898)
			(xy 438.445338 -357.986781) (xy 438.409624 -358.028001) (xy 438.368407 -358.063719) (xy 438.322526 -358.093208)
			(xy 438.272916 -358.115868) (xy 438.220586 -358.131237) (xy 438.166602 -358.139003) (xy 438.139332 -358.139492)
			(xy 437.275732 -358.139492) (xy 437.248462 -358.138971) (xy 437.194476 -358.131213) (xy 437.142143 -358.115851)
			(xy 437.09253 -358.093197) (xy 437.046646 -358.063712) (xy 437.005425 -358.027998) (xy 436.969707 -357.98678)
			(xy 436.940219 -357.940898) (xy 436.917561 -357.891287) (xy 436.902194 -357.838956) (xy 436.894432 -357.78497)
			(xy 435.411728 -357.78497) (xy 435.411728 -357.784974) (xy 435.403965 -357.838968) (xy 435.388596 -357.891307)
			(xy 435.365935 -357.940926) (xy 435.336442 -357.986815) (xy 435.300719 -358.028039) (xy 435.259492 -358.063759)
			(xy 435.213601 -358.093248) (xy 435.163981 -358.115906) (xy 435.111641 -358.131271) (xy 435.057646 -358.13903)
			(xy 435.030372 -358.139492) (xy 434.166772 -358.139492) (xy 434.139506 -358.138944) (xy 434.08553 -358.131179)
			(xy 434.033208 -358.115813) (xy 433.983605 -358.093157) (xy 433.937731 -358.063673) (xy 433.89652 -358.02796)
			(xy 433.860811 -357.986746) (xy 433.83133 -357.94087) (xy 433.808677 -357.891266) (xy 433.793315 -357.838943)
			(xy 433.785554 -357.784966) (xy 432.302706 -357.784966) (xy 432.302706 -357.784971) (xy 432.294944 -357.838958)
			(xy 432.279578 -357.89129) (xy 432.256921 -357.940904) (xy 432.227433 -357.986788) (xy 432.191717 -358.028008)
			(xy 432.150497 -358.063726) (xy 432.104614 -358.093215) (xy 432.055002 -358.115873) (xy 432.002669 -358.131241)
			(xy 431.948683 -358.139005) (xy 431.921412 -358.139492) (xy 431.057812 -358.139492) (xy 431.030543 -358.138969)
			(xy 430.976559 -358.131209) (xy 430.924229 -358.115845) (xy 430.874618 -358.09319) (xy 430.828736 -358.063705)
			(xy 430.787518 -358.027991) (xy 430.751802 -357.986773) (xy 430.722316 -357.940893) (xy 430.699659 -357.891283)
			(xy 430.684293 -357.838953) (xy 430.676531 -357.784969) (xy 429.193828 -357.784969) (xy 429.193828 -357.784975)
			(xy 429.186064 -357.838971) (xy 429.170694 -357.891311) (xy 429.148032 -357.940932) (xy 429.118537 -357.986821)
			(xy 429.082812 -358.028046) (xy 429.041583 -358.063766) (xy 428.995689 -358.093255) (xy 428.946066 -358.115911)
			(xy 428.893724 -358.131275) (xy 428.839727 -358.139032) (xy 428.812452 -358.139492) (xy 427.948852 -358.139492)
			(xy 427.921587 -358.138942) (xy 427.867613 -358.131176) (xy 427.815293 -358.115807) (xy 427.765693 -358.09315)
			(xy 427.719822 -358.063665) (xy 427.678613 -358.027953) (xy 427.642906 -357.98674) (xy 427.613427 -357.940865)
			(xy 427.590776 -357.891262) (xy 427.575414 -357.83894) (xy 427.567654 -357.784965) (xy 426.084828 -357.784965)
			(xy 426.084828 -357.784974) (xy 426.077065 -357.838965) (xy 426.061698 -357.891303) (xy 426.039038 -357.94092)
			(xy 426.009547 -357.986808) (xy 425.973826 -358.028032) (xy 425.932602 -358.063752) (xy 425.886713 -358.093241)
			(xy 425.837095 -358.1159) (xy 425.784757 -358.131267) (xy 425.730766 -358.139029) (xy 425.703492 -358.139492)
			(xy 424.839892 -358.139492) (xy 424.812625 -358.138945) (xy 424.758647 -358.131183) (xy 424.706322 -358.115818)
			(xy 424.656717 -358.093163) (xy 424.610841 -358.06368) (xy 424.569627 -358.027967) (xy 424.533916 -357.986753)
			(xy 424.504433 -357.940876) (xy 424.481779 -357.89127) (xy 424.466415 -357.838946) (xy 424.458654 -357.784967)
			(xy 422.975806 -357.784967) (xy 422.975806 -357.78497) (xy 422.968044 -357.838955) (xy 422.952679 -357.891286)
			(xy 422.930024 -357.940898) (xy 422.900538 -357.986781) (xy 422.864824 -358.028001) (xy 422.823607 -358.063719)
			(xy 422.777726 -358.093208) (xy 422.728116 -358.115868) (xy 422.675786 -358.131237) (xy 422.621802 -358.139003)
			(xy 422.594532 -358.139492) (xy 421.730932 -358.139492) (xy 421.703662 -358.138971) (xy 421.649676 -358.131213)
			(xy 421.597343 -358.115851) (xy 421.54773 -358.093197) (xy 421.501846 -358.063712) (xy 421.460625 -358.027998)
			(xy 421.424907 -357.98678) (xy 421.395419 -357.940898) (xy 421.372761 -357.891287) (xy 421.357394 -357.838956)
			(xy 421.349632 -357.78497) (xy 419.866928 -357.78497) (xy 419.866928 -357.784974) (xy 419.859165 -357.838968)
			(xy 419.843796 -357.891307) (xy 419.821135 -357.940926) (xy 419.791642 -357.986815) (xy 419.755919 -358.028039)
			(xy 419.714692 -358.063759) (xy 419.668801 -358.093248) (xy 419.619181 -358.115906) (xy 419.566841 -358.131271)
			(xy 419.512846 -358.13903) (xy 419.485572 -358.139492) (xy 418.621972 -358.139492) (xy 418.594706 -358.138944)
			(xy 418.54073 -358.131179) (xy 418.488408 -358.115813) (xy 418.438805 -358.093157) (xy 418.392931 -358.063673)
			(xy 418.35172 -358.02796) (xy 418.316011 -357.986746) (xy 418.28653 -357.94087) (xy 418.263877 -357.891266)
			(xy 418.248515 -357.838943) (xy 418.240754 -357.784966) (xy 416.757906 -357.784966) (xy 416.757906 -357.784971)
			(xy 416.750144 -357.838958) (xy 416.734778 -357.89129) (xy 416.712121 -357.940904) (xy 416.682633 -357.986788)
			(xy 416.646917 -358.028008) (xy 416.605697 -358.063726) (xy 416.559814 -358.093215) (xy 416.510202 -358.115873)
			(xy 416.457869 -358.131241) (xy 416.403883 -358.139005) (xy 416.376612 -358.139492) (xy 415.513012 -358.139492)
			(xy 415.485743 -358.138969) (xy 415.431759 -358.131209) (xy 415.379429 -358.115845) (xy 415.329818 -358.09319)
			(xy 415.283936 -358.063705) (xy 415.242718 -358.027991) (xy 415.207002 -357.986773) (xy 415.177516 -357.940893)
			(xy 415.154859 -357.891283) (xy 415.139493 -357.838953) (xy 415.131731 -357.784969) (xy 413.649028 -357.784969)
			(xy 413.649028 -357.784975) (xy 413.641264 -357.838971) (xy 413.625894 -357.891311) (xy 413.603232 -357.940932)
			(xy 413.573737 -357.986821) (xy 413.538012 -358.028046) (xy 413.496783 -358.063766) (xy 413.450889 -358.093255)
			(xy 413.401266 -358.115911) (xy 413.348924 -358.131275) (xy 413.294927 -358.139032) (xy 413.267652 -358.139492)
			(xy 412.404052 -358.139492) (xy 412.376787 -358.138942) (xy 412.322813 -358.131176) (xy 412.270493 -358.115807)
			(xy 412.220893 -358.09315) (xy 412.175022 -358.063665) (xy 412.133813 -358.027953) (xy 412.098106 -357.98674)
			(xy 412.068627 -357.940865) (xy 412.045976 -357.891262) (xy 412.030614 -357.83894) (xy 412.022854 -357.784965)
			(xy 403.522528 -357.784965) (xy 403.522528 -357.784974) (xy 403.514765 -357.838967) (xy 403.499397 -357.891305)
			(xy 403.476736 -357.940924) (xy 403.447244 -357.986812) (xy 403.411522 -358.028036) (xy 403.370296 -358.063756)
			(xy 403.324406 -358.093245) (xy 403.274787 -358.115904) (xy 403.222447 -358.131269) (xy 403.168454 -358.13903)
			(xy 403.14118 -358.139492) (xy 402.27758 -358.139492) (xy 402.250314 -358.138944) (xy 402.196337 -358.131181)
			(xy 402.144013 -358.115815) (xy 402.09441 -358.093159) (xy 402.048535 -358.063675) (xy 402.007323 -358.027963)
			(xy 401.971613 -357.986749) (xy 401.942131 -357.940873) (xy 401.919478 -357.891268) (xy 401.904115 -357.838944)
			(xy 401.896354 -357.784966) (xy 400.413506 -357.784966) (xy 400.413506 -357.784971) (xy 400.405744 -357.838957)
			(xy 400.390378 -357.891289) (xy 400.367722 -357.940901) (xy 400.338235 -357.986785) (xy 400.30252 -358.028005)
			(xy 400.261301 -358.063723) (xy 400.215419 -358.093212) (xy 400.165807 -358.115871) (xy 400.113476 -358.13124)
			(xy 400.059491 -358.139004) (xy 400.03222 -358.139492) (xy 399.16862 -358.139492) (xy 399.14135 -358.13897)
			(xy 399.087365 -358.131211) (xy 399.035034 -358.115847) (xy 398.985423 -358.093193) (xy 398.93954 -358.063708)
			(xy 398.898321 -358.027993) (xy 398.862604 -357.986776) (xy 398.833117 -357.940895) (xy 398.81046 -357.891284)
			(xy 398.795094 -357.838954) (xy 398.787331 -357.78497) (xy 397.304628 -357.78497) (xy 397.304628 -357.784975)
			(xy 397.296865 -357.83897) (xy 397.281495 -357.89131) (xy 397.258833 -357.940929) (xy 397.229339 -357.986818)
			(xy 397.193615 -358.028043) (xy 397.152386 -358.063763) (xy 397.106494 -358.093252) (xy 397.056872 -358.115909)
			(xy 397.00453 -358.131273) (xy 396.950535 -358.139031) (xy 396.92326 -358.139492) (xy 396.05966 -358.139492)
			(xy 396.032395 -358.138943) (xy 395.97842 -358.131177) (xy 395.926099 -358.11581) (xy 395.876498 -358.093153)
			(xy 395.830625 -358.063668) (xy 395.789416 -358.027956) (xy 395.753708 -357.986742) (xy 395.724228 -357.940867)
			(xy 395.701576 -357.891263) (xy 395.686214 -357.838941) (xy 395.678454 -357.784965) (xy 394.195605 -357.784965)
			(xy 394.195605 -357.784972) (xy 394.187843 -357.838959) (xy 394.172477 -357.891293) (xy 394.149819 -357.940907)
			(xy 394.120331 -357.986792) (xy 394.084612 -358.028012) (xy 394.043392 -358.063731) (xy 393.997507 -358.093219)
			(xy 393.947893 -358.115877) (xy 393.895559 -358.131243) (xy 393.841572 -358.139005) (xy 393.8143 -358.139492)
			(xy 392.9507 -358.139492) (xy 392.923433 -358.138946) (xy 392.869453 -358.131185) (xy 392.817128 -358.11582)
			(xy 392.767522 -358.093166) (xy 392.721644 -358.063682) (xy 392.68043 -358.02797) (xy 392.644718 -357.986756)
			(xy 392.615234 -357.940878) (xy 392.59258 -357.891272) (xy 392.577215 -357.838947) (xy 392.569454 -357.784967)
			(xy 391.086606 -357.784967) (xy 391.086606 -357.78497) (xy 391.078844 -357.838954) (xy 391.06348 -357.891284)
			(xy 391.040825 -357.940896) (xy 391.01134 -357.986778) (xy 390.975627 -358.027998) (xy 390.934411 -358.063716)
			(xy 390.888531 -358.093206) (xy 390.838922 -358.115866) (xy 390.786593 -358.131236) (xy 390.73261 -358.139003)
			(xy 390.70534 -358.139492) (xy 389.84174 -358.139492) (xy 389.814469 -358.138971) (xy 389.760482 -358.131214)
			(xy 389.708149 -358.115853) (xy 389.658535 -358.093199) (xy 389.61265 -358.063715) (xy 389.571428 -358.028)
			(xy 389.535709 -357.986783) (xy 389.50622 -357.940901) (xy 389.483561 -357.891289) (xy 389.468194 -357.838957)
			(xy 389.460432 -357.784971) (xy 387.977728 -357.784971) (xy 387.977728 -357.784974) (xy 387.969965 -357.838967)
			(xy 387.954597 -357.891305) (xy 387.931936 -357.940924) (xy 387.902444 -357.986812) (xy 387.866722 -358.028036)
			(xy 387.825496 -358.063756) (xy 387.779606 -358.093245) (xy 387.729987 -358.115904) (xy 387.677647 -358.131269)
			(xy 387.623654 -358.13903) (xy 387.59638 -358.139492) (xy 386.73278 -358.139492) (xy 386.705514 -358.138944)
			(xy 386.651537 -358.131181) (xy 386.599213 -358.115815) (xy 386.54961 -358.093159) (xy 386.503735 -358.063675)
			(xy 386.462523 -358.027963) (xy 386.426813 -357.986749) (xy 386.397331 -357.940873) (xy 386.374678 -357.891268)
			(xy 386.359315 -357.838944) (xy 386.351554 -357.784966) (xy 384.868706 -357.784966) (xy 384.868706 -357.784971)
			(xy 384.860944 -357.838957) (xy 384.845578 -357.891289) (xy 384.822922 -357.940901) (xy 384.793435 -357.986785)
			(xy 384.75772 -358.028005) (xy 384.716501 -358.063723) (xy 384.670619 -358.093212) (xy 384.621007 -358.115871)
			(xy 384.568676 -358.13124) (xy 384.514691 -358.139004) (xy 384.48742 -358.139492) (xy 383.62382 -358.139492)
			(xy 383.59655 -358.13897) (xy 383.542565 -358.131211) (xy 383.490234 -358.115847) (xy 383.440623 -358.093193)
			(xy 383.39474 -358.063708) (xy 383.353521 -358.027993) (xy 383.317804 -357.986776) (xy 383.288317 -357.940895)
			(xy 383.26566 -357.891284) (xy 383.250294 -357.838954) (xy 383.242531 -357.78497) (xy 381.759828 -357.78497)
			(xy 381.759828 -357.784975) (xy 381.752065 -357.83897) (xy 381.736695 -357.89131) (xy 381.714033 -357.940929)
			(xy 381.684539 -357.986818) (xy 381.648815 -358.028043) (xy 381.607586 -358.063763) (xy 381.561694 -358.093252)
			(xy 381.512072 -358.115909) (xy 381.45973 -358.131273) (xy 381.405735 -358.139031) (xy 381.37846 -358.139492)
			(xy 380.51486 -358.139492) (xy 380.487595 -358.138943) (xy 380.43362 -358.131177) (xy 380.381299 -358.11581)
			(xy 380.331698 -358.093153) (xy 380.285825 -358.063668) (xy 380.244616 -358.027956) (xy 380.208908 -357.986742)
			(xy 380.179428 -357.940867) (xy 380.156776 -357.891263) (xy 380.141414 -357.838941) (xy 380.133654 -357.784965)
			(xy 378.650805 -357.784965) (xy 378.650805 -357.784972) (xy 378.643043 -357.838959) (xy 378.627677 -357.891293)
			(xy 378.605019 -357.940907) (xy 378.575531 -357.986792) (xy 378.539812 -358.028012) (xy 378.498592 -358.063731)
			(xy 378.452707 -358.093219) (xy 378.403093 -358.115877) (xy 378.350759 -358.131243) (xy 378.296772 -358.139005)
			(xy 378.2695 -358.139492) (xy 377.4059 -358.139492) (xy 377.378633 -358.138946) (xy 377.324653 -358.131185)
			(xy 377.272328 -358.11582) (xy 377.222722 -358.093166) (xy 377.176844 -358.063682) (xy 377.13563 -358.02797)
			(xy 377.099918 -357.986756) (xy 377.070434 -357.940878) (xy 377.04778 -357.891272) (xy 377.032415 -357.838947)
			(xy 377.024654 -357.784967) (xy 375.541806 -357.784967) (xy 375.541806 -357.78497) (xy 375.534044 -357.838954)
			(xy 375.51868 -357.891284) (xy 375.496025 -357.940896) (xy 375.46654 -357.986778) (xy 375.430827 -358.027998)
			(xy 375.389611 -358.063716) (xy 375.343731 -358.093206) (xy 375.294122 -358.115866) (xy 375.241793 -358.131236)
			(xy 375.18781 -358.139003) (xy 375.16054 -358.139492) (xy 374.29694 -358.139492) (xy 374.269669 -358.138971)
			(xy 374.215682 -358.131214) (xy 374.163349 -358.115853) (xy 374.113735 -358.093199) (xy 374.06785 -358.063715)
			(xy 374.026628 -358.028) (xy 373.990909 -357.986783) (xy 373.96142 -357.940901) (xy 373.938761 -357.891289)
			(xy 373.923394 -357.838957) (xy 373.915632 -357.784971) (xy 344.837306 -357.784971) (xy 344.829543 -357.838959)
			(xy 344.814177 -357.891292) (xy 344.791519 -357.940906) (xy 344.762031 -357.98679) (xy 344.726314 -358.028011)
			(xy 344.685093 -358.063729) (xy 344.639209 -358.093217) (xy 344.589596 -358.115876) (xy 344.537263 -358.131242)
			(xy 344.483275 -358.139005) (xy 344.456004 -358.139492) (xy 343.592404 -358.139492) (xy 343.565135 -358.138969)
			(xy 343.511152 -358.131208) (xy 343.458823 -358.115843) (xy 343.409213 -358.093188) (xy 343.363333 -358.063702)
			(xy 343.322115 -358.027988) (xy 343.2864 -357.986771) (xy 343.256914 -357.94089) (xy 343.234258 -357.891281)
			(xy 343.218893 -357.838952) (xy 343.211131 -357.784969) (xy 341.728306 -357.784969) (xy 341.728306 -357.78497)
			(xy 341.720544 -357.838953) (xy 341.70518 -357.891284) (xy 341.682525 -357.940895) (xy 341.653041 -357.986777)
			(xy 341.617328 -358.027997) (xy 341.576112 -358.063715) (xy 341.530233 -358.093204) (xy 341.480625 -358.115865)
			(xy 341.428297 -358.131235) (xy 341.374313 -358.139002) (xy 341.347044 -358.139492) (xy 340.483444 -358.139492)
			(xy 340.456173 -358.138972) (xy 340.402186 -358.131215) (xy 340.349852 -358.115854) (xy 340.300237 -358.093201)
			(xy 340.254351 -358.063716) (xy 340.213129 -358.028002) (xy 340.17741 -357.986784) (xy 340.147921 -357.940902)
			(xy 340.125261 -357.891289) (xy 340.109894 -357.838957) (xy 340.102132 -357.784971) (xy 338.619428 -357.784971)
			(xy 338.619428 -357.784974) (xy 338.611665 -357.838966) (xy 338.596297 -357.891304) (xy 338.573636 -357.940923)
			(xy 338.544145 -357.986811) (xy 338.508423 -358.028034) (xy 338.467198 -358.063755) (xy 338.421308 -358.093244)
			(xy 338.371689 -358.115903) (xy 338.319351 -358.131269) (xy 338.265358 -358.13903) (xy 338.238084 -358.139492)
			(xy 337.374484 -358.139492) (xy 337.347218 -358.138945) (xy 337.29324 -358.131182) (xy 337.240916 -358.115816)
			(xy 337.191312 -358.093161) (xy 337.145437 -358.063677) (xy 337.104224 -358.027964) (xy 337.068514 -357.98675)
			(xy 337.039032 -357.940874) (xy 337.016378 -357.891269) (xy 337.001015 -357.838944) (xy 336.993254 -357.784967)
			(xy 335.510406 -357.784967) (xy 335.510406 -357.78497) (xy 335.502644 -357.838956) (xy 335.487279 -357.891288)
			(xy 335.464622 -357.9409) (xy 335.435136 -357.986784) (xy 335.399421 -358.028004) (xy 335.358203 -358.063722)
			(xy 335.312321 -358.093211) (xy 335.26271 -358.11587) (xy 335.21038 -358.131239) (xy 335.156394 -358.139004)
			(xy 335.129124 -358.139492) (xy 334.265524 -358.139492) (xy 334.238254 -358.13897) (xy 334.184269 -358.131211)
			(xy 334.131937 -358.115848) (xy 334.082325 -358.093194) (xy 334.036442 -358.063709) (xy 333.995222 -358.027995)
			(xy 333.959505 -357.986777) (xy 333.930017 -357.940896) (xy 333.90736 -357.891285) (xy 333.891994 -357.838955)
			(xy 333.884231 -357.78497) (xy 332.401528 -357.78497) (xy 332.401528 -357.784975) (xy 332.393765 -357.838969)
			(xy 332.378395 -357.891309) (xy 332.355733 -357.940928) (xy 332.32624 -357.986817) (xy 332.290516 -358.028041)
			(xy 332.249288 -358.063762) (xy 332.203397 -358.093251) (xy 332.153775 -358.115908) (xy 332.101434 -358.131272)
			(xy 332.047439 -358.139031) (xy 332.020164 -358.139492) (xy 331.156564 -358.139492) (xy 331.129298 -358.138943)
			(xy 331.075323 -358.131178) (xy 331.023002 -358.115811) (xy 330.9734 -358.093154) (xy 330.927527 -358.06367)
			(xy 330.886317 -358.027957) (xy 330.850609 -357.986744) (xy 330.821128 -357.940868) (xy 330.798477 -357.891264)
			(xy 330.783114 -357.838942) (xy 330.775354 -357.784966) (xy 329.292506 -357.784966) (xy 329.292506 -357.784971)
			(xy 329.284743 -357.838959) (xy 329.269377 -357.891292) (xy 329.246719 -357.940906) (xy 329.217231 -357.98679)
			(xy 329.181514 -358.028011) (xy 329.140293 -358.063729) (xy 329.094409 -358.093217) (xy 329.044796 -358.115876)
			(xy 328.992463 -358.131242) (xy 328.938475 -358.139005) (xy 328.911204 -358.139492) (xy 328.047604 -358.139492)
			(xy 328.020335 -358.138969) (xy 327.966352 -358.131208) (xy 327.914023 -358.115843) (xy 327.864413 -358.093188)
			(xy 327.818533 -358.063702) (xy 327.777315 -358.027988) (xy 327.7416 -357.986771) (xy 327.712114 -357.94089)
			(xy 327.689458 -357.891281) (xy 327.674093 -357.838952) (xy 327.666331 -357.784969) (xy 326.183506 -357.784969)
			(xy 326.183506 -357.78497) (xy 326.175744 -357.838953) (xy 326.16038 -357.891284) (xy 326.137725 -357.940895)
			(xy 326.108241 -357.986777) (xy 326.072528 -358.027997) (xy 326.031312 -358.063715) (xy 325.985433 -358.093204)
			(xy 325.935825 -358.115865) (xy 325.883497 -358.131235) (xy 325.829513 -358.139002) (xy 325.802244 -358.139492)
			(xy 324.938644 -358.139492) (xy 324.911373 -358.138972) (xy 324.857386 -358.131215) (xy 324.805052 -358.115854)
			(xy 324.755437 -358.093201) (xy 324.709551 -358.063716) (xy 324.668329 -358.028002) (xy 324.63261 -357.986784)
			(xy 324.603121 -357.940902) (xy 324.580461 -357.891289) (xy 324.565094 -357.838957) (xy 324.557332 -357.784971)
			(xy 323.074628 -357.784971) (xy 323.074628 -357.784974) (xy 323.066865 -357.838966) (xy 323.051497 -357.891304)
			(xy 323.028836 -357.940923) (xy 322.999345 -357.986811) (xy 322.963623 -358.028034) (xy 322.922398 -358.063755)
			(xy 322.876508 -358.093244) (xy 322.826889 -358.115903) (xy 322.774551 -358.131269) (xy 322.720558 -358.13903)
			(xy 322.693284 -358.139492) (xy 321.829684 -358.139492) (xy 321.802418 -358.138945) (xy 321.74844 -358.131182)
			(xy 321.696116 -358.115816) (xy 321.646512 -358.093161) (xy 321.600637 -358.063677) (xy 321.559424 -358.027964)
			(xy 321.523714 -357.98675) (xy 321.494232 -357.940874) (xy 321.471578 -357.891269) (xy 321.456215 -357.838944)
			(xy 321.448454 -357.784967) (xy 319.965606 -357.784967) (xy 319.965606 -357.78497) (xy 319.957844 -357.838956)
			(xy 319.942479 -357.891288) (xy 319.919822 -357.9409) (xy 319.890336 -357.986784) (xy 319.854621 -358.028004)
			(xy 319.813403 -358.063722) (xy 319.767521 -358.093211) (xy 319.71791 -358.11587) (xy 319.66558 -358.131239)
			(xy 319.611594 -358.139004) (xy 319.584324 -358.139492) (xy 318.720724 -358.139492) (xy 318.693454 -358.13897)
			(xy 318.639469 -358.131211) (xy 318.587137 -358.115848) (xy 318.537525 -358.093194) (xy 318.491642 -358.063709)
			(xy 318.450422 -358.027995) (xy 318.414705 -357.986777) (xy 318.385217 -357.940896) (xy 318.36256 -357.891285)
			(xy 318.347194 -357.838955) (xy 318.339431 -357.78497) (xy 316.856728 -357.78497) (xy 316.856728 -357.784975)
			(xy 316.848965 -357.838969) (xy 316.833595 -357.891309) (xy 316.810933 -357.940928) (xy 316.78144 -357.986817)
			(xy 316.745716 -358.028041) (xy 316.704488 -358.063762) (xy 316.658597 -358.093251) (xy 316.608975 -358.115908)
			(xy 316.556634 -358.131272) (xy 316.502639 -358.139031) (xy 316.475364 -358.139492) (xy 315.611764 -358.139492)
			(xy 315.584498 -358.138943) (xy 315.530523 -358.131178) (xy 315.478202 -358.115811) (xy 315.4286 -358.093154)
			(xy 315.382727 -358.06367) (xy 315.341517 -358.027957) (xy 315.305809 -357.986744) (xy 315.276328 -357.940868)
			(xy 315.253677 -357.891264) (xy 315.238314 -357.838942) (xy 315.230554 -357.784966) (xy 300.231606 -357.784966)
			(xy 300.231606 -357.784971) (xy 300.223843 -357.838959) (xy 300.208477 -357.891293) (xy 300.185819 -357.940907)
			(xy 300.156331 -357.986791) (xy 300.120613 -358.028012) (xy 300.079393 -358.06373) (xy 300.033508 -358.093218)
			(xy 299.983894 -358.115876) (xy 299.931561 -358.131243) (xy 299.877573 -358.139005) (xy 299.850302 -358.139492)
			(xy 298.986702 -358.139492) (xy 298.959433 -358.138969) (xy 298.90545 -358.131207) (xy 298.853121 -358.115843)
			(xy 298.803512 -358.093187) (xy 298.757632 -358.063702) (xy 298.716414 -358.027987) (xy 298.6807 -357.98677)
			(xy 298.651214 -357.94089) (xy 298.628558 -357.89128) (xy 298.613193 -357.838952) (xy 298.605431 -357.784969)
			(xy 297.122606 -357.784969) (xy 297.122606 -357.78497) (xy 297.114844 -357.838954) (xy 297.09948 -357.891284)
			(xy 297.076825 -357.940895) (xy 297.047341 -357.986778) (xy 297.011627 -358.027998) (xy 296.970411 -358.063716)
			(xy 296.924532 -358.093205) (xy 296.874923 -358.115865) (xy 296.822595 -358.131235) (xy 296.768612 -358.139003)
			(xy 296.741342 -358.139492) (xy 295.877742 -358.139492) (xy 295.850471 -358.138971) (xy 295.796484 -358.131215)
			(xy 295.74415 -358.115853) (xy 295.694536 -358.0932) (xy 295.64865 -358.063716) (xy 295.607429 -358.028001)
			(xy 295.571709 -357.986783) (xy 295.54222 -357.940901) (xy 295.519561 -357.891289) (xy 295.504194 -357.838957)
			(xy 295.496432 -357.784971) (xy 294.013728 -357.784971) (xy 294.013728 -357.784974) (xy 294.005965 -357.838967)
			(xy 293.990597 -357.891305) (xy 293.967936 -357.940923) (xy 293.938444 -357.986811) (xy 293.902722 -358.028035)
			(xy 293.861497 -358.063755) (xy 293.815607 -358.093245) (xy 293.765988 -358.115903) (xy 293.713649 -358.131269)
			(xy 293.659656 -358.13903) (xy 293.632382 -358.139492) (xy 292.768782 -358.139492) (xy 292.741516 -358.138944)
			(xy 292.687538 -358.131181) (xy 292.635215 -358.115816) (xy 292.585611 -358.09316) (xy 292.539736 -358.063676)
			(xy 292.498524 -358.027964) (xy 292.462813 -357.98675) (xy 292.433331 -357.940873) (xy 292.410678 -357.891268)
			(xy 292.395315 -357.838944) (xy 292.387554 -357.784966) (xy 290.904706 -357.784966) (xy 290.904706 -357.784971)
			(xy 290.896944 -357.838956) (xy 290.881578 -357.891288) (xy 290.858922 -357.940901) (xy 290.829436 -357.986784)
			(xy 290.79372 -358.028005) (xy 290.752502 -358.063723) (xy 290.70662 -358.093211) (xy 290.657009 -358.115871)
			(xy 290.604678 -358.131239) (xy 290.550692 -358.139004) (xy 290.523422 -358.139492) (xy 289.659822 -358.139492)
			(xy 289.632552 -358.13897) (xy 289.578567 -358.131211) (xy 289.526236 -358.115848) (xy 289.476624 -358.093193)
			(xy 289.430741 -358.063709) (xy 289.389522 -358.027994) (xy 289.353805 -357.986777) (xy 289.324317 -357.940895)
			(xy 289.30166 -357.891285) (xy 289.286294 -357.838954) (xy 289.278531 -357.78497) (xy 287.795828 -357.78497)
			(xy 287.795828 -357.784975) (xy 287.788065 -357.838969) (xy 287.772695 -357.891309) (xy 287.750033 -357.940929)
			(xy 287.72054 -357.986818) (xy 287.684815 -358.028042) (xy 287.643587 -358.063762) (xy 287.597695 -358.093251)
			(xy 287.548073 -358.115908) (xy 287.495732 -358.131273) (xy 287.441737 -358.139031) (xy 287.414462 -358.139492)
			(xy 286.550862 -358.139492) (xy 286.523597 -358.138943) (xy 286.469621 -358.131178) (xy 286.4173 -358.11581)
			(xy 286.367699 -358.093154) (xy 286.321826 -358.063669) (xy 286.280617 -358.027957) (xy 286.244908 -357.986743)
			(xy 286.215428 -357.940868) (xy 286.192777 -357.891264) (xy 286.177414 -357.838942) (xy 286.169654 -357.784966)
			(xy 284.686806 -357.784966) (xy 284.686806 -357.784971) (xy 284.679043 -357.838959) (xy 284.663677 -357.891293)
			(xy 284.641019 -357.940907) (xy 284.611531 -357.986791) (xy 284.575813 -358.028012) (xy 284.534593 -358.06373)
			(xy 284.488708 -358.093218) (xy 284.439094 -358.115876) (xy 284.386761 -358.131243) (xy 284.332773 -358.139005)
			(xy 284.305502 -358.139492) (xy 283.441902 -358.139492) (xy 283.414633 -358.138969) (xy 283.36065 -358.131207)
			(xy 283.308321 -358.115843) (xy 283.258712 -358.093187) (xy 283.212832 -358.063702) (xy 283.171614 -358.027987)
			(xy 283.1359 -357.98677) (xy 283.106414 -357.94089) (xy 283.083758 -357.89128) (xy 283.068393 -357.838952)
			(xy 283.060631 -357.784969) (xy 281.577806 -357.784969) (xy 281.577806 -357.78497) (xy 281.570044 -357.838954)
			(xy 281.55468 -357.891284) (xy 281.532025 -357.940895) (xy 281.502541 -357.986778) (xy 281.466827 -358.027998)
			(xy 281.425611 -358.063716) (xy 281.379732 -358.093205) (xy 281.330123 -358.115865) (xy 281.277795 -358.131235)
			(xy 281.223812 -358.139003) (xy 281.196542 -358.139492) (xy 280.332942 -358.139492) (xy 280.305671 -358.138971)
			(xy 280.251684 -358.131215) (xy 280.19935 -358.115853) (xy 280.149736 -358.0932) (xy 280.10385 -358.063716)
			(xy 280.062629 -358.028001) (xy 280.026909 -357.986783) (xy 279.99742 -357.940901) (xy 279.974761 -357.891289)
			(xy 279.959394 -357.838957) (xy 279.951632 -357.784971) (xy 278.468928 -357.784971) (xy 278.468928 -357.784974)
			(xy 278.461165 -357.838967) (xy 278.445797 -357.891305) (xy 278.423136 -357.940923) (xy 278.393644 -357.986811)
			(xy 278.357922 -358.028035) (xy 278.316697 -358.063755) (xy 278.270807 -358.093245) (xy 278.221188 -358.115903)
			(xy 278.168849 -358.131269) (xy 278.114856 -358.13903) (xy 278.087582 -358.139492) (xy 277.223982 -358.139492)
			(xy 277.196716 -358.138944) (xy 277.142738 -358.131181) (xy 277.090415 -358.115816) (xy 277.040811 -358.09316)
			(xy 276.994936 -358.063676) (xy 276.953724 -358.027964) (xy 276.918013 -357.98675) (xy 276.888531 -357.940873)
			(xy 276.865878 -357.891268) (xy 276.850515 -357.838944) (xy 276.842754 -357.784966) (xy 275.359906 -357.784966)
			(xy 275.359906 -357.784971) (xy 275.352144 -357.838956) (xy 275.336778 -357.891288) (xy 275.314122 -357.940901)
			(xy 275.284636 -357.986784) (xy 275.24892 -358.028005) (xy 275.207702 -358.063723) (xy 275.16182 -358.093211)
			(xy 275.112209 -358.115871) (xy 275.059878 -358.131239) (xy 275.005892 -358.139004) (xy 274.978622 -358.139492)
			(xy 274.115022 -358.139492) (xy 274.087752 -358.13897) (xy 274.033767 -358.131211) (xy 273.981436 -358.115848)
			(xy 273.931824 -358.093193) (xy 273.885941 -358.063709) (xy 273.844722 -358.027994) (xy 273.809005 -357.986777)
			(xy 273.779517 -357.940895) (xy 273.75686 -357.891285) (xy 273.741494 -357.838954) (xy 273.733731 -357.78497)
			(xy 272.251028 -357.78497) (xy 272.251028 -357.784975) (xy 272.243265 -357.838969) (xy 272.227895 -357.891309)
			(xy 272.205233 -357.940929) (xy 272.17574 -357.986818) (xy 272.140015 -358.028042) (xy 272.098787 -358.063762)
			(xy 272.052895 -358.093251) (xy 272.003273 -358.115908) (xy 271.950932 -358.131273) (xy 271.896937 -358.139031)
			(xy 271.869662 -358.139492) (xy 271.006062 -358.139492) (xy 270.978797 -358.138943) (xy 270.924821 -358.131178)
			(xy 270.8725 -358.11581) (xy 270.822899 -358.093154) (xy 270.777026 -358.063669) (xy 270.735817 -358.027957)
			(xy 270.700108 -357.986743) (xy 270.670628 -357.940868) (xy 270.647977 -357.891264) (xy 270.632614 -357.838942)
			(xy 270.624854 -357.784966) (xy 247.276485 -357.784966) (xy 247.278987 -357.797946) (xy 247.287038 -357.88226)
			(xy 247.287542 -357.924608) (xy 247.287038 -357.966956) (xy 247.278987 -358.05127) (xy 247.262958 -358.134436)
			(xy 247.239097 -358.215703) (xy 247.207618 -358.294333) (xy 247.168807 -358.369614) (xy 247.123017 -358.440866)
			(xy 247.070661 -358.507442) (xy 247.012213 -358.56874) (xy 246.948203 -358.624205) (xy 246.879211 -358.673334)
			(xy 246.805861 -358.715683) (xy 246.728818 -358.750867) (xy 246.648779 -358.778569) (xy 246.56647 -358.798537)
			(xy 246.482635 -358.81059) (xy 246.398034 -358.814621) (xy 246.313433 -358.81059) (xy 246.229598 -358.798537)
			(xy 246.147289 -358.778569) (xy 246.06725 -358.750867) (xy 245.990207 -358.715683) (xy 245.916857 -358.673334)
			(xy 245.847865 -358.624205) (xy 245.783855 -358.56874) (xy 245.725407 -358.507442) (xy 245.673051 -358.440866)
			(xy 245.627261 -358.369614) (xy 245.58845 -358.294333) (xy 245.556971 -358.215703) (xy 245.53311 -358.134436)
			(xy 245.517081 -358.05127) (xy 245.50903 -357.966956) (xy 188.223925 -357.966956) (xy 188.191672 -358.004178)
			(xy 188.150456 -358.039891) (xy 188.104577 -358.069375) (xy 188.054969 -358.092029) (xy 188.002641 -358.107393)
			(xy 187.94866 -358.115153) (xy 187.921392 -358.115616) (xy 187.057792 -358.115616) (xy 187.03052 -358.115221)
			(xy 186.97653 -358.107457) (xy 186.924196 -358.092089) (xy 186.87458 -358.06943) (xy 186.828695 -358.03994)
			(xy 186.787473 -358.004221) (xy 186.751755 -357.962999) (xy 186.722266 -357.917112) (xy 186.699608 -357.867497)
			(xy 186.684241 -357.815162) (xy 186.676479 -357.761172) (xy 185.193629 -357.761172) (xy 185.18587 -357.815139)
			(xy 185.170508 -357.86746) (xy 185.147857 -357.917062) (xy 185.118378 -357.962936) (xy 185.08267 -358.004147)
			(xy 185.041461 -358.039858) (xy 184.99559 -358.069342) (xy 184.94599 -358.091997) (xy 184.89367 -358.107363)
			(xy 184.839697 -358.115128) (xy 184.812432 -358.115616) (xy 183.948832 -358.115616) (xy 183.921556 -358.115247)
			(xy 183.867559 -358.107487) (xy 183.815217 -358.092122) (xy 183.765593 -358.069463) (xy 183.7197 -358.039973)
			(xy 183.678471 -358.004251) (xy 183.642746 -357.963025) (xy 183.613252 -357.917135) (xy 183.590589 -357.867513)
			(xy 183.57522 -357.815172) (xy 183.567456 -357.761176) (xy 182.084828 -357.761176) (xy 182.084828 -357.784974)
			(xy 182.077065 -357.838968) (xy 182.061696 -357.891307) (xy 182.039035 -357.940926) (xy 182.009542 -357.986815)
			(xy 181.973819 -358.028039) (xy 181.932592 -358.063759) (xy 181.886701 -358.093248) (xy 181.837081 -358.115906)
			(xy 181.784741 -358.131271) (xy 181.730746 -358.13903) (xy 181.703472 -358.139492) (xy 180.839872 -358.139492)
			(xy 180.812606 -358.138944) (xy 180.75863 -358.131179) (xy 180.706308 -358.115813) (xy 180.656705 -358.093157)
			(xy 180.610831 -358.063673) (xy 180.56962 -358.02796) (xy 180.533911 -357.986746) (xy 180.50443 -357.94087)
			(xy 180.481777 -357.891266) (xy 180.466415 -357.838943) (xy 180.458654 -357.784966) (xy 178.975806 -357.784966)
			(xy 178.975806 -357.784971) (xy 178.968044 -357.838958) (xy 178.952678 -357.89129) (xy 178.930021 -357.940904)
			(xy 178.900533 -357.986788) (xy 178.864817 -358.028008) (xy 178.823597 -358.063726) (xy 178.777714 -358.093215)
			(xy 178.728102 -358.115873) (xy 178.675769 -358.131241) (xy 178.621783 -358.139005) (xy 178.594512 -358.139492)
			(xy 177.730912 -358.139492) (xy 177.703643 -358.138969) (xy 177.649659 -358.131209) (xy 177.597329 -358.115845)
			(xy 177.547718 -358.09319) (xy 177.501836 -358.063705) (xy 177.460618 -358.027991) (xy 177.424902 -357.986773)
			(xy 177.395416 -357.940893) (xy 177.372759 -357.891283) (xy 177.357393 -357.838953) (xy 177.349631 -357.784969)
			(xy 175.866928 -357.784969) (xy 175.866928 -357.784975) (xy 175.859164 -357.838971) (xy 175.843794 -357.891311)
			(xy 175.821132 -357.940932) (xy 175.791637 -357.986821) (xy 175.755912 -358.028046) (xy 175.714683 -358.063766)
			(xy 175.668789 -358.093255) (xy 175.619166 -358.115911) (xy 175.566824 -358.131275) (xy 175.512827 -358.139032)
			(xy 175.485552 -358.139492) (xy 174.621952 -358.139492) (xy 174.594687 -358.138942) (xy 174.540713 -358.131176)
			(xy 174.488393 -358.115807) (xy 174.438793 -358.09315) (xy 174.392922 -358.063665) (xy 174.351713 -358.027953)
			(xy 174.316006 -357.98674) (xy 174.286527 -357.940865) (xy 174.263876 -357.891262) (xy 174.248514 -357.83894)
			(xy 174.240754 -357.784965) (xy 172.757928 -357.784965) (xy 172.757928 -357.784974) (xy 172.750165 -357.838965)
			(xy 172.734798 -357.891303) (xy 172.712138 -357.94092) (xy 172.682647 -357.986808) (xy 172.646926 -358.028032)
			(xy 172.605702 -358.063752) (xy 172.559813 -358.093241) (xy 172.510195 -358.1159) (xy 172.457857 -358.131267)
			(xy 172.403866 -358.139029) (xy 172.376592 -358.139492) (xy 171.512992 -358.139492) (xy 171.485725 -358.138945)
			(xy 171.431747 -358.131183) (xy 171.379422 -358.115818) (xy 171.329817 -358.093163) (xy 171.283941 -358.06368)
			(xy 171.242727 -358.027967) (xy 171.207016 -357.986753) (xy 171.177533 -357.940876) (xy 171.154879 -357.89127)
			(xy 171.139515 -357.838946) (xy 171.131754 -357.784967) (xy 169.648906 -357.784967) (xy 169.648906 -357.78497)
			(xy 169.641144 -357.838955) (xy 169.625779 -357.891286) (xy 169.603124 -357.940898) (xy 169.573638 -357.986781)
			(xy 169.537924 -358.028001) (xy 169.496707 -358.063719) (xy 169.450826 -358.093208) (xy 169.401216 -358.115868)
			(xy 169.348886 -358.131237) (xy 169.294902 -358.139003) (xy 169.267632 -358.139492) (xy 168.404032 -358.139492)
			(xy 168.376762 -358.138971) (xy 168.322776 -358.131213) (xy 168.270443 -358.115851) (xy 168.22083 -358.093197)
			(xy 168.174946 -358.063712) (xy 168.133725 -358.027998) (xy 168.098007 -357.98678) (xy 168.068519 -357.940898)
			(xy 168.045861 -357.891287) (xy 168.030494 -357.838956) (xy 168.022732 -357.78497) (xy 166.540028 -357.78497)
			(xy 166.540028 -357.784974) (xy 166.532265 -357.838968) (xy 166.516896 -357.891307) (xy 166.494235 -357.940926)
			(xy 166.464742 -357.986815) (xy 166.429019 -358.028039) (xy 166.387792 -358.063759) (xy 166.341901 -358.093248)
			(xy 166.292281 -358.115906) (xy 166.239941 -358.131271) (xy 166.185946 -358.13903) (xy 166.158672 -358.139492)
			(xy 165.295072 -358.139492) (xy 165.267806 -358.138944) (xy 165.21383 -358.131179) (xy 165.161508 -358.115813)
			(xy 165.111905 -358.093157) (xy 165.066031 -358.063673) (xy 165.02482 -358.02796) (xy 164.989111 -357.986746)
			(xy 164.95963 -357.94087) (xy 164.936977 -357.891266) (xy 164.921615 -357.838943) (xy 164.913854 -357.784966)
			(xy 163.431006 -357.784966) (xy 163.431006 -357.784971) (xy 163.423244 -357.838958) (xy 163.407878 -357.89129)
			(xy 163.385221 -357.940904) (xy 163.355733 -357.986788) (xy 163.320017 -358.028008) (xy 163.278797 -358.063726)
			(xy 163.232914 -358.093215) (xy 163.183302 -358.115873) (xy 163.130969 -358.131241) (xy 163.076983 -358.139005)
			(xy 163.049712 -358.139492) (xy 162.186112 -358.139492) (xy 162.158843 -358.138969) (xy 162.104859 -358.131209)
			(xy 162.052529 -358.115845) (xy 162.002918 -358.09319) (xy 161.957036 -358.063705) (xy 161.915818 -358.027991)
			(xy 161.880102 -357.986773) (xy 161.850616 -357.940893) (xy 161.827959 -357.891283) (xy 161.812593 -357.838953)
			(xy 161.804831 -357.784969) (xy 160.322128 -357.784969) (xy 160.322128 -357.784975) (xy 160.314364 -357.838971)
			(xy 160.298994 -357.891311) (xy 160.276332 -357.940932) (xy 160.246837 -357.986821) (xy 160.211112 -358.028046)
			(xy 160.169883 -358.063766) (xy 160.123989 -358.093255) (xy 160.074366 -358.115911) (xy 160.022024 -358.131275)
			(xy 159.968027 -358.139032) (xy 159.940752 -358.139492) (xy 159.077152 -358.139492) (xy 159.049887 -358.138942)
			(xy 158.995913 -358.131176) (xy 158.943593 -358.115807) (xy 158.893993 -358.09315) (xy 158.848122 -358.063665)
			(xy 158.806913 -358.027953) (xy 158.771206 -357.98674) (xy 158.741727 -357.940865) (xy 158.719076 -357.891262)
			(xy 158.703714 -357.83894) (xy 158.695954 -357.784965) (xy 144.196606 -357.784965) (xy 144.196606 -357.784971)
			(xy 144.188843 -357.838958) (xy 144.173477 -357.891291) (xy 144.15082 -357.940905) (xy 144.121332 -357.986789)
			(xy 144.085615 -358.02801) (xy 144.044395 -358.063728) (xy 143.998512 -358.093216) (xy 143.948899 -358.115875)
			(xy 143.896566 -358.131242) (xy 143.842579 -358.139005) (xy 143.815308 -358.139492) (xy 142.951708 -358.139492)
			(xy 142.924439 -358.138969) (xy 142.870455 -358.131209) (xy 142.818126 -358.115844) (xy 142.768515 -358.093189)
			(xy 142.722634 -358.063704) (xy 142.681417 -358.027989) (xy 142.645701 -357.986772) (xy 142.616215 -357.940892)
			(xy 142.593559 -357.891282) (xy 142.578193 -357.838953) (xy 142.570431 -357.784969) (xy 141.087606 -357.784969)
			(xy 141.079845 -357.838953) (xy 141.06448 -357.891283) (xy 141.041826 -357.940894) (xy 141.012342 -357.986776)
			(xy 140.976629 -358.027995) (xy 140.935414 -358.063713) (xy 140.889536 -358.093203) (xy 140.839928 -358.115864)
			(xy 140.7876 -358.131234) (xy 140.733617 -358.139002) (xy 140.706348 -358.139492) (xy 139.842748 -358.139492)
			(xy 139.815477 -358.138972) (xy 139.761489 -358.131216) (xy 139.709155 -358.115855) (xy 139.659539 -358.093202)
			(xy 139.613653 -358.063718) (xy 139.572431 -358.028003) (xy 139.536711 -357.986785) (xy 139.507221 -357.940903)
			(xy 139.484562 -357.89129) (xy 139.469194 -357.838958) (xy 139.461432 -357.784971) (xy 137.978728 -357.784971)
			(xy 137.978728 -357.784974) (xy 137.970965 -357.838966) (xy 137.955597 -357.891304) (xy 137.932937 -357.940921)
			(xy 137.903446 -357.986809) (xy 137.867724 -358.028033) (xy 137.8265 -358.063753) (xy 137.780611 -358.093243)
			(xy 137.730992 -358.115901) (xy 137.678654 -358.131268) (xy 137.624662 -358.139029) (xy 137.597388 -358.139492)
			(xy 136.733788 -358.139492) (xy 136.706521 -358.138945) (xy 136.652543 -358.131182) (xy 136.600219 -358.115817)
			(xy 136.550615 -358.093162) (xy 136.504739 -358.063678) (xy 136.463526 -358.027966) (xy 136.427815 -357.986752)
			(xy 136.398332 -357.940875) (xy 136.375679 -357.891269) (xy 136.360315 -357.838945) (xy 136.352554 -357.784967)
			(xy 134.869706 -357.784967) (xy 134.869706 -357.78497) (xy 134.861944 -357.838956) (xy 134.846579 -357.891287)
			(xy 134.823923 -357.940899) (xy 134.794437 -357.986782) (xy 134.758722 -358.028003) (xy 134.717505 -358.063721)
			(xy 134.671624 -358.09321) (xy 134.622013 -358.115869) (xy 134.569683 -358.131238) (xy 134.515698 -358.139004)
			(xy 134.488428 -358.139492) (xy 133.624828 -358.139492) (xy 133.597558 -358.13897) (xy 133.543572 -358.131212)
			(xy 133.49124 -358.11585) (xy 133.441627 -358.093195) (xy 133.395744 -358.063711) (xy 133.354524 -358.027996)
			(xy 133.318806 -357.986779) (xy 133.289318 -357.940897) (xy 133.26666 -357.891286) (xy 133.251294 -357.838955)
			(xy 133.243531 -357.78497) (xy 131.760828 -357.78497) (xy 131.760828 -357.784975) (xy 131.753065 -357.838969)
			(xy 131.737696 -357.891308) (xy 131.715034 -357.940927) (xy 131.685541 -357.986816) (xy 131.649817 -358.02804)
			(xy 131.60859 -358.06376) (xy 131.562699 -358.093249) (xy 131.513078 -358.115907) (xy 131.460737 -358.131272)
			(xy 131.406743 -358.139031) (xy 131.379468 -358.139492) (xy 130.515868 -358.139492) (xy 130.488602 -358.138943)
			(xy 130.434626 -358.131179) (xy 130.382305 -358.115812) (xy 130.332703 -358.093156) (xy 130.286829 -358.063671)
			(xy 130.245619 -358.027959) (xy 130.20991 -357.986745) (xy 130.180429 -357.940869) (xy 130.157777 -357.891265)
			(xy 130.142414 -357.838942) (xy 130.134654 -357.784966) (xy 128.651806 -357.784966) (xy 128.651806 -357.784971)
			(xy 128.644043 -357.838958) (xy 128.628677 -357.891291) (xy 128.60602 -357.940905) (xy 128.576532 -357.986789)
			(xy 128.540815 -358.02801) (xy 128.499595 -358.063728) (xy 128.453712 -358.093216) (xy 128.404099 -358.115875)
			(xy 128.351766 -358.131242) (xy 128.297779 -358.139005) (xy 128.270508 -358.139492) (xy 127.406908 -358.139492)
			(xy 127.379639 -358.138969) (xy 127.325655 -358.131209) (xy 127.273326 -358.115844) (xy 127.223715 -358.093189)
			(xy 127.177834 -358.063704) (xy 127.136617 -358.027989) (xy 127.100901 -357.986772) (xy 127.071415 -357.940892)
			(xy 127.048759 -357.891282) (xy 127.033393 -357.838953) (xy 127.025631 -357.784969) (xy 125.542806 -357.784969)
			(xy 125.535045 -357.838953) (xy 125.51968 -357.891283) (xy 125.497026 -357.940894) (xy 125.467542 -357.986776)
			(xy 125.431829 -358.027995) (xy 125.390614 -358.063713) (xy 125.344736 -358.093203) (xy 125.295128 -358.115864)
			(xy 125.2428 -358.131234) (xy 125.188817 -358.139002) (xy 125.161548 -358.139492) (xy 124.297948 -358.139492)
			(xy 124.270677 -358.138972) (xy 124.216689 -358.131216) (xy 124.164355 -358.115855) (xy 124.114739 -358.093202)
			(xy 124.068853 -358.063718) (xy 124.027631 -358.028003) (xy 123.991911 -357.986785) (xy 123.962421 -357.940903)
			(xy 123.939762 -357.89129) (xy 123.924394 -357.838958) (xy 123.916632 -357.784971) (xy 122.433928 -357.784971)
			(xy 122.433928 -357.784974) (xy 122.426165 -357.838966) (xy 122.410797 -357.891304) (xy 122.388137 -357.940921)
			(xy 122.358646 -357.986809) (xy 122.322924 -358.028033) (xy 122.2817 -358.063753) (xy 122.235811 -358.093243)
			(xy 122.186192 -358.115901) (xy 122.133854 -358.131268) (xy 122.079862 -358.139029) (xy 122.052588 -358.139492)
			(xy 121.188988 -358.139492) (xy 121.161721 -358.138945) (xy 121.107743 -358.131182) (xy 121.055419 -358.115817)
			(xy 121.005815 -358.093162) (xy 120.959939 -358.063678) (xy 120.918726 -358.027966) (xy 120.883015 -357.986752)
			(xy 120.853532 -357.940875) (xy 120.830879 -357.891269) (xy 120.815515 -357.838945) (xy 120.807754 -357.784967)
			(xy 119.324906 -357.784967) (xy 119.324906 -357.78497) (xy 119.317144 -357.838956) (xy 119.301779 -357.891287)
			(xy 119.279123 -357.940899) (xy 119.249637 -357.986782) (xy 119.213922 -358.028003) (xy 119.172705 -358.063721)
			(xy 119.126824 -358.09321) (xy 119.077213 -358.115869) (xy 119.024883 -358.131238) (xy 118.970898 -358.139004)
			(xy 118.943628 -358.139492) (xy 118.080028 -358.139492) (xy 118.052758 -358.13897) (xy 117.998772 -358.131212)
			(xy 117.94644 -358.11585) (xy 117.896827 -358.093195) (xy 117.850944 -358.063711) (xy 117.809724 -358.027996)
			(xy 117.774006 -357.986779) (xy 117.744518 -357.940897) (xy 117.72186 -357.891286) (xy 117.706494 -357.838955)
			(xy 117.698731 -357.78497) (xy 116.216028 -357.78497) (xy 116.216028 -357.784975) (xy 116.208265 -357.838969)
			(xy 116.192896 -357.891308) (xy 116.170234 -357.940927) (xy 116.140741 -357.986816) (xy 116.105017 -358.02804)
			(xy 116.06379 -358.06376) (xy 116.017899 -358.093249) (xy 115.968278 -358.115907) (xy 115.915937 -358.131272)
			(xy 115.861943 -358.139031) (xy 115.834668 -358.139492) (xy 114.971068 -358.139492) (xy 114.943802 -358.138943)
			(xy 114.889826 -358.131179) (xy 114.837505 -358.115812) (xy 114.787903 -358.093156) (xy 114.742029 -358.063671)
			(xy 114.700819 -358.027959) (xy 114.66511 -357.986745) (xy 114.635629 -357.940869) (xy 114.612977 -357.891265)
			(xy 114.597614 -357.838942) (xy 114.589854 -357.784966) (xy 93.706706 -357.784966) (xy 93.706706 -357.78497)
			(xy 93.698944 -357.838954) (xy 93.68358 -357.891284) (xy 93.660925 -357.940895) (xy 93.631441 -357.986778)
			(xy 93.595727 -358.027998) (xy 93.554511 -358.063716) (xy 93.508632 -358.093205) (xy 93.459023 -358.115865)
			(xy 93.406695 -358.131235) (xy 93.352712 -358.139003) (xy 93.325442 -358.139492) (xy 92.461842 -358.139492)
			(xy 92.434571 -358.138971) (xy 92.380584 -358.131215) (xy 92.32825 -358.115853) (xy 92.278636 -358.0932)
			(xy 92.23275 -358.063716) (xy 92.191529 -358.028001) (xy 92.155809 -357.986783) (xy 92.12632 -357.940901)
			(xy 92.103661 -357.891289) (xy 92.088294 -357.838957) (xy 92.080532 -357.784971) (xy 90.597828 -357.784971)
			(xy 90.597828 -357.784974) (xy 90.590065 -357.838967) (xy 90.574697 -357.891305) (xy 90.552036 -357.940923)
			(xy 90.522544 -357.986811) (xy 90.486822 -358.028035) (xy 90.445597 -358.063755) (xy 90.399707 -358.093245)
			(xy 90.350088 -358.115903) (xy 90.297749 -358.131269) (xy 90.243756 -358.13903) (xy 90.216482 -358.139492)
			(xy 89.352882 -358.139492) (xy 89.325616 -358.138944) (xy 89.271638 -358.131181) (xy 89.219315 -358.115816)
			(xy 89.169711 -358.09316) (xy 89.123836 -358.063676) (xy 89.082624 -358.027964) (xy 89.046913 -357.98675)
			(xy 89.017431 -357.940873) (xy 88.994778 -357.891268) (xy 88.979415 -357.838944) (xy 88.971654 -357.784966)
			(xy 87.488806 -357.784966) (xy 87.488806 -357.784971) (xy 87.481044 -357.838956) (xy 87.465678 -357.891288)
			(xy 87.443022 -357.940901) (xy 87.413536 -357.986784) (xy 87.37782 -358.028005) (xy 87.336602 -358.063723)
			(xy 87.29072 -358.093211) (xy 87.241109 -358.115871) (xy 87.188778 -358.131239) (xy 87.134792 -358.139004)
			(xy 87.107522 -358.139492) (xy 86.243922 -358.139492) (xy 86.216652 -358.13897) (xy 86.162667 -358.131211)
			(xy 86.110336 -358.115848) (xy 86.060724 -358.093193) (xy 86.014841 -358.063709) (xy 85.973622 -358.027994)
			(xy 85.937905 -357.986777) (xy 85.908417 -357.940895) (xy 85.88576 -357.891285) (xy 85.870394 -357.838954)
			(xy 85.862631 -357.78497) (xy 84.379928 -357.78497) (xy 84.379928 -357.784975) (xy 84.372165 -357.838969)
			(xy 84.356795 -357.891309) (xy 84.334133 -357.940929) (xy 84.30464 -357.986818) (xy 84.268915 -358.028042)
			(xy 84.227687 -358.063762) (xy 84.181795 -358.093251) (xy 84.132173 -358.115908) (xy 84.079832 -358.131273)
			(xy 84.025837 -358.139031) (xy 83.998562 -358.139492) (xy 83.134962 -358.139492) (xy 83.107697 -358.138943)
			(xy 83.053721 -358.131178) (xy 83.0014 -358.11581) (xy 82.951799 -358.093154) (xy 82.905926 -358.063669)
			(xy 82.864717 -358.027957) (xy 82.829008 -357.986743) (xy 82.799528 -357.940868) (xy 82.776877 -357.891264)
			(xy 82.761514 -357.838942) (xy 82.753754 -357.784966) (xy 81.270906 -357.784966) (xy 81.270906 -357.784971)
			(xy 81.263143 -357.838959) (xy 81.247777 -357.891293) (xy 81.225119 -357.940907) (xy 81.195631 -357.986791)
			(xy 81.159913 -358.028012) (xy 81.118693 -358.06373) (xy 81.072808 -358.093218) (xy 81.023194 -358.115876)
			(xy 80.970861 -358.131243) (xy 80.916873 -358.139005) (xy 80.889602 -358.139492) (xy 80.026002 -358.139492)
			(xy 79.998733 -358.138969) (xy 79.94475 -358.131207) (xy 79.892421 -358.115843) (xy 79.842812 -358.093187)
			(xy 79.796932 -358.063702) (xy 79.755714 -358.027987) (xy 79.72 -357.98677) (xy 79.690514 -357.94089)
			(xy 79.667858 -357.89128) (xy 79.652493 -357.838952) (xy 79.644731 -357.784969) (xy 78.161906 -357.784969)
			(xy 78.161906 -357.78497) (xy 78.154144 -357.838954) (xy 78.13878 -357.891284) (xy 78.116125 -357.940895)
			(xy 78.086641 -357.986778) (xy 78.050927 -358.027998) (xy 78.009711 -358.063716) (xy 77.963832 -358.093205)
			(xy 77.914223 -358.115865) (xy 77.861895 -358.131235) (xy 77.807912 -358.139003) (xy 77.780642 -358.139492)
			(xy 76.917042 -358.139492) (xy 76.889771 -358.138971) (xy 76.835784 -358.131215) (xy 76.78345 -358.115853)
			(xy 76.733836 -358.0932) (xy 76.68795 -358.063716) (xy 76.646729 -358.028001) (xy 76.611009 -357.986783)
			(xy 76.58152 -357.940901) (xy 76.558861 -357.891289) (xy 76.543494 -357.838957) (xy 76.535732 -357.784971)
			(xy 75.053028 -357.784971) (xy 75.053028 -357.784974) (xy 75.045265 -357.838967) (xy 75.029897 -357.891305)
			(xy 75.007236 -357.940923) (xy 74.977744 -357.986811) (xy 74.942022 -358.028035) (xy 74.900797 -358.063755)
			(xy 74.854907 -358.093245) (xy 74.805288 -358.115903) (xy 74.752949 -358.131269) (xy 74.698956 -358.13903)
			(xy 74.671682 -358.139492) (xy 73.808082 -358.139492) (xy 73.780816 -358.138944) (xy 73.726838 -358.131181)
			(xy 73.674515 -358.115816) (xy 73.624911 -358.09316) (xy 73.579036 -358.063676) (xy 73.537824 -358.027964)
			(xy 73.502113 -357.98675) (xy 73.472631 -357.940873) (xy 73.449978 -357.891268) (xy 73.434615 -357.838944)
			(xy 73.426854 -357.784966) (xy 71.944006 -357.784966) (xy 71.944006 -357.784971) (xy 71.936244 -357.838956)
			(xy 71.920878 -357.891288) (xy 71.898222 -357.940901) (xy 71.868736 -357.986784) (xy 71.83302 -358.028005)
			(xy 71.791802 -358.063723) (xy 71.74592 -358.093211) (xy 71.696309 -358.115871) (xy 71.643978 -358.131239)
			(xy 71.589992 -358.139004) (xy 71.562722 -358.139492) (xy 70.699122 -358.139492) (xy 70.671852 -358.13897)
			(xy 70.617867 -358.131211) (xy 70.565536 -358.115848) (xy 70.515924 -358.093193) (xy 70.470041 -358.063709)
			(xy 70.428822 -358.027994) (xy 70.393105 -357.986777) (xy 70.363617 -357.940895) (xy 70.34096 -357.891285)
			(xy 70.325594 -357.838954) (xy 70.317831 -357.78497) (xy 68.835128 -357.78497) (xy 68.835128 -357.784975)
			(xy 68.827365 -357.838969) (xy 68.811995 -357.891309) (xy 68.789333 -357.940929) (xy 68.75984 -357.986818)
			(xy 68.724115 -358.028042) (xy 68.682887 -358.063762) (xy 68.636995 -358.093251) (xy 68.587373 -358.115908)
			(xy 68.535032 -358.131273) (xy 68.481037 -358.139031) (xy 68.453762 -358.139492) (xy 67.590162 -358.139492)
			(xy 67.562897 -358.138943) (xy 67.508921 -358.131178) (xy 67.4566 -358.11581) (xy 67.406999 -358.093154)
			(xy 67.361126 -358.063669) (xy 67.319917 -358.027957) (xy 67.284208 -357.986743) (xy 67.254728 -357.940868)
			(xy 67.232077 -357.891264) (xy 67.216714 -357.838942) (xy 67.208954 -357.784966) (xy 65.726106 -357.784966)
			(xy 65.726106 -357.784971) (xy 65.718343 -357.838959) (xy 65.702977 -357.891293) (xy 65.680319 -357.940907)
			(xy 65.650831 -357.986791) (xy 65.615113 -358.028012) (xy 65.573893 -358.06373) (xy 65.528008 -358.093218)
			(xy 65.478394 -358.115876) (xy 65.426061 -358.131243) (xy 65.372073 -358.139005) (xy 65.344802 -358.139492)
			(xy 64.481202 -358.139492) (xy 64.453933 -358.138969) (xy 64.39995 -358.131207) (xy 64.347621 -358.115843)
			(xy 64.298012 -358.093187) (xy 64.252132 -358.063702) (xy 64.210914 -358.027987) (xy 64.1752 -357.98677)
			(xy 64.145714 -357.94089) (xy 64.123058 -357.89128) (xy 64.107693 -357.838952) (xy 64.099931 -357.784969)
			(xy 51.666906 -357.784969) (xy 51.659145 -357.838953) (xy 51.64378 -357.891283) (xy 51.621126 -357.940894)
			(xy 51.591642 -357.986776) (xy 51.555929 -358.027995) (xy 51.514714 -358.063713) (xy 51.468836 -358.093203)
			(xy 51.419228 -358.115864) (xy 51.3669 -358.131234) (xy 51.312917 -358.139002) (xy 51.285648 -358.139492)
			(xy 50.422048 -358.139492) (xy 50.394777 -358.138972) (xy 50.340789 -358.131216) (xy 50.288455 -358.115855)
			(xy 50.238839 -358.093202) (xy 50.192953 -358.063718) (xy 50.151731 -358.028003) (xy 50.116011 -357.986785)
			(xy 50.086521 -357.940903) (xy 50.063862 -357.89129) (xy 50.048494 -357.838958) (xy 50.040732 -357.784971)
			(xy 48.558028 -357.784971) (xy 48.558028 -357.784974) (xy 48.550265 -357.838966) (xy 48.534897 -357.891304)
			(xy 48.512237 -357.940921) (xy 48.482746 -357.986809) (xy 48.447024 -358.028033) (xy 48.4058 -358.063753)
			(xy 48.359911 -358.093243) (xy 48.310292 -358.115901) (xy 48.257954 -358.131268) (xy 48.203962 -358.139029)
			(xy 48.176688 -358.139492) (xy 47.313088 -358.139492) (xy 47.285821 -358.138945) (xy 47.231843 -358.131182)
			(xy 47.179519 -358.115817) (xy 47.129915 -358.093162) (xy 47.084039 -358.063678) (xy 47.042826 -358.027966)
			(xy 47.007115 -357.986752) (xy 46.977632 -357.940875) (xy 46.954979 -357.891269) (xy 46.939615 -357.838945)
			(xy 46.931854 -357.784967) (xy 45.449006 -357.784967) (xy 45.449006 -357.78497) (xy 45.441244 -357.838956)
			(xy 45.425879 -357.891287) (xy 45.403223 -357.940899) (xy 45.373737 -357.986782) (xy 45.338022 -358.028003)
			(xy 45.296805 -358.063721) (xy 45.250924 -358.09321) (xy 45.201313 -358.115869) (xy 45.148983 -358.131238)
			(xy 45.094998 -358.139004) (xy 45.067728 -358.139492) (xy 44.204128 -358.139492) (xy 44.176858 -358.13897)
			(xy 44.122872 -358.131212) (xy 44.07054 -358.11585) (xy 44.020927 -358.093195) (xy 43.975044 -358.063711)
			(xy 43.933824 -358.027996) (xy 43.898106 -357.986779) (xy 43.868618 -357.940897) (xy 43.84596 -357.891286)
			(xy 43.830594 -357.838955) (xy 43.822831 -357.78497) (xy 42.340128 -357.78497) (xy 42.340128 -357.784975)
			(xy 42.332365 -357.838969) (xy 42.316996 -357.891308) (xy 42.294334 -357.940927) (xy 42.264841 -357.986816)
			(xy 42.229117 -358.02804) (xy 42.18789 -358.06376) (xy 42.141999 -358.093249) (xy 42.092378 -358.115907)
			(xy 42.040037 -358.131272) (xy 41.986043 -358.139031) (xy 41.958768 -358.139492) (xy 41.095168 -358.139492)
			(xy 41.067902 -358.138943) (xy 41.013926 -358.131179) (xy 40.961605 -358.115812) (xy 40.912003 -358.093156)
			(xy 40.866129 -358.063671) (xy 40.824919 -358.027959) (xy 40.78921 -357.986745) (xy 40.759729 -357.940869)
			(xy 40.737077 -357.891265) (xy 40.721714 -357.838942) (xy 40.713954 -357.784966) (xy 39.231106 -357.784966)
			(xy 39.231106 -357.784971) (xy 39.223343 -357.838958) (xy 39.207977 -357.891291) (xy 39.18532 -357.940905)
			(xy 39.155832 -357.986789) (xy 39.120115 -358.02801) (xy 39.078895 -358.063728) (xy 39.033012 -358.093216)
			(xy 38.983399 -358.115875) (xy 38.931066 -358.131242) (xy 38.877079 -358.139005) (xy 38.849808 -358.139492)
			(xy 37.986208 -358.139492) (xy 37.958939 -358.138969) (xy 37.904955 -358.131209) (xy 37.852626 -358.115844)
			(xy 37.803015 -358.093189) (xy 37.757134 -358.063704) (xy 37.715917 -358.027989) (xy 37.680201 -357.986772)
			(xy 37.650715 -357.940892) (xy 37.628059 -357.891282) (xy 37.612693 -357.838953) (xy 37.604931 -357.784969)
			(xy 36.122106 -357.784969) (xy 36.114345 -357.838953) (xy 36.09898 -357.891283) (xy 36.076326 -357.940894)
			(xy 36.046842 -357.986776) (xy 36.011129 -358.027995) (xy 35.969914 -358.063713) (xy 35.924036 -358.093203)
			(xy 35.874428 -358.115864) (xy 35.8221 -358.131234) (xy 35.768117 -358.139002) (xy 35.740848 -358.139492)
			(xy 34.877248 -358.139492) (xy 34.849977 -358.138972) (xy 34.795989 -358.131216) (xy 34.743655 -358.115855)
			(xy 34.694039 -358.093202) (xy 34.648153 -358.063718) (xy 34.606931 -358.028003) (xy 34.571211 -357.986785)
			(xy 34.541721 -357.940903) (xy 34.519062 -357.89129) (xy 34.503694 -357.838958) (xy 34.495932 -357.784971)
			(xy 33.013228 -357.784971) (xy 33.013228 -357.784974) (xy 33.005465 -357.838966) (xy 32.990097 -357.891304)
			(xy 32.967437 -357.940921) (xy 32.937946 -357.986809) (xy 32.902224 -358.028033) (xy 32.861 -358.063753)
			(xy 32.815111 -358.093243) (xy 32.765492 -358.115901) (xy 32.713154 -358.131268) (xy 32.659162 -358.139029)
			(xy 32.631888 -358.139492) (xy 31.768288 -358.139492) (xy 31.741021 -358.138945) (xy 31.687043 -358.131182)
			(xy 31.634719 -358.115817) (xy 31.585115 -358.093162) (xy 31.539239 -358.063678) (xy 31.498026 -358.027966)
			(xy 31.462315 -357.986752) (xy 31.432832 -357.940875) (xy 31.410179 -357.891269) (xy 31.394815 -357.838945)
			(xy 31.387054 -357.784967) (xy 29.904206 -357.784967) (xy 29.904206 -357.78497) (xy 29.896444 -357.838956)
			(xy 29.881079 -357.891287) (xy 29.858423 -357.940899) (xy 29.828937 -357.986782) (xy 29.793222 -358.028003)
			(xy 29.752005 -358.063721) (xy 29.706124 -358.09321) (xy 29.656513 -358.115869) (xy 29.604183 -358.131238)
			(xy 29.550198 -358.139004) (xy 29.522928 -358.139492) (xy 28.659328 -358.139492) (xy 28.632058 -358.13897)
			(xy 28.578072 -358.131212) (xy 28.52574 -358.11585) (xy 28.476127 -358.093195) (xy 28.430244 -358.063711)
			(xy 28.389024 -358.027996) (xy 28.353306 -357.986779) (xy 28.323818 -357.940897) (xy 28.30116 -357.891286)
			(xy 28.285794 -357.838955) (xy 28.278031 -357.78497) (xy 26.795328 -357.78497) (xy 26.795328 -357.784975)
			(xy 26.787565 -357.838969) (xy 26.772196 -357.891308) (xy 26.749534 -357.940927) (xy 26.720041 -357.986816)
			(xy 26.684317 -358.02804) (xy 26.64309 -358.06376) (xy 26.597199 -358.093249) (xy 26.547578 -358.115907)
			(xy 26.495237 -358.131272) (xy 26.441243 -358.139031) (xy 26.413968 -358.139492) (xy 25.550368 -358.139492)
			(xy 25.523102 -358.138943) (xy 25.469126 -358.131179) (xy 25.416805 -358.115812) (xy 25.367203 -358.093156)
			(xy 25.321329 -358.063671) (xy 25.280119 -358.027959) (xy 25.24441 -357.986745) (xy 25.214929 -357.940869)
			(xy 25.192277 -357.891265) (xy 25.176914 -357.838942) (xy 25.169154 -357.784966) (xy 23.686306 -357.784966)
			(xy 23.686306 -357.784971) (xy 23.678543 -357.838958) (xy 23.663177 -357.891291) (xy 23.64052 -357.940905)
			(xy 23.611032 -357.986789) (xy 23.575315 -358.02801) (xy 23.534095 -358.063728) (xy 23.488212 -358.093216)
			(xy 23.438599 -358.115875) (xy 23.386266 -358.131242) (xy 23.332279 -358.139005) (xy 23.305008 -358.139492)
			(xy 22.441408 -358.139492) (xy 22.414139 -358.138969) (xy 22.360155 -358.131209) (xy 22.307826 -358.115844)
			(xy 22.258215 -358.093189) (xy 22.212334 -358.063704) (xy 22.171117 -358.027989) (xy 22.135401 -357.986772)
			(xy 22.105915 -357.940892) (xy 22.083259 -357.891282) (xy 22.067893 -357.838953) (xy 22.060131 -357.784969)
			(xy 0.509016 -357.784969) (xy 0.509016 -360.017783) (xy 101.774757 -360.017783) (xy 101.774757 -359.957817)
			(xy 101.782584 -359.898365) (xy 101.798104 -359.840443) (xy 101.821052 -359.785042) (xy 101.851035 -359.733111)
			(xy 101.88754 -359.685538) (xy 101.929942 -359.643136) (xy 101.977516 -359.606632) (xy 102.029448 -359.57665)
			(xy 102.084849 -359.553703) (xy 102.142771 -359.538183) (xy 102.202223 -359.530357) (xy 102.232206 -359.529888)
			(xy 103.095806 -359.529888) (xy 103.125793 -359.530279) (xy 103.185255 -359.538108) (xy 103.243186 -359.553631)
			(xy 103.298595 -359.576583) (xy 103.350534 -359.60657) (xy 103.398115 -359.643081) (xy 103.440523 -359.68549)
			(xy 103.477033 -359.733071) (xy 103.50702 -359.785011) (xy 103.529971 -359.84042) (xy 103.545494 -359.898351)
			(xy 103.553322 -359.957813) (xy 103.553322 -360.017787) (xy 103.545494 -360.077249) (xy 103.529971 -360.13518)
			(xy 103.50702 -360.190589) (xy 103.477033 -360.242529) (xy 103.440523 -360.29011) (xy 103.398115 -360.332519)
			(xy 103.350534 -360.36903) (xy 103.298595 -360.399017) (xy 103.243186 -360.421969) (xy 103.185255 -360.437492)
			(xy 103.125793 -360.445321) (xy 103.095806 -360.445812) (xy 102.232206 -360.445812) (xy 102.202223 -360.445243)
			(xy 102.142771 -360.437417) (xy 102.084849 -360.421897) (xy 102.029448 -360.39895) (xy 101.977516 -360.368968)
			(xy 101.929942 -360.332464) (xy 101.88754 -360.290062) (xy 101.851035 -360.242489) (xy 101.821052 -360.190558)
			(xy 101.798104 -360.135157) (xy 101.782584 -360.077235) (xy 101.774757 -360.017783) (xy 0.509016 -360.017783)
			(xy 0.509016 -362.281978) (xy 54.149752 -362.281978) (xy 54.149752 -362.08081) (xy 54.150245 -362.064055)
			(xy 54.158916 -362.031685) (xy 54.175671 -362.002664) (xy 54.199367 -361.978969) (xy 54.228389 -361.962215)
			(xy 54.260759 -361.953544) (xy 54.277514 -361.953048) (xy 54.531514 -361.953048) (xy 54.548264 -361.953572)
			(xy 54.580621 -361.962246) (xy 54.609631 -361.978998) (xy 54.633316 -362.002688) (xy 54.650063 -362.031701)
			(xy 54.658731 -362.06406) (xy 54.659276 -362.08081) (xy 54.659276 -362.281978) (xy 54.658745 -362.298731)
			(xy 54.650079 -362.331095) (xy 54.633331 -362.360114) (xy 54.609643 -362.383809) (xy 54.580629 -362.400565)
			(xy 54.548266 -362.409241) (xy 54.531514 -362.40974) (xy 54.277514 -362.40974) (xy 54.260758 -362.409252)
			(xy 54.228388 -362.40058) (xy 54.199366 -362.383825) (xy 54.17567 -362.360128) (xy 54.158916 -362.331105)
			(xy 54.150247 -362.298734) (xy 54.149752 -362.281978) (xy 0.509016 -362.281978) (xy 0.509016 -363.082078)
			(xy 54.149752 -363.082078) (xy 54.149752 -362.88091) (xy 54.150245 -362.864155) (xy 54.158916 -362.831785)
			(xy 54.175671 -362.802764) (xy 54.199367 -362.779069) (xy 54.228389 -362.762315) (xy 54.260759 -362.753644)
			(xy 54.277514 -362.753148) (xy 54.531514 -362.753148) (xy 54.548264 -362.753672) (xy 54.580621 -362.762346)
			(xy 54.609631 -362.779098) (xy 54.633316 -362.802788) (xy 54.650063 -362.831801) (xy 54.658731 -362.86416)
			(xy 54.659276 -362.88091) (xy 54.659276 -363.082078) (xy 54.658745 -363.098831) (xy 54.650079 -363.131195)
			(xy 54.633331 -363.160214) (xy 54.609643 -363.183909) (xy 54.580629 -363.200665) (xy 54.548266 -363.209341)
			(xy 54.531514 -363.20984) (xy 54.277514 -363.20984) (xy 54.260758 -363.209352) (xy 54.228388 -363.20068)
			(xy 54.199366 -363.183925) (xy 54.17567 -363.160228) (xy 54.158916 -363.131205) (xy 54.150247 -363.098834)
			(xy 54.149752 -363.082078) (xy 0.509016 -363.082078) (xy 0.509016 -363.334808) (xy 54.890416 -363.334808)
			(xy 54.890416 -362.471208) (xy 54.890906 -362.441224) (xy 54.898734 -362.381768) (xy 54.914255 -362.323843)
			(xy 54.937204 -362.268439) (xy 54.967188 -362.216505) (xy 55.003694 -362.168929) (xy 55.046099 -362.126524)
			(xy 55.093675 -362.090018) (xy 55.145609 -362.060034) (xy 55.201013 -362.037085) (xy 55.258938 -362.021564)
			(xy 55.318394 -362.013736) (xy 55.378362 -362.013736) (xy 55.437818 -362.021564) (xy 55.495743 -362.037085)
			(xy 55.551147 -362.060034) (xy 55.603081 -362.090018) (xy 55.650657 -362.126524) (xy 55.693062 -362.168929)
			(xy 55.729568 -362.216505) (xy 55.753144 -362.25734) (xy 56.01716 -362.25734) (xy 56.01716 -362.056172)
			(xy 56.017709 -362.039479) (xy 56.026344 -362.00723) (xy 56.043019 -361.978308) (xy 56.066602 -361.954677)
			(xy 56.095491 -361.937943) (xy 56.127723 -361.929243) (xy 56.144414 -361.928664) (xy 56.398922 -361.928664)
			(xy 56.415652 -361.929162) (xy 56.447974 -361.937818) (xy 56.47696 -361.954534) (xy 56.50064 -361.978176)
			(xy 56.517403 -362.007135) (xy 56.52611 -362.039443) (xy 56.526684 -362.056172) (xy 56.526684 -362.25734)
			(xy 56.526201 -362.274038) (xy 56.517558 -362.306296) (xy 56.500872 -362.335224) (xy 56.477275 -362.358856)
			(xy 56.448372 -362.375585) (xy 56.416127 -362.384275) (xy 56.39943 -362.384848) (xy 56.144922 -362.384848)
			(xy 56.128195 -362.384299) (xy 56.095876 -362.375655) (xy 56.066891 -362.358949) (xy 56.043211 -362.335318)
			(xy 56.026446 -362.306367) (xy 56.017736 -362.274066) (xy 56.01716 -362.25734) (xy 55.753144 -362.25734)
			(xy 55.759552 -362.268439) (xy 55.782501 -362.323843) (xy 55.798022 -362.381768) (xy 55.80585 -362.441224)
			(xy 55.80634 -362.471208) (xy 55.80634 -363.05744) (xy 56.01716 -363.05744) (xy 56.01716 -362.856272)
			(xy 56.017709 -362.839579) (xy 56.026344 -362.80733) (xy 56.043019 -362.778408) (xy 56.066602 -362.754777)
			(xy 56.095491 -362.738043) (xy 56.127723 -362.729343) (xy 56.144414 -362.728764) (xy 56.398922 -362.728764)
			(xy 56.415652 -362.729262) (xy 56.447974 -362.737918) (xy 56.47696 -362.754634) (xy 56.50064 -362.778276)
			(xy 56.517403 -362.807235) (xy 56.52611 -362.839543) (xy 56.526684 -362.856272) (xy 56.526684 -363.05744)
			(xy 56.526201 -363.074138) (xy 56.517558 -363.106396) (xy 56.500872 -363.135324) (xy 56.477275 -363.158956)
			(xy 56.448372 -363.175685) (xy 56.416127 -363.184375) (xy 56.39943 -363.184948) (xy 56.144922 -363.184948)
			(xy 56.128195 -363.184399) (xy 56.095876 -363.175755) (xy 56.066891 -363.159049) (xy 56.043211 -363.135418)
			(xy 56.026446 -363.106467) (xy 56.017736 -363.074166) (xy 56.01716 -363.05744) (xy 55.80634 -363.05744)
			(xy 55.80634 -363.334808) (xy 55.80585 -363.364792) (xy 55.798022 -363.424248) (xy 55.782501 -363.482173)
			(xy 55.759552 -363.537577) (xy 55.729568 -363.589511) (xy 55.693062 -363.637087) (xy 55.650657 -363.679492)
			(xy 55.603081 -363.715998) (xy 55.551147 -363.745982) (xy 55.495743 -363.768931) (xy 55.437818 -363.784452)
			(xy 55.378362 -363.79228) (xy 55.318394 -363.79228) (xy 55.258938 -363.784452) (xy 55.201013 -363.768931)
			(xy 55.145609 -363.745982) (xy 55.093675 -363.715998) (xy 55.046099 -363.679492) (xy 55.003694 -363.637087)
			(xy 54.967188 -363.589511) (xy 54.937204 -363.537577) (xy 54.914255 -363.482173) (xy 54.898734 -363.424248)
			(xy 54.890906 -363.364792) (xy 54.890416 -363.334808) (xy 0.509016 -363.334808) (xy 0.509016 -363.882178)
			(xy 54.149752 -363.882178) (xy 54.149752 -363.68101) (xy 54.150245 -363.664255) (xy 54.158916 -363.631885)
			(xy 54.175671 -363.602864) (xy 54.199367 -363.579169) (xy 54.228389 -363.562415) (xy 54.260759 -363.553744)
			(xy 54.277514 -363.553248) (xy 54.531514 -363.553248) (xy 54.548264 -363.553772) (xy 54.580621 -363.562446)
			(xy 54.609631 -363.579198) (xy 54.633316 -363.602888) (xy 54.650063 -363.631901) (xy 54.658731 -363.66426)
			(xy 54.659276 -363.68101) (xy 54.659276 -363.85754) (xy 56.01716 -363.85754) (xy 56.01716 -363.656372)
			(xy 56.017709 -363.639679) (xy 56.026344 -363.60743) (xy 56.043019 -363.578508) (xy 56.066602 -363.554877)
			(xy 56.095491 -363.538143) (xy 56.127723 -363.529443) (xy 56.144414 -363.528864) (xy 56.398922 -363.528864)
			(xy 56.415652 -363.529362) (xy 56.447974 -363.538018) (xy 56.47696 -363.554734) (xy 56.50064 -363.578376)
			(xy 56.517403 -363.607335) (xy 56.52611 -363.639643) (xy 56.526684 -363.656372) (xy 56.526684 -363.85754)
			(xy 56.526201 -363.874238) (xy 56.517558 -363.906496) (xy 56.500872 -363.935424) (xy 56.477275 -363.959056)
			(xy 56.448372 -363.975785) (xy 56.416127 -363.984475) (xy 56.39943 -363.985048) (xy 56.144922 -363.985048)
			(xy 56.128195 -363.984499) (xy 56.095876 -363.975855) (xy 56.066891 -363.959149) (xy 56.043211 -363.935518)
			(xy 56.026446 -363.906567) (xy 56.017736 -363.874266) (xy 56.01716 -363.85754) (xy 54.659276 -363.85754)
			(xy 54.659276 -363.882178) (xy 54.658745 -363.898931) (xy 54.650079 -363.931295) (xy 54.633331 -363.960314)
			(xy 54.609643 -363.984009) (xy 54.580629 -364.000765) (xy 54.548266 -364.009441) (xy 54.531514 -364.00994)
			(xy 54.277514 -364.00994) (xy 54.260758 -364.009452) (xy 54.228388 -364.00078) (xy 54.199366 -363.984025)
			(xy 54.17567 -363.960328) (xy 54.158916 -363.931305) (xy 54.150247 -363.898934) (xy 54.149752 -363.882178)
			(xy 0.509016 -363.882178) (xy 0.509016 -365.797384) (xy 54.438294 -365.797384) (xy 54.438294 -365.737416)
			(xy 54.446121 -365.67796) (xy 54.461641 -365.620034) (xy 54.484589 -365.564629) (xy 54.514571 -365.512694)
			(xy 54.551076 -365.465115) (xy 54.593478 -365.422709) (xy 54.641052 -365.386199) (xy 54.692984 -365.356211)
			(xy 54.748387 -365.333257) (xy 54.806311 -365.317731) (xy 54.865766 -365.309897) (xy 54.89575 -365.309404)
			(xy 55.75935 -365.309404) (xy 55.789336 -365.309938) (xy 55.848794 -365.31776) (xy 55.906723 -365.333276)
			(xy 55.962131 -365.356222) (xy 56.01407 -365.386203) (xy 56.06165 -365.422708) (xy 56.104059 -365.465112)
			(xy 56.140569 -365.512689) (xy 56.170556 -365.564624) (xy 56.193508 -365.620029) (xy 56.20903 -365.677957)
			(xy 56.216859 -365.737414) (xy 56.216859 -365.797386) (xy 56.20903 -365.856843) (xy 56.193508 -365.914771)
			(xy 56.170556 -365.970176) (xy 56.140569 -366.022112) (xy 56.104059 -366.069688) (xy 56.06165 -366.112092)
			(xy 56.01407 -366.148597) (xy 55.962131 -366.178578) (xy 55.906723 -366.201524) (xy 55.848794 -366.21704)
			(xy 55.789336 -366.224862) (xy 55.75935 -366.225328) (xy 54.89575 -366.225328) (xy 54.865766 -366.224903)
			(xy 54.806311 -366.217069) (xy 54.748386 -366.201543) (xy 54.692984 -366.178589) (xy 54.641052 -366.148601)
			(xy 54.593478 -366.112091) (xy 54.551076 -366.069685) (xy 54.514571 -366.022106) (xy 54.484589 -365.970171)
			(xy 54.461641 -365.914766) (xy 54.446121 -365.85684) (xy 54.438294 -365.797384) (xy 0.509016 -365.797384)
			(xy 0.509016 -368.516662) (xy 53.966364 -368.516662) (xy 53.966364 -367.653062) (xy 53.96685 -367.625793)
			(xy 53.974612 -367.571809) (xy 53.989977 -367.519479) (xy 54.012634 -367.469869) (xy 54.04212 -367.423988)
			(xy 54.077835 -367.382771) (xy 54.119052 -367.347056) (xy 54.164933 -367.31757) (xy 54.214543 -367.294913)
			(xy 54.266873 -367.279548) (xy 54.320857 -367.271786) (xy 54.375395 -367.271786) (xy 54.429379 -367.279548)
			(xy 54.481709 -367.294913) (xy 54.531319 -367.31757) (xy 54.5772 -367.347056) (xy 54.618417 -367.382771)
			(xy 54.654132 -367.423988) (xy 54.683618 -367.469869) (xy 54.706275 -367.519479) (xy 54.72164 -367.571809)
			(xy 54.729402 -367.625793) (xy 54.729888 -367.653062) (xy 54.729888 -368.516662) (xy 54.729402 -368.543931)
			(xy 54.72164 -368.597915) (xy 54.706275 -368.650245) (xy 54.690837 -368.684048) (xy 55.614824 -368.684048)
			(xy 55.614824 -368.441224) (xy 55.831486 -368.1095) (xy 55.836543 -368.098368) (xy 55.836671 -368.073954)
			(xy 55.83174 -368.062764) (xy 55.614824 -367.731802) (xy 55.614824 -367.487708) (xy 55.615283 -367.477527)
			(xy 55.623053 -367.458706) (xy 55.63742 -367.444278) (xy 55.656207 -367.436427) (xy 55.666386 -367.435892)
			(xy 56.402986 -367.435892) (xy 56.413183 -367.43638) (xy 56.432017 -367.444199) (xy 56.44641 -367.458646)
			(xy 56.454158 -367.47751) (xy 56.454548 -367.487708) (xy 56.454548 -367.730532) (xy 56.238394 -368.060224)
			(xy 56.232883 -368.071259) (xy 56.23223 -368.095891) (xy 56.237124 -368.107214) (xy 56.442356 -368.422174)
			(xy 56.44642 -368.428524) (xy 56.446928 -368.429032) (xy 56.454548 -368.441224) (xy 56.454548 -368.516662)
			(xy 57.339484 -368.516662) (xy 57.339484 -367.653062) (xy 57.33997 -367.625793) (xy 57.347732 -367.571809)
			(xy 57.363097 -367.519479) (xy 57.385754 -367.469869) (xy 57.41524 -367.423988) (xy 57.450955 -367.382771)
			(xy 57.492172 -367.347056) (xy 57.538053 -367.31757) (xy 57.587663 -367.294913) (xy 57.639993 -367.279548)
			(xy 57.693977 -367.271786) (xy 57.748515 -367.271786) (xy 57.802499 -367.279548) (xy 57.854829 -367.294913)
			(xy 57.904439 -367.31757) (xy 57.95032 -367.347056) (xy 57.991537 -367.382771) (xy 58.027252 -367.423988)
			(xy 58.056738 -367.469869) (xy 58.079395 -367.519479) (xy 58.09476 -367.571809) (xy 58.102522 -367.625793)
			(xy 58.103008 -367.653062) (xy 58.103008 -368.516662) (xy 58.102522 -368.543931) (xy 58.09476 -368.597915)
			(xy 58.079395 -368.650245) (xy 58.056738 -368.699855) (xy 58.027252 -368.745736) (xy 57.991537 -368.786953)
			(xy 57.95032 -368.822668) (xy 57.904439 -368.852154) (xy 57.854829 -368.874811) (xy 57.802499 -368.890176)
			(xy 57.748515 -368.897938) (xy 57.693977 -368.897938) (xy 57.639993 -368.890176) (xy 57.587663 -368.874811)
			(xy 57.538053 -368.852154) (xy 57.492172 -368.822668) (xy 57.450955 -368.786953) (xy 57.41524 -368.745736)
			(xy 57.385754 -368.699855) (xy 57.363097 -368.650245) (xy 57.347732 -368.597915) (xy 57.33997 -368.543931)
			(xy 57.339484 -368.516662) (xy 56.454548 -368.516662) (xy 56.454548 -368.684048) (xy 56.454065 -368.694224)
			(xy 56.44629 -368.713032) (xy 56.431932 -368.727456) (xy 56.413159 -368.735318) (xy 56.402986 -368.735864)
			(xy 55.666386 -368.735864) (xy 55.656182 -368.735442) (xy 55.637339 -368.727605) (xy 55.622945 -368.713137)
			(xy 55.615206 -368.694254) (xy 55.614824 -368.684048) (xy 54.690837 -368.684048) (xy 54.683618 -368.699855)
			(xy 54.654132 -368.745736) (xy 54.618417 -368.786953) (xy 54.5772 -368.822668) (xy 54.531319 -368.852154)
			(xy 54.481709 -368.874811) (xy 54.429379 -368.890176) (xy 54.375395 -368.897938) (xy 54.320857 -368.897938)
			(xy 54.266873 -368.890176) (xy 54.214543 -368.874811) (xy 54.164933 -368.852154) (xy 54.119052 -368.822668)
			(xy 54.077835 -368.786953) (xy 54.04212 -368.745736) (xy 54.012634 -368.699855) (xy 53.989977 -368.650245)
			(xy 53.974612 -368.597915) (xy 53.96685 -368.543931) (xy 53.966364 -368.516662) (xy 0.509016 -368.516662)
			(xy 0.509016 -370.523703) (xy 27.348898 -370.523703) (xy 27.348899 -370.456279) (xy 27.356975 -370.38934)
			(xy 27.373012 -370.323851) (xy 27.396776 -370.260753) (xy 27.427927 -370.200957) (xy 27.466016 -370.145322)
			(xy 27.48788 -370.119656) (xy 27.493675 -370.11251) (xy 27.500191 -370.09532) (xy 27.50058 -370.086128)
			(xy 27.50058 -369.928902) (xy 27.501029 -369.918771) (xy 27.508764 -369.900042) (xy 27.523062 -369.885684)
			(xy 27.541759 -369.877872) (xy 27.551888 -369.87734) (xy 28.268168 -369.87734) (xy 28.278293 -369.877743)
			(xy 28.297004 -369.885488) (xy 28.311321 -369.899809) (xy 28.31906 -369.918522) (xy 28.319476 -369.928648)
			(xy 28.319476 -370.086128) (xy 28.319878 -370.095316) (xy 28.326398 -370.1125) (xy 28.332176 -370.119656)
			(xy 28.354029 -370.145331) (xy 28.39212 -370.200963) (xy 28.423272 -370.260758) (xy 28.447038 -370.323854)
			(xy 28.463075 -370.389342) (xy 28.471152 -370.456279) (xy 28.471153 -370.523644) (xy 31.749193 -370.523644)
			(xy 31.749194 -370.456338) (xy 31.75724 -370.389514) (xy 31.773215 -370.324131) (xy 31.79689 -370.261126)
			(xy 31.827927 -370.201402) (xy 31.865879 -370.145816) (xy 31.887668 -370.120164) (xy 31.893471 -370.113023)
			(xy 31.89998 -370.095829) (xy 31.900368 -370.086636) (xy 31.900368 -369.928902) (xy 31.900766 -369.918727)
			(xy 31.908556 -369.899926) (xy 31.92295 -369.88554) (xy 31.941755 -369.877761) (xy 31.95193 -369.87734)
			(xy 32.66821 -369.87734) (xy 32.678369 -369.877825) (xy 32.697138 -369.885603) (xy 32.711503 -369.899972)
			(xy 32.719277 -369.918743) (xy 32.719772 -369.928902) (xy 32.719772 -370.086636) (xy 32.720171 -370.095824)
			(xy 32.726693 -370.113008) (xy 32.732472 -370.120164) (xy 32.754248 -370.145826) (xy 32.792196 -370.201411)
			(xy 32.823229 -370.261134) (xy 32.846902 -370.324137) (xy 32.862876 -370.389518) (xy 32.870921 -370.456339)
			(xy 32.870922 -370.523643) (xy 32.870915 -370.523703) (xy 36.148986 -370.523703) (xy 36.148987 -370.456279)
			(xy 36.157063 -370.389341) (xy 36.173099 -370.323851) (xy 36.196863 -370.260754) (xy 36.228013 -370.200957)
			(xy 36.266101 -370.145322) (xy 36.287964 -370.119656) (xy 36.29377 -370.112518) (xy 36.300277 -370.095322)
			(xy 36.300664 -370.086128) (xy 36.300664 -369.928902) (xy 36.301129 -369.918772) (xy 36.308861 -369.900047)
			(xy 36.323154 -369.88569) (xy 36.341845 -369.877875) (xy 36.351972 -369.87734) (xy 37.068252 -369.87734)
			(xy 37.078408 -369.877762) (xy 37.097167 -369.885549) (xy 37.111494 -369.899947) (xy 37.119188 -369.918744)
			(xy 37.11956 -369.928902) (xy 37.11956 -370.086128) (xy 37.119966 -370.095315) (xy 37.126483 -370.112499)
			(xy 37.13226 -370.119656) (xy 37.154114 -370.14533) (xy 37.192205 -370.200963) (xy 37.223359 -370.260757)
			(xy 37.247125 -370.323853) (xy 37.263163 -370.389341) (xy 37.27124 -370.456279) (xy 37.271241 -370.523703)
			(xy 37.271241 -370.523704) (xy 40.548752 -370.523704) (xy 40.548753 -370.456278) (xy 40.556831 -370.389338)
			(xy 40.572869 -370.323848) (xy 40.596637 -370.26075) (xy 40.627792 -370.200954) (xy 40.665885 -370.14532)
			(xy 40.687752 -370.119656) (xy 40.693556 -370.112516) (xy 40.700065 -370.095321) (xy 40.700452 -370.086128)
			(xy 40.700452 -369.928902) (xy 40.700929 -369.918774) (xy 40.708658 -369.900051) (xy 40.722947 -369.885694)
			(xy 40.741634 -369.877877) (xy 40.75176 -369.87734) (xy 41.46804 -369.87734) (xy 41.478202 -369.87769)
			(xy 41.496963 -369.885506) (xy 41.511286 -369.899925) (xy 41.518977 -369.918738) (xy 41.519348 -369.928902)
			(xy 41.519348 -370.086128) (xy 41.519756 -370.095315) (xy 41.526273 -370.112499) (xy 41.532048 -370.119656)
			(xy 41.553902 -370.14533) (xy 41.591994 -370.200962) (xy 41.623149 -370.260757) (xy 41.646916 -370.323852)
			(xy 41.662954 -370.389341) (xy 41.671031 -370.456279) (xy 41.671032 -370.523644) (xy 44.949071 -370.523644)
			(xy 44.949073 -370.456338) (xy 44.957118 -370.389515) (xy 44.973092 -370.324132) (xy 44.996766 -370.261127)
			(xy 45.027801 -370.201403) (xy 45.065751 -370.145816) (xy 45.08754 -370.120164) (xy 45.093339 -370.113021)
			(xy 45.099851 -370.095829) (xy 45.10024 -370.086636) (xy 45.10024 -369.928902) (xy 45.100665 -369.91873)
			(xy 45.10845 -369.899935) (xy 45.122835 -369.88555) (xy 45.14163 -369.877765) (xy 45.151802 -369.87734)
			(xy 45.868082 -369.87734) (xy 45.878253 -369.877778) (xy 45.897047 -369.885558) (xy 45.911433 -369.899939)
			(xy 45.919218 -369.918731) (xy 45.919644 -369.928902) (xy 45.919644 -370.086636) (xy 45.92005 -370.095823)
			(xy 45.926568 -370.113007) (xy 45.932344 -370.120164) (xy 45.95412 -370.145826) (xy 45.992071 -370.20141)
			(xy 46.023105 -370.261132) (xy 46.046779 -370.324136) (xy 46.062754 -370.389517) (xy 46.070799 -370.456339)
			(xy 46.0708 -370.523643) (xy 46.062757 -370.590465) (xy 46.046785 -370.655847) (xy 46.023113 -370.718851)
			(xy 45.99208 -370.778574) (xy 45.954131 -370.83416) (xy 45.932344 -370.859812) (xy 45.926553 -370.866961)
			(xy 45.920036 -370.884149) (xy 45.919644 -370.89334) (xy 45.919644 -371.386862) (xy 45.920085 -371.396046)
			(xy 45.926578 -371.41323) (xy 45.932344 -371.42039) (xy 45.954146 -371.44603) (xy 45.992096 -371.501618)
			(xy 46.023129 -371.561343) (xy 46.046568 -371.623726) (xy 47.14919 -371.623726) (xy 47.149193 -371.556417)
			(xy 47.157242 -371.489591) (xy 47.17322 -371.424206) (xy 47.1969 -371.3612) (xy 47.22794 -371.301475)
			(xy 47.265897 -371.24589) (xy 47.287688 -371.220238) (xy 47.293492 -371.213098) (xy 47.300003 -371.195904)
			(xy 47.300388 -371.18671) (xy 47.300388 -371.028722) (xy 47.300783 -371.018546) (xy 47.30857 -370.999742)
			(xy 47.322966 -370.985355) (xy 47.341773 -370.977578) (xy 47.35195 -370.97716) (xy 48.06823 -370.97716)
			(xy 48.078392 -370.977609) (xy 48.097167 -370.985398) (xy 48.111532 -370.999777) (xy 48.119301 -371.018559)
			(xy 48.119792 -371.028722) (xy 48.119792 -371.18671) (xy 48.120199 -371.195898) (xy 48.126715 -371.213082)
			(xy 48.132492 -371.220238) (xy 48.154241 -371.245921) (xy 48.192189 -371.301504) (xy 48.196948 -371.310662)
			(xy 53.966364 -371.310662) (xy 53.966364 -370.447062) (xy 53.96685 -370.419793) (xy 53.974612 -370.365809)
			(xy 53.989977 -370.313479) (xy 54.012634 -370.263869) (xy 54.04212 -370.217988) (xy 54.077835 -370.176771)
			(xy 54.119052 -370.141056) (xy 54.164933 -370.11157) (xy 54.214543 -370.088913) (xy 54.266873 -370.073548)
			(xy 54.320857 -370.065786) (xy 54.375395 -370.065786) (xy 54.429379 -370.073548) (xy 54.481709 -370.088913)
			(xy 54.531319 -370.11157) (xy 54.5772 -370.141056) (xy 54.618417 -370.176771) (xy 54.654132 -370.217988)
			(xy 54.683618 -370.263869) (xy 54.706275 -370.313479) (xy 54.72164 -370.365809) (xy 54.729402 -370.419793)
			(xy 54.729888 -370.447062) (xy 54.729888 -371.310662) (xy 54.729402 -371.337931) (xy 54.72164 -371.391915)
			(xy 54.706275 -371.444245) (xy 54.690837 -371.478048) (xy 55.614824 -371.478048) (xy 55.614824 -371.235224)
			(xy 55.831486 -370.9035) (xy 55.836543 -370.892368) (xy 55.836671 -370.867954) (xy 55.83174 -370.856764)
			(xy 55.614824 -370.525802) (xy 55.614824 -370.281708) (xy 55.615283 -370.271527) (xy 55.623053 -370.252706)
			(xy 55.63742 -370.238278) (xy 55.656207 -370.230427) (xy 55.666386 -370.229892) (xy 56.402986 -370.229892)
			(xy 56.413183 -370.23038) (xy 56.432017 -370.238199) (xy 56.44641 -370.252646) (xy 56.454158 -370.27151)
			(xy 56.454548 -370.281708) (xy 56.454548 -370.524532) (xy 56.238394 -370.854224) (xy 56.232883 -370.865259)
			(xy 56.23223 -370.889891) (xy 56.237124 -370.901214) (xy 56.442356 -371.216174) (xy 56.44642 -371.222524)
			(xy 56.446928 -371.223032) (xy 56.454548 -371.235224) (xy 56.454548 -371.310662) (xy 57.339484 -371.310662)
			(xy 57.339484 -370.447062) (xy 57.33997 -370.419793) (xy 57.347732 -370.365809) (xy 57.363097 -370.313479)
			(xy 57.385754 -370.263869) (xy 57.41524 -370.217988) (xy 57.450955 -370.176771) (xy 57.492172 -370.141056)
			(xy 57.538053 -370.11157) (xy 57.587663 -370.088913) (xy 57.639993 -370.073548) (xy 57.693977 -370.065786)
			(xy 57.748515 -370.065786) (xy 57.802499 -370.073548) (xy 57.854829 -370.088913) (xy 57.904439 -370.11157)
			(xy 57.95032 -370.141056) (xy 57.991537 -370.176771) (xy 58.027252 -370.217988) (xy 58.056738 -370.263869)
			(xy 58.079395 -370.313479) (xy 58.09476 -370.365809) (xy 58.102522 -370.419793) (xy 58.103008 -370.447062)
			(xy 58.103008 -370.523703) (xy 71.348807 -370.523703) (xy 71.348808 -370.456279) (xy 71.356885 -370.38934)
			(xy 71.372921 -370.32385) (xy 71.396686 -370.260753) (xy 71.427838 -370.200956) (xy 71.465928 -370.145321)
			(xy 71.487792 -370.119656) (xy 71.493589 -370.112511) (xy 71.500104 -370.09532) (xy 71.500492 -370.086128)
			(xy 71.500492 -369.928902) (xy 71.501027 -369.918781) (xy 71.508745 -369.900069) (xy 71.523016 -369.885715)
			(xy 71.541682 -369.877887) (xy 71.5518 -369.87734) (xy 72.26808 -369.87734) (xy 72.278238 -369.877739)
			(xy 72.296998 -369.885535) (xy 72.311323 -369.89994) (xy 72.319016 -369.918742) (xy 72.319388 -369.928902)
			(xy 72.319388 -370.086128) (xy 72.319787 -370.095316) (xy 72.326309 -370.1125) (xy 72.332088 -370.119656)
			(xy 72.353941 -370.145331) (xy 72.39203 -370.200964) (xy 72.423182 -370.260758) (xy 72.446948 -370.323854)
			(xy 72.462984 -370.389342) (xy 72.471061 -370.45628) (xy 72.471063 -370.523644) (xy 75.749102 -370.523644)
			(xy 75.749103 -370.456338) (xy 75.757149 -370.389513) (xy 75.773125 -370.32413) (xy 75.796801 -370.261125)
			(xy 75.827837 -370.201401) (xy 75.86579 -370.145816) (xy 75.88758 -370.120164) (xy 75.893372 -370.113015)
			(xy 75.89989 -370.095828) (xy 75.90028 -370.086636) (xy 75.90028 -369.928902) (xy 75.900666 -369.918725)
			(xy 75.908459 -369.899923) (xy 75.922856 -369.885536) (xy 75.941665 -369.877759) (xy 75.951842 -369.87734)
			(xy 76.668122 -369.87734) (xy 76.678281 -369.877815) (xy 76.697052 -369.885597) (xy 76.711416 -369.899969)
			(xy 76.71919 -369.918742) (xy 76.719684 -369.928902) (xy 76.719684 -370.086636) (xy 76.72008 -370.095825)
			(xy 76.726604 -370.113009) (xy 76.732384 -370.120164) (xy 76.754159 -370.145826) (xy 76.792107 -370.201412)
			(xy 76.82314 -370.261134) (xy 76.846812 -370.324137) (xy 76.862785 -370.389518) (xy 76.87083 -370.456339)
			(xy 76.870831 -370.523643) (xy 76.870824 -370.523703) (xy 80.148895 -370.523703) (xy 80.148896 -370.456279)
			(xy 80.156972 -370.38934) (xy 80.173008 -370.323851) (xy 80.196773 -370.260754) (xy 80.227924 -370.200957)
			(xy 80.266012 -370.145322) (xy 80.287876 -370.119656) (xy 80.293671 -370.112509) (xy 80.300187 -370.09532)
			(xy 80.300576 -370.086128) (xy 80.300576 -369.928902) (xy 80.301029 -369.918771) (xy 80.308763 -369.900043)
			(xy 80.32306 -369.885685) (xy 80.341755 -369.877873) (xy 80.351884 -369.87734) (xy 81.068164 -369.87734)
			(xy 81.078289 -369.877747) (xy 81.096999 -369.88549) (xy 81.111316 -369.899811) (xy 81.119056 -369.918523)
			(xy 81.119472 -369.928648) (xy 81.119472 -370.086128) (xy 81.119875 -370.095316) (xy 81.126394 -370.1125)
			(xy 81.132172 -370.119656) (xy 81.154025 -370.14533) (xy 81.192116 -370.200963) (xy 81.223269 -370.260758)
			(xy 81.247035 -370.323853) (xy 81.263072 -370.389342) (xy 81.271149 -370.456279) (xy 81.27115 -370.523703)
			(xy 84.548686 -370.523703) (xy 84.548687 -370.456279) (xy 84.556763 -370.389341) (xy 84.572799 -370.323851)
			(xy 84.596563 -370.260754) (xy 84.627713 -370.200957) (xy 84.665801 -370.145322) (xy 84.687664 -370.119656)
			(xy 84.69347 -370.112518) (xy 84.699977 -370.095322) (xy 84.700364 -370.086128) (xy 84.700364 -369.928902)
			(xy 84.700829 -369.918772) (xy 84.708561 -369.900047) (xy 84.722854 -369.88569) (xy 84.741545 -369.877875)
			(xy 84.751672 -369.87734) (xy 85.467952 -369.87734) (xy 85.478076 -369.877756) (xy 85.496787 -369.885496)
			(xy 85.511104 -369.899813) (xy 85.518844 -369.918524) (xy 85.51926 -369.928648) (xy 85.51926 -370.086128)
			(xy 85.519666 -370.095315) (xy 85.526183 -370.112499) (xy 85.53196 -370.119656) (xy 85.553814 -370.14533)
			(xy 85.591905 -370.200963) (xy 85.623059 -370.260757) (xy 85.646825 -370.323853) (xy 85.662863 -370.389341)
			(xy 85.67094 -370.456279) (xy 85.670941 -370.523644) (xy 115.349244 -370.523644) (xy 115.349245 -370.456338)
			(xy 115.35729 -370.389516) (xy 115.373263 -370.324133) (xy 115.396936 -370.261128) (xy 115.427969 -370.201404)
			(xy 115.465917 -370.145817) (xy 115.487704 -370.120164) (xy 115.493499 -370.113018) (xy 115.500014 -370.095828)
			(xy 115.500404 -370.086636) (xy 115.500404 -369.928902) (xy 115.500934 -369.918749) (xy 115.508702 -369.899986)
			(xy 115.523056 -369.885622) (xy 115.541813 -369.877841) (xy 115.551966 -369.87734) (xy 116.268246 -369.87734)
			(xy 116.278407 -369.877796) (xy 116.297177 -369.885586) (xy 116.311541 -369.899963) (xy 116.319314 -369.918741)
			(xy 116.319808 -369.928902) (xy 116.319808 -370.086636) (xy 116.320199 -370.095825) (xy 116.326726 -370.11301)
			(xy 116.332508 -370.120164) (xy 116.354286 -370.145825) (xy 116.392238 -370.201409) (xy 116.423275 -370.261131)
			(xy 116.446951 -370.324134) (xy 116.462926 -370.389516) (xy 116.470972 -370.456338) (xy 116.470973 -370.523644)
			(xy 116.470966 -370.523703) (xy 119.749013 -370.523703) (xy 119.749014 -370.456279) (xy 119.757091 -370.38934)
			(xy 119.773128 -370.32385) (xy 119.796893 -370.260752) (xy 119.828045 -370.200956) (xy 119.866135 -370.145321)
			(xy 119.888 -370.119656) (xy 119.893798 -370.112512) (xy 119.900312 -370.09532) (xy 119.9007 -370.086128)
			(xy 119.9007 -369.928902) (xy 119.901227 -369.91878) (xy 119.908947 -369.900067) (xy 119.92322 -369.885712)
			(xy 119.941889 -369.877886) (xy 119.952008 -369.87734) (xy 120.668288 -369.87734) (xy 120.678446 -369.877732)
			(xy 120.697206 -369.885531) (xy 120.711531 -369.899938) (xy 120.719224 -369.918741) (xy 120.719596 -369.928902)
			(xy 120.719596 -370.086128) (xy 120.719993 -370.095317) (xy 120.726516 -370.112501) (xy 120.732296 -370.119656)
			(xy 120.754148 -370.145331) (xy 120.792238 -370.200964) (xy 120.823389 -370.260759) (xy 120.847154 -370.323854)
			(xy 120.863191 -370.389342) (xy 120.871267 -370.45628) (xy 120.871269 -370.523644) (xy 124.149308 -370.523644)
			(xy 124.149309 -370.456338) (xy 124.157355 -370.389513) (xy 124.173331 -370.32413) (xy 124.197007 -370.261125)
			(xy 124.228045 -370.201401) (xy 124.265998 -370.145816) (xy 124.287788 -370.120164) (xy 124.293581 -370.113016)
			(xy 124.300098 -370.095828) (xy 124.300488 -370.086636) (xy 124.300488 -369.928902) (xy 124.300867 -369.918724)
			(xy 124.30866 -369.89992) (xy 124.32306 -369.885533) (xy 124.341872 -369.877757) (xy 124.35205 -369.87734)
			(xy 125.06833 -369.87734) (xy 125.07849 -369.877809) (xy 125.09726 -369.885593) (xy 125.111625 -369.899967)
			(xy 125.119398 -369.918742) (xy 125.119892 -369.928902) (xy 125.119892 -370.086636) (xy 125.120286 -370.095825)
			(xy 125.126811 -370.113009) (xy 125.132592 -370.120164) (xy 125.154367 -370.145826) (xy 125.192314 -370.201412)
			(xy 125.223346 -370.261134) (xy 125.247018 -370.324138) (xy 125.262991 -370.389518) (xy 125.271036 -370.456339)
			(xy 125.271037 -370.523643) (xy 125.271037 -370.523644) (xy 128.549099 -370.523644) (xy 128.5491 -370.456338)
			(xy 128.557146 -370.389514) (xy 128.573121 -370.32413) (xy 128.596797 -370.261125) (xy 128.627834 -370.201402)
			(xy 128.665787 -370.145816) (xy 128.687576 -370.120164) (xy 128.693368 -370.113015) (xy 128.699886 -370.095828)
			(xy 128.700276 -370.086636) (xy 128.700276 -369.928902) (xy 128.700666 -369.918726) (xy 128.708458 -369.899924)
			(xy 128.722854 -369.885538) (xy 128.741661 -369.877759) (xy 128.751838 -369.87734) (xy 129.468118 -369.87734)
			(xy 129.478277 -369.877818) (xy 129.497047 -369.885599) (xy 129.511412 -369.89997) (xy 129.519185 -369.918743)
			(xy 129.51968 -369.928902) (xy 129.51968 -370.086636) (xy 129.520077 -370.095824) (xy 129.5266 -370.113008)
			(xy 129.53238 -370.120164) (xy 129.554155 -370.145826) (xy 129.592103 -370.201412) (xy 129.623136 -370.261134)
			(xy 129.646809 -370.324137) (xy 129.662782 -370.389518) (xy 129.670827 -370.456339) (xy 129.670828 -370.523643)
			(xy 129.670828 -370.523644) (xy 159.349153 -370.523644) (xy 159.349154 -370.456338) (xy 159.357199 -370.389515)
			(xy 159.373173 -370.324133) (xy 159.396846 -370.261128) (xy 159.427879 -370.201404) (xy 159.465828 -370.145816)
			(xy 159.487616 -370.120164) (xy 159.493412 -370.113019) (xy 159.499927 -370.095828) (xy 159.500316 -370.086636)
			(xy 159.500316 -369.928902) (xy 159.500835 -369.918747) (xy 159.508604 -369.899982) (xy 159.522962 -369.885618)
			(xy 159.541723 -369.877839) (xy 159.551878 -369.87734) (xy 160.268158 -369.87734) (xy 160.278327 -369.877798)
			(xy 160.297121 -369.88557) (xy 160.311508 -369.899945) (xy 160.319294 -369.918733) (xy 160.31972 -369.928902)
			(xy 160.31972 -370.086636) (xy 160.320109 -370.095826) (xy 160.326637 -370.11301) (xy 160.33242 -370.120164)
			(xy 160.354197 -370.145825) (xy 160.392149 -370.20141) (xy 160.423185 -370.261131) (xy 160.44686 -370.324135)
			(xy 160.462835 -370.389516) (xy 160.470881 -370.456339) (xy 160.470882 -370.523643) (xy 160.470875 -370.523703)
			(xy 163.748922 -370.523703) (xy 163.748923 -370.456279) (xy 163.757 -370.389339) (xy 163.773037 -370.323849)
			(xy 163.796803 -370.260752) (xy 163.827956 -370.200955) (xy 163.866047 -370.145321) (xy 163.887912 -370.119656)
			(xy 163.893711 -370.112513) (xy 163.900224 -370.095321) (xy 163.900612 -370.086128) (xy 163.900612 -369.928902)
			(xy 163.901127 -369.918779) (xy 163.908849 -369.900063) (xy 163.923126 -369.885708) (xy 163.9418 -369.877884)
			(xy 163.95192 -369.87734) (xy 164.6682 -369.87734) (xy 164.678359 -369.877722) (xy 164.697119 -369.885526)
			(xy 164.711444 -369.899935) (xy 164.719136 -369.918741) (xy 164.719508 -369.928902) (xy 164.719508 -370.086128)
			(xy 164.719903 -370.095317) (xy 164.726427 -370.112501) (xy 164.732208 -370.119656) (xy 164.75406 -370.145331)
			(xy 164.792148 -370.200964) (xy 164.823299 -370.260759) (xy 164.847064 -370.323855) (xy 164.8631 -370.389343)
			(xy 164.871176 -370.45628) (xy 164.871178 -370.523644) (xy 168.149241 -370.523644) (xy 168.149242 -370.456338)
			(xy 168.157287 -370.389516) (xy 168.17326 -370.324133) (xy 168.196933 -370.261128) (xy 168.227965 -370.201404)
			(xy 168.265913 -370.145817) (xy 168.2877 -370.120164) (xy 168.293494 -370.113017) (xy 168.30001 -370.095828)
			(xy 168.3004 -370.086636) (xy 168.3004 -369.928902) (xy 168.300934 -369.918749) (xy 168.308701 -369.899987)
			(xy 168.323054 -369.885623) (xy 168.341809 -369.877842) (xy 168.351962 -369.87734) (xy 169.068242 -369.87734)
			(xy 169.078403 -369.877799) (xy 169.097173 -369.885588) (xy 169.111537 -369.899964) (xy 169.11931 -369.918741)
			(xy 169.119804 -369.928902) (xy 169.119804 -370.086636) (xy 169.120196 -370.095825) (xy 169.126722 -370.113009)
			(xy 169.132504 -370.120164) (xy 169.154279 -370.145826) (xy 169.192225 -370.201412) (xy 169.223256 -370.261135)
			(xy 169.246928 -370.324138) (xy 169.2629 -370.389519) (xy 169.270945 -370.456339) (xy 169.270946 -370.523643)
			(xy 169.270946 -370.523644) (xy 172.549008 -370.523644) (xy 172.549009 -370.456338) (xy 172.557055 -370.389513)
			(xy 172.573031 -370.32413) (xy 172.596707 -370.261125) (xy 172.627745 -370.201401) (xy 172.665698 -370.145816)
			(xy 172.687488 -370.120164) (xy 172.693281 -370.113016) (xy 172.699798 -370.095828) (xy 172.700188 -370.086636)
			(xy 172.700188 -369.928902) (xy 172.700567 -369.918724) (xy 172.70836 -369.89992) (xy 172.72276 -369.885533)
			(xy 172.741572 -369.877757) (xy 172.75175 -369.87734) (xy 173.46803 -369.87734) (xy 173.47819 -369.877809)
			(xy 173.49696 -369.885593) (xy 173.511325 -369.899967) (xy 173.519098 -369.918742) (xy 173.519592 -369.928902)
			(xy 173.519592 -370.086636) (xy 173.519986 -370.095825) (xy 173.526511 -370.113009) (xy 173.532292 -370.120164)
			(xy 173.554067 -370.145826) (xy 173.592014 -370.201412) (xy 173.623046 -370.261134) (xy 173.646718 -370.324138)
			(xy 173.662691 -370.389518) (xy 173.670736 -370.456339) (xy 173.670737 -370.523643) (xy 173.662694 -370.590464)
			(xy 173.646724 -370.655845) (xy 173.623054 -370.718849) (xy 173.592023 -370.778573) (xy 173.554078 -370.834159)
			(xy 173.532292 -370.859812) (xy 173.526507 -370.866965) (xy 173.519986 -370.88415) (xy 173.519592 -370.89334)
			(xy 173.519592 -371.386862) (xy 173.520022 -371.396047) (xy 173.526522 -371.413231) (xy 173.532292 -371.42039)
			(xy 173.554093 -371.446031) (xy 173.592039 -371.50162) (xy 173.62307 -371.561345) (xy 173.646506 -371.623725)
			(xy 174.74915 -371.623725) (xy 174.749154 -371.556417) (xy 174.757201 -371.489592) (xy 174.773178 -371.424208)
			(xy 174.796855 -371.361202) (xy 174.827893 -371.301477) (xy 174.865846 -371.24589) (xy 174.887636 -371.220238)
			(xy 174.893446 -371.213102) (xy 174.899952 -371.195904) (xy 174.900336 -371.18671) (xy 174.900336 -371.028722)
			(xy 174.900782 -371.018552) (xy 174.908559 -370.999758) (xy 174.922938 -370.985373) (xy 174.941728 -370.977587)
			(xy 174.951898 -370.97716) (xy 175.668178 -370.97716) (xy 175.678351 -370.977583) (xy 175.697149 -370.985364)
			(xy 175.711536 -370.999751) (xy 175.719317 -371.018549) (xy 175.71974 -371.028722) (xy 175.71974 -371.18671)
			(xy 175.720159 -371.195896) (xy 175.726668 -371.21308) (xy 175.73244 -371.220238) (xy 175.754191 -371.245921)
			(xy 175.792142 -371.301502) (xy 175.823178 -371.361221) (xy 175.846854 -371.424222) (xy 175.86283 -371.489601)
			(xy 175.870878 -371.55642) (xy 175.870881 -371.623723) (xy 175.862841 -371.690543) (xy 175.846871 -371.755923)
			(xy 175.823202 -371.818926) (xy 175.792172 -371.878649) (xy 175.754226 -371.934234) (xy 175.73244 -371.959886)
			(xy 175.726617 -371.967012) (xy 175.72012 -371.984218) (xy 175.71974 -371.993414) (xy 175.71974 -372.486682)
			(xy 175.720172 -372.495867) (xy 175.726672 -372.51305) (xy 175.73244 -372.52021) (xy 175.754262 -372.545834)
			(xy 175.792211 -372.601424) (xy 175.823244 -372.661151) (xy 175.846916 -372.72416) (xy 175.862887 -372.789545)
			(xy 175.870929 -372.856371) (xy 175.870926 -372.92368) (xy 175.862878 -372.990505) (xy 175.846901 -373.055889)
			(xy 175.823223 -373.118895) (xy 175.792185 -373.17862) (xy 175.754231 -373.234206) (xy 175.73244 -373.259858)
			(xy 175.726629 -373.266993) (xy 175.720125 -373.284191) (xy 175.71974 -373.293386) (xy 175.71974 -373.451374)
			(xy 175.719314 -373.461547) (xy 175.711534 -373.480345) (xy 175.697148 -373.494731) (xy 175.678351 -373.502513)
			(xy 175.668178 -373.502936) (xy 174.951898 -373.502936) (xy 174.941723 -373.502537) (xy 174.922923 -373.494747)
			(xy 174.908538 -373.480353) (xy 174.900757 -373.461549) (xy 174.900336 -373.451374) (xy 174.900336 -373.293386)
			(xy 174.899925 -373.284199) (xy 174.893411 -373.267015) (xy 174.887636 -373.259858) (xy 174.865882 -373.234178)
			(xy 174.827932 -373.178596) (xy 174.796898 -373.118876) (xy 174.773223 -373.055875) (xy 174.757248 -372.990496)
			(xy 174.749201 -372.923677) (xy 174.749198 -372.856374) (xy 174.757239 -372.789554) (xy 174.773208 -372.724174)
			(xy 174.796877 -372.661171) (xy 174.827906 -372.601448) (xy 174.865851 -372.545862) (xy 174.887636 -372.52021)
			(xy 174.893458 -372.513083) (xy 174.899957 -372.495878) (xy 174.900336 -372.486682) (xy 174.900336 -371.993414)
			(xy 174.899911 -371.984229) (xy 174.893407 -371.967044) (xy 174.887636 -371.959886) (xy 174.865811 -371.934265)
			(xy 174.827863 -371.878674) (xy 174.796832 -371.818946) (xy 174.773161 -371.755937) (xy 174.757191 -371.690551)
			(xy 174.74915 -371.623725) (xy 173.646506 -371.623725) (xy 173.646741 -371.624351) (xy 173.662712 -371.689734)
			(xy 173.670754 -371.756558) (xy 173.670753 -371.823863) (xy 173.662708 -371.890686) (xy 173.646734 -371.956069)
			(xy 173.623061 -372.019074) (xy 173.592028 -372.078798) (xy 173.55408 -372.134385) (xy 173.532292 -372.160038)
			(xy 173.526496 -372.167183) (xy 173.519981 -372.184374) (xy 173.519592 -372.193566) (xy 173.519592 -372.351554)
			(xy 173.519099 -372.361719) (xy 173.511335 -372.380507) (xy 173.496971 -372.394892) (xy 173.478194 -372.402684)
			(xy 173.46803 -372.403116) (xy 172.75175 -372.403116) (xy 172.741576 -372.402694) (xy 172.722773 -372.394917)
			(xy 172.708385 -372.38053) (xy 172.700607 -372.361728) (xy 172.700188 -372.351554) (xy 172.700188 -372.193566)
			(xy 172.699797 -372.184377) (xy 172.69327 -372.167192) (xy 172.687488 -372.160038) (xy 172.665713 -372.134375)
			(xy 172.62776 -372.078791) (xy 172.596724 -372.01907) (xy 172.573048 -371.956067) (xy 172.557072 -371.890685)
			(xy 172.549026 -371.823863) (xy 172.549025 -371.756558) (xy 172.557069 -371.689736) (xy 172.573042 -371.624354)
			(xy 172.596715 -371.561349) (xy 172.627749 -371.501627) (xy 172.6657 -371.446041) (xy 172.687488 -371.42039)
			(xy 172.69327 -371.413234) (xy 172.699794 -371.396052) (xy 172.700188 -371.386862) (xy 172.700188 -370.89334)
			(xy 172.699761 -370.884154) (xy 172.69326 -370.86697) (xy 172.687488 -370.859812) (xy 172.665687 -370.83417)
			(xy 172.627735 -370.778583) (xy 172.5967 -370.718859) (xy 172.573026 -370.655853) (xy 172.557052 -370.590469)
			(xy 172.549008 -370.523644) (xy 169.270946 -370.523644) (xy 169.262904 -370.590464) (xy 169.246933 -370.655845)
			(xy 169.223264 -370.718849) (xy 169.192234 -370.778572) (xy 169.15429 -370.834159) (xy 169.132504 -370.859812)
			(xy 169.12672 -370.866966) (xy 169.120198 -370.88415) (xy 169.119804 -370.89334) (xy 169.119804 -371.386862)
			(xy 169.120231 -371.396047) (xy 169.126733 -371.413232) (xy 169.132504 -371.42039) (xy 169.154304 -371.446031)
			(xy 169.19225 -371.50162) (xy 169.22328 -371.561346) (xy 169.246737 -371.623785) (xy 170.348831 -371.623785)
			(xy 170.348834 -371.556358) (xy 170.356914 -371.489416) (xy 170.372955 -371.423924) (xy 170.396726 -371.360825)
			(xy 170.427884 -371.301029) (xy 170.46598 -371.245394) (xy 170.487848 -371.21973) (xy 170.493663 -371.212598)
			(xy 170.500165 -371.195397) (xy 170.500548 -371.186202) (xy 170.500548 -371.028722) (xy 170.501045 -371.018596)
			(xy 170.508767 -370.999873) (xy 170.52305 -370.985516) (xy 170.541732 -370.977698) (xy 170.551856 -370.97716)
			(xy 171.268136 -370.97716) (xy 171.278287 -370.977591) (xy 171.297033 -370.985391) (xy 171.311354 -370.999784)
			(xy 171.319059 -371.018568) (xy 171.319444 -371.028722) (xy 171.319444 -371.186202) (xy 171.319866 -371.195388)
			(xy 171.326373 -371.212571) (xy 171.332144 -371.21973) (xy 171.353973 -371.245425) (xy 171.392066 -371.301054)
			(xy 171.423222 -371.360846) (xy 171.44699 -371.423939) (xy 171.46303 -371.489425) (xy 171.47111 -371.556361)
			(xy 171.471113 -371.623782) (xy 171.46304 -371.690719) (xy 171.447007 -371.756207) (xy 171.423245 -371.819302)
			(xy 171.392096 -371.879097) (xy 171.354008 -371.93473) (xy 171.332144 -371.960394) (xy 171.326361 -371.967548)
			(xy 171.31984 -371.984732) (xy 171.319444 -371.993922) (xy 171.319444 -372.486174) (xy 171.319879 -372.495358)
			(xy 171.326377 -372.512542) (xy 171.332144 -372.519702) (xy 171.354043 -372.545339) (xy 171.392135 -372.600976)
			(xy 171.423287 -372.660776) (xy 171.447052 -372.723876) (xy 171.463087 -372.789369) (xy 171.471161 -372.856312)
			(xy 171.471158 -372.923739) (xy 171.463077 -372.990681) (xy 171.447037 -373.056172) (xy 171.423266 -373.119271)
			(xy 171.392108 -373.179068) (xy 171.354012 -373.234702) (xy 171.332144 -373.260366) (xy 171.32633 -373.267499)
			(xy 171.319827 -373.284699) (xy 171.319444 -373.293894) (xy 171.319444 -373.451374) (xy 171.318952 -373.461501)
			(xy 171.31123 -373.480225) (xy 171.296945 -373.494583) (xy 171.27826 -373.5024) (xy 171.268136 -373.502936)
			(xy 170.551856 -373.502936) (xy 170.541704 -373.502515) (xy 170.522957 -373.494712) (xy 170.508637 -373.480316)
			(xy 170.500932 -373.461529) (xy 170.500548 -373.451374) (xy 170.500548 -373.293894) (xy 170.50013 -373.284708)
			(xy 170.493621 -373.267524) (xy 170.487848 -373.260366) (xy 170.466016 -373.234674) (xy 170.427923 -373.179044)
			(xy 170.396768 -373.119252) (xy 170.373 -373.056159) (xy 170.356961 -372.990673) (xy 170.348881 -372.923736)
			(xy 170.348878 -372.856315) (xy 170.356951 -372.789378) (xy 170.372985 -372.72389) (xy 170.396747 -372.660794)
			(xy 170.427897 -372.600999) (xy 170.465984 -372.545366) (xy 170.487848 -372.519702) (xy 170.493632 -372.512548)
			(xy 170.500153 -372.495364) (xy 170.500548 -372.486174) (xy 170.500548 -371.993922) (xy 170.500117 -371.984737)
			(xy 170.493617 -371.967553) (xy 170.487848 -371.960394) (xy 170.465945 -371.93476) (xy 170.427854 -371.879122)
			(xy 170.396703 -371.819322) (xy 170.372938 -371.756221) (xy 170.356904 -371.690728) (xy 170.348831 -371.623785)
			(xy 169.246737 -371.623785) (xy 169.24695 -371.624352) (xy 169.262921 -371.689735) (xy 169.270963 -371.756558)
			(xy 169.270962 -371.823863) (xy 169.262917 -371.890686) (xy 169.246944 -371.956068) (xy 169.223271 -372.019073)
			(xy 169.192239 -372.078798) (xy 169.154291 -372.134385) (xy 169.132504 -372.160038) (xy 169.126709 -372.167185)
			(xy 169.120193 -372.184374) (xy 169.119804 -372.193566) (xy 169.119804 -372.351554) (xy 169.1193 -372.361717)
			(xy 169.111537 -372.380503) (xy 169.097177 -372.394888) (xy 169.078405 -372.402682) (xy 169.068242 -372.403116)
			(xy 168.351962 -372.403116) (xy 168.341782 -372.402766) (xy 168.322978 -372.39496) (xy 168.308593 -372.380552)
			(xy 168.300817 -372.361734) (xy 168.3004 -372.351554) (xy 168.3004 -372.193566) (xy 168.300006 -372.184377)
			(xy 168.293481 -372.167193) (xy 168.2877 -372.160038) (xy 168.265927 -372.134374) (xy 168.227981 -372.078788)
			(xy 168.196949 -372.019066) (xy 168.173277 -371.956063) (xy 168.157304 -371.890683) (xy 168.14926 -371.823862)
			(xy 168.149258 -371.756559) (xy 168.1573 -371.689738) (xy 168.173271 -371.624357) (xy 168.19694 -371.561353)
			(xy 168.22797 -371.50163) (xy 168.265914 -371.446043) (xy 168.2877 -371.42039) (xy 168.293483 -371.413235)
			(xy 168.300006 -371.396052) (xy 168.3004 -371.386862) (xy 168.3004 -370.89334) (xy 168.299971 -370.884155)
			(xy 168.29347 -370.86697) (xy 168.2877 -370.859812) (xy 168.265902 -370.834169) (xy 168.227956 -370.77858)
			(xy 168.196925 -370.718855) (xy 168.173255 -370.65585) (xy 168.157284 -370.590467) (xy 168.149241 -370.523644)
			(xy 164.871178 -370.523644) (xy 164.871178 -370.523702) (xy 164.863103 -370.59064) (xy 164.847069 -370.656128)
			(xy 164.823307 -370.719224) (xy 164.792158 -370.77902) (xy 164.754071 -370.834655) (xy 164.732208 -370.86032)
			(xy 164.726421 -370.867472) (xy 164.7199 -370.884657) (xy 164.719508 -370.893848) (xy 164.719508 -371.386354)
			(xy 164.719938 -371.395539) (xy 164.726438 -371.412724) (xy 164.732208 -371.419882) (xy 164.754085 -371.445536)
			(xy 164.792173 -371.501172) (xy 164.823323 -371.56097) (xy 164.846957 -371.623726) (xy 165.949062 -371.623726)
			(xy 165.949066 -371.556417) (xy 165.957114 -371.489592) (xy 165.973091 -371.424207) (xy 165.996769 -371.361201)
			(xy 166.027807 -371.301477) (xy 166.065761 -371.24589) (xy 166.087552 -371.220238) (xy 166.093364 -371.213104)
			(xy 166.099868 -371.195905) (xy 166.100252 -371.18671) (xy 166.100252 -371.028722) (xy 166.100682 -371.01855)
			(xy 166.108463 -370.999753) (xy 166.122847 -370.985367) (xy 166.141642 -370.977584) (xy 166.151814 -370.97716)
			(xy 166.868094 -370.97716) (xy 166.878268 -370.977569) (xy 166.897067 -370.985356) (xy 166.911453 -370.999747)
			(xy 166.919234 -371.018548) (xy 166.919656 -371.028722) (xy 166.919656 -371.18671) (xy 166.920071 -371.195896)
			(xy 166.926582 -371.21308) (xy 166.932356 -371.220238) (xy 166.954106 -371.245921) (xy 166.992057 -371.301503)
			(xy 167.023092 -371.361222) (xy 167.046767 -371.424223) (xy 167.062743 -371.489601) (xy 167.07079 -371.55642)
			(xy 167.070793 -371.623722) (xy 167.062753 -371.690543) (xy 167.046784 -371.755923) (xy 167.023115 -371.818926)
			(xy 166.992086 -371.878648) (xy 166.954141 -371.934234) (xy 166.932356 -371.959886) (xy 166.926535 -371.967014)
			(xy 166.920036 -371.984218) (xy 166.919656 -371.993414) (xy 166.919656 -372.486682) (xy 166.920085 -372.495867)
			(xy 166.926586 -372.513051) (xy 166.932356 -372.52021) (xy 166.954177 -372.545834) (xy 166.992126 -372.601425)
			(xy 167.023158 -372.661152) (xy 167.046829 -372.72416) (xy 167.0628 -372.789546) (xy 167.070841 -372.856372)
			(xy 167.070838 -372.923679) (xy 167.06279 -372.990504) (xy 167.046814 -373.055889) (xy 167.023137 -373.118895)
			(xy 166.992099 -373.178619) (xy 166.954146 -373.234206) (xy 166.932356 -373.259858) (xy 166.926547 -373.266994)
			(xy 166.920041 -373.284192) (xy 166.919656 -373.293386) (xy 166.919656 -373.451374) (xy 166.919215 -373.461545)
			(xy 166.911437 -373.48034) (xy 166.897057 -373.494726) (xy 166.878264 -373.502511) (xy 166.868094 -373.502936)
			(xy 166.151814 -373.502936) (xy 166.14164 -373.502524) (xy 166.122841 -373.494739) (xy 166.108454 -373.480349)
			(xy 166.100673 -373.461548) (xy 166.100252 -373.451374) (xy 166.100252 -373.293386) (xy 166.099837 -373.2842)
			(xy 166.093325 -373.267016) (xy 166.087552 -373.259858) (xy 166.065797 -373.234178) (xy 166.027847 -373.178596)
			(xy 165.996811 -373.118877) (xy 165.973136 -373.055876) (xy 165.95716 -372.990497) (xy 165.949113 -372.923677)
			(xy 165.94911 -372.856374) (xy 165.957151 -372.789554) (xy 165.973121 -372.724173) (xy 165.99679 -372.66117)
			(xy 166.02782 -372.601448) (xy 166.065766 -372.545862) (xy 166.087552 -372.52021) (xy 166.093376 -372.513084)
			(xy 166.099873 -372.495879) (xy 166.100252 -372.486682) (xy 166.100252 -371.993414) (xy 166.099824 -371.984229)
			(xy 166.093321 -371.967045) (xy 166.087552 -371.959886) (xy 166.065726 -371.934265) (xy 166.027778 -371.878674)
			(xy 165.996745 -371.818947) (xy 165.973074 -371.755938) (xy 165.957104 -371.690552) (xy 165.949062 -371.623726)
			(xy 164.846957 -371.623726) (xy 164.847086 -371.624068) (xy 164.86312 -371.689559) (xy 164.871195 -371.756498)
			(xy 164.871194 -371.823923) (xy 164.863116 -371.890862) (xy 164.84708 -371.956352) (xy 164.823314 -372.019449)
			(xy 164.792162 -372.079246) (xy 164.754073 -372.134881) (xy 164.732208 -372.160546) (xy 164.72641 -372.16769)
			(xy 164.719896 -372.184881) (xy 164.719508 -372.194074) (xy 164.719508 -372.351554) (xy 164.718937 -372.361672)
			(xy 164.711233 -372.380383) (xy 164.696973 -372.394739) (xy 164.678314 -372.402568) (xy 164.6682 -372.403116)
			(xy 163.95192 -372.403116) (xy 163.941769 -372.402662) (xy 163.92302 -372.394876) (xy 163.908697 -372.38049)
			(xy 163.900993 -372.361707) (xy 163.900612 -372.351554) (xy 163.900612 -372.194074) (xy 163.900212 -372.184886)
			(xy 163.893691 -372.167702) (xy 163.887912 -372.160546) (xy 163.866061 -372.13487) (xy 163.827971 -372.079237)
			(xy 163.796819 -372.019442) (xy 163.773054 -371.956347) (xy 163.757017 -371.890859) (xy 163.74894 -371.823922)
			(xy 163.748939 -371.756499) (xy 163.757013 -371.689562) (xy 163.773048 -371.624073) (xy 163.796811 -371.560977)
			(xy 163.827961 -371.501181) (xy 163.866048 -371.445547) (xy 163.887912 -371.419882) (xy 163.8937 -371.412731)
			(xy 163.900219 -371.395545) (xy 163.900612 -371.386354) (xy 163.900612 -370.893848) (xy 163.900176 -370.884664)
			(xy 163.89368 -370.867479) (xy 163.887912 -370.86032) (xy 163.866036 -370.834665) (xy 163.827947 -370.779029)
			(xy 163.796796 -370.719232) (xy 163.773032 -370.656133) (xy 163.756997 -370.590643) (xy 163.748922 -370.523703)
			(xy 160.470875 -370.523703) (xy 160.462839 -370.590466) (xy 160.446866 -370.655848) (xy 160.423192 -370.718852)
			(xy 160.392158 -370.778575) (xy 160.354208 -370.83416) (xy 160.33242 -370.859812) (xy 160.326638 -370.866968)
			(xy 160.320114 -370.88415) (xy 160.31972 -370.89334) (xy 160.31972 -371.386862) (xy 160.320144 -371.396048)
			(xy 160.326647 -371.413233) (xy 160.33242 -371.42039) (xy 160.354223 -371.44603) (xy 160.392174 -371.501618)
			(xy 160.423209 -371.561342) (xy 160.44667 -371.623784) (xy 161.548767 -371.623784) (xy 161.548771 -371.556358)
			(xy 161.55685 -371.489418) (xy 161.572888 -371.423928) (xy 161.596655 -371.360829) (xy 161.627808 -371.301032)
			(xy 161.665899 -371.245396) (xy 161.687764 -371.21973) (xy 161.693581 -371.212599) (xy 161.700082 -371.195397)
			(xy 161.700464 -371.186202) (xy 161.700464 -371.028722) (xy 161.700945 -371.018594) (xy 161.70867 -370.999868)
			(xy 161.722959 -370.985511) (xy 161.741646 -370.977695) (xy 161.751772 -370.97716) (xy 162.468052 -370.97716)
			(xy 162.478166 -370.977654) (xy 162.496861 -370.985379) (xy 162.511176 -370.999671) (xy 162.51893 -371.018354)
			(xy 162.51936 -371.028468) (xy 162.51936 -371.186202) (xy 162.519778 -371.195388) (xy 162.526287 -371.212572)
			(xy 162.53206 -371.21973) (xy 162.553888 -371.245425) (xy 162.591981 -371.301055) (xy 162.623135 -371.360846)
			(xy 162.646903 -371.423939) (xy 162.662942 -371.489425) (xy 162.671022 -371.556361) (xy 162.671025 -371.623782)
			(xy 162.662953 -371.690719) (xy 162.64692 -371.756206) (xy 162.623158 -371.819302) (xy 162.59201 -371.879096)
			(xy 162.553923 -371.934729) (xy 162.53206 -371.960394) (xy 162.526278 -371.96755) (xy 162.519756 -371.984732)
			(xy 162.51936 -371.993922) (xy 162.51936 -372.486174) (xy 162.519791 -372.495359) (xy 162.526291 -372.512543)
			(xy 162.53206 -372.519702) (xy 162.553959 -372.545339) (xy 162.592049 -372.600977) (xy 162.623201 -372.660776)
			(xy 162.646965 -372.723877) (xy 162.662999 -372.78937) (xy 162.671073 -372.856312) (xy 162.67107 -372.923739)
			(xy 162.66299 -372.99068) (xy 162.646949 -373.056172) (xy 162.62318 -373.11927) (xy 162.592023 -373.179067)
			(xy 162.553927 -373.234701) (xy 162.53206 -373.260366) (xy 162.526248 -373.2675) (xy 162.519743 -373.284699)
			(xy 162.51936 -373.293894) (xy 162.51936 -373.451374) (xy 162.518852 -373.461499) (xy 162.511133 -373.48022)
			(xy 162.496853 -373.494577) (xy 162.478174 -373.502397) (xy 162.468052 -373.502936) (xy 161.751772 -373.502936)
			(xy 161.741666 -373.502439) (xy 161.722994 -373.494699) (xy 161.708701 -373.480406) (xy 161.700961 -373.461734)
			(xy 161.700464 -373.451628) (xy 161.700464 -373.293894) (xy 161.700042 -373.284708) (xy 161.693535 -373.267525)
			(xy 161.687764 -373.260366) (xy 161.665935 -373.234673) (xy 161.627847 -373.179041) (xy 161.596697 -373.119249)
			(xy 161.572933 -373.056155) (xy 161.556896 -372.99067) (xy 161.548818 -372.923736) (xy 161.548815 -372.856315)
			(xy 161.556887 -372.78938) (xy 161.572918 -372.723893) (xy 161.596676 -372.660798) (xy 161.627821 -372.601003)
			(xy 161.665903 -372.545368) (xy 161.687764 -372.519702) (xy 161.69355 -372.51255) (xy 161.700069 -372.495364)
			(xy 161.700464 -372.486174) (xy 161.700464 -371.993922) (xy 161.700029 -371.984738) (xy 161.693531 -371.967554)
			(xy 161.687764 -371.960394) (xy 161.665864 -371.934759) (xy 161.627779 -371.879119) (xy 161.596632 -371.819319)
			(xy 161.572871 -371.756218) (xy 161.55684 -371.690725) (xy 161.548767 -371.623784) (xy 160.44667 -371.623784)
			(xy 160.446882 -371.624348) (xy 160.462856 -371.689733) (xy 160.470899 -371.756557) (xy 160.470898 -371.823864)
			(xy 160.462852 -371.890688) (xy 160.446876 -371.956072) (xy 160.4232 -372.019077) (xy 160.392163 -372.078801)
			(xy 160.35421 -372.134386) (xy 160.33242 -372.160038) (xy 160.326627 -372.167186) (xy 160.32011 -372.184374)
			(xy 160.31972 -372.193566) (xy 160.31972 -372.351554) (xy 160.319297 -372.361728) (xy 160.31152 -372.38053)
			(xy 160.297133 -372.394918) (xy 160.278332 -372.402697) (xy 160.268158 -372.403116) (xy 159.551878 -372.403116)
			(xy 159.541699 -372.402753) (xy 159.522895 -372.394952) (xy 159.50851 -372.380547) (xy 159.500734 -372.361733)
			(xy 159.500316 -372.351554) (xy 159.500316 -372.193566) (xy 159.499919 -372.184378) (xy 159.493396 -372.167193)
			(xy 159.487616 -372.160038) (xy 159.465843 -372.134374) (xy 159.427895 -372.078789) (xy 159.396862 -372.019067)
			(xy 159.37319 -371.956064) (xy 159.357216 -371.890683) (xy 159.349172 -371.823862) (xy 159.34917 -371.756559)
			(xy 159.357213 -371.689738) (xy 159.373184 -371.624356) (xy 159.396854 -371.561353) (xy 159.427884 -371.501629)
			(xy 159.46583 -371.446042) (xy 159.487616 -371.42039) (xy 159.493401 -371.413237) (xy 159.499922 -371.396052)
			(xy 159.500316 -371.386862) (xy 159.500316 -370.89334) (xy 159.499883 -370.884155) (xy 159.493385 -370.866971)
			(xy 159.487616 -370.859812) (xy 159.465817 -370.834169) (xy 159.42787 -370.778581) (xy 159.396839 -370.718856)
			(xy 159.373168 -370.65585) (xy 159.357196 -370.590467) (xy 159.349153 -370.523644) (xy 129.670828 -370.523644)
			(xy 129.662785 -370.590464) (xy 129.646814 -370.655846) (xy 129.623143 -370.71885) (xy 129.592113 -370.778573)
			(xy 129.554166 -370.83416) (xy 129.53238 -370.859812) (xy 129.526594 -370.866964) (xy 129.520073 -370.884149)
			(xy 129.51968 -370.89334) (xy 129.51968 -371.386862) (xy 129.520113 -371.396047) (xy 129.526611 -371.413231)
			(xy 129.53238 -371.42039) (xy 129.554181 -371.446031) (xy 129.592128 -371.50162) (xy 129.62316 -371.561345)
			(xy 129.646596 -371.623725) (xy 130.749241 -371.623725) (xy 130.749245 -371.556418) (xy 130.757292 -371.489593)
			(xy 130.773269 -371.424208) (xy 130.796945 -371.361202) (xy 130.827982 -371.301478) (xy 130.865934 -371.24589)
			(xy 130.887724 -371.220238) (xy 130.893532 -371.213101) (xy 130.900039 -371.195904) (xy 130.900424 -371.18671)
			(xy 130.900424 -371.028722) (xy 130.900882 -371.018554) (xy 130.908657 -370.999762) (xy 130.923032 -370.985377)
			(xy 130.941818 -370.977589) (xy 130.951986 -370.97716) (xy 131.668266 -370.97716) (xy 131.678438 -370.977592)
			(xy 131.697236 -370.98537) (xy 131.711623 -370.999754) (xy 131.719405 -371.01855) (xy 131.719828 -371.028722)
			(xy 131.719828 -371.18671) (xy 131.720227 -371.195898) (xy 131.726748 -371.213083) (xy 131.732528 -371.220238)
			(xy 131.754279 -371.24592) (xy 131.792231 -371.301502) (xy 131.823268 -371.361221) (xy 131.846945 -371.424221)
			(xy 131.862921 -371.4896) (xy 131.870969 -371.55642) (xy 131.870972 -371.623723) (xy 131.862931 -371.690543)
			(xy 131.846961 -371.755924) (xy 131.823291 -371.818927) (xy 131.792261 -371.878649) (xy 131.754314 -371.934234)
			(xy 131.732528 -371.959886) (xy 131.726704 -371.967011) (xy 131.720208 -371.984217) (xy 131.719828 -371.993414)
			(xy 131.719828 -372.486682) (xy 131.72024 -372.495869) (xy 131.726752 -372.513054) (xy 131.732528 -372.52021)
			(xy 131.75435 -372.545834) (xy 131.7923 -372.601424) (xy 131.823334 -372.661151) (xy 131.847006 -372.724159)
			(xy 131.862978 -372.789545) (xy 131.87102 -372.856371) (xy 131.871017 -372.92368) (xy 131.862969 -372.990505)
			(xy 131.846991 -373.05589) (xy 131.823313 -373.118896) (xy 131.792274 -373.17862) (xy 131.754319 -373.234206)
			(xy 131.732528 -373.259858) (xy 131.726716 -373.266992) (xy 131.720212 -373.284191) (xy 131.719828 -373.293386)
			(xy 131.719828 -373.451374) (xy 131.719414 -373.461548) (xy 131.711631 -373.480349) (xy 131.697242 -373.494736)
			(xy 131.67844 -373.502515) (xy 131.668266 -373.502936) (xy 130.951986 -373.502936) (xy 130.94181 -373.502547)
			(xy 130.92301 -373.494752) (xy 130.908625 -373.480356) (xy 130.900845 -373.46155) (xy 130.900424 -373.451374)
			(xy 130.900424 -373.293386) (xy 130.900015 -373.284199) (xy 130.8935 -373.267015) (xy 130.887724 -373.259858)
			(xy 130.86597 -373.234178) (xy 130.828022 -373.178595) (xy 130.796988 -373.118875) (xy 130.773314 -373.055874)
			(xy 130.757339 -372.990496) (xy 130.749292 -372.923677) (xy 130.749289 -372.856375) (xy 130.75733 -372.789555)
			(xy 130.773299 -372.724174) (xy 130.796967 -372.661171) (xy 130.827995 -372.601449) (xy 130.865939 -372.545863)
			(xy 130.887724 -372.52021) (xy 130.893544 -372.513082) (xy 130.900044 -372.495878) (xy 130.900424 -372.486682)
			(xy 130.900424 -371.993414) (xy 130.900002 -371.984228) (xy 130.893496 -371.967044) (xy 130.887724 -371.959886)
			(xy 130.865899 -371.934264) (xy 130.827953 -371.878673) (xy 130.796922 -371.818945) (xy 130.773252 -371.755937)
			(xy 130.757282 -371.690551) (xy 130.749241 -371.623725) (xy 129.646596 -371.623725) (xy 129.646831 -371.624351)
			(xy 129.662802 -371.689734) (xy 129.670845 -371.756558) (xy 129.670844 -371.823863) (xy 129.662799 -371.890687)
			(xy 129.646825 -371.956069) (xy 129.623151 -372.019074) (xy 129.592117 -372.078799) (xy 129.554168 -372.134386)
			(xy 129.53238 -372.160038) (xy 129.526582 -372.167182) (xy 129.520069 -372.184374) (xy 129.51968 -372.193566)
			(xy 129.51968 -372.351554) (xy 129.519199 -372.36172) (xy 129.511432 -372.380511) (xy 129.497064 -372.394896)
			(xy 129.478284 -372.402686) (xy 129.468118 -372.403116) (xy 128.751838 -372.403116) (xy 128.741663 -372.402704)
			(xy 128.722861 -372.394923) (xy 128.708473 -372.380533) (xy 128.700695 -372.361729) (xy 128.700276 -372.351554)
			(xy 128.700276 -372.193566) (xy 128.699887 -372.184376) (xy 128.693359 -372.167192) (xy 128.687576 -372.160038)
			(xy 128.665801 -372.134375) (xy 128.627849 -372.078791) (xy 128.596813 -372.019069) (xy 128.573138 -371.956066)
			(xy 128.557163 -371.890685) (xy 128.549117 -371.823863) (xy 128.549116 -371.756558) (xy 128.557159 -371.689736)
			(xy 128.573132 -371.624354) (xy 128.596805 -371.56135) (xy 128.627838 -371.501627) (xy 128.665788 -371.446042)
			(xy 128.687576 -371.42039) (xy 128.693357 -371.413233) (xy 128.699882 -371.396052) (xy 128.700276 -371.386862)
			(xy 128.700276 -370.89334) (xy 128.699852 -370.884154) (xy 128.693349 -370.866969) (xy 128.687576 -370.859812)
			(xy 128.665775 -370.83417) (xy 128.627825 -370.778583) (xy 128.59679 -370.718858) (xy 128.573116 -370.655852)
			(xy 128.557143 -370.590469) (xy 128.549099 -370.523644) (xy 125.271037 -370.523644) (xy 125.262994 -370.590464)
			(xy 125.247024 -370.655845) (xy 125.223354 -370.718849) (xy 125.192323 -370.778573) (xy 125.154378 -370.834159)
			(xy 125.132592 -370.859812) (xy 125.126807 -370.866965) (xy 125.120286 -370.88415) (xy 125.119892 -370.89334)
			(xy 125.119892 -371.386862) (xy 125.120322 -371.396047) (xy 125.126822 -371.413231) (xy 125.132592 -371.42039)
			(xy 125.154393 -371.446031) (xy 125.192339 -371.50162) (xy 125.22337 -371.561345) (xy 125.246828 -371.623785)
			(xy 126.348921 -371.623785) (xy 126.348925 -371.556358) (xy 126.357005 -371.489416) (xy 126.373046 -371.423925)
			(xy 126.396816 -371.360826) (xy 126.427973 -371.301029) (xy 126.466069 -371.245395) (xy 126.487936 -371.21973)
			(xy 126.493749 -371.212597) (xy 126.500253 -371.195397) (xy 126.500636 -371.186202) (xy 126.500636 -371.028722)
			(xy 126.501144 -371.018597) (xy 126.508864 -370.999877) (xy 126.523144 -370.98552) (xy 126.541822 -370.9777)
			(xy 126.551944 -370.97716) (xy 127.268224 -370.97716) (xy 127.278375 -370.977601) (xy 127.29712 -370.985397)
			(xy 127.311441 -370.999787) (xy 127.319147 -371.018569) (xy 127.319532 -371.028722) (xy 127.319532 -371.186202)
			(xy 127.319956 -371.195387) (xy 127.326462 -371.212571) (xy 127.332232 -371.21973) (xy 127.354058 -371.245427)
			(xy 127.392145 -371.301057) (xy 127.423296 -371.36085) (xy 127.447061 -371.423942) (xy 127.463098 -371.489427)
			(xy 127.471176 -371.556361) (xy 127.47118 -371.623781) (xy 127.463108 -371.690717) (xy 127.447078 -371.756203)
			(xy 127.423319 -371.819298) (xy 127.392175 -371.879094) (xy 127.354093 -371.934728) (xy 127.332232 -371.960394)
			(xy 127.326447 -371.967547) (xy 127.319927 -371.984732) (xy 127.319532 -371.993922) (xy 127.319532 -372.486174)
			(xy 127.31997 -372.495358) (xy 127.326466 -372.512542) (xy 127.332232 -372.519702) (xy 127.354128 -372.54534)
			(xy 127.392214 -372.600979) (xy 127.423361 -372.66078) (xy 127.447122 -372.72388) (xy 127.463154 -372.789372)
			(xy 127.471227 -372.856313) (xy 127.471224 -372.923738) (xy 127.463145 -372.990678) (xy 127.447107 -373.056169)
			(xy 127.42334 -373.119267) (xy 127.392188 -373.179064) (xy 127.354097 -373.2347) (xy 127.332232 -373.260366)
			(xy 127.326417 -373.267498) (xy 127.319915 -373.284699) (xy 127.319532 -373.293894) (xy 127.319532 -373.451374)
			(xy 127.319051 -373.461503) (xy 127.311327 -373.480228) (xy 127.297038 -373.494587) (xy 127.27835 -373.502402)
			(xy 127.268224 -373.502936) (xy 126.551944 -373.502936) (xy 126.541797 -373.502443) (xy 126.523053 -373.494669)
			(xy 126.508729 -373.480294) (xy 126.501021 -373.461522) (xy 126.500636 -373.451374) (xy 126.500636 -373.293894)
			(xy 126.500221 -373.284708) (xy 126.49371 -373.267524) (xy 126.487936 -373.260366) (xy 126.466104 -373.234674)
			(xy 126.428012 -373.179044) (xy 126.396858 -373.119252) (xy 126.37309 -373.056158) (xy 126.357051 -372.990672)
			(xy 126.348972 -372.923736) (xy 126.348969 -372.856315) (xy 126.357042 -372.789378) (xy 126.373075 -372.72389)
			(xy 126.396837 -372.660795) (xy 126.427986 -372.601) (xy 126.466073 -372.545367) (xy 126.487936 -372.519702)
			(xy 126.493719 -372.512547) (xy 126.500241 -372.495364) (xy 126.500636 -372.486174) (xy 126.500636 -371.993922)
			(xy 126.500207 -371.984737) (xy 126.493706 -371.967553) (xy 126.487936 -371.960394) (xy 126.466033 -371.93476)
			(xy 126.427943 -371.879122) (xy 126.396792 -371.819322) (xy 126.373029 -371.756221) (xy 126.356995 -371.690727)
			(xy 126.348921 -371.623785) (xy 125.246828 -371.623785) (xy 125.247041 -371.624351) (xy 125.263012 -371.689734)
			(xy 125.271054 -371.756558) (xy 125.271053 -371.823863) (xy 125.263008 -371.890686) (xy 125.247034 -371.956069)
			(xy 125.223361 -372.019074) (xy 125.192328 -372.078798) (xy 125.15438 -372.134385) (xy 125.132592 -372.160038)
			(xy 125.126796 -372.167183) (xy 125.120281 -372.184374) (xy 125.119892 -372.193566) (xy 125.119892 -372.351554)
			(xy 125.119399 -372.361719) (xy 125.111635 -372.380507) (xy 125.097271 -372.394892) (xy 125.078494 -372.402684)
			(xy 125.06833 -372.403116) (xy 124.35205 -372.403116) (xy 124.341876 -372.402694) (xy 124.323073 -372.394917)
			(xy 124.308685 -372.38053) (xy 124.300907 -372.361728) (xy 124.300488 -372.351554) (xy 124.300488 -372.193566)
			(xy 124.300097 -372.184377) (xy 124.29357 -372.167192) (xy 124.287788 -372.160038) (xy 124.266013 -372.134375)
			(xy 124.22806 -372.078791) (xy 124.197024 -372.01907) (xy 124.173348 -371.956067) (xy 124.157372 -371.890685)
			(xy 124.149326 -371.823863) (xy 124.149325 -371.756558) (xy 124.157369 -371.689736) (xy 124.173342 -371.624354)
			(xy 124.197015 -371.561349) (xy 124.228049 -371.501627) (xy 124.266 -371.446041) (xy 124.287788 -371.42039)
			(xy 124.29357 -371.413234) (xy 124.300094 -371.396052) (xy 124.300488 -371.386862) (xy 124.300488 -370.89334)
			(xy 124.300061 -370.884154) (xy 124.29356 -370.86697) (xy 124.287788 -370.859812) (xy 124.265987 -370.83417)
			(xy 124.228035 -370.778583) (xy 124.197 -370.718859) (xy 124.173326 -370.655853) (xy 124.157352 -370.590469)
			(xy 124.149308 -370.523644) (xy 120.871269 -370.523644) (xy 120.871269 -370.523702) (xy 120.863194 -370.59064)
			(xy 120.847159 -370.656128) (xy 120.823396 -370.719225) (xy 120.792247 -370.779021) (xy 120.754159 -370.834655)
			(xy 120.732296 -370.86032) (xy 120.726508 -370.867471) (xy 120.719988 -370.884657) (xy 120.719596 -370.893848)
			(xy 120.719596 -371.386354) (xy 120.720029 -371.395539) (xy 120.726527 -371.412723) (xy 120.732296 -371.419882)
			(xy 120.754174 -371.445536) (xy 120.792262 -371.501172) (xy 120.823413 -371.56097) (xy 120.847047 -371.623725)
			(xy 121.949153 -371.623725) (xy 121.949157 -371.556417) (xy 121.957205 -371.489592) (xy 121.973182 -371.424208)
			(xy 121.996859 -371.361202) (xy 122.027896 -371.301477) (xy 122.06585 -371.24589) (xy 122.08764 -371.220238)
			(xy 122.09345 -371.213103) (xy 122.099956 -371.195904) (xy 122.10034 -371.18671) (xy 122.10034 -371.028722)
			(xy 122.100782 -371.018552) (xy 122.10856 -370.999757) (xy 122.12294 -370.985371) (xy 122.141732 -370.977586)
			(xy 122.151902 -370.97716) (xy 122.868182 -370.97716) (xy 122.878355 -370.977579) (xy 122.897154 -370.985362)
			(xy 122.91154 -370.99975) (xy 122.919322 -371.018549) (xy 122.919744 -371.028722) (xy 122.919744 -371.18671)
			(xy 122.920162 -371.195896) (xy 122.926672 -371.21308) (xy 122.932444 -371.220238) (xy 122.954195 -371.245921)
			(xy 122.992146 -371.301502) (xy 123.023182 -371.361222) (xy 123.046857 -371.424222) (xy 123.062833 -371.489601)
			(xy 123.070881 -371.55642) (xy 123.070884 -371.623723) (xy 123.062844 -371.690543) (xy 123.046874 -371.755923)
			(xy 123.023205 -371.818926) (xy 122.992175 -371.878648) (xy 122.95423 -371.934234) (xy 122.932444 -371.959886)
			(xy 122.926622 -371.967013) (xy 122.920124 -371.984218) (xy 122.919744 -371.993414) (xy 122.919744 -372.486682)
			(xy 122.920175 -372.495867) (xy 122.926676 -372.513051) (xy 122.932444 -372.52021) (xy 122.954266 -372.545834)
			(xy 122.992215 -372.601424) (xy 123.023248 -372.661152) (xy 123.046919 -372.72416) (xy 123.06289 -372.789546)
			(xy 123.070932 -372.856372) (xy 123.070929 -372.92368) (xy 123.062881 -372.990505) (xy 123.046904 -373.055889)
			(xy 123.023227 -373.118895) (xy 122.992188 -373.17862) (xy 122.954234 -373.234206) (xy 122.932444 -373.259858)
			(xy 122.926633 -373.266993) (xy 122.920129 -373.284192) (xy 122.919744 -373.293386) (xy 122.919744 -373.451374)
			(xy 122.919314 -373.461546) (xy 122.911534 -373.480344) (xy 122.89715 -373.49473) (xy 122.878354 -373.502513)
			(xy 122.868182 -373.502936) (xy 122.151902 -373.502936) (xy 122.141727 -373.502534) (xy 122.122928 -373.494745)
			(xy 122.108542 -373.480352) (xy 122.100761 -373.461549) (xy 122.10034 -373.451374) (xy 122.10034 -373.293386)
			(xy 122.099928 -373.284199) (xy 122.093415 -373.267015) (xy 122.08764 -373.259858) (xy 122.065886 -373.234178)
			(xy 122.027936 -373.178596) (xy 121.996901 -373.118876) (xy 121.973226 -373.055875) (xy 121.957251 -372.990496)
			(xy 121.949204 -372.923677) (xy 121.949201 -372.856374) (xy 121.957242 -372.789554) (xy 121.973211 -372.724174)
			(xy 121.99688 -372.661171) (xy 122.02791 -372.601448) (xy 122.065855 -372.545862) (xy 122.08764 -372.52021)
			(xy 122.093462 -372.513083) (xy 122.099961 -372.495878) (xy 122.10034 -372.486682) (xy 122.10034 -371.993414)
			(xy 122.099914 -371.984229) (xy 122.093411 -371.967045) (xy 122.08764 -371.959886) (xy 122.065815 -371.934265)
			(xy 122.027867 -371.878674) (xy 121.996835 -371.818946) (xy 121.973165 -371.755937) (xy 121.957194 -371.690551)
			(xy 121.949153 -371.623725) (xy 120.847047 -371.623725) (xy 120.847176 -371.624068) (xy 120.863211 -371.689558)
			(xy 120.871286 -371.756498) (xy 120.871284 -371.823923) (xy 120.863207 -371.890862) (xy 120.84717 -371.956352)
			(xy 120.823404 -372.01945) (xy 120.792252 -372.079246) (xy 120.754161 -372.134881) (xy 120.732296 -372.160546)
			(xy 120.726497 -372.167689) (xy 120.719984 -372.184881) (xy 120.719596 -372.194074) (xy 120.719596 -372.351554)
			(xy 120.719037 -372.361673) (xy 120.711331 -372.380387) (xy 120.697067 -372.394743) (xy 120.678404 -372.40257)
			(xy 120.668288 -372.403116) (xy 119.952008 -372.403116) (xy 119.941856 -372.402672) (xy 119.923107 -372.394882)
			(xy 119.908784 -372.380493) (xy 119.901081 -372.361707) (xy 119.9007 -372.351554) (xy 119.9007 -372.194074)
			(xy 119.900303 -372.184885) (xy 119.89378 -372.167701) (xy 119.888 -372.160546) (xy 119.86615 -372.134869)
			(xy 119.828061 -372.079237) (xy 119.796909 -372.019442) (xy 119.773144 -371.956346) (xy 119.757108 -371.890859)
			(xy 119.749031 -371.823922) (xy 119.74903 -371.756499) (xy 119.757104 -371.689562) (xy 119.773138 -371.624074)
			(xy 119.796901 -371.560977) (xy 119.82805 -371.501182) (xy 119.866137 -371.445547) (xy 119.888 -371.419882)
			(xy 119.893787 -371.41273) (xy 119.900307 -371.395545) (xy 119.9007 -371.386354) (xy 119.9007 -370.893848)
			(xy 119.900267 -370.884663) (xy 119.893769 -370.867479) (xy 119.888 -370.86032) (xy 119.866124 -370.834664)
			(xy 119.828036 -370.779029) (xy 119.796886 -370.719231) (xy 119.773122 -370.656133) (xy 119.757088 -370.590643)
			(xy 119.749013 -370.523703) (xy 116.470966 -370.523703) (xy 116.462929 -370.590466) (xy 116.446956 -370.655848)
			(xy 116.423282 -370.718853) (xy 116.392247 -370.778575) (xy 116.354297 -370.834161) (xy 116.332508 -370.859812)
			(xy 116.326725 -370.866967) (xy 116.320202 -370.88415) (xy 116.319808 -370.89334) (xy 116.319808 -371.386862)
			(xy 116.320235 -371.396047) (xy 116.326737 -371.413232) (xy 116.332508 -371.42039) (xy 116.354311 -371.44603)
			(xy 116.392263 -371.501617) (xy 116.423299 -371.561342) (xy 116.446761 -371.623785) (xy 117.548834 -371.623785)
			(xy 117.548837 -371.556358) (xy 117.556917 -371.489416) (xy 117.572959 -371.423924) (xy 117.596729 -371.360825)
			(xy 117.627887 -371.301028) (xy 117.665984 -371.245394) (xy 117.687852 -371.21973) (xy 117.693667 -371.212598)
			(xy 117.700169 -371.195397) (xy 117.700552 -371.186202) (xy 117.700552 -371.028722) (xy 117.701045 -371.018595)
			(xy 117.708768 -370.999872) (xy 117.723052 -370.985515) (xy 117.741736 -370.977697) (xy 117.75186 -370.97716)
			(xy 118.46814 -370.97716) (xy 118.478292 -370.977588) (xy 118.497037 -370.985389) (xy 118.511358 -370.999783)
			(xy 118.519063 -371.018568) (xy 118.519448 -371.028722) (xy 118.519448 -371.186202) (xy 118.519869 -371.195388)
			(xy 118.526376 -371.212572) (xy 118.532148 -371.21973) (xy 118.553976 -371.245425) (xy 118.59207 -371.301054)
			(xy 118.623225 -371.360846) (xy 118.646994 -371.423939) (xy 118.663033 -371.489425) (xy 118.671113 -371.556361)
			(xy 118.671116 -371.623782) (xy 118.663044 -371.690719) (xy 118.647011 -371.756207) (xy 118.623248 -371.819302)
			(xy 118.592099 -371.879097) (xy 118.554012 -371.93473) (xy 118.532148 -371.960394) (xy 118.526365 -371.967549)
			(xy 118.519844 -371.984732) (xy 118.519448 -371.993922) (xy 118.519448 -372.486174) (xy 118.519882 -372.495358)
			(xy 118.52638 -372.512542) (xy 118.532148 -372.519702) (xy 118.554047 -372.545339) (xy 118.592138 -372.600976)
			(xy 118.62329 -372.660776) (xy 118.647055 -372.723877) (xy 118.66309 -372.78937) (xy 118.671164 -372.856312)
			(xy 118.671161 -372.923739) (xy 118.663081 -372.990681) (xy 118.64704 -373.056172) (xy 118.62327 -373.119271)
			(xy 118.592112 -373.179068) (xy 118.554016 -373.234702) (xy 118.532148 -373.260366) (xy 118.526334 -373.267499)
			(xy 118.519831 -373.284699) (xy 118.519448 -373.293894) (xy 118.519448 -373.451374) (xy 118.518952 -373.461501)
			(xy 118.51123 -373.480223) (xy 118.496947 -373.494581) (xy 118.478264 -373.502399) (xy 118.46814 -373.502936)
			(xy 117.75186 -373.502936) (xy 117.741708 -373.502512) (xy 117.722961 -373.49471) (xy 117.708641 -373.480315)
			(xy 117.700936 -373.461528) (xy 117.700552 -373.451374) (xy 117.700552 -373.293894) (xy 117.700133 -373.284708)
			(xy 117.693624 -373.267524) (xy 117.687852 -373.260366) (xy 117.66602 -373.234674) (xy 117.627926 -373.179045)
			(xy 117.596771 -373.119253) (xy 117.573003 -373.056159) (xy 117.556964 -372.990673) (xy 117.548884 -372.923737)
			(xy 117.548881 -372.856315) (xy 117.556954 -372.789378) (xy 117.572988 -372.72389) (xy 117.596751 -372.660794)
			(xy 117.6279 -372.600999) (xy 117.665988 -372.545366) (xy 117.687852 -372.519702) (xy 117.693637 -372.512549)
			(xy 117.700157 -372.495364) (xy 117.700552 -372.486174) (xy 117.700552 -371.993922) (xy 117.70012 -371.984737)
			(xy 117.69362 -371.967553) (xy 117.687852 -371.960394) (xy 117.665949 -371.93476) (xy 117.627858 -371.879123)
			(xy 117.596706 -371.819323) (xy 117.572942 -371.756221) (xy 117.556907 -371.690728) (xy 117.548834 -371.623785)
			(xy 116.446761 -371.623785) (xy 116.446973 -371.624348) (xy 116.462946 -371.689732) (xy 116.47099 -371.756557)
			(xy 116.470989 -371.823864) (xy 116.462943 -371.890689) (xy 116.446967 -371.956072) (xy 116.42329 -372.019077)
			(xy 116.392252 -372.078801) (xy 116.354298 -372.134387) (xy 116.332508 -372.160038) (xy 116.326714 -372.167185)
			(xy 116.320197 -372.184374) (xy 116.319808 -372.193566) (xy 116.319808 -372.351554) (xy 116.31923 -372.361703)
			(xy 116.311479 -372.380462) (xy 116.29714 -372.394828) (xy 116.278394 -372.402612) (xy 116.268246 -372.403116)
			(xy 115.551966 -372.403116) (xy 115.541786 -372.402763) (xy 115.522982 -372.394958) (xy 115.508597 -372.380551)
			(xy 115.500821 -372.361734) (xy 115.500404 -372.351554) (xy 115.500404 -372.193566) (xy 115.500009 -372.184377)
			(xy 115.493485 -372.167193) (xy 115.487704 -372.160038) (xy 115.465931 -372.134374) (xy 115.427984 -372.078788)
			(xy 115.396952 -372.019066) (xy 115.37328 -371.956063) (xy 115.357307 -371.890683) (xy 115.349263 -371.823862)
			(xy 115.349261 -371.756559) (xy 115.357303 -371.689738) (xy 115.373274 -371.624357) (xy 115.396944 -371.561353)
			(xy 115.427973 -371.50163) (xy 115.465918 -371.446043) (xy 115.487704 -371.42039) (xy 115.493488 -371.413236)
			(xy 115.50001 -371.396052) (xy 115.500404 -371.386862) (xy 115.500404 -370.89334) (xy 115.499974 -370.884155)
			(xy 115.493474 -370.86697) (xy 115.487704 -370.859812) (xy 115.465906 -370.834169) (xy 115.427959 -370.77858)
			(xy 115.396929 -370.718855) (xy 115.373258 -370.65585) (xy 115.357287 -370.590467) (xy 115.349244 -370.523644)
			(xy 85.670941 -370.523644) (xy 85.670941 -370.523703) (xy 85.662866 -370.590641) (xy 85.646831 -370.65613)
			(xy 85.623066 -370.719226) (xy 85.591915 -370.779022) (xy 85.553825 -370.834655) (xy 85.53196 -370.86032)
			(xy 85.526167 -370.867468) (xy 85.519651 -370.884656) (xy 85.51926 -370.893848) (xy 85.51926 -371.386354)
			(xy 85.519701 -371.395538) (xy 85.526194 -371.412722) (xy 85.53196 -371.419882) (xy 85.553839 -371.445535)
			(xy 85.59193 -371.501171) (xy 85.623082 -371.560968) (xy 85.646742 -371.623785) (xy 86.748803 -371.623785)
			(xy 86.748807 -371.556358) (xy 86.756887 -371.489417) (xy 86.772927 -371.423926) (xy 86.796696 -371.360827)
			(xy 86.827851 -371.30103) (xy 86.865945 -371.245395) (xy 86.887812 -371.21973) (xy 86.893622 -371.212594)
			(xy 86.900128 -371.195397) (xy 86.900512 -371.186202) (xy 86.900512 -371.028722) (xy 86.901044 -371.0186)
			(xy 86.908759 -370.999885) (xy 86.923031 -370.985529) (xy 86.941701 -370.977704) (xy 86.95182 -370.97716)
			(xy 87.6681 -370.97716) (xy 87.678204 -370.977684) (xy 87.696874 -370.985414) (xy 87.711168 -370.999699)
			(xy 87.718909 -371.018365) (xy 87.719408 -371.028468) (xy 87.719408 -371.186202) (xy 87.719815 -371.195389)
			(xy 87.726331 -371.212574) (xy 87.732108 -371.21973) (xy 87.753934 -371.245426) (xy 87.792024 -371.301056)
			(xy 87.823176 -371.360848) (xy 87.846942 -371.423941) (xy 87.862979 -371.489426) (xy 87.871058 -371.556361)
			(xy 87.871062 -371.623782) (xy 87.86299 -371.690717) (xy 87.846958 -371.756204) (xy 87.823199 -371.819299)
			(xy 87.792053 -371.879095) (xy 87.753969 -371.934729) (xy 87.732108 -371.960394) (xy 87.726332 -371.967554)
			(xy 87.719805 -371.984733) (xy 87.719408 -371.993922) (xy 87.719408 -372.486174) (xy 87.719829 -372.49536)
			(xy 87.726335 -372.512545) (xy 87.732108 -372.519702) (xy 87.754005 -372.54534) (xy 87.792092 -372.600978)
			(xy 87.823241 -372.660779) (xy 87.847003 -372.723879) (xy 87.863036 -372.789371) (xy 87.871109 -372.856312)
			(xy 87.871106 -372.923739) (xy 87.863027 -372.990679) (xy 87.846988 -373.05617) (xy 87.82322 -373.119268)
			(xy 87.792066 -373.179065) (xy 87.753974 -373.234701) (xy 87.732108 -373.260366) (xy 87.726302 -373.267504)
			(xy 87.719793 -373.2847) (xy 87.719408 -373.293894) (xy 87.719408 -373.451374) (xy 87.718854 -373.461493)
			(xy 87.711143 -373.480205) (xy 87.696878 -373.49456) (xy 87.678216 -373.502389) (xy 87.6681 -373.502936)
			(xy 86.95182 -373.502936) (xy 86.941717 -373.502399) (xy 86.923046 -373.494675) (xy 86.908752 -373.480394)
			(xy 86.90101 -373.461731) (xy 86.900512 -373.451628) (xy 86.900512 -373.293894) (xy 86.900102 -373.284707)
			(xy 86.893588 -373.267523) (xy 86.887812 -373.260366) (xy 86.865981 -373.234673) (xy 86.82789 -373.179043)
			(xy 86.796738 -373.119251) (xy 86.772971 -373.056157) (xy 86.756933 -372.990672) (xy 86.748854 -372.923736)
			(xy 86.748851 -372.856315) (xy 86.756924 -372.789379) (xy 86.772956 -372.723891) (xy 86.796717 -372.660796)
			(xy 86.827864 -372.601001) (xy 86.86595 -372.545367) (xy 86.887812 -372.519702) (xy 86.893592 -372.512545)
			(xy 86.900116 -372.495363) (xy 86.900512 -372.486174) (xy 86.900512 -371.993922) (xy 86.900088 -371.984736)
			(xy 86.893584 -371.967552) (xy 86.887812 -371.960394) (xy 86.86591 -371.93476) (xy 86.827822 -371.879121)
			(xy 86.796672 -371.819321) (xy 86.77291 -371.75622) (xy 86.756876 -371.690727) (xy 86.748803 -371.623785)
			(xy 85.646742 -371.623785) (xy 85.646848 -371.624067) (xy 85.662883 -371.689557) (xy 85.670959 -371.756498)
			(xy 85.670957 -371.823923) (xy 85.662879 -371.890863) (xy 85.646841 -371.956354) (xy 85.623074 -372.019451)
			(xy 85.591919 -372.079248) (xy 85.553826 -372.134881) (xy 85.53196 -372.160546) (xy 85.526156 -372.167686)
			(xy 85.519647 -372.184881) (xy 85.51926 -372.194074) (xy 85.51926 -372.351554) (xy 85.518736 -372.361678)
			(xy 85.511023 -372.380398) (xy 85.496748 -372.394756) (xy 85.478073 -372.402576) (xy 85.467952 -372.403116)
			(xy 84.751672 -372.403116) (xy 84.741563 -372.402638) (xy 84.722888 -372.394894) (xy 84.708594 -372.380596)
			(xy 84.700858 -372.361917) (xy 84.700364 -372.351808) (xy 84.700364 -372.194074) (xy 84.699952 -372.184887)
			(xy 84.693438 -372.167704) (xy 84.687664 -372.160546) (xy 84.665815 -372.134869) (xy 84.627728 -372.079235)
			(xy 84.596579 -372.01944) (xy 84.572816 -371.956345) (xy 84.55678 -371.890858) (xy 84.548704 -371.823921)
			(xy 84.548703 -371.7565) (xy 84.556776 -371.689563) (xy 84.572809 -371.624075) (xy 84.59657 -371.560979)
			(xy 84.627717 -371.501183) (xy 84.665802 -371.445548) (xy 84.687664 -371.419882) (xy 84.693459 -371.412736)
			(xy 84.699973 -371.395546) (xy 84.700364 -371.386354) (xy 84.700364 -370.893848) (xy 84.699917 -370.884665)
			(xy 84.693427 -370.867481) (xy 84.687664 -370.86032) (xy 84.66579 -370.834664) (xy 84.627704 -370.779027)
			(xy 84.596555 -370.719229) (xy 84.572793 -370.656131) (xy 84.55676 -370.590642) (xy 84.548686 -370.523703)
			(xy 81.27115 -370.523703) (xy 81.263075 -370.590641) (xy 81.24704 -370.656129) (xy 81.223276 -370.719226)
			(xy 81.192125 -370.779021) (xy 81.154036 -370.834655) (xy 81.132172 -370.86032) (xy 81.126381 -370.867469)
			(xy 81.119864 -370.884657) (xy 81.119472 -370.893848) (xy 81.119472 -371.386354) (xy 81.119911 -371.395538)
			(xy 81.126405 -371.412722) (xy 81.132172 -371.419882) (xy 81.154051 -371.445535) (xy 81.192141 -371.501171)
			(xy 81.223293 -371.560969) (xy 81.246928 -371.623725) (xy 82.349035 -371.623725) (xy 82.349038 -371.556418)
			(xy 82.357086 -371.489593) (xy 82.373062 -371.424209) (xy 82.396738 -371.361203) (xy 82.427775 -371.301478)
			(xy 82.465727 -371.24589) (xy 82.487516 -371.220238) (xy 82.493323 -371.2131) (xy 82.499831 -371.195904)
			(xy 82.500216 -371.18671) (xy 82.500216 -371.028722) (xy 82.500751 -371.018568) (xy 82.508514 -370.999804)
			(xy 82.522867 -370.985439) (xy 82.541625 -370.977659) (xy 82.551778 -370.97716) (xy 83.268058 -370.97716)
			(xy 83.27823 -370.977599) (xy 83.297028 -370.985374) (xy 83.311415 -370.999756) (xy 83.319197 -371.018551)
			(xy 83.31962 -371.028722) (xy 83.31962 -371.18671) (xy 83.320021 -371.195898) (xy 83.326541 -371.213083)
			(xy 83.33232 -371.220238) (xy 83.354072 -371.24592) (xy 83.392024 -371.301501) (xy 83.423061 -371.361221)
			(xy 83.446738 -371.424221) (xy 83.462715 -371.4896) (xy 83.470763 -371.55642) (xy 83.470766 -371.623723)
			(xy 83.462725 -371.690544) (xy 83.446755 -371.755924) (xy 83.423085 -371.818927) (xy 83.392054 -371.878649)
			(xy 83.354107 -371.934234) (xy 83.33232 -371.959886) (xy 83.326507 -371.96702) (xy 83.320001 -371.984219)
			(xy 83.31962 -371.993414) (xy 83.31962 -372.486682) (xy 83.320034 -372.495869) (xy 83.326545 -372.513054)
			(xy 83.33232 -372.52021) (xy 83.354142 -372.545834) (xy 83.392093 -372.601424) (xy 83.423127 -372.661151)
			(xy 83.446799 -372.724159) (xy 83.462771 -372.789545) (xy 83.470813 -372.856371) (xy 83.47081 -372.92368)
			(xy 83.462762 -372.990505) (xy 83.446784 -373.05589) (xy 83.423106 -373.118896) (xy 83.392066 -373.17862)
			(xy 83.354111 -373.234206) (xy 83.33232 -373.259858) (xy 83.326519 -373.267) (xy 83.320006 -373.284193)
			(xy 83.31962 -373.293386) (xy 83.31962 -373.451374) (xy 83.319214 -373.461549) (xy 83.311429 -373.480351)
			(xy 83.297038 -373.494738) (xy 83.278233 -373.502517) (xy 83.268058 -373.502936) (xy 82.551778 -373.502936)
			(xy 82.541602 -373.502553) (xy 82.522802 -373.494756) (xy 82.508417 -373.480358) (xy 82.500637 -373.461551)
			(xy 82.500216 -373.451374) (xy 82.500216 -373.293386) (xy 82.499809 -373.284199) (xy 82.493293 -373.267014)
			(xy 82.487516 -373.259858) (xy 82.465763 -373.234178) (xy 82.427814 -373.178595) (xy 82.396781 -373.118875)
			(xy 82.373107 -373.055874) (xy 82.357133 -372.990496) (xy 82.349086 -372.923677) (xy 82.349083 -372.856375)
			(xy 82.357123 -372.789555) (xy 82.373092 -372.724175) (xy 82.39676 -372.661172) (xy 82.427788 -372.601449)
			(xy 82.465731 -372.545863) (xy 82.487516 -372.52021) (xy 82.493335 -372.513081) (xy 82.499836 -372.495878)
			(xy 82.500216 -372.486682) (xy 82.500216 -371.993414) (xy 82.499795 -371.984228) (xy 82.493288 -371.967044)
			(xy 82.487516 -371.959886) (xy 82.465692 -371.934264) (xy 82.427745 -371.878673) (xy 82.396715 -371.818945)
			(xy 82.373045 -371.755936) (xy 82.357076 -371.690551) (xy 82.349035 -371.623725) (xy 81.246928 -371.623725)
			(xy 81.247057 -371.624067) (xy 81.263092 -371.689558) (xy 81.271168 -371.756498) (xy 81.271166 -371.823923)
			(xy 81.263089 -371.890863) (xy 81.247051 -371.956353) (xy 81.223284 -372.019451) (xy 81.19213 -372.079247)
			(xy 81.154038 -372.134881) (xy 81.132172 -372.160546) (xy 81.12637 -372.167687) (xy 81.119859 -372.184881)
			(xy 81.119472 -372.194074) (xy 81.119472 -372.351554) (xy 81.118936 -372.361676) (xy 81.111226 -372.380394)
			(xy 81.096954 -372.394752) (xy 81.078283 -372.402574) (xy 81.068164 -372.403116) (xy 80.351884 -372.403116)
			(xy 80.341776 -372.402628) (xy 80.323101 -372.394888) (xy 80.308807 -372.380592) (xy 80.30107 -372.361916)
			(xy 80.300576 -372.351808) (xy 80.300576 -372.194074) (xy 80.300184 -372.184885) (xy 80.293658 -372.1677)
			(xy 80.287876 -372.160546) (xy 80.266027 -372.134869) (xy 80.227939 -372.079236) (xy 80.196789 -372.019441)
			(xy 80.173025 -371.956346) (xy 80.156989 -371.890858) (xy 80.148913 -371.823922) (xy 80.148912 -371.756499)
			(xy 80.156986 -371.689563) (xy 80.173019 -371.624075) (xy 80.196781 -371.560978) (xy 80.227928 -371.501182)
			(xy 80.266014 -371.445548) (xy 80.287876 -371.419882) (xy 80.29366 -371.412728) (xy 80.300183 -371.395544)
			(xy 80.300576 -371.386354) (xy 80.300576 -370.893848) (xy 80.300148 -370.884663) (xy 80.293647 -370.867478)
			(xy 80.287876 -370.86032) (xy 80.266001 -370.834664) (xy 80.227914 -370.779028) (xy 80.196765 -370.71923)
			(xy 80.173003 -370.656132) (xy 80.156969 -370.590642) (xy 80.148895 -370.523703) (xy 76.870824 -370.523703)
			(xy 76.862788 -370.590464) (xy 76.846817 -370.655845) (xy 76.823147 -370.718849) (xy 76.792116 -370.778573)
			(xy 76.75417 -370.83416) (xy 76.732384 -370.859812) (xy 76.726598 -370.866965) (xy 76.720078 -370.88415)
			(xy 76.719684 -370.89334) (xy 76.719684 -371.386862) (xy 76.720116 -371.396047) (xy 76.726615 -371.413231)
			(xy 76.732384 -371.42039) (xy 76.754185 -371.446031) (xy 76.792132 -371.50162) (xy 76.823163 -371.561345)
			(xy 76.846621 -371.623785) (xy 77.948715 -371.623785) (xy 77.948719 -371.556358) (xy 77.956799 -371.489417)
			(xy 77.972839 -371.423925) (xy 77.996609 -371.360826) (xy 78.027766 -371.301029) (xy 78.065861 -371.245395)
			(xy 78.087728 -371.21973) (xy 78.09354 -371.212596) (xy 78.100045 -371.195397) (xy 78.100428 -371.186202)
			(xy 78.100428 -371.028722) (xy 78.100944 -371.018598) (xy 78.108662 -370.99988) (xy 78.12294 -370.985523)
			(xy 78.141615 -370.977701) (xy 78.151736 -370.97716) (xy 78.868016 -370.97716) (xy 78.878121 -370.977671)
			(xy 78.896792 -370.985407) (xy 78.911084 -370.999695) (xy 78.918826 -371.018363) (xy 78.919324 -371.028468)
			(xy 78.919324 -371.186202) (xy 78.919728 -371.19539) (xy 78.926245 -371.212575) (xy 78.932024 -371.21973)
			(xy 78.95385 -371.245426) (xy 78.991938 -371.301057) (xy 79.023089 -371.360849) (xy 79.046854 -371.423942)
			(xy 79.062892 -371.489427) (xy 79.07097 -371.556361) (xy 79.070974 -371.623782) (xy 79.062902 -371.690717)
			(xy 79.046871 -371.756203) (xy 79.023112 -371.819299) (xy 78.991967 -371.879094) (xy 78.953885 -371.934728)
			(xy 78.932024 -371.960394) (xy 78.92625 -371.967556) (xy 78.919721 -371.984733) (xy 78.919324 -371.993922)
			(xy 78.919324 -372.486174) (xy 78.919741 -372.495361) (xy 78.926249 -372.512545) (xy 78.932024 -372.519702)
			(xy 78.953921 -372.54534) (xy 78.992007 -372.600979) (xy 79.023155 -372.660779) (xy 79.046916 -372.72388)
			(xy 79.062948 -372.789372) (xy 79.071021 -372.856313) (xy 79.071018 -372.923738) (xy 79.062939 -372.990679)
			(xy 79.046901 -373.056169) (xy 79.023134 -373.119267) (xy 78.99198 -373.179065) (xy 78.953889 -373.2347)
			(xy 78.932024 -373.260366) (xy 78.92622 -373.267506) (xy 78.919709 -373.2847) (xy 78.919324 -373.293894)
			(xy 78.919324 -373.451374) (xy 78.918851 -373.461504) (xy 78.911125 -373.480231) (xy 78.896834 -373.49459)
			(xy 78.878143 -373.502403) (xy 78.868016 -373.502936) (xy 78.151736 -373.502936) (xy 78.14162 -373.502455)
			(xy 78.122924 -373.494726) (xy 78.10861 -373.480429) (xy 78.100857 -373.461743) (xy 78.100428 -373.451628)
			(xy 78.100428 -373.293894) (xy 78.100015 -373.284707) (xy 78.093503 -373.267523) (xy 78.087728 -373.260366)
			(xy 78.065896 -373.234674) (xy 78.027805 -373.179044) (xy 77.996651 -373.119251) (xy 77.972884 -373.056158)
			(xy 77.956845 -372.990672) (xy 77.948766 -372.923736) (xy 77.948763 -372.856315) (xy 77.956836 -372.789378)
			(xy 77.972869 -372.723891) (xy 77.99663 -372.660795) (xy 78.027779 -372.601) (xy 78.065865 -372.545367)
			(xy 78.087728 -372.519702) (xy 78.09351 -372.512547) (xy 78.100033 -372.495364) (xy 78.100428 -372.486174)
			(xy 78.100428 -371.993922) (xy 78.100001 -371.984737) (xy 78.093498 -371.967553) (xy 78.087728 -371.960394)
			(xy 78.065826 -371.93476) (xy 78.027736 -371.879122) (xy 77.996586 -371.819321) (xy 77.972822 -371.75622)
			(xy 77.956789 -371.690727) (xy 77.948715 -371.623785) (xy 76.846621 -371.623785) (xy 76.846834 -371.624351)
			(xy 76.862805 -371.689734) (xy 76.870848 -371.756558) (xy 76.870847 -371.823863) (xy 76.862802 -371.890687)
			(xy 76.846828 -371.956069) (xy 76.823155 -372.019074) (xy 76.792121 -372.078798) (xy 76.754172 -372.134386)
			(xy 76.732384 -372.160038) (xy 76.726587 -372.167183) (xy 76.720073 -372.184374) (xy 76.719684 -372.193566)
			(xy 76.719684 -372.351554) (xy 76.719199 -372.36172) (xy 76.711433 -372.380509) (xy 76.697067 -372.394895)
			(xy 76.678287 -372.402686) (xy 76.668122 -372.403116) (xy 75.951842 -372.403116) (xy 75.941667 -372.402701)
			(xy 75.922865 -372.394921) (xy 75.908477 -372.380532) (xy 75.900699 -372.361729) (xy 75.90028 -372.351554)
			(xy 75.90028 -372.193566) (xy 75.899891 -372.184377) (xy 75.893363 -372.167192) (xy 75.88758 -372.160038)
			(xy 75.865805 -372.134375) (xy 75.827853 -372.078791) (xy 75.796817 -372.019069) (xy 75.773141 -371.956066)
			(xy 75.757166 -371.890685) (xy 75.74912 -371.823863) (xy 75.749119 -371.756558) (xy 75.757162 -371.689736)
			(xy 75.773135 -371.624354) (xy 75.796808 -371.56135) (xy 75.827842 -371.501627) (xy 75.865792 -371.446042)
			(xy 75.88758 -371.42039) (xy 75.893361 -371.413234) (xy 75.899886 -371.396052) (xy 75.90028 -371.386862)
			(xy 75.90028 -370.89334) (xy 75.899855 -370.884154) (xy 75.893352 -370.866969) (xy 75.88758 -370.859812)
			(xy 75.865779 -370.83417) (xy 75.827828 -370.778583) (xy 75.796793 -370.718859) (xy 75.773119 -370.655853)
			(xy 75.757146 -370.590469) (xy 75.749102 -370.523644) (xy 72.471063 -370.523644) (xy 72.471063 -370.523702)
			(xy 72.462988 -370.59064) (xy 72.446953 -370.656129) (xy 72.42319 -370.719225) (xy 72.39204 -370.779021)
			(xy 72.353952 -370.834655) (xy 72.332088 -370.86032) (xy 72.326299 -370.867471) (xy 72.31978 -370.884657)
			(xy 72.319388 -370.893848) (xy 72.319388 -371.386354) (xy 72.319823 -371.395539) (xy 72.32632 -371.412723)
			(xy 72.332088 -371.419882) (xy 72.353966 -371.445536) (xy 72.392055 -371.501172) (xy 72.423206 -371.560969)
			(xy 72.446841 -371.623725) (xy 73.548947 -371.623725) (xy 73.548951 -371.556417) (xy 73.556998 -371.489592)
			(xy 73.572975 -371.424208) (xy 73.596652 -371.361202) (xy 73.627689 -371.301477) (xy 73.665642 -371.24589)
			(xy 73.687432 -371.220238) (xy 73.693242 -371.213102) (xy 73.699748 -371.195904) (xy 73.700132 -371.18671)
			(xy 73.700132 -371.028722) (xy 73.700582 -371.018553) (xy 73.708359 -370.99976) (xy 73.722736 -370.985374)
			(xy 73.741525 -370.977587) (xy 73.751694 -370.97716) (xy 74.467974 -370.97716) (xy 74.478147 -370.977586)
			(xy 74.496945 -370.985366) (xy 74.511331 -370.999752) (xy 74.519113 -371.018549) (xy 74.519536 -371.028722)
			(xy 74.519536 -371.18671) (xy 74.519956 -371.195896) (xy 74.526464 -371.21308) (xy 74.532236 -371.220238)
			(xy 74.553987 -371.245921) (xy 74.591939 -371.301502) (xy 74.622975 -371.361221) (xy 74.646651 -371.424222)
			(xy 74.662627 -371.489601) (xy 74.670675 -371.55642) (xy 74.670678 -371.623723) (xy 74.662638 -371.690543)
			(xy 74.646668 -371.755924) (xy 74.622998 -371.818926) (xy 74.591968 -371.878649) (xy 74.554022 -371.934234)
			(xy 74.532236 -371.959886) (xy 74.526413 -371.967012) (xy 74.519916 -371.984217) (xy 74.519536 -371.993414)
			(xy 74.519536 -372.486682) (xy 74.519969 -372.495866) (xy 74.526468 -372.51305) (xy 74.532236 -372.52021)
			(xy 74.554058 -372.545834) (xy 74.592008 -372.601424) (xy 74.623041 -372.661151) (xy 74.646713 -372.724159)
			(xy 74.662684 -372.789545) (xy 74.670726 -372.856371) (xy 74.670723 -372.92368) (xy 74.662675 -372.990505)
			(xy 74.646698 -373.055889) (xy 74.62302 -373.118896) (xy 74.591981 -373.17862) (xy 74.554027 -373.234206)
			(xy 74.532236 -373.259858) (xy 74.526425 -373.266992) (xy 74.519921 -373.284191) (xy 74.519536 -373.293386)
			(xy 74.519536 -373.451374) (xy 74.519114 -373.461547) (xy 74.511333 -373.480346) (xy 74.496946 -373.494733)
			(xy 74.478147 -373.502514) (xy 74.467974 -373.502936) (xy 73.751694 -373.502936) (xy 73.741519 -373.50254)
			(xy 73.722719 -373.494749) (xy 73.708333 -373.480354) (xy 73.700553 -373.461549) (xy 73.700132 -373.451374)
			(xy 73.700132 -373.293386) (xy 73.699722 -373.284199) (xy 73.693207 -373.267015) (xy 73.687432 -373.259858)
			(xy 73.665678 -373.234178) (xy 73.627729 -373.178595) (xy 73.596694 -373.118876) (xy 73.57302 -373.055875)
			(xy 73.557045 -372.990496) (xy 73.548998 -372.923677) (xy 73.548995 -372.856374) (xy 73.557036 -372.789554)
			(xy 73.573005 -372.724174) (xy 73.596674 -372.661171) (xy 73.627702 -372.601448) (xy 73.665647 -372.545862)
			(xy 73.687432 -372.52021) (xy 73.693253 -372.513083) (xy 73.699753 -372.495878) (xy 73.700132 -372.486682)
			(xy 73.700132 -371.993414) (xy 73.699708 -371.984228) (xy 73.693203 -371.967044) (xy 73.687432 -371.959886)
			(xy 73.665607 -371.934265) (xy 73.62766 -371.878674) (xy 73.596629 -371.818946) (xy 73.572958 -371.755937)
			(xy 73.556988 -371.690551) (xy 73.548947 -371.623725) (xy 72.446841 -371.623725) (xy 72.44697 -371.624068)
			(xy 72.463005 -371.689558) (xy 72.47108 -371.756498) (xy 72.471078 -371.823923) (xy 72.463001 -371.890862)
			(xy 72.446964 -371.956352) (xy 72.423197 -372.01945) (xy 72.392044 -372.079246) (xy 72.353953 -372.134881)
			(xy 72.332088 -372.160546) (xy 72.326288 -372.167689) (xy 72.319776 -372.184881) (xy 72.319388 -372.194074)
			(xy 72.319388 -372.351554) (xy 72.318836 -372.361674) (xy 72.311129 -372.380389) (xy 72.296863 -372.394746)
			(xy 72.278197 -372.402572) (xy 72.26808 -372.403116) (xy 71.5518 -372.403116) (xy 71.541648 -372.402679)
			(xy 71.522899 -372.394886) (xy 71.508576 -372.380494) (xy 71.500873 -372.361708) (xy 71.500492 -372.351554)
			(xy 71.500492 -372.194074) (xy 71.500096 -372.184885) (xy 71.493573 -372.167701) (xy 71.487792 -372.160546)
			(xy 71.465942 -372.134869) (xy 71.427853 -372.079236) (xy 71.396703 -372.019442) (xy 71.372938 -371.956346)
			(xy 71.356902 -371.890859) (xy 71.348825 -371.823922) (xy 71.348824 -371.756499) (xy 71.356898 -371.689562)
			(xy 71.372932 -371.624074) (xy 71.396694 -371.560978) (xy 71.427843 -371.501182) (xy 71.465929 -371.445547)
			(xy 71.487792 -371.419882) (xy 71.493578 -371.412729) (xy 71.500099 -371.395545) (xy 71.500492 -371.386354)
			(xy 71.500492 -370.893848) (xy 71.500061 -370.884663) (xy 71.493562 -370.867478) (xy 71.487792 -370.86032)
			(xy 71.465917 -370.834664) (xy 71.427829 -370.779028) (xy 71.396679 -370.719231) (xy 71.372916 -370.656133)
			(xy 71.356881 -370.590642) (xy 71.348807 -370.523703) (xy 58.103008 -370.523703) (xy 58.103008 -371.310662)
			(xy 58.102522 -371.337931) (xy 58.09476 -371.391915) (xy 58.079395 -371.444245) (xy 58.056738 -371.493855)
			(xy 58.027252 -371.539736) (xy 57.991537 -371.580953) (xy 57.95032 -371.616668) (xy 57.904439 -371.646154)
			(xy 57.854829 -371.668811) (xy 57.802499 -371.684176) (xy 57.748515 -371.691938) (xy 57.693977 -371.691938)
			(xy 57.639993 -371.684176) (xy 57.587663 -371.668811) (xy 57.538053 -371.646154) (xy 57.492172 -371.616668)
			(xy 57.450955 -371.580953) (xy 57.41524 -371.539736) (xy 57.385754 -371.493855) (xy 57.363097 -371.444245)
			(xy 57.347732 -371.391915) (xy 57.33997 -371.337931) (xy 57.339484 -371.310662) (xy 56.454548 -371.310662)
			(xy 56.454548 -371.478048) (xy 56.454065 -371.488224) (xy 56.44629 -371.507032) (xy 56.431932 -371.521456)
			(xy 56.413159 -371.529318) (xy 56.402986 -371.529864) (xy 55.666386 -371.529864) (xy 55.656182 -371.529442)
			(xy 55.637339 -371.521605) (xy 55.622945 -371.507137) (xy 55.615206 -371.488254) (xy 55.614824 -371.478048)
			(xy 54.690837 -371.478048) (xy 54.683618 -371.493855) (xy 54.654132 -371.539736) (xy 54.618417 -371.580953)
			(xy 54.5772 -371.616668) (xy 54.531319 -371.646154) (xy 54.481709 -371.668811) (xy 54.429379 -371.684176)
			(xy 54.375395 -371.691938) (xy 54.320857 -371.691938) (xy 54.266873 -371.684176) (xy 54.214543 -371.668811)
			(xy 54.164933 -371.646154) (xy 54.119052 -371.616668) (xy 54.077835 -371.580953) (xy 54.04212 -371.539736)
			(xy 54.012634 -371.493855) (xy 53.989977 -371.444245) (xy 53.974612 -371.391915) (xy 53.96685 -371.337931)
			(xy 53.966364 -371.310662) (xy 48.196948 -371.310662) (xy 48.223223 -371.361224) (xy 48.246896 -371.424224)
			(xy 48.262871 -371.489602) (xy 48.270918 -371.556421) (xy 48.270921 -371.623722) (xy 48.262881 -371.690542)
			(xy 48.246913 -371.755921) (xy 48.223246 -371.818924) (xy 48.192219 -371.878647) (xy 48.154277 -371.934234)
			(xy 48.132492 -371.959886) (xy 48.126675 -371.967017) (xy 48.120173 -371.984218) (xy 48.119792 -371.993414)
			(xy 48.119792 -372.486682) (xy 48.120213 -372.495868) (xy 48.126719 -372.513052) (xy 48.132492 -372.52021)
			(xy 48.154312 -372.545835) (xy 48.192258 -372.601426) (xy 48.223288 -372.661154) (xy 48.246958 -372.724162)
			(xy 48.262927 -372.789547) (xy 48.270968 -372.856372) (xy 48.270965 -372.923679) (xy 48.262918 -372.990504)
			(xy 48.246942 -373.055887) (xy 48.223267 -373.118893) (xy 48.192232 -373.178618) (xy 48.154281 -373.234205)
			(xy 48.132492 -373.259858) (xy 48.126687 -373.266997) (xy 48.120178 -373.284192) (xy 48.119792 -373.293386)
			(xy 48.119792 -373.451374) (xy 48.119246 -373.461526) (xy 48.111486 -373.480289) (xy 48.097136 -373.494655)
			(xy 48.078382 -373.502435) (xy 48.06823 -373.502936) (xy 47.35195 -373.502936) (xy 47.341778 -373.502495)
			(xy 47.32298 -373.494721) (xy 47.308592 -373.48034) (xy 47.30081 -373.461545) (xy 47.300388 -373.451374)
			(xy 47.300388 -373.293386) (xy 47.299987 -373.284198) (xy 47.293467 -373.267013) (xy 47.287688 -373.259858)
			(xy 47.265932 -373.234179) (xy 47.227979 -373.178598) (xy 47.196942 -373.118878) (xy 47.173265 -373.055877)
			(xy 47.157288 -372.990498) (xy 47.14924 -372.923677) (xy 47.149237 -372.856374) (xy 47.157279 -372.789553)
			(xy 47.17325 -372.724172) (xy 47.196921 -372.661169) (xy 47.227953 -372.601446) (xy 47.265901 -372.545861)
			(xy 47.287688 -372.52021) (xy 47.293504 -372.513078) (xy 47.300007 -372.495878) (xy 47.300388 -372.486682)
			(xy 47.300388 -371.993414) (xy 47.299974 -371.984227) (xy 47.293463 -371.967043) (xy 47.287688 -371.959886)
			(xy 47.265861 -371.934265) (xy 47.227911 -371.878675) (xy 47.196876 -371.818948) (xy 47.173204 -371.755939)
			(xy 47.157232 -371.690553) (xy 47.14919 -371.623726) (xy 46.046568 -371.623726) (xy 46.046802 -371.624349)
			(xy 46.062775 -371.689733) (xy 46.070818 -371.756557) (xy 46.070817 -371.823864) (xy 46.062771 -371.890688)
			(xy 46.046796 -371.956071) (xy 46.023121 -372.019076) (xy 45.992085 -372.0788) (xy 45.954133 -372.134386)
			(xy 45.932344 -372.160038) (xy 45.926542 -372.167179) (xy 45.920032 -372.184373) (xy 45.919644 -372.193566)
			(xy 45.919644 -372.351554) (xy 45.919198 -372.361725) (xy 45.911425 -372.380522) (xy 45.897046 -372.394909)
			(xy 45.878253 -372.402693) (xy 45.868082 -372.403116) (xy 45.151802 -372.403116) (xy 45.141625 -372.402733)
			(xy 45.122821 -372.394941) (xy 45.108435 -372.380542) (xy 45.100658 -372.361732) (xy 45.10024 -372.351554)
			(xy 45.10024 -372.193566) (xy 45.099837 -372.184378) (xy 45.093317 -372.167194) (xy 45.08754 -372.160038)
			(xy 45.065766 -372.134374) (xy 45.027817 -372.07879) (xy 44.996783 -372.019068) (xy 44.973109 -371.956065)
			(xy 44.957135 -371.890684) (xy 44.94909 -371.823862) (xy 44.949089 -371.756559) (xy 44.957132 -371.689737)
			(xy 44.973103 -371.624356) (xy 44.996774 -371.561352) (xy 45.027806 -371.501628) (xy 45.065753 -371.446042)
			(xy 45.08754 -371.42039) (xy 45.093328 -371.413239) (xy 45.099847 -371.396053) (xy 45.10024 -371.386862)
			(xy 45.10024 -370.89334) (xy 45.099801 -370.884156) (xy 45.093306 -370.866972) (xy 45.08754 -370.859812)
			(xy 45.06574 -370.83417) (xy 45.027792 -370.778582) (xy 44.996759 -370.718857) (xy 44.973087 -370.655851)
			(xy 44.957115 -370.590468) (xy 44.949071 -370.523644) (xy 41.671032 -370.523644) (xy 41.671032 -370.523703)
			(xy 41.662957 -370.590641) (xy 41.646921 -370.65613) (xy 41.623156 -370.719227) (xy 41.592004 -370.779022)
			(xy 41.553913 -370.834656) (xy 41.532048 -370.86032) (xy 41.526254 -370.867467) (xy 41.519739 -370.884656)
			(xy 41.519348 -370.893848) (xy 41.519348 -371.386354) (xy 41.519792 -371.395537) (xy 41.526284 -371.412721)
			(xy 41.532048 -371.419882) (xy 41.553928 -371.445535) (xy 41.592019 -371.50117) (xy 41.623172 -371.560967)
			(xy 41.646832 -371.623785) (xy 42.748894 -371.623785) (xy 42.748898 -371.556358) (xy 42.756977 -371.489417)
			(xy 42.773017 -371.423926) (xy 42.796785 -371.360828) (xy 42.827941 -371.30103) (xy 42.866034 -371.245395)
			(xy 42.8879 -371.21973) (xy 42.893709 -371.212593) (xy 42.900216 -371.195396) (xy 42.9006 -371.186202)
			(xy 42.9006 -371.028722) (xy 42.901143 -371.018602) (xy 42.908856 -370.999888) (xy 42.923125 -370.985533)
			(xy 42.941791 -370.977706) (xy 42.951908 -370.97716) (xy 43.668188 -370.97716) (xy 43.678336 -370.977631)
			(xy 43.697081 -370.985415) (xy 43.711403 -370.999796) (xy 43.71911 -371.018572) (xy 43.719496 -371.028722)
			(xy 43.719496 -371.186202) (xy 43.719906 -371.195389) (xy 43.72642 -371.212573) (xy 43.732196 -371.21973)
			(xy 43.754023 -371.245426) (xy 43.792113 -371.301056) (xy 43.823265 -371.360848) (xy 43.847032 -371.423941)
			(xy 43.86307 -371.489426) (xy 43.871149 -371.556361) (xy 43.871153 -371.623782) (xy 43.86308 -371.690718)
			(xy 43.847049 -371.756205) (xy 43.823289 -371.8193) (xy 43.792142 -371.879095) (xy 43.754058 -371.934729)
			(xy 43.732196 -371.960394) (xy 43.726419 -371.967553) (xy 43.719893 -371.984733) (xy 43.719496 -371.993922)
			(xy 43.719496 -372.486174) (xy 43.71992 -372.49536) (xy 43.726424 -372.512544) (xy 43.732196 -372.519702)
			(xy 43.754094 -372.54534) (xy 43.792181 -372.600978) (xy 43.823331 -372.660778) (xy 43.847093 -372.723878)
			(xy 43.863127 -372.789371) (xy 43.8712 -372.856312) (xy 43.871197 -372.923739) (xy 43.863117 -372.990679)
			(xy 43.847078 -373.05617) (xy 43.82331 -373.119269) (xy 43.792155 -373.179066) (xy 43.754062 -373.234701)
			(xy 43.732196 -373.260366) (xy 43.726388 -373.267503) (xy 43.71988 -373.2847) (xy 43.719496 -373.293894)
			(xy 43.719496 -373.451374) (xy 43.718953 -373.461495) (xy 43.711241 -373.480208) (xy 43.696972 -373.494564)
			(xy 43.678306 -373.502391) (xy 43.668188 -373.502936) (xy 42.951908 -373.502936) (xy 42.941759 -373.502473)
			(xy 42.923014 -373.494686) (xy 42.908691 -373.480303) (xy 42.900985 -373.461525) (xy 42.9006 -373.451374)
			(xy 42.9006 -373.293894) (xy 42.900193 -373.284707) (xy 42.893677 -373.267522) (xy 42.8879 -373.260366)
			(xy 42.866069 -373.234673) (xy 42.82798 -373.179043) (xy 42.796828 -373.11925) (xy 42.773061 -373.056157)
			(xy 42.757024 -372.990671) (xy 42.748945 -372.923736) (xy 42.748942 -372.856315) (xy 42.757014 -372.789379)
			(xy 42.773046 -372.723892) (xy 42.796807 -372.660796) (xy 42.827953 -372.601001) (xy 42.866038 -372.545367)
			(xy 42.8879 -372.519702) (xy 42.893678 -372.512544) (xy 42.900204 -372.495363) (xy 42.9006 -372.486174)
			(xy 42.9006 -371.993922) (xy 42.900179 -371.984736) (xy 42.893673 -371.967551) (xy 42.8879 -371.960394)
			(xy 42.865999 -371.93476) (xy 42.827911 -371.879121) (xy 42.796762 -371.81932) (xy 42.773 -371.756219)
			(xy 42.756967 -371.690726) (xy 42.748894 -371.623785) (xy 41.646832 -371.623785) (xy 41.646938 -371.624066)
			(xy 41.662974 -371.689557) (xy 41.67105 -371.756498) (xy 41.671048 -371.823923) (xy 41.66297 -371.890864)
			(xy 41.646932 -371.956354) (xy 41.623164 -372.019452) (xy 41.592008 -372.079248) (xy 41.553915 -372.134882)
			(xy 41.532048 -372.160546) (xy 41.526243 -372.167685) (xy 41.519735 -372.18488) (xy 41.519348 -372.194074)
			(xy 41.519348 -372.351554) (xy 41.518835 -372.361679) (xy 41.51112 -372.380402) (xy 41.496842 -372.39476)
			(xy 41.478162 -372.402579) (xy 41.46804 -372.403116) (xy 40.75176 -372.403116) (xy 40.741605 -372.402711)
			(xy 40.722855 -372.394906) (xy 40.708534 -372.380504) (xy 40.700833 -372.361711) (xy 40.700452 -372.351554)
			(xy 40.700452 -372.194074) (xy 40.700043 -372.184887) (xy 40.693527 -372.167703) (xy 40.687752 -372.160546)
			(xy 40.6659 -372.13487) (xy 40.627807 -372.079238) (xy 40.596653 -372.019444) (xy 40.572886 -371.956349)
			(xy 40.556848 -371.89086) (xy 40.54877 -371.823922) (xy 40.548769 -371.756499) (xy 40.556844 -371.68956)
			(xy 40.57288 -371.624072) (xy 40.596645 -371.560975) (xy 40.627797 -371.50118) (xy 40.665887 -371.445546)
			(xy 40.687752 -371.419882) (xy 40.693545 -371.412735) (xy 40.70006 -371.395546) (xy 40.700452 -371.386354)
			(xy 40.700452 -370.893848) (xy 40.700007 -370.884665) (xy 40.693516 -370.867481) (xy 40.687752 -370.86032)
			(xy 40.665874 -370.834665) (xy 40.627783 -370.779031) (xy 40.59663 -370.719233) (xy 40.572864 -370.656135)
			(xy 40.556828 -370.590644) (xy 40.548752 -370.523704) (xy 37.271241 -370.523704) (xy 37.263166 -370.590641)
			(xy 37.247131 -370.65613) (xy 37.223366 -370.719226) (xy 37.192215 -370.779022) (xy 37.154125 -370.834655)
			(xy 37.13226 -370.86032) (xy 37.126467 -370.867468) (xy 37.119951 -370.884656) (xy 37.11956 -370.893848)
			(xy 37.11956 -371.386354) (xy 37.120001 -371.395538) (xy 37.126494 -371.412722) (xy 37.13226 -371.419882)
			(xy 37.154139 -371.445535) (xy 37.19223 -371.501171) (xy 37.223382 -371.560968) (xy 37.247019 -371.623725)
			(xy 38.349126 -371.623725) (xy 38.349129 -371.556418) (xy 38.357177 -371.489593) (xy 38.373153 -371.424209)
			(xy 38.396828 -371.361203) (xy 38.427864 -371.301478) (xy 38.465815 -371.245891) (xy 38.487604 -371.220238)
			(xy 38.49341 -371.213099) (xy 38.499919 -371.195904) (xy 38.500304 -371.18671) (xy 38.500304 -371.028722)
			(xy 38.50085 -371.01857) (xy 38.508611 -370.999808) (xy 38.522961 -370.985443) (xy 38.541714 -370.977661)
			(xy 38.551866 -370.97716) (xy 39.268146 -370.97716) (xy 39.278309 -370.977596) (xy 39.297084 -370.98539)
			(xy 39.311448 -370.999773) (xy 39.319217 -371.018558) (xy 39.319708 -371.028722) (xy 39.319708 -371.18671)
			(xy 39.320112 -371.195898) (xy 39.32663 -371.213082) (xy 39.332408 -371.220238) (xy 39.35416 -371.24592)
			(xy 39.392113 -371.301501) (xy 39.423151 -371.36122) (xy 39.446829 -371.424221) (xy 39.462806 -371.4896)
			(xy 39.470854 -371.55642) (xy 39.470857 -371.623723) (xy 39.462816 -371.690544) (xy 39.446845 -371.755925)
			(xy 39.423175 -371.818928) (xy 39.392143 -371.87865) (xy 39.354195 -371.934235) (xy 39.332408 -371.959886)
			(xy 39.326593 -371.967018) (xy 39.320089 -371.984219) (xy 39.319708 -371.993414) (xy 39.319708 -372.486682)
			(xy 39.320125 -372.495868) (xy 39.326634 -372.513053) (xy 39.332408 -372.52021) (xy 39.354231 -372.545834)
			(xy 39.392182 -372.601423) (xy 39.423217 -372.66115) (xy 39.44689 -372.724158) (xy 39.462862 -372.789545)
			(xy 39.470904 -372.856371) (xy 39.470901 -372.92368) (xy 39.462853 -372.990506) (xy 39.446875 -373.05589)
			(xy 39.423196 -373.118897) (xy 39.392156 -373.178621) (xy 39.354199 -373.234207) (xy 39.332408 -373.259858)
			(xy 39.326605 -373.266999) (xy 39.320094 -373.284193) (xy 39.319708 -373.293386) (xy 39.319708 -373.451374)
			(xy 39.319147 -373.461525) (xy 39.311389 -373.480284) (xy 39.297045 -373.494649) (xy 39.278296 -373.502432)
			(xy 39.268146 -373.502936) (xy 38.551866 -373.502936) (xy 38.541703 -373.502494) (xy 38.522928 -373.494703)
			(xy 38.508563 -373.480322) (xy 38.500794 -373.461538) (xy 38.500304 -373.451374) (xy 38.500304 -373.293386)
			(xy 38.4999 -373.284198) (xy 38.493382 -373.267014) (xy 38.487604 -373.259858) (xy 38.465851 -373.234178)
			(xy 38.427903 -373.178595) (xy 38.39687 -373.118875) (xy 38.373197 -373.055874) (xy 38.357223 -372.990495)
			(xy 38.349177 -372.923676) (xy 38.349174 -372.856375) (xy 38.357214 -372.789555) (xy 38.373182 -372.724175)
			(xy 38.396849 -372.661172) (xy 38.427877 -372.601449) (xy 38.465819 -372.545863) (xy 38.487604 -372.52021)
			(xy 38.493422 -372.51308) (xy 38.499924 -372.495878) (xy 38.500304 -372.486682) (xy 38.500304 -371.993414)
			(xy 38.499886 -371.984228) (xy 38.493378 -371.967043) (xy 38.487604 -371.959886) (xy 38.46578 -371.934264)
			(xy 38.427835 -371.878672) (xy 38.396805 -371.818944) (xy 38.373136 -371.755936) (xy 38.357167 -371.69055)
			(xy 38.349126 -371.623725) (xy 37.247019 -371.623725) (xy 37.247148 -371.624067) (xy 37.263183 -371.689557)
			(xy 37.271259 -371.756498) (xy 37.271257 -371.823923) (xy 37.263179 -371.890863) (xy 37.247141 -371.956354)
			(xy 37.223374 -372.019451) (xy 37.192219 -372.079248) (xy 37.154126 -372.134881) (xy 37.13226 -372.160546)
			(xy 37.126456 -372.167686) (xy 37.119947 -372.184881) (xy 37.11956 -372.194074) (xy 37.11956 -372.351554)
			(xy 37.119036 -372.361678) (xy 37.111323 -372.380398) (xy 37.097048 -372.394756) (xy 37.078373 -372.402576)
			(xy 37.068252 -372.403116) (xy 36.351972 -372.403116) (xy 36.341818 -372.402702) (xy 36.323068 -372.3949)
			(xy 36.308746 -372.380501) (xy 36.301045 -372.36171) (xy 36.300664 -372.351554) (xy 36.300664 -372.194074)
			(xy 36.300252 -372.184887) (xy 36.293738 -372.167704) (xy 36.287964 -372.160546) (xy 36.266115 -372.134869)
			(xy 36.228028 -372.079235) (xy 36.196879 -372.01944) (xy 36.173116 -371.956345) (xy 36.15708 -371.890858)
			(xy 36.149004 -371.823921) (xy 36.149003 -371.7565) (xy 36.157076 -371.689563) (xy 36.173109 -371.624075)
			(xy 36.19687 -371.560979) (xy 36.228017 -371.501183) (xy 36.266102 -371.445548) (xy 36.287964 -371.419882)
			(xy 36.293759 -371.412736) (xy 36.300273 -371.395546) (xy 36.300664 -371.386354) (xy 36.300664 -370.893848)
			(xy 36.300217 -370.884665) (xy 36.293727 -370.867481) (xy 36.287964 -370.86032) (xy 36.26609 -370.834664)
			(xy 36.228004 -370.779027) (xy 36.196855 -370.719229) (xy 36.173093 -370.656131) (xy 36.15706 -370.590642)
			(xy 36.148986 -370.523703) (xy 32.870915 -370.523703) (xy 32.862879 -370.590465) (xy 32.846908 -370.655846)
			(xy 32.823237 -370.71885) (xy 32.792205 -370.778573) (xy 32.754259 -370.83416) (xy 32.732472 -370.859812)
			(xy 32.726684 -370.866963) (xy 32.720165 -370.884149) (xy 32.719772 -370.89334) (xy 32.719772 -371.386862)
			(xy 32.720207 -371.396046) (xy 32.726704 -371.413231) (xy 32.732472 -371.42039) (xy 32.754273 -371.446031)
			(xy 32.792221 -371.501619) (xy 32.823253 -371.561344) (xy 32.846713 -371.623785) (xy 33.948806 -371.623785)
			(xy 33.94881 -371.556358) (xy 33.95689 -371.489417) (xy 33.97293 -371.423925) (xy 33.996699 -371.360827)
			(xy 34.027855 -371.30103) (xy 34.065949 -371.245395) (xy 34.087816 -371.21973) (xy 34.093627 -371.212595)
			(xy 34.100132 -371.195397) (xy 34.100516 -371.186202) (xy 34.100516 -371.028722) (xy 34.101044 -371.0186)
			(xy 34.10876 -370.999883) (xy 34.123033 -370.985527) (xy 34.141705 -370.977703) (xy 34.151824 -370.97716)
			(xy 34.868104 -370.97716) (xy 34.878253 -370.977618) (xy 34.896998 -370.985407) (xy 34.91132 -370.999792)
			(xy 34.919027 -371.018571) (xy 34.919412 -371.028722) (xy 34.919412 -371.186202) (xy 34.919819 -371.19539)
			(xy 34.926334 -371.212574) (xy 34.932112 -371.21973) (xy 34.953938 -371.245426) (xy 34.992027 -371.301057)
			(xy 35.023179 -371.360849) (xy 35.046945 -371.423941) (xy 35.062982 -371.489427) (xy 35.071061 -371.556361)
			(xy 35.071065 -371.623782) (xy 35.062993 -371.690717) (xy 35.046962 -371.756204) (xy 35.023202 -371.819299)
			(xy 34.992057 -371.879094) (xy 34.953973 -371.934729) (xy 34.932112 -371.960394) (xy 34.926337 -371.967555)
			(xy 34.919809 -371.984733) (xy 34.919412 -371.993922) (xy 34.919412 -372.486174) (xy 34.919832 -372.49536)
			(xy 34.926338 -372.512545) (xy 34.932112 -372.519702) (xy 34.954009 -372.54534) (xy 34.992096 -372.600979)
			(xy 35.023244 -372.660779) (xy 35.047006 -372.723879) (xy 35.063039 -372.789371) (xy 35.071112 -372.856312)
			(xy 35.071109 -372.923739) (xy 35.06303 -372.990679) (xy 35.046991 -373.05617) (xy 35.023224 -373.119268)
			(xy 34.99207 -373.179065) (xy 34.953978 -373.234701) (xy 34.932112 -373.260366) (xy 34.926306 -373.267505)
			(xy 34.919797 -373.2847) (xy 34.919412 -373.293894) (xy 34.919412 -373.451374) (xy 34.918854 -373.461493)
			(xy 34.911144 -373.480203) (xy 34.89688 -373.494559) (xy 34.878219 -373.502388) (xy 34.868104 -373.502936)
			(xy 34.151824 -373.502936) (xy 34.141676 -373.50246) (xy 34.122931 -373.494679) (xy 34.108608 -373.480299)
			(xy 34.100901 -373.461524) (xy 34.100516 -373.451374) (xy 34.100516 -373.293894) (xy 34.100105 -373.284707)
			(xy 34.093592 -373.267523) (xy 34.087816 -373.260366) (xy 34.065985 -373.234673) (xy 34.027894 -373.179043)
			(xy 33.996741 -373.119251) (xy 33.972974 -373.056158) (xy 33.956936 -372.990672) (xy 33.948857 -372.923736)
			(xy 33.948854 -372.856315) (xy 33.956927 -372.789379) (xy 33.972959 -372.723891) (xy 33.99672 -372.660796)
			(xy 34.027868 -372.601001) (xy 34.065953 -372.545367) (xy 34.087816 -372.519702) (xy 34.093596 -372.512545)
			(xy 34.10012 -372.495364) (xy 34.100516 -372.486174) (xy 34.100516 -371.993922) (xy 34.100092 -371.984736)
			(xy 34.093587 -371.967552) (xy 34.087816 -371.960394) (xy 34.065914 -371.93476) (xy 34.027826 -371.879121)
			(xy 33.996676 -371.819321) (xy 33.972913 -371.75622) (xy 33.956879 -371.690727) (xy 33.948806 -371.623785)
			(xy 32.846713 -371.623785) (xy 32.846925 -371.62435) (xy 32.862896 -371.689734) (xy 32.870939 -371.756558)
			(xy 32.870938 -371.823864) (xy 32.862892 -371.890687) (xy 32.846918 -371.95607) (xy 32.823244 -372.019075)
			(xy 32.79221 -372.078799) (xy 32.75426 -372.134386) (xy 32.732472 -372.160038) (xy 32.726673 -372.167181)
			(xy 32.72016 -372.184373) (xy 32.719772 -372.193566) (xy 32.719772 -372.351554) (xy 32.719299 -372.361721)
			(xy 32.711531 -372.380513) (xy 32.69716 -372.394899) (xy 32.678377 -372.402688) (xy 32.66821 -372.403116)
			(xy 31.95193 -372.403116) (xy 31.941755 -372.40271) (xy 31.922952 -372.394927) (xy 31.908564 -372.380535)
			(xy 31.900787 -372.361729) (xy 31.900368 -372.351554) (xy 31.900368 -372.193566) (xy 31.899959 -372.184379)
			(xy 31.893443 -372.167195) (xy 31.887668 -372.160038) (xy 31.865893 -372.134375) (xy 31.827942 -372.078791)
			(xy 31.796907 -372.019069) (xy 31.773232 -371.956066) (xy 31.757257 -371.890685) (xy 31.749211 -371.823863)
			(xy 31.74921 -371.756558) (xy 31.757253 -371.689736) (xy 31.773226 -371.624354) (xy 31.796898 -371.56135)
			(xy 31.827931 -371.501627) (xy 31.86588 -371.446042) (xy 31.887668 -371.42039) (xy 31.89346 -371.413242)
			(xy 31.899975 -371.396053) (xy 31.900368 -371.386862) (xy 31.900368 -370.89334) (xy 31.899923 -370.884157)
			(xy 31.893432 -370.866973) (xy 31.887668 -370.859812) (xy 31.865868 -370.83417) (xy 31.827917 -370.778583)
			(xy 31.796883 -370.718858) (xy 31.77321 -370.655852) (xy 31.757237 -370.590468) (xy 31.749193 -370.523644)
			(xy 28.471153 -370.523644) (xy 28.471153 -370.523703) (xy 28.463078 -370.59064) (xy 28.447043 -370.656129)
			(xy 28.42328 -370.719226) (xy 28.392129 -370.779021) (xy 28.35404 -370.834655) (xy 28.332176 -370.86032)
			(xy 28.326386 -370.867469) (xy 28.319868 -370.884657) (xy 28.319476 -370.893848) (xy 28.319476 -371.386354)
			(xy 28.319914 -371.395538) (xy 28.326409 -371.412722) (xy 28.332176 -371.419882) (xy 28.354055 -371.445535)
			(xy 28.392144 -371.501171) (xy 28.423296 -371.560969) (xy 28.446931 -371.623725) (xy 29.549038 -371.623725)
			(xy 29.549042 -371.556418) (xy 29.557089 -371.489593) (xy 29.573066 -371.424209) (xy 29.596742 -371.361203)
			(xy 29.627778 -371.301478) (xy 29.665731 -371.24589) (xy 29.68752 -371.220238) (xy 29.693328 -371.213101)
			(xy 29.699835 -371.195904) (xy 29.70022 -371.18671) (xy 29.70022 -371.028722) (xy 29.700682 -371.018554)
			(xy 29.708456 -370.999763) (xy 29.72283 -370.985378) (xy 29.741614 -370.97759) (xy 29.751782 -370.97716)
			(xy 30.468062 -370.97716) (xy 30.478234 -370.977596) (xy 30.497032 -370.985372) (xy 30.511419 -370.999755)
			(xy 30.519201 -371.01855) (xy 30.519624 -371.028722) (xy 30.519624 -371.18671) (xy 30.520024 -371.195898)
			(xy 30.526544 -371.213083) (xy 30.532324 -371.220238) (xy 30.554075 -371.24592) (xy 30.592028 -371.301502)
			(xy 30.623065 -371.361221) (xy 30.646741 -371.424221) (xy 30.662718 -371.4896) (xy 30.670766 -371.55642)
			(xy 30.670769 -371.623723) (xy 30.662728 -371.690543) (xy 30.646758 -371.755924) (xy 30.623088 -371.818927)
			(xy 30.592057 -371.878649) (xy 30.554111 -371.934234) (xy 30.532324 -371.959886) (xy 30.526511 -371.96702)
			(xy 30.520005 -371.984219) (xy 30.519624 -371.993414) (xy 30.519624 -372.486682) (xy 30.520037 -372.495869)
			(xy 30.526548 -372.513054) (xy 30.532324 -372.52021) (xy 30.554146 -372.545834) (xy 30.592096 -372.601424)
			(xy 30.62313 -372.661151) (xy 30.646803 -372.724159) (xy 30.662774 -372.789545) (xy 30.670816 -372.856371)
			(xy 30.670813 -372.92368) (xy 30.662765 -372.990505) (xy 30.646788 -373.05589) (xy 30.623109 -373.118896)
			(xy 30.59207 -373.17862) (xy 30.554115 -373.234206) (xy 30.532324 -373.259858) (xy 30.526523 -373.267)
			(xy 30.52001 -373.284193) (xy 30.519624 -373.293386) (xy 30.519624 -373.451374) (xy 30.519214 -373.461549)
			(xy 30.51143 -373.48035) (xy 30.49704 -373.494737) (xy 30.478237 -373.502516) (xy 30.468062 -373.502936)
			(xy 29.751782 -373.502936) (xy 29.741606 -373.50255) (xy 29.722806 -373.494754) (xy 29.708421 -373.480357)
			(xy 29.700641 -373.46155) (xy 29.70022 -373.451374) (xy 29.70022 -373.293386) (xy 29.699812 -373.284199)
			(xy 29.693297 -373.267015) (xy 29.68752 -373.259858) (xy 29.665767 -373.234178) (xy 29.627818 -373.178595)
			(xy 29.596784 -373.118875) (xy 29.57311 -373.055874) (xy 29.557136 -372.990496) (xy 29.549089 -372.923677)
			(xy 29.549086 -372.856375) (xy 29.557127 -372.789555) (xy 29.573095 -372.724175) (xy 29.596763 -372.661172)
			(xy 29.627792 -372.601449) (xy 29.665735 -372.545863) (xy 29.68752 -372.52021) (xy 29.69334 -372.513081)
			(xy 29.69984 -372.495878) (xy 29.70022 -372.486682) (xy 29.70022 -371.993414) (xy 29.699798 -371.984228)
			(xy 29.693292 -371.967044) (xy 29.68752 -371.959886) (xy 29.665695 -371.934264) (xy 29.627749 -371.878673)
			(xy 29.596718 -371.818945) (xy 29.573049 -371.755937) (xy 29.557079 -371.690551) (xy 29.549038 -371.623725)
			(xy 28.446931 -371.623725) (xy 28.44706 -371.624067) (xy 28.463096 -371.689558) (xy 28.471171 -371.756498)
			(xy 28.471169 -371.823923) (xy 28.463092 -371.890863) (xy 28.447054 -371.956353) (xy 28.423287 -372.01945)
			(xy 28.392134 -372.079247) (xy 28.354042 -372.134881) (xy 28.332176 -372.160546) (xy 28.326375 -372.167688)
			(xy 28.319864 -372.184881) (xy 28.319476 -372.194074) (xy 28.319476 -372.351554) (xy 28.318936 -372.361676)
			(xy 28.311226 -372.380393) (xy 28.296956 -372.39475) (xy 28.278287 -372.402574) (xy 28.268168 -372.403116)
			(xy 27.551888 -372.403116) (xy 27.541781 -372.402625) (xy 27.523105 -372.394886) (xy 27.508811 -372.380591)
			(xy 27.501074 -372.361916) (xy 27.50058 -372.351808) (xy 27.50058 -372.194074) (xy 27.500187 -372.184885)
			(xy 27.493662 -372.167701) (xy 27.48788 -372.160546) (xy 27.46603 -372.134869) (xy 27.427943 -372.079236)
			(xy 27.396792 -372.019441) (xy 27.373028 -371.956346) (xy 27.356993 -371.890858) (xy 27.348916 -371.823922)
			(xy 27.348915 -371.756499) (xy 27.356989 -371.689562) (xy 27.373022 -371.624074) (xy 27.396784 -371.560978)
			(xy 27.427932 -371.501182) (xy 27.466018 -371.445548) (xy 27.48788 -371.419882) (xy 27.493664 -371.412728)
			(xy 27.500187 -371.395544) (xy 27.50058 -371.386354) (xy 27.50058 -370.893848) (xy 27.500151 -370.884663)
			(xy 27.493651 -370.867478) (xy 27.48788 -370.86032) (xy 27.466005 -370.834664) (xy 27.427918 -370.779028)
			(xy 27.396769 -370.71923) (xy 27.373006 -370.656132) (xy 27.356972 -370.590642) (xy 27.348898 -370.523703)
			(xy 0.509016 -370.523703) (xy 0.509016 -372.100847) (xy 8.642336 -372.100847) (xy 8.642336 -372.040913)
			(xy 8.650159 -371.981491) (xy 8.665671 -371.923598) (xy 8.688607 -371.868226) (xy 8.718575 -371.81632)
			(xy 8.755061 -371.768771) (xy 8.797441 -371.726391) (xy 8.84499 -371.689905) (xy 8.896896 -371.659937)
			(xy 8.952268 -371.637001) (xy 9.010161 -371.621489) (xy 9.069583 -371.613666) (xy 9.09955 -371.613176)
			(xy 9.96315 -371.613176) (xy 9.993118 -371.613658) (xy 10.052541 -371.621481) (xy 10.110435 -371.636994)
			(xy 10.165808 -371.65993) (xy 10.217714 -371.689898) (xy 10.265264 -371.726385) (xy 10.307645 -371.768766)
			(xy 10.344132 -371.816316) (xy 10.3741 -371.868222) (xy 10.397036 -371.923595) (xy 10.412549 -371.981489)
			(xy 10.420372 -372.040912) (xy 10.420372 -372.100848) (xy 10.412549 -372.160271) (xy 10.397036 -372.218165)
			(xy 10.3741 -372.273538) (xy 10.344132 -372.325444) (xy 10.307645 -372.372994) (xy 10.265264 -372.415375)
			(xy 10.217714 -372.451862) (xy 10.165808 -372.48183) (xy 10.110435 -372.504766) (xy 10.052541 -372.520279)
			(xy 9.993118 -372.528102) (xy 9.96315 -372.528592) (xy 9.09955 -372.528592) (xy 9.069583 -372.528094)
			(xy 9.010161 -372.520271) (xy 8.952268 -372.504759) (xy 8.896896 -372.481823) (xy 8.84499 -372.451855)
			(xy 8.797441 -372.415369) (xy 8.755061 -372.372989) (xy 8.718575 -372.32544) (xy 8.688607 -372.273534)
			(xy 8.665671 -372.218162) (xy 8.650159 -372.160269) (xy 8.642336 -372.100847) (xy 0.509016 -372.100847)
			(xy 0.509016 -374.423871) (xy 27.348897 -374.423871) (xy 27.348897 -374.356446) (xy 27.356974 -374.289508)
			(xy 27.37301 -374.224019) (xy 27.396774 -374.160922) (xy 27.427926 -374.101125) (xy 27.466016 -374.045491)
			(xy 27.48788 -374.019826) (xy 27.493688 -374.012689) (xy 27.500197 -373.995492) (xy 27.50058 -373.986298)
			(xy 27.50058 -373.828818) (xy 27.501042 -373.818688) (xy 27.508772 -373.799959) (xy 27.523066 -373.785601)
			(xy 27.54176 -373.777788) (xy 27.551888 -373.777256) (xy 28.268168 -373.777256) (xy 28.278269 -373.77781)
			(xy 28.296938 -373.785529) (xy 28.311233 -373.799804) (xy 28.318977 -373.818463) (xy 28.319476 -373.828564)
			(xy 28.319476 -373.986298) (xy 28.319892 -373.995484) (xy 28.326402 -374.012669) (xy 28.332176 -374.019826)
			(xy 28.354038 -374.045493) (xy 28.392127 -374.101127) (xy 28.423278 -374.160923) (xy 28.447043 -374.22402)
			(xy 28.463078 -374.289509) (xy 28.471154 -374.356447) (xy 28.471155 -374.423823) (xy 31.749171 -374.423823)
			(xy 31.749175 -374.356514) (xy 31.757224 -374.289688) (xy 31.773202 -374.224303) (xy 31.796881 -374.161297)
			(xy 31.827921 -374.101572) (xy 31.865877 -374.045986) (xy 31.887668 -374.020334) (xy 31.893483 -374.013202)
			(xy 31.899985 -373.996001) (xy 31.900368 -373.986806) (xy 31.900368 -373.828818) (xy 31.900779 -373.818644)
			(xy 31.908564 -373.799844) (xy 31.922954 -373.785457) (xy 31.941756 -373.777677) (xy 31.95193 -373.777256)
			(xy 32.66821 -373.777256) (xy 32.678384 -373.777656) (xy 32.697183 -373.785448) (xy 32.711568 -373.799841)
			(xy 32.719349 -373.818643) (xy 32.719772 -373.828818) (xy 32.719772 -373.986806) (xy 32.720185 -373.995993)
			(xy 32.726697 -374.013177) (xy 32.732472 -374.020334) (xy 32.754218 -374.04602) (xy 32.792167 -374.101602)
			(xy 32.823202 -374.161321) (xy 32.846876 -374.224321) (xy 32.862852 -374.289699) (xy 32.870899 -374.356518)
			(xy 32.870903 -374.423819) (xy 32.870895 -374.423882) (xy 36.148964 -374.423882) (xy 36.148968 -374.356455)
			(xy 36.157048 -374.289515) (xy 36.173087 -374.224024) (xy 36.196854 -374.160925) (xy 36.228007 -374.101128)
			(xy 36.266099 -374.045492) (xy 36.287964 -374.019826) (xy 36.293782 -374.012697) (xy 36.300282 -373.995494)
			(xy 36.300664 -373.986298) (xy 36.300664 -373.828818) (xy 36.301142 -373.818689) (xy 36.308868 -373.799964)
			(xy 36.323158 -373.785606) (xy 36.341846 -373.777791) (xy 36.351972 -373.777256) (xy 37.068252 -373.777256)
			(xy 37.078398 -373.77776) (xy 37.09714 -373.785532) (xy 37.111464 -373.799903) (xy 37.119173 -373.818671)
			(xy 37.11956 -373.828818) (xy 37.11956 -373.986298) (xy 37.11998 -373.995484) (xy 37.126488 -374.012668)
			(xy 37.13226 -374.019826) (xy 37.154084 -374.045525) (xy 37.192177 -374.101153) (xy 37.223331 -374.160945)
			(xy 37.2471 -374.224037) (xy 37.263139 -374.289523) (xy 37.271219 -374.356458) (xy 37.271223 -374.423879)
			(xy 37.271223 -374.423882) (xy 40.548731 -374.423882) (xy 40.548735 -374.356454) (xy 40.556815 -374.289512)
			(xy 40.572857 -374.22402) (xy 40.596628 -374.160921) (xy 40.627787 -374.101124) (xy 40.665884 -374.04549)
			(xy 40.687752 -374.019826) (xy 40.693569 -374.012695) (xy 40.70007 -373.995494) (xy 40.700452 -373.986298)
			(xy 40.700452 -373.828818) (xy 40.700942 -373.818691) (xy 40.708666 -373.799968) (xy 40.722951 -373.785611)
			(xy 40.741636 -373.777793) (xy 40.75176 -373.777256) (xy 41.46804 -373.777256) (xy 41.478191 -373.777688)
			(xy 41.496936 -373.785489) (xy 41.511256 -373.799881) (xy 41.518963 -373.818665) (xy 41.519348 -373.828818)
			(xy 41.519348 -373.986298) (xy 41.519771 -373.995484) (xy 41.526277 -374.012667) (xy 41.532048 -374.019826)
			(xy 41.553873 -374.045524) (xy 41.591966 -374.101153) (xy 41.623121 -374.160944) (xy 41.64689 -374.224037)
			(xy 41.66293 -374.289522) (xy 41.67101 -374.356458) (xy 41.671014 -374.423823) (xy 44.94905 -374.423823)
			(xy 44.949054 -374.356514) (xy 44.957102 -374.289689) (xy 44.97308 -374.224304) (xy 44.996757 -374.161298)
			(xy 45.027796 -374.101573) (xy 45.06575 -374.045986) (xy 45.08754 -374.020334) (xy 45.093352 -374.0132)
			(xy 45.099857 -373.996001) (xy 45.10024 -373.986806) (xy 45.10024 -373.828818) (xy 45.100678 -373.818647)
			(xy 45.108458 -373.799853) (xy 45.122839 -373.785467) (xy 45.141631 -373.777682) (xy 45.151802 -373.777256)
			(xy 45.868082 -373.777256) (xy 45.878255 -373.777679) (xy 45.897053 -373.785461) (xy 45.911439 -373.799847)
			(xy 45.919221 -373.818645) (xy 45.919644 -373.828818) (xy 45.919644 -373.986806) (xy 45.920064 -373.995992)
			(xy 45.926572 -374.013176) (xy 45.932344 -374.020334) (xy 45.954091 -374.04602) (xy 45.992042 -374.101601)
			(xy 46.023078 -374.16132) (xy 46.046754 -374.22432) (xy 46.06273 -374.289698) (xy 46.070778 -374.356517)
			(xy 46.070782 -374.423819) (xy 46.070774 -374.423882) (xy 71.348786 -374.423882) (xy 71.348789 -374.356455)
			(xy 71.356869 -374.289514) (xy 71.372909 -374.224023) (xy 71.396677 -374.160924) (xy 71.427833 -374.101127)
			(xy 71.465926 -374.045491) (xy 71.487792 -374.019826) (xy 71.493602 -374.01269) (xy 71.500109 -373.995492)
			(xy 71.500492 -373.986298) (xy 71.500492 -373.828818) (xy 71.50104 -373.818698) (xy 71.508753 -373.799987)
			(xy 71.52302 -373.785631) (xy 71.541684 -373.777803) (xy 71.5518 -373.777256) (xy 72.26808 -373.777256)
			(xy 72.278227 -373.777737) (xy 72.296971 -373.785518) (xy 72.311293 -373.799896) (xy 72.319002 -373.818669)
			(xy 72.319388 -373.828818) (xy 72.319388 -373.986298) (xy 72.319802 -373.995485) (xy 72.326313 -374.012669)
			(xy 72.332088 -374.019826) (xy 72.353911 -374.045525) (xy 72.392002 -374.101154) (xy 72.423155 -374.160946)
			(xy 72.446922 -374.224038) (xy 72.462961 -374.289523) (xy 72.47104 -374.356458) (xy 72.471044 -374.423823)
			(xy 75.749081 -374.423823) (xy 75.749084 -374.356514) (xy 75.757133 -374.289688) (xy 75.773112 -374.224303)
			(xy 75.796791 -374.161296) (xy 75.827832 -374.101572) (xy 75.865788 -374.045985) (xy 75.88758 -374.020334)
			(xy 75.893385 -374.013194) (xy 75.899895 -373.996) (xy 75.90028 -373.986806) (xy 75.90028 -373.828818)
			(xy 75.900679 -373.818642) (xy 75.908466 -373.79984) (xy 75.92286 -373.785453) (xy 75.941666 -373.777675)
			(xy 75.951842 -373.777256) (xy 76.668122 -373.777256) (xy 76.678283 -373.777716) (xy 76.697057 -373.785501)
			(xy 76.711422 -373.799877) (xy 76.719192 -373.818656) (xy 76.719684 -373.828818) (xy 76.719684 -373.986806)
			(xy 76.720095 -373.995993) (xy 76.726608 -374.013177) (xy 76.732384 -374.020334) (xy 76.754129 -374.046021)
			(xy 76.792078 -374.101603) (xy 76.823112 -374.161322) (xy 76.846786 -374.224322) (xy 76.862761 -374.289699)
			(xy 76.870808 -374.356518) (xy 76.870812 -374.423819) (xy 76.870804 -374.423882) (xy 80.148873 -374.423882)
			(xy 80.148877 -374.356455) (xy 80.156957 -374.289515) (xy 80.172996 -374.224023) (xy 80.196764 -374.160925)
			(xy 80.227918 -374.101127) (xy 80.26601 -374.045492) (xy 80.287876 -374.019826) (xy 80.293684 -374.012689)
			(xy 80.300193 -373.995492) (xy 80.300576 -373.986298) (xy 80.300576 -373.828818) (xy 80.301042 -373.818688)
			(xy 80.308771 -373.79996) (xy 80.323064 -373.785602) (xy 80.341756 -373.777789) (xy 80.351884 -373.777256)
			(xy 81.068164 -373.777256) (xy 81.078265 -373.777814) (xy 81.096934 -373.785531) (xy 81.111228 -373.799806)
			(xy 81.118972 -373.818464) (xy 81.119472 -373.828564) (xy 81.119472 -373.986298) (xy 81.119889 -373.995484)
			(xy 81.126399 -374.012668) (xy 81.132172 -374.019826) (xy 81.153996 -374.045525) (xy 81.192087 -374.101154)
			(xy 81.223242 -374.160945) (xy 81.247009 -374.224038) (xy 81.263049 -374.289523) (xy 81.271128 -374.356458)
			(xy 81.271132 -374.423879) (xy 81.271132 -374.423882) (xy 84.548664 -374.423882) (xy 84.548668 -374.356455)
			(xy 84.556748 -374.289515) (xy 84.572787 -374.224024) (xy 84.596554 -374.160925) (xy 84.627707 -374.101128)
			(xy 84.665799 -374.045492) (xy 84.687664 -374.019826) (xy 84.693482 -374.012697) (xy 84.699982 -373.995494)
			(xy 84.700364 -373.986298) (xy 84.700364 -373.828818) (xy 84.700842 -373.818689) (xy 84.708568 -373.799964)
			(xy 84.722858 -373.785606) (xy 84.741546 -373.777791) (xy 84.751672 -373.777256) (xy 85.467952 -373.777256)
			(xy 85.478066 -373.777754) (xy 85.49676 -373.785478) (xy 85.511074 -373.799769) (xy 85.518829 -373.818451)
			(xy 85.51926 -373.828564) (xy 85.51926 -373.986298) (xy 85.51968 -373.995484) (xy 85.526188 -374.012668)
			(xy 85.53196 -374.019826) (xy 85.553784 -374.045525) (xy 85.591877 -374.101153) (xy 85.623031 -374.160945)
			(xy 85.6468 -374.224037) (xy 85.662839 -374.289523) (xy 85.670919 -374.356458) (xy 85.670923 -374.423822)
			(xy 115.349223 -374.423822) (xy 115.349227 -374.356515) (xy 115.357275 -374.28969) (xy 115.373251 -374.224306)
			(xy 115.396927 -374.1613) (xy 115.427963 -374.101574) (xy 115.465915 -374.045987) (xy 115.487704 -374.020334)
			(xy 115.493512 -374.013197) (xy 115.50002 -373.996) (xy 115.500404 -373.986806) (xy 115.500404 -373.828818)
			(xy 115.500947 -373.818666) (xy 115.508709 -373.799903) (xy 115.52306 -373.785539) (xy 115.541814 -373.777757)
			(xy 115.551966 -373.777256) (xy 116.268246 -373.777256) (xy 116.278409 -373.777696) (xy 116.297183 -373.785489)
			(xy 116.311547 -373.799871) (xy 116.319316 -373.818654) (xy 116.319808 -373.828818) (xy 116.319808 -373.986806)
			(xy 116.320214 -373.995994) (xy 116.32673 -374.013178) (xy 116.332508 -374.020334) (xy 116.354256 -374.046019)
			(xy 116.39221 -374.1016) (xy 116.423248 -374.161318) (xy 116.446925 -374.224319) (xy 116.462903 -374.289697)
			(xy 116.470951 -374.356517) (xy 116.470955 -374.42382) (xy 116.470948 -374.423882) (xy 119.748992 -374.423882)
			(xy 119.748995 -374.356455) (xy 119.757075 -374.289514) (xy 119.773115 -374.224022) (xy 119.796884 -374.160924)
			(xy 119.82804 -374.101126) (xy 119.866134 -374.045491) (xy 119.888 -374.019826) (xy 119.89381 -374.012691)
			(xy 119.900317 -373.995493) (xy 119.9007 -373.986298) (xy 119.9007 -373.828818) (xy 119.90124 -373.818697)
			(xy 119.908955 -373.799984) (xy 119.923224 -373.785629) (xy 119.94189 -373.777802) (xy 119.952008 -373.777256)
			(xy 120.668288 -373.777256) (xy 120.678436 -373.777731) (xy 120.69718 -373.785514) (xy 120.711502 -373.799894)
			(xy 120.71921 -373.818669) (xy 120.719596 -373.828818) (xy 120.719596 -373.986298) (xy 120.720008 -373.995485)
			(xy 120.726521 -374.012669) (xy 120.732296 -374.019826) (xy 120.754119 -374.045525) (xy 120.792209 -374.101155)
			(xy 120.823362 -374.160946) (xy 120.847129 -374.224039) (xy 120.863167 -374.289524) (xy 120.871246 -374.356458)
			(xy 120.87125 -374.423823) (xy 124.149287 -374.423823) (xy 124.149291 -374.356514) (xy 124.15734 -374.289688)
			(xy 124.173319 -374.224302) (xy 124.196998 -374.161296) (xy 124.228039 -374.101572) (xy 124.265996 -374.045986)
			(xy 124.287788 -374.020334) (xy 124.293594 -374.013195) (xy 124.300103 -373.996) (xy 124.300488 -373.986806)
			(xy 124.300488 -373.828818) (xy 124.30088 -373.818641) (xy 124.308668 -373.799837) (xy 124.323064 -373.78545)
			(xy 124.341873 -373.777673) (xy 124.35205 -373.777256) (xy 125.06833 -373.777256) (xy 125.078492 -373.777709)
			(xy 125.097265 -373.785497) (xy 125.11163 -373.799875) (xy 125.1194 -373.818656) (xy 125.119892 -373.828818)
			(xy 125.119892 -373.986806) (xy 125.120301 -373.995993) (xy 125.126816 -374.013177) (xy 125.132592 -374.020334)
			(xy 125.154338 -374.04602) (xy 125.192286 -374.101603) (xy 125.223319 -374.161322) (xy 125.246993 -374.224322)
			(xy 125.262968 -374.2897) (xy 125.271015 -374.356518) (xy 125.271019 -374.423819) (xy 125.271019 -374.423823)
			(xy 128.549078 -374.423823) (xy 128.549081 -374.356514) (xy 128.55713 -374.289688) (xy 128.573109 -374.224303)
			(xy 128.596788 -374.161296) (xy 128.627828 -374.101572) (xy 128.665784 -374.045985) (xy 128.687576 -374.020334)
			(xy 128.69338 -374.013194) (xy 128.699891 -373.996) (xy 128.700276 -373.986806) (xy 128.700276 -373.828818)
			(xy 128.700679 -373.818643) (xy 128.708465 -373.799841) (xy 128.722858 -373.785454) (xy 128.741663 -373.777675)
			(xy 128.751838 -373.777256) (xy 129.468118 -373.777256) (xy 129.478279 -373.777719) (xy 129.497052 -373.785503)
			(xy 129.511418 -373.799878) (xy 129.519188 -373.818656) (xy 129.51968 -373.828818) (xy 129.51968 -373.986806)
			(xy 129.520092 -373.995993) (xy 129.526605 -374.013177) (xy 129.53238 -374.020334) (xy 129.554126 -374.046021)
			(xy 129.592074 -374.101603) (xy 129.623108 -374.161322) (xy 129.646783 -374.224321) (xy 129.662758 -374.289699)
			(xy 129.670805 -374.356518) (xy 129.670809 -374.423819) (xy 129.670809 -374.423822) (xy 159.349132 -374.423822)
			(xy 159.349136 -374.356514) (xy 159.357184 -374.289689) (xy 159.373161 -374.224305) (xy 159.396837 -374.161299)
			(xy 159.427874 -374.101574) (xy 159.465826 -374.045986) (xy 159.487616 -374.020334) (xy 159.493425 -374.013198)
			(xy 159.499932 -373.996) (xy 159.500316 -373.986806) (xy 159.500316 -373.828818) (xy 159.500847 -373.818664)
			(xy 159.508612 -373.799899) (xy 159.522966 -373.785534) (xy 159.541724 -373.777755) (xy 159.551878 -373.777256)
			(xy 160.268158 -373.777256) (xy 160.278329 -373.777699) (xy 160.297126 -373.785473) (xy 160.311513 -373.799854)
			(xy 160.319297 -373.818647) (xy 160.31972 -373.828818) (xy 160.31972 -373.986806) (xy 160.320123 -373.995994)
			(xy 160.326641 -374.013179) (xy 160.33242 -374.020334) (xy 160.354168 -374.04602) (xy 160.39212 -374.1016)
			(xy 160.423158 -374.161319) (xy 160.446835 -374.224319) (xy 160.462812 -374.289698) (xy 160.47086 -374.356517)
			(xy 160.470864 -374.42382) (xy 160.470857 -374.423882) (xy 163.748901 -374.423882) (xy 163.748904 -374.356455)
			(xy 163.756985 -374.289514) (xy 163.773025 -374.224022) (xy 163.796794 -374.160923) (xy 163.827951 -374.101126)
			(xy 163.866045 -374.045491) (xy 163.887912 -374.019826) (xy 163.893724 -374.012692) (xy 163.900229 -373.995493)
			(xy 163.900612 -373.986298) (xy 163.900612 -373.828818) (xy 163.90114 -373.818696) (xy 163.908857 -373.79998)
			(xy 163.92313 -373.785624) (xy 163.941801 -373.7778) (xy 163.95192 -373.777256) (xy 164.6682 -373.777256)
			(xy 164.678349 -373.777721) (xy 164.697092 -373.785508) (xy 164.711414 -373.799891) (xy 164.719122 -373.818668)
			(xy 164.719508 -373.828818) (xy 164.719508 -373.986298) (xy 164.719917 -373.995485) (xy 164.726431 -374.01267)
			(xy 164.732208 -374.019826) (xy 164.75403 -374.045525) (xy 164.79212 -374.101155) (xy 164.823272 -374.160947)
			(xy 164.847038 -374.224039) (xy 164.863076 -374.289524) (xy 164.871155 -374.356458) (xy 164.871159 -374.423822)
			(xy 168.14922 -374.423822) (xy 168.149224 -374.356515) (xy 168.157272 -374.28969) (xy 168.173248 -374.224306)
			(xy 168.196924 -374.1613) (xy 168.22796 -374.101575) (xy 168.265911 -374.045987) (xy 168.2877 -374.020334)
			(xy 168.293507 -374.013196) (xy 168.300015 -373.996) (xy 168.3004 -373.986806) (xy 168.3004 -373.828818)
			(xy 168.300947 -373.818666) (xy 168.308709 -373.799905) (xy 168.323058 -373.78554) (xy 168.341811 -373.777758)
			(xy 168.351962 -373.777256) (xy 169.068242 -373.777256) (xy 169.078405 -373.777699) (xy 169.097178 -373.785491)
			(xy 169.111543 -373.799872) (xy 169.119312 -373.818655) (xy 169.119804 -373.828818) (xy 169.119804 -373.986806)
			(xy 169.120211 -373.995994) (xy 169.126727 -374.013178) (xy 169.132504 -374.020334) (xy 169.154249 -374.046021)
			(xy 169.192196 -374.101603) (xy 169.223229 -374.161322) (xy 169.246902 -374.224322) (xy 169.262877 -374.2897)
			(xy 169.270924 -374.356518) (xy 169.270928 -374.423819) (xy 169.270928 -374.423823) (xy 172.548987 -374.423823)
			(xy 172.548991 -374.356514) (xy 172.55704 -374.289688) (xy 172.573019 -374.224302) (xy 172.596698 -374.161296)
			(xy 172.627739 -374.101572) (xy 172.665696 -374.045986) (xy 172.687488 -374.020334) (xy 172.693294 -374.013195)
			(xy 172.699803 -373.996) (xy 172.700188 -373.986806) (xy 172.700188 -373.828818) (xy 172.70058 -373.818641)
			(xy 172.708368 -373.799837) (xy 172.722764 -373.78545) (xy 172.741573 -373.777673) (xy 172.75175 -373.777256)
			(xy 173.46803 -373.777256) (xy 173.478192 -373.777709) (xy 173.496965 -373.785497) (xy 173.51133 -373.799875)
			(xy 173.5191 -373.818656) (xy 173.519592 -373.828818) (xy 173.519592 -373.986806) (xy 173.520001 -373.995993)
			(xy 173.526516 -374.013177) (xy 173.532292 -374.020334) (xy 173.554038 -374.04602) (xy 173.591986 -374.101603)
			(xy 173.623019 -374.161322) (xy 173.646693 -374.224322) (xy 173.662668 -374.2897) (xy 173.670715 -374.356518)
			(xy 173.670719 -374.423819) (xy 173.662679 -374.490638) (xy 173.646712 -374.556018) (xy 173.623045 -374.61902)
			(xy 173.592018 -374.678743) (xy 173.554076 -374.73433) (xy 173.532292 -374.759982) (xy 173.526477 -374.767114)
			(xy 173.519974 -374.784315) (xy 173.519592 -374.79351) (xy 173.519592 -375.286778) (xy 173.520015 -375.295964)
			(xy 173.52652 -375.313148) (xy 173.532292 -375.320306) (xy 173.554108 -375.345934) (xy 173.592054 -375.401525)
			(xy 173.623084 -375.461252) (xy 173.646754 -375.52426) (xy 173.662724 -375.589644) (xy 173.670765 -375.656469)
			(xy 173.670763 -375.723776) (xy 173.662716 -375.7906) (xy 173.646741 -375.855984) (xy 173.623066 -375.918989)
			(xy 173.592031 -375.978714) (xy 173.554081 -376.034301) (xy 173.532292 -376.059954) (xy 173.526489 -376.067095)
			(xy 173.519978 -376.084289) (xy 173.519592 -376.093482) (xy 173.519592 -376.25147) (xy 173.519043 -376.261622)
			(xy 173.511284 -376.280385) (xy 173.496935 -376.29475) (xy 173.478182 -376.302531) (xy 173.46803 -376.303032)
			(xy 172.75175 -376.303032) (xy 172.741578 -376.302595) (xy 172.722779 -376.29482) (xy 172.708391 -376.280438)
			(xy 172.700609 -376.261642) (xy 172.700188 -376.25147) (xy 172.700188 -376.093482) (xy 172.699789 -376.084294)
			(xy 172.693268 -376.067109) (xy 172.687488 -376.059954) (xy 172.665728 -376.034278) (xy 172.627775 -375.978696)
			(xy 172.596738 -375.918976) (xy 172.573061 -375.855975) (xy 172.557085 -375.790595) (xy 172.549038 -375.723774)
			(xy 172.549035 -375.656471) (xy 172.557077 -375.589649) (xy 172.573048 -375.524268) (xy 172.59672 -375.461265)
			(xy 172.627752 -375.401542) (xy 172.665701 -375.345957) (xy 172.687488 -375.320306) (xy 172.693263 -375.313145)
			(xy 172.699791 -375.295967) (xy 172.700188 -375.286778) (xy 172.700188 -374.79351) (xy 172.699776 -374.784323)
			(xy 172.693264 -374.767138) (xy 172.687488 -374.759982) (xy 172.665658 -374.734364) (xy 172.627707 -374.678774)
			(xy 172.596673 -374.619046) (xy 172.573 -374.556037) (xy 172.557029 -374.49065) (xy 172.548987 -374.423823)
			(xy 169.270928 -374.423823) (xy 169.262888 -374.490638) (xy 169.246921 -374.556017) (xy 169.223255 -374.61902)
			(xy 169.192229 -374.678743) (xy 169.154288 -374.734329) (xy 169.132504 -374.759982) (xy 169.126691 -374.767115)
			(xy 169.120186 -374.784315) (xy 169.119804 -374.79351) (xy 169.119804 -375.286778) (xy 169.120224 -375.295964)
			(xy 169.126731 -375.313149) (xy 169.132504 -375.320306) (xy 169.15432 -375.345935) (xy 169.192265 -375.401525)
			(xy 169.223295 -375.461253) (xy 169.246964 -375.52426) (xy 169.262933 -375.589645) (xy 169.270974 -375.656469)
			(xy 169.270972 -375.723776) (xy 169.262925 -375.7906) (xy 169.24695 -375.855983) (xy 169.223276 -375.918989)
			(xy 169.192242 -375.978713) (xy 169.154292 -376.034301) (xy 169.132504 -376.059954) (xy 169.126702 -376.067096)
			(xy 169.120191 -376.084289) (xy 169.119804 -376.093482) (xy 169.119804 -376.25147) (xy 169.119243 -376.261621)
			(xy 169.111487 -376.280381) (xy 169.097142 -376.294746) (xy 169.078392 -376.302529) (xy 169.068242 -376.303032)
			(xy 168.351962 -376.303032) (xy 168.341798 -376.302597) (xy 168.323022 -376.294804) (xy 168.308657 -376.280421)
			(xy 168.30089 -376.261635) (xy 168.3004 -376.25147) (xy 168.3004 -376.093482) (xy 168.299998 -376.084294)
			(xy 168.293479 -376.06711) (xy 168.2877 -376.059954) (xy 168.265943 -376.034277) (xy 168.227996 -375.978693)
			(xy 168.196963 -375.918973) (xy 168.173291 -375.855972) (xy 168.157317 -375.790593) (xy 168.149271 -375.723774)
			(xy 168.149268 -375.656472) (xy 168.157309 -375.589652) (xy 168.173277 -375.524272) (xy 168.196945 -375.461269)
			(xy 168.227973 -375.401546) (xy 168.265915 -375.345959) (xy 168.2877 -375.320306) (xy 168.293477 -375.313147)
			(xy 168.300003 -375.295967) (xy 168.3004 -375.286778) (xy 168.3004 -374.79351) (xy 168.299985 -374.784323)
			(xy 168.293475 -374.767139) (xy 168.2877 -374.759982) (xy 168.265872 -374.734363) (xy 168.227927 -374.678771)
			(xy 168.196898 -374.619043) (xy 168.173229 -374.556034) (xy 168.15726 -374.490648) (xy 168.14922 -374.423822)
			(xy 164.871159 -374.423822) (xy 164.871159 -374.423879) (xy 164.863088 -374.490814) (xy 164.847057 -374.5563)
			(xy 164.823298 -374.619396) (xy 164.792152 -374.679191) (xy 164.754069 -374.734825) (xy 164.732208 -374.76049)
			(xy 164.726392 -374.767621) (xy 164.719889 -374.784822) (xy 164.719508 -374.794018) (xy 164.719508 -375.28627)
			(xy 164.719931 -375.295456) (xy 164.726435 -375.31264) (xy 164.732208 -375.319798) (xy 164.754101 -375.345439)
			(xy 164.792188 -375.401077) (xy 164.823337 -375.460877) (xy 164.8471 -375.523977) (xy 164.863133 -375.589469)
			(xy 164.871206 -375.65641) (xy 164.871203 -375.723835) (xy 164.863125 -375.790776) (xy 164.847086 -375.856266)
			(xy 164.823319 -375.919364) (xy 164.792165 -375.979161) (xy 164.754073 -376.034797) (xy 164.732208 -376.060462)
			(xy 164.726404 -376.067602) (xy 164.719893 -376.084796) (xy 164.719508 -376.09399) (xy 164.719508 -376.25147)
			(xy 164.71895 -376.261589) (xy 164.711241 -376.2803) (xy 164.696977 -376.294656) (xy 164.678316 -376.302485)
			(xy 164.6682 -376.303032) (xy 163.95192 -376.303032) (xy 163.941771 -376.302563) (xy 163.923025 -376.29478)
			(xy 163.908702 -376.280398) (xy 163.900996 -376.26162) (xy 163.900612 -376.25147) (xy 163.900612 -376.09399)
			(xy 163.900204 -376.084803) (xy 163.893689 -376.067618) (xy 163.887912 -376.060462) (xy 163.866077 -376.034773)
			(xy 163.827987 -375.979142) (xy 163.796834 -375.919349) (xy 163.773068 -375.856255) (xy 163.75703 -375.790769)
			(xy 163.748951 -375.723833) (xy 163.748949 -375.656412) (xy 163.757022 -375.589475) (xy 163.773054 -375.523988)
			(xy 163.796816 -375.460892) (xy 163.827963 -375.401097) (xy 163.866049 -375.345463) (xy 163.887912 -375.319798)
			(xy 163.893693 -375.312642) (xy 163.900217 -375.29546) (xy 163.900612 -375.28627) (xy 163.900612 -374.794018)
			(xy 163.90019 -374.784832) (xy 163.893684 -374.767648) (xy 163.887912 -374.76049) (xy 163.866006 -374.734859)
			(xy 163.827918 -374.67922) (xy 163.796769 -374.619419) (xy 163.773006 -374.556318) (xy 163.756973 -374.490824)
			(xy 163.748901 -374.423882) (xy 160.470857 -374.423882) (xy 160.462823 -374.49064) (xy 160.446853 -374.556021)
			(xy 160.423184 -374.619023) (xy 160.392153 -374.678745) (xy 160.354206 -374.73433) (xy 160.33242 -374.759982)
			(xy 160.326608 -374.767117) (xy 160.320102 -374.784315) (xy 160.31972 -374.79351) (xy 160.31972 -375.286778)
			(xy 160.320136 -375.295965) (xy 160.326645 -375.313149) (xy 160.33242 -375.320306) (xy 160.354238 -375.345933)
			(xy 160.392189 -375.401522) (xy 160.423223 -375.461249) (xy 160.446896 -375.524257) (xy 160.462868 -375.589643)
			(xy 160.470911 -375.656468) (xy 160.470908 -375.723777) (xy 160.46286 -375.790602) (xy 160.446883 -375.855986)
			(xy 160.423205 -375.918992) (xy 160.392166 -375.978716) (xy 160.354211 -376.034302) (xy 160.33242 -376.059954)
			(xy 160.32662 -376.067097) (xy 160.320107 -376.084289) (xy 160.31972 -376.093482) (xy 160.31972 -376.25147)
			(xy 160.31931 -376.261645) (xy 160.311528 -376.280447) (xy 160.297137 -376.294834) (xy 160.278333 -376.302613)
			(xy 160.268158 -376.303032) (xy 159.551878 -376.303032) (xy 159.541701 -376.302653) (xy 159.5229 -376.294855)
			(xy 159.508515 -376.280456) (xy 159.500737 -376.261647) (xy 159.500316 -376.25147) (xy 159.500316 -376.093482)
			(xy 159.499911 -376.084294) (xy 159.493393 -376.06711) (xy 159.487616 -376.059954) (xy 159.465858 -376.034277)
			(xy 159.42791 -375.978694) (xy 159.396877 -375.918973) (xy 159.373203 -375.855972) (xy 159.357229 -375.790593)
			(xy 159.349183 -375.723774) (xy 159.34918 -375.656471) (xy 159.357221 -375.589651) (xy 159.37319 -375.524271)
			(xy 159.396858 -375.461268) (xy 159.427887 -375.401545) (xy 159.465831 -375.345958) (xy 159.487616 -375.320306)
			(xy 159.493394 -375.313148) (xy 159.499919 -375.295967) (xy 159.500316 -375.286778) (xy 159.500316 -374.79351)
			(xy 159.499897 -374.784324) (xy 159.493389 -374.76714) (xy 159.487616 -374.759982) (xy 159.465788 -374.734364)
			(xy 159.427842 -374.678772) (xy 159.396811 -374.619043) (xy 159.373142 -374.556034) (xy 159.357173 -374.490648)
			(xy 159.349132 -374.423822) (xy 129.670809 -374.423822) (xy 129.662769 -374.490638) (xy 129.646801 -374.556018)
			(xy 129.623134 -374.619021) (xy 129.592107 -374.678743) (xy 129.554164 -374.734329) (xy 129.53238 -374.759982)
			(xy 129.526564 -374.767113) (xy 129.520062 -374.784315) (xy 129.51968 -374.79351) (xy 129.51968 -375.286778)
			(xy 129.520105 -375.295963) (xy 129.526609 -375.313148) (xy 129.53238 -375.320306) (xy 129.554197 -375.345934)
			(xy 129.592143 -375.401524) (xy 129.623174 -375.461252) (xy 129.646845 -375.524259) (xy 129.662815 -375.589644)
			(xy 129.670856 -375.656469) (xy 129.670854 -375.723776) (xy 129.662807 -375.7906) (xy 129.646831 -375.855984)
			(xy 129.623156 -375.91899) (xy 129.59212 -375.978714) (xy 129.554169 -376.034302) (xy 129.53238 -376.059954)
			(xy 129.526576 -376.067094) (xy 129.520066 -376.084288) (xy 129.51968 -376.093482) (xy 129.51968 -376.25147)
			(xy 129.519212 -376.261637) (xy 129.51144 -376.280428) (xy 129.497068 -376.294813) (xy 129.478285 -376.302602)
			(xy 129.468118 -376.303032) (xy 128.751838 -376.303032) (xy 128.741665 -376.302604) (xy 128.722866 -376.294826)
			(xy 128.708478 -376.280441) (xy 128.700697 -376.261643) (xy 128.700276 -376.25147) (xy 128.700276 -376.093482)
			(xy 128.69988 -376.084293) (xy 128.693357 -376.067109) (xy 128.687576 -376.059954) (xy 128.665817 -376.034278)
			(xy 128.627865 -375.978696) (xy 128.596828 -375.918976) (xy 128.573152 -375.855974) (xy 128.557176 -375.790595)
			(xy 128.549129 -375.723774) (xy 128.549126 -375.656471) (xy 128.557168 -375.58965) (xy 128.573138 -375.524269)
			(xy 128.59681 -375.461265) (xy 128.627841 -375.401543) (xy 128.665789 -375.345958) (xy 128.687576 -375.320306)
			(xy 128.69335 -375.313144) (xy 128.699879 -375.295967) (xy 128.700276 -375.286778) (xy 128.700276 -374.79351)
			(xy 128.699866 -374.784323) (xy 128.693353 -374.767138) (xy 128.687576 -374.759982) (xy 128.665746 -374.734365)
			(xy 128.627796 -374.678774) (xy 128.596762 -374.619046) (xy 128.57309 -374.556037) (xy 128.557119 -374.49065)
			(xy 128.549078 -374.423823) (xy 125.271019 -374.423823) (xy 125.262979 -374.490638) (xy 125.247012 -374.556018)
			(xy 125.223345 -374.61902) (xy 125.192318 -374.678743) (xy 125.154376 -374.73433) (xy 125.132592 -374.759982)
			(xy 125.126777 -374.767114) (xy 125.120274 -374.784315) (xy 125.119892 -374.79351) (xy 125.119892 -375.286778)
			(xy 125.120315 -375.295964) (xy 125.12682 -375.313148) (xy 125.132592 -375.320306) (xy 125.154408 -375.345934)
			(xy 125.192354 -375.401525) (xy 125.223384 -375.461252) (xy 125.247054 -375.52426) (xy 125.263024 -375.589644)
			(xy 125.271065 -375.656469) (xy 125.271063 -375.723776) (xy 125.263016 -375.7906) (xy 125.247041 -375.855984)
			(xy 125.223366 -375.918989) (xy 125.192331 -375.978714) (xy 125.154381 -376.034301) (xy 125.132592 -376.059954)
			(xy 125.126789 -376.067095) (xy 125.120278 -376.084289) (xy 125.119892 -376.093482) (xy 125.119892 -376.25147)
			(xy 125.119343 -376.261622) (xy 125.111584 -376.280385) (xy 125.097235 -376.29475) (xy 125.078482 -376.302531)
			(xy 125.06833 -376.303032) (xy 124.35205 -376.303032) (xy 124.341878 -376.302595) (xy 124.323079 -376.29482)
			(xy 124.308691 -376.280438) (xy 124.300909 -376.261642) (xy 124.300488 -376.25147) (xy 124.300488 -376.093482)
			(xy 124.300089 -376.084294) (xy 124.293568 -376.067109) (xy 124.287788 -376.059954) (xy 124.266028 -376.034278)
			(xy 124.228075 -375.978696) (xy 124.197038 -375.918976) (xy 124.173361 -375.855975) (xy 124.157385 -375.790595)
			(xy 124.149338 -375.723774) (xy 124.149335 -375.656471) (xy 124.157377 -375.589649) (xy 124.173348 -375.524268)
			(xy 124.19702 -375.461265) (xy 124.228052 -375.401542) (xy 124.266001 -375.345957) (xy 124.287788 -375.320306)
			(xy 124.293563 -375.313145) (xy 124.300091 -375.295967) (xy 124.300488 -375.286778) (xy 124.300488 -374.79351)
			(xy 124.300076 -374.784323) (xy 124.293564 -374.767138) (xy 124.287788 -374.759982) (xy 124.265958 -374.734364)
			(xy 124.228007 -374.678774) (xy 124.196973 -374.619046) (xy 124.1733 -374.556037) (xy 124.157329 -374.49065)
			(xy 124.149287 -374.423823) (xy 120.87125 -374.423823) (xy 120.87125 -374.423879) (xy 120.863178 -374.490814)
			(xy 120.847147 -374.556301) (xy 120.823388 -374.619396) (xy 120.792242 -374.679191) (xy 120.754158 -374.734825)
			(xy 120.732296 -374.76049) (xy 120.726478 -374.76762) (xy 120.719976 -374.784822) (xy 120.719596 -374.794018)
			(xy 120.719596 -375.28627) (xy 120.720022 -375.295456) (xy 120.726525 -375.31264) (xy 120.732296 -375.319798)
			(xy 120.75419 -375.345439) (xy 120.792278 -375.401077) (xy 120.823427 -375.460876) (xy 120.84719 -375.523976)
			(xy 120.863223 -375.589468) (xy 120.871297 -375.656409) (xy 120.871294 -375.723836) (xy 120.863215 -375.790776)
			(xy 120.847177 -375.856267) (xy 120.823409 -375.919365) (xy 120.792254 -375.979162) (xy 120.754162 -376.034797)
			(xy 120.732296 -376.060462) (xy 120.72649 -376.067601) (xy 120.719981 -376.084796) (xy 120.719596 -376.09399)
			(xy 120.719596 -376.25147) (xy 120.71905 -376.26159) (xy 120.711339 -376.280304) (xy 120.697071 -376.29466)
			(xy 120.678405 -376.302487) (xy 120.668288 -376.303032) (xy 119.952008 -376.303032) (xy 119.941858 -376.302572)
			(xy 119.923112 -376.294786) (xy 119.90879 -376.280401) (xy 119.901084 -376.261621) (xy 119.9007 -376.25147)
			(xy 119.9007 -376.09399) (xy 119.900294 -376.084802) (xy 119.893777 -376.067618) (xy 119.888 -376.060462)
			(xy 119.866166 -376.034772) (xy 119.828076 -375.979141) (xy 119.796924 -375.919349) (xy 119.773158 -375.856255)
			(xy 119.75712 -375.790769) (xy 119.749042 -375.723833) (xy 119.749039 -375.656412) (xy 119.757112 -375.589476)
			(xy 119.773145 -375.523988) (xy 119.796905 -375.460893) (xy 119.828053 -375.401097) (xy 119.866138 -375.345463)
			(xy 119.888 -375.319798) (xy 119.89378 -375.312641) (xy 119.900305 -375.29546) (xy 119.9007 -375.28627)
			(xy 119.9007 -374.794018) (xy 119.900281 -374.784832) (xy 119.893773 -374.767647) (xy 119.888 -374.76049)
			(xy 119.866095 -374.734859) (xy 119.828007 -374.679219) (xy 119.796858 -374.619418) (xy 119.773097 -374.556317)
			(xy 119.757064 -374.490824) (xy 119.748992 -374.423882) (xy 116.470948 -374.423882) (xy 116.462914 -374.49064)
			(xy 116.446944 -374.556021) (xy 116.423273 -374.619024) (xy 116.392242 -374.678746) (xy 116.354295 -374.734331)
			(xy 116.332508 -374.759982) (xy 116.326695 -374.767116) (xy 116.32019 -374.784315) (xy 116.319808 -374.79351)
			(xy 116.319808 -375.286778) (xy 116.320227 -375.295964) (xy 116.326734 -375.313149) (xy 116.332508 -375.320306)
			(xy 116.354327 -375.345933) (xy 116.392278 -375.401522) (xy 116.423313 -375.461249) (xy 116.446986 -375.524256)
			(xy 116.462959 -375.589642) (xy 116.471001 -375.656468) (xy 116.470999 -375.723777) (xy 116.462951 -375.790602)
			(xy 116.446973 -375.855987) (xy 116.423295 -375.918993) (xy 116.392255 -375.978717) (xy 116.354299 -376.034303)
			(xy 116.332508 -376.059954) (xy 116.326707 -376.067096) (xy 116.320195 -376.084289) (xy 116.319808 -376.093482)
			(xy 116.319808 -376.25147) (xy 116.319243 -376.26162) (xy 116.311487 -376.28038) (xy 116.297144 -376.294745)
			(xy 116.278395 -376.302528) (xy 116.268246 -376.303032) (xy 115.551966 -376.303032) (xy 115.541802 -376.302594)
			(xy 115.523027 -376.294803) (xy 115.508662 -376.28042) (xy 115.500894 -376.261634) (xy 115.500404 -376.25147)
			(xy 115.500404 -376.093482) (xy 115.500002 -376.084294) (xy 115.493483 -376.06711) (xy 115.487704 -376.059954)
			(xy 115.465947 -376.034277) (xy 115.427999 -375.978693) (xy 115.396967 -375.918973) (xy 115.373294 -375.855972)
			(xy 115.35732 -375.790593) (xy 115.349274 -375.723774) (xy 115.349271 -375.656472) (xy 115.357312 -375.589652)
			(xy 115.37328 -375.524271) (xy 115.396948 -375.461268) (xy 115.427976 -375.401545) (xy 115.465919 -375.345959)
			(xy 115.487704 -375.320306) (xy 115.493481 -375.313147) (xy 115.500007 -375.295967) (xy 115.500404 -375.286778)
			(xy 115.500404 -374.79351) (xy 115.499988 -374.784323) (xy 115.493478 -374.767139) (xy 115.487704 -374.759982)
			(xy 115.465876 -374.734363) (xy 115.427931 -374.678771) (xy 115.396901 -374.619043) (xy 115.373232 -374.556034)
			(xy 115.357263 -374.490648) (xy 115.349223 -374.423822) (xy 85.670923 -374.423822) (xy 85.670923 -374.423879)
			(xy 85.662851 -374.490815) (xy 85.646818 -374.556302) (xy 85.623057 -374.619398) (xy 85.591909 -374.679192)
			(xy 85.553823 -374.734826) (xy 85.53196 -374.76049) (xy 85.526138 -374.767617) (xy 85.519639 -374.784822)
			(xy 85.51926 -374.794018) (xy 85.51926 -375.28627) (xy 85.519694 -375.295454) (xy 85.526192 -375.312639)
			(xy 85.53196 -375.319798) (xy 85.553855 -375.345438) (xy 85.591945 -375.401075) (xy 85.623097 -375.460875)
			(xy 85.646861 -375.523975) (xy 85.662896 -375.589467) (xy 85.67097 -375.656409) (xy 85.670967 -375.723836)
			(xy 85.662888 -375.790777) (xy 85.646848 -375.856268) (xy 85.623079 -375.919367) (xy 85.591922 -375.979163)
			(xy 85.553827 -376.034797) (xy 85.53196 -376.060462) (xy 85.52615 -376.067597) (xy 85.519644 -376.084796)
			(xy 85.51926 -376.09399) (xy 85.51926 -376.25147) (xy 85.518749 -376.261595) (xy 85.511031 -376.280315)
			(xy 85.496752 -376.294673) (xy 85.478074 -376.302493) (xy 85.467952 -376.303032) (xy 84.751672 -376.303032)
			(xy 84.741565 -376.302539) (xy 84.722893 -376.294798) (xy 84.7086 -376.280504) (xy 84.700861 -376.261831)
			(xy 84.700364 -376.251724) (xy 84.700364 -376.09399) (xy 84.699944 -376.084804) (xy 84.693436 -376.06762)
			(xy 84.687664 -376.060462) (xy 84.665831 -376.034772) (xy 84.627744 -375.97914) (xy 84.596594 -375.919347)
			(xy 84.572829 -375.856253) (xy 84.556793 -375.790768) (xy 84.548715 -375.723833) (xy 84.548712 -375.656412)
			(xy 84.556785 -375.589477) (xy 84.572816 -375.52399) (xy 84.596575 -375.460894) (xy 84.62772 -375.401099)
			(xy 84.665803 -375.345464) (xy 84.687664 -375.319798) (xy 84.693452 -375.312647) (xy 84.69997 -375.295461)
			(xy 84.700364 -375.28627) (xy 84.700364 -374.794018) (xy 84.699931 -374.784834) (xy 84.693432 -374.76765)
			(xy 84.687664 -374.76049) (xy 84.66576 -374.734858) (xy 84.627675 -374.679218) (xy 84.596528 -374.619417)
			(xy 84.572768 -374.556316) (xy 84.556736 -374.490823) (xy 84.548664 -374.423882) (xy 81.271132 -374.423882)
			(xy 81.26306 -374.490815) (xy 81.247028 -374.556302) (xy 81.223267 -374.619397) (xy 81.19212 -374.679192)
			(xy 81.154034 -374.734825) (xy 81.132172 -374.76049) (xy 81.126351 -374.767618) (xy 81.119852 -374.784822)
			(xy 81.119472 -374.794018) (xy 81.119472 -375.28627) (xy 81.119903 -375.295455) (xy 81.126403 -375.312639)
			(xy 81.132172 -375.319798) (xy 81.154066 -375.345438) (xy 81.192156 -375.401076) (xy 81.223307 -375.460875)
			(xy 81.247071 -375.523975) (xy 81.263105 -375.589468) (xy 81.271179 -375.656409) (xy 81.271176 -375.723836)
			(xy 81.263097 -375.790777) (xy 81.247057 -375.856268) (xy 81.223289 -375.919366) (xy 81.192133 -375.979163)
			(xy 81.154039 -376.034797) (xy 81.132172 -376.060462) (xy 81.126363 -376.067598) (xy 81.119856 -376.084796)
			(xy 81.119472 -376.09399) (xy 81.119472 -376.25147) (xy 81.118949 -376.261593) (xy 81.111234 -376.280312)
			(xy 81.096958 -376.294669) (xy 81.078284 -376.302491) (xy 81.068164 -376.303032) (xy 80.351884 -376.303032)
			(xy 80.341778 -376.302529) (xy 80.323106 -376.294792) (xy 80.308813 -376.280501) (xy 80.301073 -376.26183)
			(xy 80.300576 -376.251724) (xy 80.300576 -376.09399) (xy 80.300176 -376.084802) (xy 80.293656 -376.067617)
			(xy 80.287876 -376.060462) (xy 80.266042 -376.034772) (xy 80.227954 -375.97914) (xy 80.196804 -375.919347)
			(xy 80.173039 -375.856254) (xy 80.157002 -375.790768) (xy 80.148924 -375.723833) (xy 80.148921 -375.656412)
			(xy 80.156994 -375.589476) (xy 80.173025 -375.523989) (xy 80.196785 -375.460894) (xy 80.227931 -375.401098)
			(xy 80.266015 -375.345464) (xy 80.287876 -375.319798) (xy 80.293653 -375.312639) (xy 80.30018 -375.295459)
			(xy 80.300576 -375.28627) (xy 80.300576 -374.794018) (xy 80.300163 -374.784831) (xy 80.293652 -374.767646)
			(xy 80.287876 -374.76049) (xy 80.265972 -374.734858) (xy 80.227886 -374.679218) (xy 80.196738 -374.619417)
			(xy 80.172977 -374.556316) (xy 80.156946 -374.490823) (xy 80.148873 -374.423882) (xy 76.870804 -374.423882)
			(xy 76.862772 -374.490638) (xy 76.846805 -374.556018) (xy 76.823138 -374.619021) (xy 76.79211 -374.678743)
			(xy 76.754168 -374.734329) (xy 76.732384 -374.759982) (xy 76.726568 -374.767114) (xy 76.720066 -374.784315)
			(xy 76.719684 -374.79351) (xy 76.719684 -375.286778) (xy 76.720108 -375.295964) (xy 76.726613 -375.313148)
			(xy 76.732384 -375.320306) (xy 76.754201 -375.345934) (xy 76.792147 -375.401525) (xy 76.823178 -375.461252)
			(xy 76.846848 -375.524259) (xy 76.862818 -375.589644) (xy 76.870859 -375.656469) (xy 76.870857 -375.723776)
			(xy 76.86281 -375.7906) (xy 76.846834 -375.855984) (xy 76.823159 -375.91899) (xy 76.792124 -375.978714)
			(xy 76.754173 -376.034302) (xy 76.732384 -376.059954) (xy 76.72658 -376.067094) (xy 76.72007 -376.084289)
			(xy 76.719684 -376.093482) (xy 76.719684 -376.25147) (xy 76.719212 -376.261637) (xy 76.711441 -376.280427)
			(xy 76.69707 -376.294812) (xy 76.678288 -376.302602) (xy 76.668122 -376.303032) (xy 75.951842 -376.303032)
			(xy 75.941669 -376.302601) (xy 75.92287 -376.294824) (xy 75.908482 -376.28044) (xy 75.900701 -376.261643)
			(xy 75.90028 -376.25147) (xy 75.90028 -376.093482) (xy 75.899883 -376.084293) (xy 75.893361 -376.067109)
			(xy 75.88758 -376.059954) (xy 75.865821 -376.034278) (xy 75.827868 -375.978696) (xy 75.796831 -375.918976)
			(xy 75.773155 -375.855975) (xy 75.757179 -375.790595) (xy 75.749132 -375.723774) (xy 75.749129 -375.656471)
			(xy 75.757171 -375.58965) (xy 75.773142 -375.524269) (xy 75.796813 -375.461265) (xy 75.827845 -375.401543)
			(xy 75.865793 -375.345958) (xy 75.88758 -375.320306) (xy 75.893354 -375.313145) (xy 75.899883 -375.295967)
			(xy 75.90028 -375.286778) (xy 75.90028 -374.79351) (xy 75.89987 -374.784323) (xy 75.893357 -374.767138)
			(xy 75.88758 -374.759982) (xy 75.865749 -374.734365) (xy 75.827799 -374.678774) (xy 75.796765 -374.619046)
			(xy 75.773093 -374.556037) (xy 75.757122 -374.49065) (xy 75.749081 -374.423823) (xy 72.471044 -374.423823)
			(xy 72.471044 -374.423879) (xy 72.462972 -374.490814) (xy 72.446941 -374.556301) (xy 72.423181 -374.619396)
			(xy 72.392034 -374.679191) (xy 72.35395 -374.734825) (xy 72.332088 -374.76049) (xy 72.326269 -374.76762)
			(xy 72.319768 -374.784822) (xy 72.319388 -374.794018) (xy 72.319388 -375.28627) (xy 72.319815 -375.295455)
			(xy 72.326317 -375.31264) (xy 72.332088 -375.319798) (xy 72.353982 -375.345439) (xy 72.39207 -375.401076)
			(xy 72.423221 -375.460876) (xy 72.446984 -375.523976) (xy 72.463017 -375.589468) (xy 72.471091 -375.656409)
			(xy 72.471088 -375.723836) (xy 72.463009 -375.790776) (xy 72.44697 -375.856267) (xy 72.423202 -375.919365)
			(xy 72.392047 -375.979162) (xy 72.353954 -376.034797) (xy 72.332088 -376.060462) (xy 72.326281 -376.0676)
			(xy 72.319773 -376.084796) (xy 72.319388 -376.09399) (xy 72.319388 -376.25147) (xy 72.31885 -376.261591)
			(xy 72.311137 -376.280307) (xy 72.296867 -376.294663) (xy 72.278198 -376.302488) (xy 72.26808 -376.303032)
			(xy 71.5518 -376.303032) (xy 71.54165 -376.302579) (xy 71.522904 -376.294789) (xy 71.508582 -376.280403)
			(xy 71.500876 -376.261622) (xy 71.500492 -376.25147) (xy 71.500492 -376.09399) (xy 71.500088 -376.084802)
			(xy 71.49357 -376.067618) (xy 71.487792 -376.060462) (xy 71.465958 -376.034772) (xy 71.427869 -375.979141)
			(xy 71.396717 -375.919348) (xy 71.372952 -375.856255) (xy 71.356914 -375.790769) (xy 71.348836 -375.723833)
			(xy 71.348833 -375.656412) (xy 71.356906 -375.589476) (xy 71.372938 -375.523989) (xy 71.396699 -375.460893)
			(xy 71.427845 -375.401098) (xy 71.46593 -375.345463) (xy 71.487792 -375.319798) (xy 71.493571 -375.31264)
			(xy 71.500096 -375.295459) (xy 71.500492 -375.28627) (xy 71.500492 -374.794018) (xy 71.500075 -374.784832)
			(xy 71.493566 -374.767647) (xy 71.487792 -374.76049) (xy 71.465887 -374.734859) (xy 71.4278 -374.679219)
			(xy 71.396652 -374.619418) (xy 71.37289 -374.556317) (xy 71.356858 -374.490824) (xy 71.348786 -374.423882)
			(xy 46.070774 -374.423882) (xy 46.062742 -374.490639) (xy 46.046773 -374.55602) (xy 46.023104 -374.619022)
			(xy 45.992075 -374.678745) (xy 45.95413 -374.73433) (xy 45.932344 -374.759982) (xy 45.926523 -374.76711)
			(xy 45.920025 -374.784314) (xy 45.919644 -374.79351) (xy 45.919644 -375.286778) (xy 45.920077 -375.295962)
			(xy 45.926576 -375.313146) (xy 45.932344 -375.320306) (xy 45.954162 -375.345934) (xy 45.992111 -375.401523)
			(xy 46.023144 -375.46125) (xy 46.046816 -375.524258) (xy 46.062787 -375.589643) (xy 46.070829 -375.656469)
			(xy 46.070826 -375.723776) (xy 46.062779 -375.790601) (xy 46.046802 -375.855985) (xy 46.023125 -375.918991)
			(xy 45.992088 -375.978716) (xy 45.954134 -376.034302) (xy 45.932344 -376.059954) (xy 45.926535 -376.06709)
			(xy 45.920029 -376.084288) (xy 45.919644 -376.093482) (xy 45.919644 -376.25147) (xy 45.919211 -376.261642)
			(xy 45.911433 -376.280439) (xy 45.897049 -376.294826) (xy 45.878254 -376.302609) (xy 45.868082 -376.303032)
			(xy 45.151802 -376.303032) (xy 45.141627 -376.302634) (xy 45.122826 -376.294844) (xy 45.10844 -376.28045)
			(xy 45.100661 -376.261645) (xy 45.10024 -376.25147) (xy 45.10024 -376.093482) (xy 45.09983 -376.084295)
			(xy 45.093315 -376.067111) (xy 45.08754 -376.059954) (xy 45.065782 -376.034277) (xy 45.027832 -375.978695)
			(xy 44.996798 -375.918974) (xy 44.973123 -375.855973) (xy 44.957148 -375.790594) (xy 44.949101 -375.723774)
			(xy 44.949099 -375.656471) (xy 44.95714 -375.589651) (xy 44.97311 -375.52427) (xy 44.996779 -375.461267)
			(xy 45.027809 -375.401544) (xy 45.065754 -375.345958) (xy 45.08754 -375.320306) (xy 45.093322 -375.31315)
			(xy 45.099844 -375.295968) (xy 45.10024 -375.286778) (xy 45.10024 -374.79351) (xy 45.099816 -374.784324)
			(xy 45.093311 -374.76714) (xy 45.08754 -374.759982) (xy 45.065711 -374.734364) (xy 45.027763 -374.678773)
			(xy 44.996732 -374.619044) (xy 44.973061 -374.556035) (xy 44.957091 -374.490649) (xy 44.94905 -374.423823)
			(xy 41.671014 -374.423823) (xy 41.671014 -374.423879) (xy 41.662941 -374.490816) (xy 41.646909 -374.556303)
			(xy 41.623147 -374.619398) (xy 41.591998 -374.679193) (xy 41.553911 -374.734826) (xy 41.532048 -374.76049)
			(xy 41.526224 -374.767616) (xy 41.519727 -374.784821) (xy 41.519348 -374.794018) (xy 41.519348 -375.28627)
			(xy 41.519784 -375.295454) (xy 41.526281 -375.312638) (xy 41.532048 -375.319798) (xy 41.553943 -375.345438)
			(xy 41.592035 -375.401075) (xy 41.623187 -375.460874) (xy 41.646952 -375.523974) (xy 41.662987 -375.589467)
			(xy 41.671061 -375.656409) (xy 41.671058 -375.723836) (xy 41.662978 -375.790777) (xy 41.646938 -375.856269)
			(xy 41.623168 -375.919367) (xy 41.592011 -375.979164) (xy 41.553916 -376.034798) (xy 41.532048 -376.060462)
			(xy 41.526236 -376.067596) (xy 41.519732 -376.084795) (xy 41.519348 -376.09399) (xy 41.519348 -376.25147)
			(xy 41.518849 -376.261596) (xy 41.511129 -376.280319) (xy 41.496846 -376.294677) (xy 41.478164 -376.302495)
			(xy 41.46804 -376.303032) (xy 40.75176 -376.303032) (xy 40.741607 -376.302612) (xy 40.72286 -376.294809)
			(xy 40.708539 -376.280413) (xy 40.700835 -376.261625) (xy 40.700452 -376.25147) (xy 40.700452 -376.09399)
			(xy 40.700035 -376.084804) (xy 40.693525 -376.06762) (xy 40.687752 -376.060462) (xy 40.665916 -376.034773)
			(xy 40.627823 -375.979143) (xy 40.596668 -375.919351) (xy 40.5729 -375.856257) (xy 40.55686 -375.79077)
			(xy 40.548781 -375.723834) (xy 40.548779 -375.656411) (xy 40.556852 -375.589474) (xy 40.572886 -375.523986)
			(xy 40.596649 -375.46089) (xy 40.627799 -375.401095) (xy 40.665888 -375.345462) (xy 40.687752 -375.319798)
			(xy 40.693538 -375.312646) (xy 40.700058 -375.29546) (xy 40.700452 -375.28627) (xy 40.700452 -374.794018)
			(xy 40.700022 -374.784833) (xy 40.693521 -374.767649) (xy 40.687752 -374.76049) (xy 40.665845 -374.73486)
			(xy 40.627754 -374.679221) (xy 40.596602 -374.619421) (xy 40.572838 -374.556319) (xy 40.556804 -374.490825)
			(xy 40.548731 -374.423882) (xy 37.271223 -374.423882) (xy 37.263151 -374.490815) (xy 37.247118 -374.556302)
			(xy 37.223357 -374.619398) (xy 37.192209 -374.679192) (xy 37.154123 -374.734826) (xy 37.13226 -374.76049)
			(xy 37.126438 -374.767617) (xy 37.119939 -374.784822) (xy 37.11956 -374.794018) (xy 37.11956 -375.28627)
			(xy 37.119994 -375.295454) (xy 37.126492 -375.312639) (xy 37.13226 -375.319798) (xy 37.154155 -375.345438)
			(xy 37.192245 -375.401075) (xy 37.223397 -375.460875) (xy 37.247161 -375.523975) (xy 37.263196 -375.589467)
			(xy 37.27127 -375.656409) (xy 37.271267 -375.723836) (xy 37.263188 -375.790777) (xy 37.247148 -375.856268)
			(xy 37.223379 -375.919367) (xy 37.192222 -375.979163) (xy 37.154127 -376.034797) (xy 37.13226 -376.060462)
			(xy 37.12645 -376.067597) (xy 37.119944 -376.084796) (xy 37.11956 -376.09399) (xy 37.11956 -376.25147)
			(xy 37.119049 -376.261595) (xy 37.111331 -376.280315) (xy 37.097052 -376.294673) (xy 37.078374 -376.302493)
			(xy 37.068252 -376.303032) (xy 36.351972 -376.303032) (xy 36.34182 -376.302602) (xy 36.323073 -376.294803)
			(xy 36.308752 -376.28041) (xy 36.301047 -376.261624) (xy 36.300664 -376.25147) (xy 36.300664 -376.09399)
			(xy 36.300244 -376.084804) (xy 36.293736 -376.06762) (xy 36.287964 -376.060462) (xy 36.266131 -376.034772)
			(xy 36.228044 -375.97914) (xy 36.196894 -375.919347) (xy 36.173129 -375.856253) (xy 36.157093 -375.790768)
			(xy 36.149015 -375.723833) (xy 36.149012 -375.656412) (xy 36.157085 -375.589477) (xy 36.173116 -375.52399)
			(xy 36.196875 -375.460894) (xy 36.22802 -375.401099) (xy 36.266103 -375.345464) (xy 36.287964 -375.319798)
			(xy 36.293752 -375.312647) (xy 36.30027 -375.295461) (xy 36.300664 -375.28627) (xy 36.300664 -374.794018)
			(xy 36.300231 -374.784834) (xy 36.293732 -374.76765) (xy 36.287964 -374.76049) (xy 36.26606 -374.734858)
			(xy 36.227975 -374.679218) (xy 36.196828 -374.619417) (xy 36.173068 -374.556316) (xy 36.157036 -374.490823)
			(xy 36.148964 -374.423882) (xy 32.870895 -374.423882) (xy 32.862863 -374.490639) (xy 32.846895 -374.556018)
			(xy 32.823227 -374.619021) (xy 32.7922 -374.678743) (xy 32.754257 -374.73433) (xy 32.732472 -374.759982)
			(xy 32.726654 -374.767112) (xy 32.720153 -374.784314) (xy 32.719772 -374.79351) (xy 32.719772 -375.286778)
			(xy 32.720199 -375.295963) (xy 32.726702 -375.313147) (xy 32.732472 -375.320306) (xy 32.754289 -375.345934)
			(xy 32.792236 -375.401524) (xy 32.823268 -375.461251) (xy 32.846938 -375.524259) (xy 32.862909 -375.589644)
			(xy 32.87095 -375.656469) (xy 32.870948 -375.723776) (xy 32.862901 -375.790601) (xy 32.846925 -375.855984)
			(xy 32.823249 -375.91899) (xy 32.792213 -375.978715) (xy 32.754261 -376.034302) (xy 32.732472 -376.059954)
			(xy 32.726666 -376.067093) (xy 32.720158 -376.084288) (xy 32.719772 -376.093482) (xy 32.719772 -376.25147)
			(xy 32.719312 -376.261638) (xy 32.711538 -376.28043) (xy 32.697164 -376.294816) (xy 32.678378 -376.302604)
			(xy 32.66821 -376.303032) (xy 31.95193 -376.303032) (xy 31.941757 -376.302611) (xy 31.922957 -376.29483)
			(xy 31.90857 -376.280443) (xy 31.900789 -376.261643) (xy 31.900368 -376.25147) (xy 31.900368 -376.093482)
			(xy 31.899951 -376.084296) (xy 31.89344 -376.067112) (xy 31.887668 -376.059954) (xy 31.865909 -376.034278)
			(xy 31.827957 -375.978696) (xy 31.796921 -375.918976) (xy 31.773245 -375.855974) (xy 31.75727 -375.790595)
			(xy 31.749223 -375.723774) (xy 31.74922 -375.656471) (xy 31.757261 -375.58965) (xy 31.773232 -375.524269)
			(xy 31.796903 -375.461266) (xy 31.827934 -375.401543) (xy 31.865881 -375.345958) (xy 31.887668 -375.320306)
			(xy 31.893453 -375.313153) (xy 31.899973 -375.295968) (xy 31.900368 -375.286778) (xy 31.900368 -374.79351)
			(xy 31.899938 -374.784325) (xy 31.893436 -374.767142) (xy 31.887668 -374.759982) (xy 31.865838 -374.734364)
			(xy 31.827888 -374.678774) (xy 31.796855 -374.619046) (xy 31.773184 -374.556036) (xy 31.757213 -374.49065)
			(xy 31.749171 -374.423823) (xy 28.471155 -374.423823) (xy 28.471155 -374.42387) (xy 28.463079 -374.490809)
			(xy 28.447044 -374.556297) (xy 28.423279 -374.619394) (xy 28.392129 -374.67919) (xy 28.35404 -374.734825)
			(xy 28.332176 -374.76049) (xy 28.326356 -374.767618) (xy 28.319856 -374.784822) (xy 28.319476 -374.794018)
			(xy 28.319476 -375.28627) (xy 28.319906 -375.295455) (xy 28.326407 -375.312639) (xy 28.332176 -375.319798)
			(xy 28.35407 -375.345439) (xy 28.39216 -375.401076) (xy 28.42331 -375.460875) (xy 28.447074 -375.523976)
			(xy 28.463108 -375.589468) (xy 28.471182 -375.656409) (xy 28.471179 -375.723836) (xy 28.4631 -375.790777)
			(xy 28.447061 -375.856268) (xy 28.423292 -375.919366) (xy 28.392136 -375.979163) (xy 28.354043 -376.034797)
			(xy 28.332176 -376.060462) (xy 28.326368 -376.067599) (xy 28.319861 -376.084796) (xy 28.319476 -376.09399)
			(xy 28.319476 -376.25147) (xy 28.31895 -376.261593) (xy 28.311235 -376.28031) (xy 28.29696 -376.294667)
			(xy 28.278288 -376.30249) (xy 28.268168 -376.303032) (xy 27.551888 -376.303032) (xy 27.541783 -376.302525)
			(xy 27.52311 -376.29479) (xy 27.508817 -376.2805) (xy 27.501077 -376.261829) (xy 27.50058 -376.251724)
			(xy 27.50058 -376.09399) (xy 27.500179 -376.084802) (xy 27.493659 -376.067617) (xy 27.48788 -376.060462)
			(xy 27.466046 -376.034772) (xy 27.427958 -375.979141) (xy 27.396807 -375.919348) (xy 27.373042 -375.856254)
			(xy 27.357005 -375.790768) (xy 27.348927 -375.723833) (xy 27.348924 -375.656412) (xy 27.356997 -375.589476)
			(xy 27.373029 -375.523989) (xy 27.396789 -375.460894) (xy 27.427935 -375.401098) (xy 27.466019 -375.345464)
			(xy 27.48788 -375.319798) (xy 27.493658 -375.312639) (xy 27.500184 -375.295459) (xy 27.50058 -375.28627)
			(xy 27.50058 -374.794018) (xy 27.500166 -374.784831) (xy 27.493655 -374.767646) (xy 27.48788 -374.76049)
			(xy 27.466014 -374.734827) (xy 27.427924 -374.679192) (xy 27.396773 -374.619396) (xy 27.373009 -374.556299)
			(xy 27.356973 -374.490809) (xy 27.348897 -374.423871) (xy 0.509016 -374.423871) (xy 0.509016 -377.10364)
			(xy 13.552932 -377.10364) (xy 13.552932 -376.696986) (xy 13.553422 -376.686828) (xy 13.5612 -376.66806)
			(xy 13.575567 -376.653695) (xy 13.594336 -376.64592) (xy 13.604494 -376.645424) (xy 14.00683 -376.645424)
			(xy 14.016988 -376.645908) (xy 14.035755 -376.65369) (xy 14.050119 -376.668058) (xy 14.057895 -376.686828)
			(xy 14.058392 -376.696986) (xy 14.058392 -376.756551) (xy 29.549067 -376.756551) (xy 29.557111 -376.689729)
			(xy 29.573083 -376.624347) (xy 29.596754 -376.561343) (xy 29.627786 -376.501619) (xy 29.665733 -376.446032)
			(xy 29.68752 -376.42038) (xy 29.69331 -376.41323) (xy 29.699828 -376.396043) (xy 29.70022 -376.386852)
			(xy 29.70022 -375.893584) (xy 29.699813 -375.884397) (xy 29.693297 -375.867212) (xy 29.68752 -375.860056)
			(xy 29.665765 -375.834378) (xy 29.627816 -375.778794) (xy 29.596782 -375.719074) (xy 29.573109 -375.656073)
			(xy 29.557134 -375.590694) (xy 29.549088 -375.523875) (xy 29.549085 -375.456573) (xy 29.557126 -375.389753)
			(xy 29.573095 -375.324373) (xy 29.596763 -375.26137) (xy 29.627791 -375.201647) (xy 29.665735 -375.146061)
			(xy 29.68752 -375.120408) (xy 29.693298 -375.11325) (xy 29.699823 -375.096069) (xy 29.70022 -375.08688)
			(xy 29.70022 -374.928638) (xy 29.700695 -374.918471) (xy 29.708464 -374.899681) (xy 29.722834 -374.885295)
			(xy 29.741616 -374.877506) (xy 29.751782 -374.877076) (xy 30.468062 -374.877076) (xy 30.478236 -374.877496)
			(xy 30.497037 -374.885276) (xy 30.511424 -374.899663) (xy 30.519204 -374.918464) (xy 30.519624 -374.928638)
			(xy 30.519624 -375.08688) (xy 30.520038 -375.096067) (xy 30.526548 -375.113252) (xy 30.532324 -375.120408)
			(xy 30.554144 -375.146034) (xy 30.592094 -375.201623) (xy 30.623128 -375.26135) (xy 30.646801 -375.324358)
			(xy 30.662773 -375.389744) (xy 30.670815 -375.45657) (xy 30.670812 -375.523878) (xy 30.662764 -375.590704)
			(xy 30.646787 -375.656088) (xy 30.623109 -375.719094) (xy 30.59207 -375.778818) (xy 30.554115 -375.834404)
			(xy 30.532324 -375.860056) (xy 30.526524 -375.867199) (xy 30.520011 -375.884391) (xy 30.519624 -375.893584)
			(xy 30.519624 -376.386852) (xy 30.520052 -376.396037) (xy 30.526553 -376.413222) (xy 30.532324 -376.42038)
			(xy 30.554117 -376.446028) (xy 30.592068 -376.501615) (xy 30.623103 -376.561338) (xy 30.646777 -376.624343)
			(xy 30.662751 -376.689726) (xy 30.670795 -376.75655) (xy 30.670795 -376.823856) (xy 30.670788 -376.823915)
			(xy 33.948836 -376.823915) (xy 33.948836 -376.756491) (xy 33.956911 -376.689553) (xy 33.972947 -376.624064)
			(xy 33.996711 -376.560967) (xy 34.027862 -376.501171) (xy 34.065952 -376.445537) (xy 34.087816 -376.419872)
			(xy 34.093609 -376.412724) (xy 34.100125 -376.395536) (xy 34.100516 -376.386344) (xy 34.100516 -375.894092)
			(xy 34.100106 -375.884905) (xy 34.093592 -375.867721) (xy 34.087816 -375.860564) (xy 34.065983 -375.834873)
			(xy 34.027892 -375.779243) (xy 33.996739 -375.71945) (xy 33.972973 -375.656357) (xy 33.956934 -375.59087)
			(xy 33.948856 -375.523935) (xy 33.948853 -375.456513) (xy 33.956926 -375.389577) (xy 33.972958 -375.324089)
			(xy 33.99672 -375.260994) (xy 34.027867 -375.201199) (xy 34.065953 -375.145565) (xy 34.087816 -375.1199)
			(xy 34.093597 -375.112744) (xy 34.10012 -375.095562) (xy 34.100516 -375.086372) (xy 34.100516 -374.928638)
			(xy 34.101057 -374.918517) (xy 34.108768 -374.899801) (xy 34.123038 -374.885444) (xy 34.141706 -374.87762)
			(xy 34.151824 -374.877076) (xy 34.868104 -374.877076) (xy 34.878255 -374.877518) (xy 34.897003 -374.88531)
			(xy 34.911325 -374.8997) (xy 34.919029 -374.918485) (xy 34.919412 -374.928638) (xy 34.919412 -375.086372)
			(xy 34.919833 -375.095558) (xy 34.926339 -375.112743) (xy 34.932112 -375.1199) (xy 34.954007 -375.14554)
			(xy 34.992094 -375.201178) (xy 35.023243 -375.260978) (xy 35.047004 -375.324078) (xy 35.063037 -375.38957)
			(xy 35.07111 -375.456511) (xy 35.071108 -375.523937) (xy 35.063029 -375.590877) (xy 35.04699 -375.656368)
			(xy 35.023223 -375.719466) (xy 34.992069 -375.779263) (xy 34.953977 -375.834899) (xy 34.932112 -375.860564)
			(xy 34.926307 -375.867703) (xy 34.919797 -375.884898) (xy 34.919412 -375.894092) (xy 34.919412 -376.386344)
			(xy 34.919798 -376.395534) (xy 34.926328 -376.412718) (xy 34.932112 -376.419872) (xy 34.953979 -376.445534)
			(xy 34.992067 -376.501169) (xy 35.023217 -376.560966) (xy 35.046981 -376.624063) (xy 35.063015 -376.689553)
			(xy 35.071091 -376.756491) (xy 35.071091 -376.756551) (xy 38.349155 -376.756551) (xy 38.357198 -376.689729)
			(xy 38.37317 -376.624348) (xy 38.396841 -376.561343) (xy 38.427872 -376.50162) (xy 38.465818 -376.446033)
			(xy 38.487604 -376.42038) (xy 38.493392 -376.413229) (xy 38.499912 -376.396043) (xy 38.500304 -376.386852)
			(xy 38.500304 -375.893584) (xy 38.499901 -375.884396) (xy 38.493382 -375.867212) (xy 38.487604 -375.860056)
			(xy 38.465849 -375.834378) (xy 38.427901 -375.778794) (xy 38.396869 -375.719074) (xy 38.373195 -375.656073)
			(xy 38.357221 -375.590694) (xy 38.349175 -375.523875) (xy 38.349172 -375.456573) (xy 38.357213 -375.389753)
			(xy 38.373181 -375.324373) (xy 38.396849 -375.26137) (xy 38.427876 -375.201647) (xy 38.465819 -375.146061)
			(xy 38.487604 -375.120408) (xy 38.49338 -375.113248) (xy 38.499907 -375.096069) (xy 38.500304 -375.08688)
			(xy 38.500304 -374.928638) (xy 38.500794 -374.918473) (xy 38.50856 -374.899686) (xy 38.522925 -374.885301)
			(xy 38.541702 -374.877508) (xy 38.551866 -374.877076) (xy 39.268146 -374.877076) (xy 39.278311 -374.877497)
			(xy 39.297089 -374.885293) (xy 39.311454 -374.899682) (xy 39.31922 -374.918472) (xy 39.319708 -374.928638)
			(xy 39.319708 -375.08688) (xy 39.320126 -375.096066) (xy 39.326634 -375.113251) (xy 39.332408 -375.120408)
			(xy 39.354229 -375.146034) (xy 39.39218 -375.201623) (xy 39.423215 -375.261349) (xy 39.446888 -375.324357)
			(xy 39.462861 -375.389743) (xy 39.470903 -375.45657) (xy 39.4709 -375.523878) (xy 39.462852 -375.590704)
			(xy 39.446874 -375.656089) (xy 39.423195 -375.719095) (xy 39.392155 -375.778819) (xy 39.354199 -375.834405)
			(xy 39.332408 -375.860056) (xy 39.326606 -375.867197) (xy 39.320094 -375.884391) (xy 39.319708 -375.893584)
			(xy 39.319708 -376.386852) (xy 39.320139 -376.396037) (xy 39.326638 -376.413222) (xy 39.332408 -376.42038)
			(xy 39.354201 -376.446028) (xy 39.392153 -376.501614) (xy 39.423189 -376.561338) (xy 39.446864 -376.624343)
			(xy 39.462839 -376.689726) (xy 39.470883 -376.75655) (xy 39.470883 -376.823856) (xy 39.470876 -376.823915)
			(xy 42.748924 -376.823915) (xy 42.748924 -376.756491) (xy 42.756999 -376.689553) (xy 42.773034 -376.624064)
			(xy 42.796798 -376.560968) (xy 42.827948 -376.501172) (xy 42.866036 -376.445537) (xy 42.8879 -376.419872)
			(xy 42.893691 -376.412723) (xy 42.900209 -376.395535) (xy 42.9006 -376.386344) (xy 42.9006 -375.894092)
			(xy 42.900194 -375.884904) (xy 42.893677 -375.86772) (xy 42.8879 -375.860564) (xy 42.866067 -375.834873)
			(xy 42.827978 -375.779242) (xy 42.796826 -375.719449) (xy 42.77306 -375.656356) (xy 42.757022 -375.59087)
			(xy 42.748944 -375.523935) (xy 42.748941 -375.456513) (xy 42.757013 -375.389577) (xy 42.773045 -375.32409)
			(xy 42.796806 -375.260995) (xy 42.827953 -375.201199) (xy 42.866038 -375.145565) (xy 42.8879 -375.1199)
			(xy 42.893679 -375.112742) (xy 42.900204 -375.095561) (xy 42.9006 -375.086372) (xy 42.9006 -374.928638)
			(xy 42.901157 -374.918519) (xy 42.908865 -374.899806) (xy 42.923129 -374.88545) (xy 42.941792 -374.877622)
			(xy 42.951908 -374.877076) (xy 43.668188 -374.877076) (xy 43.678338 -374.877531) (xy 43.697086 -374.885318)
			(xy 43.711409 -374.899704) (xy 43.719113 -374.918486) (xy 43.719496 -374.928638) (xy 43.719496 -375.086372)
			(xy 43.719921 -375.095558) (xy 43.726424 -375.112742) (xy 43.732196 -375.1199) (xy 43.754092 -375.145539)
			(xy 43.79218 -375.201177) (xy 43.823329 -375.260977) (xy 43.847092 -375.324077) (xy 43.863125 -375.38957)
			(xy 43.871198 -375.456511) (xy 43.871196 -375.523937) (xy 43.863116 -375.590878) (xy 43.847077 -375.656369)
			(xy 43.823309 -375.719467) (xy 43.792155 -375.779264) (xy 43.754062 -375.834899) (xy 43.732196 -375.860564)
			(xy 43.726389 -375.867702) (xy 43.719881 -375.884898) (xy 43.719496 -375.894092) (xy 43.719496 -376.386344)
			(xy 43.719886 -376.395533) (xy 43.726414 -376.412717) (xy 43.732196 -376.419872) (xy 43.754064 -376.445534)
			(xy 43.792153 -376.501169) (xy 43.823304 -376.560965) (xy 43.847068 -376.624063) (xy 43.863103 -376.689552)
			(xy 43.871179 -376.756491) (xy 43.871178 -376.823856) (xy 47.149219 -376.823856) (xy 47.149219 -376.75655)
			(xy 47.157264 -376.689727) (xy 47.173238 -376.624344) (xy 47.196912 -376.56134) (xy 47.227948 -376.501617)
			(xy 47.265899 -376.446031) (xy 47.287688 -376.42038) (xy 47.293474 -376.413227) (xy 47.299995 -376.396043)
			(xy 47.300388 -376.386852) (xy 47.300388 -375.893584) (xy 47.299988 -375.884396) (xy 47.293468 -375.867211)
			(xy 47.287688 -375.860056) (xy 47.26593 -375.834379) (xy 47.227977 -375.778797) (xy 47.19694 -375.719077)
			(xy 47.173263 -375.656076) (xy 47.157287 -375.590696) (xy 47.149239 -375.523876) (xy 47.149236 -375.456572)
			(xy 47.157278 -375.389751) (xy 47.173249 -375.32437) (xy 47.19692 -375.261367) (xy 47.227952 -375.201644)
			(xy 47.265901 -375.146059) (xy 47.287688 -375.120408) (xy 47.293462 -375.113247) (xy 47.299991 -375.096069)
			(xy 47.300388 -375.08688) (xy 47.300388 -374.928892) (xy 47.300815 -374.918739) (xy 47.308611 -374.899989)
			(xy 47.323006 -374.885666) (xy 47.341795 -374.877965) (xy 47.35195 -374.877584) (xy 48.06823 -374.877584)
			(xy 48.078364 -374.878003) (xy 48.097094 -374.885749) (xy 48.111451 -374.900056) (xy 48.119261 -374.91876)
			(xy 48.119792 -374.928892) (xy 48.119792 -375.08688) (xy 48.120214 -375.096066) (xy 48.12672 -375.11325)
			(xy 48.132492 -375.120408) (xy 48.15431 -375.146035) (xy 48.192256 -375.201626) (xy 48.223286 -375.261353)
			(xy 48.246956 -375.324361) (xy 48.262926 -375.389746) (xy 48.270967 -375.456571) (xy 48.270964 -375.523878)
			(xy 48.262917 -375.590702) (xy 48.246942 -375.656085) (xy 48.223267 -375.719091) (xy 48.192231 -375.778816)
			(xy 48.154281 -375.834403) (xy 48.132492 -375.860056) (xy 48.126688 -375.867196) (xy 48.120178 -375.884391)
			(xy 48.119792 -375.893584) (xy 48.119792 -376.386852) (xy 48.120227 -376.396037) (xy 48.126724 -376.413221)
			(xy 48.132492 -376.42038) (xy 48.154283 -376.446029) (xy 48.192229 -376.501617) (xy 48.223261 -376.561341)
			(xy 48.246932 -376.624346) (xy 48.262904 -376.689728) (xy 48.270947 -376.756551) (xy 73.548976 -376.756551)
			(xy 73.55702 -376.689728) (xy 73.572992 -376.624347) (xy 73.596664 -376.561342) (xy 73.627697 -376.501619)
			(xy 73.665645 -376.446032) (xy 73.687432 -376.42038) (xy 73.693224 -376.413231) (xy 73.699741 -376.396043)
			(xy 73.700132 -376.386852) (xy 73.700132 -375.893584) (xy 73.699722 -375.884397) (xy 73.693208 -375.867213)
			(xy 73.687432 -375.860056) (xy 73.665676 -375.834378) (xy 73.627727 -375.778795) (xy 73.596693 -375.719075)
			(xy 73.573018 -375.656074) (xy 73.557043 -375.590695) (xy 73.548997 -375.523875) (xy 73.548994 -375.456573)
			(xy 73.557035 -375.389753) (xy 73.573004 -375.324372) (xy 73.596673 -375.261369) (xy 73.627702 -375.201647)
			(xy 73.665647 -375.14606) (xy 73.687432 -375.120408) (xy 73.693212 -375.113251) (xy 73.699736 -375.096069)
			(xy 73.700132 -375.08688) (xy 73.700132 -374.928638) (xy 73.700595 -374.91847) (xy 73.708366 -374.899677)
			(xy 73.72274 -374.885291) (xy 73.741526 -374.877504) (xy 73.751694 -374.877076) (xy 74.467974 -374.877076)
			(xy 74.478149 -374.877486) (xy 74.49695 -374.88527) (xy 74.511337 -374.89966) (xy 74.519116 -374.918463)
			(xy 74.519536 -374.928638) (xy 74.519536 -375.08688) (xy 74.51997 -375.096064) (xy 74.526469 -375.113248)
			(xy 74.532236 -375.120408) (xy 74.554056 -375.146034) (xy 74.592006 -375.201623) (xy 74.623039 -375.26135)
			(xy 74.646711 -375.324358) (xy 74.662683 -375.389744) (xy 74.670725 -375.45657) (xy 74.670722 -375.523878)
			(xy 74.662674 -375.590703) (xy 74.646697 -375.656088) (xy 74.623019 -375.719094) (xy 74.591981 -375.778818)
			(xy 74.554027 -375.834404) (xy 74.532236 -375.860056) (xy 74.526425 -375.867191) (xy 74.519921 -375.88439)
			(xy 74.519536 -375.893584) (xy 74.519536 -376.386852) (xy 74.519983 -376.396035) (xy 74.526473 -376.413219)
			(xy 74.532236 -376.42038) (xy 74.554028 -376.446029) (xy 74.591979 -376.501615) (xy 74.623013 -376.561339)
			(xy 74.646687 -376.624344) (xy 74.66266 -376.689727) (xy 74.670704 -376.75655) (xy 74.670704 -376.823856)
			(xy 74.670697 -376.823915) (xy 77.948745 -376.823915) (xy 77.948745 -376.756491) (xy 77.956821 -376.689553)
			(xy 77.972856 -376.624063) (xy 77.996621 -376.560967) (xy 78.027773 -376.501171) (xy 78.065863 -376.445537)
			(xy 78.087728 -376.419872) (xy 78.093523 -376.412726) (xy 78.100038 -376.395536) (xy 78.100428 -376.386344)
			(xy 78.100428 -375.894092) (xy 78.100016 -375.884905) (xy 78.093503 -375.867721) (xy 78.087728 -375.860564)
			(xy 78.065894 -375.834873) (xy 78.027803 -375.779243) (xy 77.996649 -375.719451) (xy 77.972882 -375.656357)
			(xy 77.956844 -375.590871) (xy 77.948765 -375.523935) (xy 77.948762 -375.456513) (xy 77.956835 -375.389577)
			(xy 77.972868 -375.324089) (xy 77.99663 -375.260993) (xy 78.027778 -375.201198) (xy 78.065865 -375.145565)
			(xy 78.087728 -375.1199) (xy 78.093511 -375.112745) (xy 78.100033 -375.095562) (xy 78.100428 -375.086372)
			(xy 78.100428 -374.928638) (xy 78.100958 -374.918515) (xy 78.108671 -374.899797) (xy 78.122944 -374.88544)
			(xy 78.141616 -374.877618) (xy 78.151736 -374.877076) (xy 78.868016 -374.877076) (xy 78.878123 -374.877572)
			(xy 78.896797 -374.88531) (xy 78.91109 -374.899603) (xy 78.918828 -374.918277) (xy 78.919324 -374.928384)
			(xy 78.919324 -375.086372) (xy 78.919742 -375.095558) (xy 78.92625 -375.112743) (xy 78.932024 -375.1199)
			(xy 78.953919 -375.14554) (xy 78.992005 -375.201178) (xy 79.023153 -375.260978) (xy 79.046914 -375.324079)
			(xy 79.062947 -375.38957) (xy 79.07102 -375.456511) (xy 79.071017 -375.523937) (xy 79.062938 -375.590877)
			(xy 79.0469 -375.656367) (xy 79.023133 -375.719466) (xy 78.99198 -375.779263) (xy 78.953889 -375.834898)
			(xy 78.932024 -375.860564) (xy 78.926221 -375.867704) (xy 78.919709 -375.884898) (xy 78.919324 -375.894092)
			(xy 78.919324 -376.386344) (xy 78.919708 -376.395534) (xy 78.926239 -376.412718) (xy 78.932024 -376.419872)
			(xy 78.953891 -376.445534) (xy 78.991978 -376.50117) (xy 79.023127 -376.560967) (xy 79.04689 -376.624064)
			(xy 79.062925 -376.689553) (xy 79.071 -376.756491) (xy 79.071 -376.756551) (xy 82.349064 -376.756551)
			(xy 82.357108 -376.689729) (xy 82.373079 -376.624347) (xy 82.396751 -376.561343) (xy 82.427782 -376.501619)
			(xy 82.465729 -376.446032) (xy 82.487516 -376.42038) (xy 82.493305 -376.41323) (xy 82.499824 -376.396043)
			(xy 82.500216 -376.386852) (xy 82.500216 -375.893584) (xy 82.49981 -375.884396) (xy 82.493293 -375.867212)
			(xy 82.487516 -375.860056) (xy 82.46576 -375.834378) (xy 82.427812 -375.778795) (xy 82.396779 -375.719074)
			(xy 82.373105 -375.656073) (xy 82.357131 -375.590694) (xy 82.349084 -375.523875) (xy 82.349081 -375.456573)
			(xy 82.357122 -375.389753) (xy 82.373091 -375.324373) (xy 82.396759 -375.26137) (xy 82.427787 -375.201647)
			(xy 82.465731 -375.14606) (xy 82.487516 -375.120408) (xy 82.493294 -375.113249) (xy 82.499819 -375.096069)
			(xy 82.500216 -375.08688) (xy 82.500216 -374.928638) (xy 82.500694 -374.918472) (xy 82.508463 -374.899682)
			(xy 82.522832 -374.885297) (xy 82.541612 -374.877506) (xy 82.551778 -374.877076) (xy 83.268058 -374.877076)
			(xy 83.278232 -374.877499) (xy 83.297033 -374.885277) (xy 83.31142 -374.899664) (xy 83.3192 -374.918464)
			(xy 83.31962 -374.928638) (xy 83.31962 -375.08688) (xy 83.320035 -375.096067) (xy 83.326545 -375.113251)
			(xy 83.33232 -375.120408) (xy 83.35414 -375.146034) (xy 83.392091 -375.201623) (xy 83.423125 -375.26135)
			(xy 83.446798 -375.324358) (xy 83.46277 -375.389744) (xy 83.470812 -375.45657) (xy 83.470809 -375.523878)
			(xy 83.462761 -375.590704) (xy 83.446784 -375.656088) (xy 83.423105 -375.719094) (xy 83.392066 -375.778818)
			(xy 83.354111 -375.834404) (xy 83.33232 -375.860056) (xy 83.326519 -375.867199) (xy 83.320007 -375.884391)
			(xy 83.31962 -375.893584) (xy 83.31962 -376.386852) (xy 83.320049 -376.396037) (xy 83.326549 -376.413222)
			(xy 83.33232 -376.42038) (xy 83.354113 -376.446028) (xy 83.392064 -376.501614) (xy 83.4231 -376.561338)
			(xy 83.446774 -376.624343) (xy 83.462748 -376.689726) (xy 83.470792 -376.75655) (xy 83.470792 -376.823856)
			(xy 83.470785 -376.823915) (xy 86.748833 -376.823915) (xy 86.748833 -376.756491) (xy 86.756908 -376.689553)
			(xy 86.772944 -376.624064) (xy 86.796708 -376.560967) (xy 86.827859 -376.501171) (xy 86.865948 -376.445537)
			(xy 86.887812 -376.419872) (xy 86.893604 -376.412724) (xy 86.900121 -376.395536) (xy 86.900512 -376.386344)
			(xy 86.900512 -375.894092) (xy 86.900103 -375.884905) (xy 86.893588 -375.86772) (xy 86.887812 -375.860564)
			(xy 86.865979 -375.834873) (xy 86.827889 -375.779242) (xy 86.796736 -375.71945) (xy 86.772969 -375.656356)
			(xy 86.756931 -375.59087) (xy 86.748853 -375.523935) (xy 86.74885 -375.456513) (xy 86.756923 -375.389577)
			(xy 86.772955 -375.32409) (xy 86.796716 -375.260994) (xy 86.827864 -375.201199) (xy 86.86595 -375.145565)
			(xy 86.887812 -375.1199) (xy 86.893592 -375.112743) (xy 86.900116 -375.095562) (xy 86.900512 -375.086372)
			(xy 86.900512 -374.928638) (xy 86.901057 -374.918517) (xy 86.908767 -374.899802) (xy 86.923035 -374.885446)
			(xy 86.941702 -374.87762) (xy 86.95182 -374.877076) (xy 87.6681 -374.877076) (xy 87.678206 -374.877585)
			(xy 87.696879 -374.885318) (xy 87.711173 -374.899607) (xy 87.718912 -374.918278) (xy 87.719408 -374.928384)
			(xy 87.719408 -375.086372) (xy 87.71983 -375.095558) (xy 87.726335 -375.112743) (xy 87.732108 -375.1199)
			(xy 87.754003 -375.145539) (xy 87.79209 -375.201178) (xy 87.798441 -375.213371) (xy 104.681961 -375.213371)
			(xy 104.681961 -375.153429) (xy 104.689785 -375.094001) (xy 104.7053 -375.036103) (xy 104.72824 -374.980725)
			(xy 104.758212 -374.928815) (xy 104.794703 -374.881262) (xy 104.837089 -374.838879) (xy 104.884645 -374.802391)
			(xy 104.936557 -374.772424) (xy 104.991937 -374.749489) (xy 105.049837 -374.733978) (xy 105.109265 -374.726159)
			(xy 105.139236 -374.725692) (xy 106.002836 -374.725692) (xy 106.032802 -374.726184) (xy 106.092221 -374.734011)
			(xy 106.15011 -374.749527) (xy 106.205479 -374.772465) (xy 106.25738 -374.802434) (xy 106.304926 -374.838921)
			(xy 106.347303 -374.881301) (xy 106.383786 -374.92885) (xy 106.413751 -374.980753) (xy 106.436685 -375.036124)
			(xy 106.452196 -375.094014) (xy 106.460018 -375.153434) (xy 106.460018 -375.213366) (xy 106.452196 -375.272786)
			(xy 106.436685 -375.330676) (xy 106.413751 -375.386047) (xy 106.383786 -375.43795) (xy 106.347303 -375.485499)
			(xy 106.304926 -375.527879) (xy 106.25738 -375.564366) (xy 106.205479 -375.594335) (xy 106.15011 -375.617273)
			(xy 106.092221 -375.632789) (xy 106.032802 -375.640616) (xy 106.002836 -375.641108) (xy 105.139236 -375.641108)
			(xy 105.109265 -375.640641) (xy 105.049837 -375.632822) (xy 104.991937 -375.617311) (xy 104.936557 -375.594376)
			(xy 104.884645 -375.564409) (xy 104.837089 -375.527921) (xy 104.794703 -375.485538) (xy 104.758212 -375.437985)
			(xy 104.72824 -375.386075) (xy 104.7053 -375.330697) (xy 104.689785 -375.272799) (xy 104.681961 -375.213371)
			(xy 87.798441 -375.213371) (xy 87.823239 -375.260978) (xy 87.847001 -375.324078) (xy 87.863034 -375.38957)
			(xy 87.871107 -375.456511) (xy 87.871105 -375.523937) (xy 87.863026 -375.590877) (xy 87.846987 -375.656368)
			(xy 87.82322 -375.719466) (xy 87.792066 -375.779263) (xy 87.753974 -375.834899) (xy 87.732108 -375.860564)
			(xy 87.726303 -375.867703) (xy 87.719793 -375.884898) (xy 87.719408 -375.894092) (xy 87.719408 -376.386344)
			(xy 87.719795 -376.395534) (xy 87.726324 -376.412718) (xy 87.732108 -376.419872) (xy 87.753976 -376.445534)
			(xy 87.792064 -376.501169) (xy 87.823214 -376.560966) (xy 87.846977 -376.624063) (xy 87.863012 -376.689553)
			(xy 87.871088 -376.756491) (xy 87.871087 -376.823915) (xy 117.548863 -376.823915) (xy 117.548863 -376.756491)
			(xy 117.556939 -376.689552) (xy 117.572976 -376.624062) (xy 117.596742 -376.560965) (xy 117.627895 -376.50117)
			(xy 117.665986 -376.445536) (xy 117.687852 -376.419872) (xy 117.693649 -376.412728) (xy 117.700162 -376.395536)
			(xy 117.700552 -376.386344) (xy 117.700552 -375.894092) (xy 117.700134 -375.884906) (xy 117.693625 -375.867722)
			(xy 117.687852 -375.860564) (xy 117.666018 -375.834874) (xy 117.627925 -375.779244) (xy 117.59677 -375.719452)
			(xy 117.573001 -375.656358) (xy 117.556962 -375.590871) (xy 117.548883 -375.523935) (xy 117.54888 -375.456513)
			(xy 117.556953 -375.389576) (xy 117.572987 -375.324088) (xy 117.59675 -375.260992) (xy 117.6279 -375.201197)
			(xy 117.665988 -375.145564) (xy 117.687852 -375.1199) (xy 117.693638 -375.112747) (xy 117.700157 -375.095562)
			(xy 117.700552 -375.086372) (xy 117.700552 -374.928638) (xy 117.701058 -374.918512) (xy 117.708776 -374.89979)
			(xy 117.723056 -374.885432) (xy 117.741737 -374.877613) (xy 117.75186 -374.877076) (xy 118.46814 -374.877076)
			(xy 118.478294 -374.877488) (xy 118.497042 -374.885293) (xy 118.511363 -374.899691) (xy 118.519066 -374.918482)
			(xy 118.519448 -374.928638) (xy 118.519448 -375.086372) (xy 118.519883 -375.095556) (xy 118.526381 -375.11274)
			(xy 118.532148 -375.1199) (xy 118.554045 -375.145538) (xy 118.592136 -375.201176) (xy 118.623289 -375.260975)
			(xy 118.647053 -375.324075) (xy 118.663088 -375.389568) (xy 118.671162 -375.45651) (xy 118.671159 -375.523938)
			(xy 118.66308 -375.590879) (xy 118.647039 -375.656371) (xy 118.623269 -375.719469) (xy 118.592112 -375.779266)
			(xy 118.554016 -375.8349) (xy 118.532148 -375.860564) (xy 118.526335 -375.867698) (xy 118.519832 -375.884897)
			(xy 118.519448 -375.894092) (xy 118.519448 -376.386344) (xy 118.519849 -376.395532) (xy 118.52637 -376.412715)
			(xy 118.532148 -376.419872) (xy 118.554018 -376.445533) (xy 118.59211 -376.501167) (xy 118.623263 -376.560963)
			(xy 118.647029 -376.624061) (xy 118.663066 -376.689551) (xy 118.671143 -376.75649) (xy 118.671143 -376.756551)
			(xy 121.949182 -376.756551) (xy 121.957226 -376.689728) (xy 121.973199 -376.624346) (xy 121.996871 -376.561342)
			(xy 122.027904 -376.501618) (xy 122.065852 -376.446032) (xy 122.08764 -376.42038) (xy 122.093433 -376.413232)
			(xy 122.099949 -376.396044) (xy 122.10034 -376.386852) (xy 122.10034 -375.893584) (xy 122.099929 -375.884397)
			(xy 122.093415 -375.867213) (xy 122.08764 -375.860056) (xy 122.065884 -375.834378) (xy 122.027934 -375.778795)
			(xy 121.996899 -375.719075) (xy 121.973225 -375.656074) (xy 121.95725 -375.590695) (xy 121.949203 -375.523875)
			(xy 121.9492 -375.456573) (xy 121.957241 -375.389752) (xy 121.973211 -375.324372) (xy 121.99688 -375.261369)
			(xy 122.027909 -375.201646) (xy 122.065854 -375.14606) (xy 122.08764 -375.120408) (xy 122.093421 -375.113252)
			(xy 122.099944 -375.09607) (xy 122.10034 -375.08688) (xy 122.10034 -374.928638) (xy 122.100795 -374.918469)
			(xy 122.108568 -374.899674) (xy 122.122944 -374.885288) (xy 122.141733 -374.877502) (xy 122.151902 -374.877076)
			(xy 122.868182 -374.877076) (xy 122.878357 -374.877479) (xy 122.897159 -374.885265) (xy 122.911546 -374.899658)
			(xy 122.919325 -374.918463) (xy 122.919744 -374.928638) (xy 122.919744 -375.08688) (xy 122.920176 -375.096065)
			(xy 122.926676 -375.113249) (xy 122.932444 -375.120408) (xy 122.954264 -375.146034) (xy 122.992213 -375.201624)
			(xy 123.023246 -375.261351) (xy 123.046917 -375.324359) (xy 123.062889 -375.389744) (xy 123.070931 -375.45657)
			(xy 123.070928 -375.523878) (xy 123.06288 -375.590703) (xy 123.046903 -375.656087) (xy 123.023226 -375.719093)
			(xy 122.992188 -375.778818) (xy 122.954234 -375.834404) (xy 122.932444 -375.860056) (xy 122.926634 -375.867192)
			(xy 122.920129 -375.88439) (xy 122.919744 -375.893584) (xy 122.919744 -376.386852) (xy 122.92019 -376.396035)
			(xy 122.92668 -376.413219) (xy 122.932444 -376.42038) (xy 122.954236 -376.446029) (xy 122.992186 -376.501615)
			(xy 123.02322 -376.561339) (xy 123.046893 -376.624344) (xy 123.062866 -376.689727) (xy 123.07091 -376.75655)
			(xy 123.07091 -376.823856) (xy 123.070903 -376.823915) (xy 126.348951 -376.823915) (xy 126.348951 -376.756491)
			(xy 126.357027 -376.689552) (xy 126.373063 -376.624063) (xy 126.396828 -376.560966) (xy 126.42798 -376.50117)
			(xy 126.466071 -376.445537) (xy 126.487936 -376.419872) (xy 126.493732 -376.412726) (xy 126.500246 -376.395536)
			(xy 126.500636 -376.386344) (xy 126.500636 -375.894092) (xy 126.500222 -375.884905) (xy 126.49371 -375.867721)
			(xy 126.487936 -375.860564) (xy 126.466102 -375.834873) (xy 126.42801 -375.779243) (xy 126.396856 -375.719451)
			(xy 126.373088 -375.656357) (xy 126.35705 -375.590871) (xy 126.348971 -375.523935) (xy 126.348968 -375.456513)
			(xy 126.357041 -375.389576) (xy 126.373074 -375.324089) (xy 126.396836 -375.260993) (xy 126.427985 -375.201198)
			(xy 126.466073 -375.145565) (xy 126.487936 -375.1199) (xy 126.49372 -375.112746) (xy 126.500241 -375.095562)
			(xy 126.500636 -375.086372) (xy 126.500636 -374.928638) (xy 126.501158 -374.918514) (xy 126.508872 -374.899795)
			(xy 126.523148 -374.885437) (xy 126.541823 -374.877616) (xy 126.551944 -374.877076) (xy 127.268224 -374.877076)
			(xy 127.278377 -374.877501) (xy 127.297125 -374.8853) (xy 127.311447 -374.899695) (xy 127.31915 -374.918483)
			(xy 127.319532 -374.928638) (xy 127.319532 -375.086372) (xy 127.319971 -375.095556) (xy 127.326466 -375.11274)
			(xy 127.332232 -375.1199) (xy 127.354126 -375.14554) (xy 127.392212 -375.201179) (xy 127.423359 -375.260979)
			(xy 127.44712 -375.324079) (xy 127.463153 -375.389571) (xy 127.471226 -375.456511) (xy 127.471223 -375.523937)
			(xy 127.463144 -375.590877) (xy 127.447106 -375.656367) (xy 127.42334 -375.719465) (xy 127.392187 -375.779263)
			(xy 127.354097 -375.834898) (xy 127.332232 -375.860564) (xy 127.326417 -375.867696) (xy 127.319915 -375.884897)
			(xy 127.319532 -375.894092) (xy 127.319532 -376.386344) (xy 127.319936 -376.395532) (xy 127.326456 -376.412715)
			(xy 127.332232 -376.419872) (xy 127.354099 -376.445535) (xy 127.392185 -376.50117) (xy 127.423334 -376.560967)
			(xy 127.447097 -376.624064) (xy 127.463131 -376.689553) (xy 127.471206 -376.756491) (xy 127.471206 -376.756551)
			(xy 130.74927 -376.756551) (xy 130.757314 -376.689729) (xy 130.773286 -376.624347) (xy 130.796958 -376.561343)
			(xy 130.827989 -376.501619) (xy 130.865937 -376.446032) (xy 130.887724 -376.42038) (xy 130.893514 -376.413231)
			(xy 130.900032 -376.396043) (xy 130.900424 -376.386852) (xy 130.900424 -375.893584) (xy 130.900016 -375.884397)
			(xy 130.8935 -375.867213) (xy 130.887724 -375.860056) (xy 130.865968 -375.834378) (xy 130.82802 -375.778795)
			(xy 130.796986 -375.719074) (xy 130.773312 -375.656073) (xy 130.757337 -375.590695) (xy 130.749291 -375.523875)
			(xy 130.749288 -375.456573) (xy 130.757329 -375.389753) (xy 130.773298 -375.324373) (xy 130.796966 -375.26137)
			(xy 130.827995 -375.201647) (xy 130.865939 -375.146061) (xy 130.887724 -375.120408) (xy 130.893502 -375.11325)
			(xy 130.900027 -375.096069) (xy 130.900424 -375.08688) (xy 130.900424 -374.928638) (xy 130.900895 -374.918471)
			(xy 130.908665 -374.899679) (xy 130.923036 -374.885294) (xy 130.941819 -374.877505) (xy 130.951986 -374.877076)
			(xy 131.668266 -374.877076) (xy 131.67844 -374.877493) (xy 131.697241 -374.885274) (xy 131.711629 -374.899662)
			(xy 131.719408 -374.918464) (xy 131.719828 -374.928638) (xy 131.719828 -375.08688) (xy 131.720241 -375.096067)
			(xy 131.726752 -375.113252) (xy 131.732528 -375.120408) (xy 131.754348 -375.146034) (xy 131.792298 -375.201623)
			(xy 131.823332 -375.26135) (xy 131.847005 -375.324358) (xy 131.862976 -375.389744) (xy 131.871018 -375.45657)
			(xy 131.871016 -375.523878) (xy 131.862968 -375.590704) (xy 131.84699 -375.656088) (xy 131.823313 -375.719094)
			(xy 131.792274 -375.778818) (xy 131.754319 -375.834404) (xy 131.732528 -375.860056) (xy 131.726716 -375.86719)
			(xy 131.720213 -375.884389) (xy 131.719828 -375.893584) (xy 131.719828 -376.386852) (xy 131.720255 -376.396037)
			(xy 131.726756 -376.413222) (xy 131.732528 -376.42038) (xy 131.754321 -376.446029) (xy 131.792271 -376.501615)
			(xy 131.823306 -376.561338) (xy 131.84698 -376.624344) (xy 131.862954 -376.689727) (xy 131.870991 -376.756492)
			(xy 161.548796 -376.756492) (xy 161.556871 -376.689554) (xy 161.572905 -376.624066) (xy 161.596667 -376.560969)
			(xy 161.627816 -376.501173) (xy 161.665902 -376.445538) (xy 161.687764 -376.419872) (xy 161.693563 -376.412729)
			(xy 161.700074 -376.395536) (xy 161.700464 -376.386344) (xy 161.700464 -375.894092) (xy 161.700043 -375.884906)
			(xy 161.693535 -375.867723) (xy 161.687764 -375.860564) (xy 161.665933 -375.834872) (xy 161.627845 -375.779241)
			(xy 161.596695 -375.719448) (xy 161.572931 -375.656354) (xy 161.556894 -375.590869) (xy 161.548816 -375.523934)
			(xy 161.548814 -375.456514) (xy 161.556886 -375.389578) (xy 161.572917 -375.324092) (xy 161.596676 -375.260996)
			(xy 161.627821 -375.201201) (xy 161.665903 -375.145566) (xy 161.687764 -375.1199) (xy 161.693551 -375.112748)
			(xy 161.70007 -375.095562) (xy 161.700464 -375.086372) (xy 161.700464 -374.928638) (xy 161.700959 -374.918511)
			(xy 161.708678 -374.899786) (xy 161.722963 -374.885428) (xy 161.741647 -374.877611) (xy 161.751772 -374.877076)
			(xy 162.468052 -374.877076) (xy 162.478168 -374.877555) (xy 162.496866 -374.885283) (xy 162.511181 -374.89958)
			(xy 162.518933 -374.918268) (xy 162.51936 -374.928384) (xy 162.51936 -375.086372) (xy 162.519793 -375.095557)
			(xy 162.526292 -375.112741) (xy 162.53206 -375.1199) (xy 162.553957 -375.145539) (xy 162.592047 -375.201176)
			(xy 162.623199 -375.260976) (xy 162.646963 -375.324076) (xy 162.662997 -375.389569) (xy 162.671071 -375.456511)
			(xy 162.671068 -375.523938) (xy 162.662989 -375.590879) (xy 162.646949 -375.65637) (xy 162.623179 -375.719468)
			(xy 162.592022 -375.779265) (xy 162.553927 -375.834899) (xy 162.53206 -375.860564) (xy 162.526249 -375.867699)
			(xy 162.519744 -375.884897) (xy 162.51936 -375.894092) (xy 162.51936 -376.386344) (xy 162.519758 -376.395532)
			(xy 162.526281 -376.412716) (xy 162.53206 -376.419872) (xy 162.553929 -376.445533) (xy 162.592021 -376.501167)
			(xy 162.623173 -376.560964) (xy 162.646939 -376.624061) (xy 162.662975 -376.689551) (xy 162.671052 -376.756491)
			(xy 162.671051 -376.823855) (xy 165.949092 -376.823855) (xy 165.949092 -376.756551) (xy 165.957136 -376.689728)
			(xy 165.973109 -376.624346) (xy 165.996782 -376.561342) (xy 166.027815 -376.501618) (xy 166.065764 -376.446032)
			(xy 166.087552 -376.42038) (xy 166.093346 -376.413233) (xy 166.099861 -376.396044) (xy 166.100252 -376.386852)
			(xy 166.100252 -375.893584) (xy 166.099838 -375.884397) (xy 166.093326 -375.867214) (xy 166.087552 -375.860056)
			(xy 166.065795 -375.834378) (xy 166.027845 -375.778796) (xy 165.996809 -375.719076) (xy 165.973134 -375.656075)
			(xy 165.957159 -375.590695) (xy 165.949112 -375.523875) (xy 165.949109 -375.456573) (xy 165.95715 -375.389752)
			(xy 165.97312 -375.324371) (xy 165.99679 -375.261368) (xy 166.02782 -375.201646) (xy 166.065766 -375.14606)
			(xy 166.087552 -375.120408) (xy 166.093334 -375.113253) (xy 166.099856 -375.09607) (xy 166.100252 -375.08688)
			(xy 166.100252 -374.928638) (xy 166.100695 -374.918467) (xy 166.10847 -374.899671) (xy 166.12285 -374.885284)
			(xy 166.141643 -374.8775) (xy 166.151814 -374.877076) (xy 166.868094 -374.877076) (xy 166.87827 -374.87747)
			(xy 166.897072 -374.88526) (xy 166.911458 -374.899655) (xy 166.919237 -374.918462) (xy 166.919656 -374.928638)
			(xy 166.919656 -375.08688) (xy 166.920085 -375.096065) (xy 166.926587 -375.113249) (xy 166.932356 -375.120408)
			(xy 166.954175 -375.146034) (xy 166.992124 -375.201624) (xy 167.023156 -375.261351) (xy 167.046827 -375.324359)
			(xy 167.062798 -375.389745) (xy 167.07084 -375.45657) (xy 167.070837 -375.523878) (xy 167.062789 -375.590703)
			(xy 167.046813 -375.656087) (xy 167.023136 -375.719093) (xy 166.992099 -375.778817) (xy 166.954146 -375.834404)
			(xy 166.932356 -375.860056) (xy 166.926548 -375.867193) (xy 166.920041 -375.88439) (xy 166.919656 -375.893584)
			(xy 166.919656 -376.386852) (xy 166.920099 -376.396035) (xy 166.926591 -376.41322) (xy 166.932356 -376.42038)
			(xy 166.954148 -376.446029) (xy 166.992097 -376.501616) (xy 167.02313 -376.56134) (xy 167.046803 -376.624345)
			(xy 167.062776 -376.689727) (xy 167.07082 -376.75655) (xy 167.07082 -376.823856) (xy 167.070813 -376.823915)
			(xy 170.34886 -376.823915) (xy 170.34886 -376.756491) (xy 170.356936 -376.689552) (xy 170.372972 -376.624063)
			(xy 170.396738 -376.560966) (xy 170.427891 -376.50117) (xy 170.465983 -376.445536) (xy 170.487848 -376.419872)
			(xy 170.493645 -376.412727) (xy 170.500158 -376.395536) (xy 170.500548 -376.386344) (xy 170.500548 -375.894092)
			(xy 170.500131 -375.884906) (xy 170.493621 -375.867722) (xy 170.487848 -375.860564) (xy 170.466014 -375.834874)
			(xy 170.427921 -375.779244) (xy 170.396766 -375.719452) (xy 170.372998 -375.656358) (xy 170.356959 -375.590871)
			(xy 170.34888 -375.523935) (xy 170.348877 -375.456513) (xy 170.35695 -375.389576) (xy 170.372984 -375.324088)
			(xy 170.396747 -375.260992) (xy 170.427896 -375.201197) (xy 170.465984 -375.145564) (xy 170.487848 -375.1199)
			(xy 170.493633 -375.112747) (xy 170.500153 -375.095562) (xy 170.500548 -375.086372) (xy 170.500548 -374.928638)
			(xy 170.501058 -374.918513) (xy 170.508775 -374.899791) (xy 170.523054 -374.885433) (xy 170.541734 -374.877614)
			(xy 170.551856 -374.877076) (xy 171.268136 -374.877076) (xy 171.278289 -374.877492) (xy 171.297038 -374.885295)
			(xy 171.311359 -374.899692) (xy 171.319062 -374.918482) (xy 171.319444 -374.928638) (xy 171.319444 -375.086372)
			(xy 171.31988 -375.095556) (xy 171.326377 -375.11274) (xy 171.332144 -375.1199) (xy 171.354041 -375.145538)
			(xy 171.392133 -375.201175) (xy 171.423285 -375.260975) (xy 171.44705 -375.324075) (xy 171.463085 -375.389568)
			(xy 171.471159 -375.45651) (xy 171.471156 -375.523938) (xy 171.463076 -375.590879) (xy 171.447036 -375.656371)
			(xy 171.423266 -375.719469) (xy 171.392108 -375.779266) (xy 171.354012 -375.8349) (xy 171.332144 -375.860564)
			(xy 171.326331 -375.867697) (xy 171.319828 -375.884897) (xy 171.319444 -375.894092) (xy 171.319444 -376.386344)
			(xy 171.319845 -376.395532) (xy 171.326366 -376.412716) (xy 171.332144 -376.419872) (xy 171.354014 -376.445533)
			(xy 171.392106 -376.501167) (xy 171.42326 -376.560963) (xy 171.447026 -376.624061) (xy 171.463063 -376.689551)
			(xy 171.47114 -376.75649) (xy 171.47114 -376.756551) (xy 174.749179 -376.756551) (xy 174.757223 -376.689728)
			(xy 174.773195 -376.624346) (xy 174.796868 -376.561342) (xy 174.8279 -376.501619) (xy 174.865848 -376.446032)
			(xy 174.887636 -376.42038) (xy 174.893428 -376.413232) (xy 174.899945 -376.396043) (xy 174.900336 -376.386852)
			(xy 174.900336 -375.893584) (xy 174.899926 -375.884397) (xy 174.893411 -375.867213) (xy 174.887636 -375.860056)
			(xy 174.86588 -375.834378) (xy 174.82793 -375.778795) (xy 174.796896 -375.719075) (xy 174.773222 -375.656074)
			(xy 174.757246 -375.590695) (xy 174.7492 -375.523875) (xy 174.749197 -375.456573) (xy 174.757238 -375.389752)
			(xy 174.773207 -375.324372) (xy 174.796876 -375.261369) (xy 174.827906 -375.201646) (xy 174.865851 -375.14606)
			(xy 174.887636 -375.120408) (xy 174.893416 -375.113251) (xy 174.89994 -375.096069) (xy 174.900336 -375.08688)
			(xy 174.900336 -374.928638) (xy 174.900795 -374.918469) (xy 174.908567 -374.899676) (xy 174.922942 -374.88529)
			(xy 174.941729 -374.877503) (xy 174.951898 -374.877076) (xy 175.668178 -374.877076) (xy 175.678353 -374.877483)
			(xy 175.697154 -374.885268) (xy 175.711541 -374.899659) (xy 175.71932 -374.918463) (xy 175.71974 -374.928638)
			(xy 175.71974 -375.08688) (xy 175.720173 -375.096064) (xy 175.726672 -375.113248) (xy 175.73244 -375.120408)
			(xy 175.75426 -375.146034) (xy 175.792209 -375.201624) (xy 175.823242 -375.261351) (xy 175.846914 -375.324359)
			(xy 175.862886 -375.389744) (xy 175.870928 -375.45657) (xy 175.870925 -375.523878) (xy 175.862877 -375.590703)
			(xy 175.8469 -375.656087) (xy 175.823223 -375.719093) (xy 175.792185 -375.778818) (xy 175.754231 -375.834404)
			(xy 175.73244 -375.860056) (xy 175.72663 -375.867191) (xy 175.720125 -375.88439) (xy 175.71974 -375.893584)
			(xy 175.71974 -376.386852) (xy 175.720186 -376.396035) (xy 175.726676 -376.413219) (xy 175.73244 -376.42038)
			(xy 175.754232 -376.446029) (xy 175.792182 -376.501615) (xy 175.823216 -376.561339) (xy 175.84689 -376.624344)
			(xy 175.862863 -376.689727) (xy 175.870907 -376.75655) (xy 175.870907 -376.823856) (xy 175.862862 -376.890679)
			(xy 175.846888 -376.956062) (xy 175.823214 -377.019066) (xy 175.792179 -377.07879) (xy 175.754228 -377.134376)
			(xy 175.73244 -377.160028) (xy 175.726642 -377.167172) (xy 175.72013 -377.184364) (xy 175.71974 -377.193556)
			(xy 175.71974 -377.35129) (xy 175.719328 -377.361464) (xy 175.711542 -377.380262) (xy 175.697152 -377.394648)
			(xy 175.678352 -377.40243) (xy 175.668178 -377.402852) (xy 174.951898 -377.402852) (xy 174.941725 -377.402438)
			(xy 174.922928 -377.39465) (xy 174.908543 -377.380262) (xy 174.90076 -377.361463) (xy 174.900336 -377.35129)
			(xy 174.900336 -377.193556) (xy 174.899939 -377.184368) (xy 174.893415 -377.167184) (xy 174.887636 -377.160028)
			(xy 174.865852 -377.134373) (xy 174.827903 -377.078787) (xy 174.79687 -377.019063) (xy 174.773197 -376.956059)
			(xy 174.757224 -376.890678) (xy 174.74918 -376.823855) (xy 174.749179 -376.756551) (xy 171.47114 -376.756551)
			(xy 171.471139 -376.823916) (xy 171.463062 -376.890855) (xy 171.447024 -376.956345) (xy 171.423257 -377.019442)
			(xy 171.392103 -377.079238) (xy 171.35401 -377.134872) (xy 171.332144 -377.160536) (xy 171.326343 -377.167678)
			(xy 171.319832 -377.184871) (xy 171.319444 -377.194064) (xy 171.319444 -377.35129) (xy 171.318965 -377.361418)
			(xy 171.311237 -377.380142) (xy 171.296948 -377.394499) (xy 171.278262 -377.402316) (xy 171.268136 -377.402852)
			(xy 170.551856 -377.402852) (xy 170.541706 -377.402415) (xy 170.522962 -377.394615) (xy 170.508642 -377.380224)
			(xy 170.500935 -377.361442) (xy 170.500548 -377.35129) (xy 170.500548 -377.194064) (xy 170.500144 -377.184876)
			(xy 170.493625 -377.167693) (xy 170.487848 -377.160536) (xy 170.465986 -377.134868) (xy 170.427894 -377.079235)
			(xy 170.396741 -377.01944) (xy 170.372974 -376.956343) (xy 170.356937 -376.890854) (xy 170.34886 -376.823915)
			(xy 167.070813 -376.823915) (xy 167.062775 -376.890679) (xy 167.046801 -376.956061) (xy 167.023128 -377.019066)
			(xy 166.992094 -377.07879) (xy 166.954144 -377.134376) (xy 166.932356 -377.160028) (xy 166.92656 -377.167173)
			(xy 166.920046 -377.184364) (xy 166.919656 -377.193556) (xy 166.919656 -377.35129) (xy 166.919228 -377.361462)
			(xy 166.911445 -377.380257) (xy 166.897061 -377.394643) (xy 166.878266 -377.402427) (xy 166.868094 -377.402852)
			(xy 166.151814 -377.402852) (xy 166.141642 -377.402425) (xy 166.122846 -377.394642) (xy 166.10846 -377.380258)
			(xy 166.100676 -377.361462) (xy 166.100252 -377.35129) (xy 166.100252 -377.193556) (xy 166.099851 -377.184368)
			(xy 166.09333 -377.167185) (xy 166.087552 -377.160028) (xy 166.065768 -377.134373) (xy 166.027818 -377.078787)
			(xy 165.996784 -377.019064) (xy 165.97311 -376.95606) (xy 165.957137 -376.890678) (xy 165.949092 -376.823855)
			(xy 162.671051 -376.823855) (xy 162.671051 -376.823915) (xy 162.662974 -376.890855) (xy 162.646937 -376.956344)
			(xy 162.623171 -377.019442) (xy 162.592017 -377.079238) (xy 162.553926 -377.134871) (xy 162.53206 -377.160536)
			(xy 162.526261 -377.167679) (xy 162.519749 -377.184871) (xy 162.51936 -377.194064) (xy 162.51936 -377.35129)
			(xy 162.518865 -377.361416) (xy 162.511141 -377.380137) (xy 162.496857 -377.394494) (xy 162.478175 -377.402313)
			(xy 162.468052 -377.402852) (xy 161.751772 -377.402852) (xy 161.741668 -377.402339) (xy 161.722999 -377.394602)
			(xy 161.708707 -377.380314) (xy 161.700964 -377.361648) (xy 161.700464 -377.351544) (xy 161.700464 -377.194064)
			(xy 161.700057 -377.184877) (xy 161.69354 -377.167693) (xy 161.687764 -377.160536) (xy 161.665905 -377.134867)
			(xy 161.627819 -377.079232) (xy 161.59667 -377.019436) (xy 161.572907 -376.95634) (xy 161.556872 -376.890852)
			(xy 161.548797 -376.823914) (xy 161.548796 -376.756492) (xy 131.870991 -376.756492) (xy 131.870998 -376.75655)
			(xy 131.870998 -376.823856) (xy 131.862953 -376.890679) (xy 131.846979 -376.956062) (xy 131.823304 -377.019067)
			(xy 131.792268 -377.07879) (xy 131.754317 -377.134376) (xy 131.732528 -377.160028) (xy 131.726728 -377.167171)
			(xy 131.720218 -377.184363) (xy 131.719828 -377.193556) (xy 131.719828 -377.35129) (xy 131.719427 -377.361465)
			(xy 131.711639 -377.380266) (xy 131.697246 -377.394653) (xy 131.678441 -377.402432) (xy 131.668266 -377.402852)
			(xy 130.951986 -377.402852) (xy 130.941826 -377.402378) (xy 130.923055 -377.394597) (xy 130.90869 -377.380225)
			(xy 130.900918 -377.36145) (xy 130.900424 -377.35129) (xy 130.900424 -377.193556) (xy 130.90003 -377.184367)
			(xy 130.893504 -377.167183) (xy 130.887724 -377.160028) (xy 130.865941 -377.134372) (xy 130.827993 -377.078786)
			(xy 130.79696 -377.019063) (xy 130.773288 -376.956059) (xy 130.757315 -376.890677) (xy 130.749271 -376.823855)
			(xy 130.74927 -376.756551) (xy 127.471206 -376.756551) (xy 127.471205 -376.823915) (xy 127.46313 -376.890853)
			(xy 127.447095 -376.956342) (xy 127.423332 -377.019438) (xy 127.392182 -377.079235) (xy 127.354095 -377.13487)
			(xy 127.332232 -377.160536) (xy 127.326429 -377.167677) (xy 127.31992 -377.184871) (xy 127.319532 -377.194064)
			(xy 127.319532 -377.35129) (xy 127.319064 -377.36142) (xy 127.311335 -377.380146) (xy 127.297042 -377.394503)
			(xy 127.278351 -377.402318) (xy 127.268224 -377.402852) (xy 126.551944 -377.402852) (xy 126.541799 -377.402343)
			(xy 126.523058 -377.394572) (xy 126.508735 -377.380202) (xy 126.501024 -377.361436) (xy 126.500636 -377.35129)
			(xy 126.500636 -377.194064) (xy 126.500235 -377.184876) (xy 126.493714 -377.167692) (xy 126.487936 -377.160536)
			(xy 126.466075 -377.134868) (xy 126.427984 -377.079235) (xy 126.396831 -377.019439) (xy 126.373065 -376.956343)
			(xy 126.357028 -376.890854) (xy 126.348951 -376.823915) (xy 123.070903 -376.823915) (xy 123.062865 -376.890679)
			(xy 123.046891 -376.956062) (xy 123.023217 -377.019066) (xy 122.992183 -377.07879) (xy 122.954232 -377.134376)
			(xy 122.932444 -377.160028) (xy 122.926646 -377.167172) (xy 122.920134 -377.184364) (xy 122.919744 -377.193556)
			(xy 122.919744 -377.35129) (xy 122.919328 -377.361463) (xy 122.911543 -377.380261) (xy 122.897154 -377.394647)
			(xy 122.878355 -377.402429) (xy 122.868182 -377.402852) (xy 122.151902 -377.402852) (xy 122.141729 -377.402434)
			(xy 122.122933 -377.394648) (xy 122.108547 -377.380261) (xy 122.100764 -377.361463) (xy 122.10034 -377.35129)
			(xy 122.10034 -377.193556) (xy 122.099942 -377.184368) (xy 122.093419 -377.167184) (xy 122.08764 -377.160028)
			(xy 122.065856 -377.134373) (xy 122.027907 -377.078787) (xy 121.996873 -377.019064) (xy 121.9732 -376.95606)
			(xy 121.957227 -376.890678) (xy 121.949183 -376.823855) (xy 121.949182 -376.756551) (xy 118.671143 -376.756551)
			(xy 118.671142 -376.823916) (xy 118.663065 -376.890855) (xy 118.647028 -376.956345) (xy 118.623261 -377.019442)
			(xy 118.592107 -377.079238) (xy 118.554014 -377.134872) (xy 118.532148 -377.160536) (xy 118.526347 -377.167678)
			(xy 118.519836 -377.184871) (xy 118.519448 -377.194064) (xy 118.519448 -377.35129) (xy 118.518965 -377.361418)
			(xy 118.511238 -377.380141) (xy 118.496951 -377.394498) (xy 118.478265 -377.402315) (xy 118.46814 -377.402852)
			(xy 117.75186 -377.402852) (xy 117.74171 -377.402412) (xy 117.722967 -377.394613) (xy 117.708647 -377.380223)
			(xy 117.700939 -377.361442) (xy 117.700552 -377.35129) (xy 117.700552 -377.194064) (xy 117.700147 -377.184876)
			(xy 117.693628 -377.167693) (xy 117.687852 -377.160536) (xy 117.66599 -377.134868) (xy 117.627898 -377.079235)
			(xy 117.596744 -377.01944) (xy 117.572977 -376.956343) (xy 117.55694 -376.890854) (xy 117.548863 -376.823915)
			(xy 87.871087 -376.823915) (xy 87.863011 -376.890853) (xy 87.846976 -376.956342) (xy 87.823211 -377.019439)
			(xy 87.792061 -377.079236) (xy 87.753972 -377.134871) (xy 87.732108 -377.160536) (xy 87.726315 -377.167684)
			(xy 87.719798 -377.184872) (xy 87.719408 -377.194064) (xy 87.719408 -377.35129) (xy 87.718867 -377.36141)
			(xy 87.711151 -377.380122) (xy 87.696882 -377.394477) (xy 87.678217 -377.402305) (xy 87.6681 -377.402852)
			(xy 86.95182 -377.402852) (xy 86.941719 -377.4023) (xy 86.923051 -377.394578) (xy 86.908757 -377.380303)
			(xy 86.901013 -377.361644) (xy 86.900512 -377.351544) (xy 86.900512 -377.194064) (xy 86.900117 -377.184875)
			(xy 86.893592 -377.167691) (xy 86.887812 -377.160536) (xy 86.865952 -377.134868) (xy 86.827862 -377.079234)
			(xy 86.79671 -377.019438) (xy 86.772945 -376.956342) (xy 86.756909 -376.890853) (xy 86.748833 -376.823915)
			(xy 83.470785 -376.823915) (xy 83.462747 -376.89068) (xy 83.446772 -376.956063) (xy 83.423097 -377.019067)
			(xy 83.392061 -377.078791) (xy 83.354109 -377.134376) (xy 83.33232 -377.160028) (xy 83.326531 -377.167179)
			(xy 83.320011 -377.184365) (xy 83.31962 -377.193556) (xy 83.31962 -377.35129) (xy 83.319227 -377.361466)
			(xy 83.311438 -377.380269) (xy 83.297042 -377.394655) (xy 83.278234 -377.402433) (xy 83.268058 -377.402852)
			(xy 82.551778 -377.402852) (xy 82.541618 -377.402385) (xy 82.522846 -377.394601) (xy 82.508481 -377.380227)
			(xy 82.500709 -377.361451) (xy 82.500216 -377.35129) (xy 82.500216 -377.193556) (xy 82.499823 -377.184367)
			(xy 82.493297 -377.167183) (xy 82.487516 -377.160028) (xy 82.465733 -377.134372) (xy 82.427785 -377.078786)
			(xy 82.396753 -377.019063) (xy 82.373081 -376.956059) (xy 82.357109 -376.890677) (xy 82.349065 -376.823855)
			(xy 82.349064 -376.756551) (xy 79.071 -376.756551) (xy 79.070999 -376.823915) (xy 79.062924 -376.890853)
			(xy 79.046888 -376.956342) (xy 79.023125 -377.019439) (xy 78.991975 -377.079235) (xy 78.953887 -377.13487)
			(xy 78.932024 -377.160536) (xy 78.926232 -377.167685) (xy 78.919714 -377.184872) (xy 78.919324 -377.194064)
			(xy 78.919324 -377.35129) (xy 78.918864 -377.36142) (xy 78.911133 -377.380148) (xy 78.896838 -377.394506)
			(xy 78.878144 -377.402319) (xy 78.868016 -377.402852) (xy 78.151736 -377.402852) (xy 78.141636 -377.402286)
			(xy 78.122969 -377.39457) (xy 78.108674 -377.380299) (xy 78.100929 -377.361643) (xy 78.100428 -377.351544)
			(xy 78.100428 -377.194064) (xy 78.100029 -377.184876) (xy 78.093507 -377.167692) (xy 78.087728 -377.160536)
			(xy 78.065867 -377.134868) (xy 78.027776 -377.079235) (xy 77.996624 -377.019439) (xy 77.972858 -376.956342)
			(xy 77.956822 -376.890853) (xy 77.948745 -376.823915) (xy 74.670697 -376.823915) (xy 74.662659 -376.890679)
			(xy 74.646685 -376.956062) (xy 74.623011 -377.019067) (xy 74.591976 -377.07879) (xy 74.554025 -377.134376)
			(xy 74.532236 -377.160028) (xy 74.526437 -377.167171) (xy 74.519926 -377.184364) (xy 74.519536 -377.193556)
			(xy 74.519536 -377.35129) (xy 74.519127 -377.361464) (xy 74.511341 -377.380264) (xy 74.49695 -377.39465)
			(xy 74.478148 -377.402431) (xy 74.467974 -377.402852) (xy 73.751694 -377.402852) (xy 73.741521 -377.402441)
			(xy 73.722724 -377.394652) (xy 73.708339 -377.380263) (xy 73.700556 -377.361463) (xy 73.700132 -377.35129)
			(xy 73.700132 -377.193556) (xy 73.699736 -377.184367) (xy 73.693212 -377.167184) (xy 73.687432 -377.160028)
			(xy 73.665648 -377.134373) (xy 73.6277 -377.078786) (xy 73.596667 -377.019063) (xy 73.572994 -376.956059)
			(xy 73.557021 -376.890677) (xy 73.548977 -376.823855) (xy 73.548976 -376.756551) (xy 48.270947 -376.756551)
			(xy 48.270947 -376.823855) (xy 48.262903 -376.890678) (xy 48.24693 -376.95606) (xy 48.223258 -377.019064)
			(xy 48.192226 -377.078788) (xy 48.154279 -377.134375) (xy 48.132492 -377.160028) (xy 48.1267 -377.167176)
			(xy 48.120183 -377.184365) (xy 48.119792 -377.193556) (xy 48.119792 -377.351544) (xy 48.119414 -377.361702)
			(xy 48.111603 -377.380457) (xy 48.097193 -377.394779) (xy 48.07839 -377.402476) (xy 48.06823 -377.402852)
			(xy 47.35195 -377.402852) (xy 47.341825 -377.402332) (xy 47.323104 -377.394619) (xy 47.308746 -377.380343)
			(xy 47.300926 -377.361666) (xy 47.300388 -377.351544) (xy 47.300388 -377.193556) (xy 47.300002 -377.184366)
			(xy 47.293472 -377.167182) (xy 47.287688 -377.160028) (xy 47.265903 -377.134373) (xy 47.227951 -377.078788)
			(xy 47.196914 -377.019066) (xy 47.173239 -376.956061) (xy 47.157265 -376.890679) (xy 47.149219 -376.823856)
			(xy 43.871178 -376.823856) (xy 43.871178 -376.823915) (xy 43.863102 -376.890854) (xy 43.847066 -376.956343)
			(xy 43.823301 -377.01944) (xy 43.79215 -377.079236) (xy 43.75406 -377.134871) (xy 43.732196 -377.160536)
			(xy 43.726401 -377.167682) (xy 43.719886 -377.184872) (xy 43.719496 -377.194064) (xy 43.719496 -377.35129)
			(xy 43.718966 -377.361412) (xy 43.711248 -377.380126) (xy 43.696976 -377.394481) (xy 43.678307 -377.402307)
			(xy 43.668188 -377.402852) (xy 42.951908 -377.402852) (xy 42.941761 -377.402373) (xy 42.923019 -377.39459)
			(xy 42.908697 -377.380211) (xy 42.900988 -377.361439) (xy 42.9006 -377.35129) (xy 42.9006 -377.194064)
			(xy 42.900207 -377.184875) (xy 42.893682 -377.167691) (xy 42.8879 -377.160536) (xy 42.86604 -377.134868)
			(xy 42.827951 -377.079233) (xy 42.7968 -377.019438) (xy 42.773036 -376.956341) (xy 42.757 -376.890853)
			(xy 42.748924 -376.823915) (xy 39.470876 -376.823915) (xy 39.462838 -376.89068) (xy 39.446863 -376.956063)
			(xy 39.423187 -377.019068) (xy 39.39215 -377.078791) (xy 39.354198 -377.134377) (xy 39.332408 -377.160028)
			(xy 39.326618 -377.167178) (xy 39.320099 -377.184365) (xy 39.319708 -377.193556) (xy 39.319708 -377.35129)
			(xy 39.31916 -377.361441) (xy 39.311397 -377.380202) (xy 39.297049 -377.394566) (xy 39.278297 -377.402349)
			(xy 39.268146 -377.402852) (xy 38.551866 -377.402852) (xy 38.541705 -377.402394) (xy 38.522933 -377.394607)
			(xy 38.508569 -377.38023) (xy 38.500797 -377.361452) (xy 38.500304 -377.35129) (xy 38.500304 -377.193556)
			(xy 38.499914 -377.184367) (xy 38.493386 -377.167183) (xy 38.487604 -377.160028) (xy 38.465821 -377.134372)
			(xy 38.427875 -377.078785) (xy 38.396843 -377.019062) (xy 38.373172 -376.956058) (xy 38.357199 -376.890677)
			(xy 38.349156 -376.823855) (xy 38.349155 -376.756551) (xy 35.071091 -376.756551) (xy 35.07109 -376.823915)
			(xy 35.063014 -376.890853) (xy 35.046979 -376.956342) (xy 35.023215 -377.019439) (xy 34.992064 -377.079236)
			(xy 34.953976 -377.134871) (xy 34.932112 -377.160536) (xy 34.926319 -377.167684) (xy 34.919802 -377.184872)
			(xy 34.919412 -377.194064) (xy 34.919412 -377.35129) (xy 34.918867 -377.36141) (xy 34.911152 -377.380121)
			(xy 34.896884 -377.394476) (xy 34.878221 -377.402304) (xy 34.868104 -377.402852) (xy 34.151824 -377.402852)
			(xy 34.141678 -377.40236) (xy 34.122936 -377.394582) (xy 34.108614 -377.380208) (xy 34.100904 -377.361438)
			(xy 34.100516 -377.35129) (xy 34.100516 -377.194064) (xy 34.10012 -377.184875) (xy 34.093596 -377.167691)
			(xy 34.087816 -377.160536) (xy 34.065955 -377.134868) (xy 34.027866 -377.079234) (xy 33.996714 -377.019438)
			(xy 33.972949 -376.956342) (xy 33.956912 -376.890853) (xy 33.948836 -376.823915) (xy 30.670788 -376.823915)
			(xy 30.66275 -376.89068) (xy 30.646775 -376.956062) (xy 30.6231 -377.019067) (xy 30.592065 -377.078791)
			(xy 30.554113 -377.134376) (xy 30.532324 -377.160028) (xy 30.526536 -377.167179) (xy 30.520015 -377.184365)
			(xy 30.519624 -377.193556) (xy 30.519624 -377.35129) (xy 30.519227 -377.361466) (xy 30.511438 -377.380267)
			(xy 30.497044 -377.394654) (xy 30.478238 -377.402433) (xy 30.468062 -377.402852) (xy 29.751782 -377.402852)
			(xy 29.741622 -377.402381) (xy 29.72285 -377.394599) (xy 29.708485 -377.380226) (xy 29.700713 -377.36145)
			(xy 29.70022 -377.35129) (xy 29.70022 -377.193556) (xy 29.699827 -377.184367) (xy 29.693301 -377.167183)
			(xy 29.68752 -377.160028) (xy 29.665737 -377.134372) (xy 29.627789 -377.078786) (xy 29.596757 -377.019063)
			(xy 29.573084 -376.956059) (xy 29.557112 -376.890677) (xy 29.549068 -376.823855) (xy 29.549067 -376.756551)
			(xy 14.058392 -376.756551) (xy 14.058392 -377.10364) (xy 14.058011 -377.113798) (xy 14.050201 -377.132553)
			(xy 14.035792 -377.146875) (xy 14.01699 -377.154572) (xy 14.00683 -377.154948) (xy 13.604494 -377.154948)
			(xy 13.594365 -377.154478) (xy 13.575642 -377.146746) (xy 13.561285 -377.132454) (xy 13.553469 -377.113766)
			(xy 13.552932 -377.10364) (xy 0.509016 -377.10364) (xy 0.509016 -378.154184) (xy 13.548868 -378.154184)
			(xy 13.548868 -377.74753) (xy 13.549289 -377.737357) (xy 13.55707 -377.718557) (xy 13.571457 -377.70417)
			(xy 13.590257 -377.696389) (xy 13.60043 -377.695968) (xy 14.002766 -377.695968) (xy 14.012939 -377.696393)
			(xy 14.031739 -377.704172) (xy 14.046126 -377.718558) (xy 14.053907 -377.737357) (xy 14.054328 -377.74753)
			(xy 14.054328 -378.154184) (xy 14.053866 -378.164334) (xy 14.046081 -378.18308) (xy 14.031697 -378.197403)
			(xy 14.012917 -378.205109) (xy 14.002766 -378.205492) (xy 13.60043 -378.205492) (xy 13.590309 -378.20495)
			(xy 13.571595 -378.197238) (xy 13.557238 -378.182969) (xy 13.549412 -378.164302) (xy 13.548868 -378.154184)
			(xy 0.509016 -378.154184) (xy 0.509016 -378.323793) (xy 27.348888 -378.323793) (xy 27.34889 -378.256368)
			(xy 27.356968 -378.189428) (xy 27.373006 -378.123938) (xy 27.396772 -378.06084) (xy 27.427925 -378.001043)
			(xy 27.466015 -377.945408) (xy 27.48788 -377.919742) (xy 27.493681 -377.9126) (xy 27.500194 -377.895407)
			(xy 27.50058 -377.886214) (xy 27.50058 -377.728734) (xy 27.501056 -377.718605) (xy 27.50878 -377.699877)
			(xy 27.52307 -377.685518) (xy 27.541761 -377.677705) (xy 27.551888 -377.677172) (xy 28.268168 -377.677172)
			(xy 28.278285 -377.677641) (xy 28.296983 -377.685374) (xy 28.311297 -377.699674) (xy 28.319048 -377.718363)
			(xy 28.319476 -377.72848) (xy 28.319476 -377.886214) (xy 28.319885 -377.895401) (xy 28.3264 -377.912585)
			(xy 28.332176 -377.919742) (xy 28.354015 -377.945428) (xy 28.392106 -378.001059) (xy 28.42326 -378.060852)
			(xy 28.447026 -378.123946) (xy 28.463064 -378.189433) (xy 28.471143 -378.256369) (xy 28.471145 -378.323734)
			(xy 31.749183 -378.323734) (xy 31.749186 -378.256427) (xy 31.757233 -378.189602) (xy 31.773209 -378.124218)
			(xy 31.796886 -378.061212) (xy 31.827924 -378.001488) (xy 31.865878 -377.945902) (xy 31.887668 -377.92025)
			(xy 31.893477 -377.913114) (xy 31.899982 -377.895916) (xy 31.900368 -377.886722) (xy 31.900368 -377.728734)
			(xy 31.900793 -377.718561) (xy 31.908572 -377.699761) (xy 31.922958 -377.685374) (xy 31.941757 -377.677593)
			(xy 31.95193 -377.677172) (xy 32.66821 -377.677172) (xy 32.678386 -377.677557) (xy 32.697188 -377.685351)
			(xy 32.711574 -377.699749) (xy 32.719352 -377.718557) (xy 32.719772 -377.728734) (xy 32.719772 -377.886722)
			(xy 32.720178 -377.89591) (xy 32.726695 -377.913094) (xy 32.732472 -377.92025) (xy 32.754234 -377.945924)
			(xy 32.792182 -378.001507) (xy 32.823216 -378.061228) (xy 32.84689 -378.12423) (xy 32.862864 -378.189609)
			(xy 32.87091 -378.256429) (xy 32.870913 -378.323732) (xy 32.870906 -378.323793) (xy 36.148976 -378.323793)
			(xy 36.148978 -378.256368) (xy 36.157056 -378.189429) (xy 36.173093 -378.123939) (xy 36.196859 -378.060841)
			(xy 36.22801 -378.001044) (xy 36.2661 -377.945408) (xy 36.287964 -377.919742) (xy 36.293775 -377.912608)
			(xy 36.300279 -377.895409) (xy 36.300664 -377.886214) (xy 36.300664 -377.728734) (xy 36.301155 -377.718607)
			(xy 36.308876 -377.699882) (xy 36.323162 -377.685523) (xy 36.341847 -377.677707) (xy 36.351972 -377.677172)
			(xy 37.068252 -377.677172) (xy 37.0784 -377.67766) (xy 37.097145 -377.685435) (xy 37.11147 -377.699811)
			(xy 37.119176 -377.718585) (xy 37.11956 -377.728734) (xy 37.11956 -377.886214) (xy 37.119972 -377.895401)
			(xy 37.126485 -377.912585) (xy 37.13226 -377.919742) (xy 37.1541 -377.945428) (xy 37.192192 -378.001058)
			(xy 37.223346 -378.060851) (xy 37.247113 -378.123946) (xy 37.263152 -378.189433) (xy 37.27123 -378.256369)
			(xy 37.271233 -378.323792) (xy 37.271233 -378.323794) (xy 40.548742 -378.323794) (xy 40.548744 -378.256367)
			(xy 40.556824 -378.189426) (xy 40.572863 -378.123935) (xy 40.596633 -378.060837) (xy 40.627789 -378.00104)
			(xy 40.665885 -377.945406) (xy 40.687752 -377.919742) (xy 40.693562 -377.912607) (xy 40.700067 -377.895408)
			(xy 40.700452 -377.886214) (xy 40.700452 -377.728734) (xy 40.700955 -377.718608) (xy 40.708674 -377.699885)
			(xy 40.722955 -377.685528) (xy 40.741637 -377.677709) (xy 40.75176 -377.677172) (xy 41.46804 -377.677172)
			(xy 41.478193 -377.677588) (xy 41.496941 -377.685392) (xy 41.511262 -377.699789) (xy 41.518965 -377.718579)
			(xy 41.519348 -377.728734) (xy 41.519348 -377.886214) (xy 41.519763 -377.8954) (xy 41.526275 -377.912584)
			(xy 41.532048 -377.919742) (xy 41.553888 -377.945427) (xy 41.591981 -378.001058) (xy 41.623136 -378.060851)
			(xy 41.646904 -378.123945) (xy 41.662943 -378.189432) (xy 41.671021 -378.256369) (xy 41.671024 -378.323792)
			(xy 41.671024 -378.323793) (xy 71.348797 -378.323793) (xy 71.348799 -378.256368) (xy 71.356877 -378.189428)
			(xy 71.372915 -378.123937) (xy 71.396682 -378.060839) (xy 71.427835 -378.001042) (xy 71.465927 -377.945407)
			(xy 71.487792 -377.919742) (xy 71.493595 -377.912601) (xy 71.500106 -377.895407) (xy 71.500492 -377.886214)
			(xy 71.500492 -377.728734) (xy 71.501053 -377.718615) (xy 71.508761 -377.699904) (xy 71.523024 -377.685548)
			(xy 71.541685 -377.67772) (xy 71.5518 -377.677172) (xy 72.26808 -377.677172) (xy 72.278229 -377.677637)
			(xy 72.296976 -377.685421) (xy 72.311299 -377.699804) (xy 72.319005 -377.718583) (xy 72.319388 -377.728734)
			(xy 72.319388 -377.886214) (xy 72.319794 -377.895402) (xy 72.326311 -377.912586) (xy 72.332088 -377.919742)
			(xy 72.353927 -377.945428) (xy 72.392017 -378.001059) (xy 72.42317 -378.060853) (xy 72.446936 -378.123947)
			(xy 72.462973 -378.189433) (xy 72.471052 -378.25637) (xy 72.471054 -378.323734) (xy 75.749092 -378.323734)
			(xy 75.749095 -378.256427) (xy 75.757142 -378.189601) (xy 75.773119 -378.124217) (xy 75.796796 -378.061212)
			(xy 75.827835 -378.001488) (xy 75.86579 -377.945902) (xy 75.88758 -377.92025) (xy 75.893378 -377.913106)
			(xy 75.899892 -377.895915) (xy 75.90028 -377.886722) (xy 75.90028 -377.728734) (xy 75.900693 -377.718559)
			(xy 75.908474 -377.699757) (xy 75.922864 -377.68537) (xy 75.941667 -377.677591) (xy 75.951842 -377.677172)
			(xy 76.668122 -377.677172) (xy 76.678299 -377.677547) (xy 76.697101 -377.685345) (xy 76.711486 -377.699746)
			(xy 76.719264 -377.718556) (xy 76.719684 -377.728734) (xy 76.719684 -377.886722) (xy 76.720087 -377.89591)
			(xy 76.726606 -377.913094) (xy 76.732384 -377.92025) (xy 76.754146 -377.945923) (xy 76.792094 -378.001507)
			(xy 76.823127 -378.061228) (xy 76.8468 -378.12423) (xy 76.862774 -378.189609) (xy 76.87082 -378.256429)
			(xy 76.870822 -378.323732) (xy 76.870815 -378.323793) (xy 80.148885 -378.323793) (xy 80.148887 -378.256368)
			(xy 80.156965 -378.189428) (xy 80.173003 -378.123938) (xy 80.196769 -378.06084) (xy 80.227921 -378.001043)
			(xy 80.266011 -377.945408) (xy 80.287876 -377.919742) (xy 80.293677 -377.9126) (xy 80.30019 -377.895407)
			(xy 80.300576 -377.886214) (xy 80.300576 -377.728734) (xy 80.301056 -377.718605) (xy 80.308779 -377.699878)
			(xy 80.323068 -377.685519) (xy 80.341758 -377.677705) (xy 80.351884 -377.677172) (xy 81.068164 -377.677172)
			(xy 81.078281 -377.677645) (xy 81.096978 -377.685376) (xy 81.111293 -377.699675) (xy 81.119044 -377.718364)
			(xy 81.119472 -377.72848) (xy 81.119472 -377.886214) (xy 81.119882 -377.895401) (xy 81.126396 -377.912585)
			(xy 81.132172 -377.919742) (xy 81.154011 -377.945428) (xy 81.192103 -378.001059) (xy 81.223256 -378.060852)
			(xy 81.247023 -378.123946) (xy 81.263061 -378.189433) (xy 81.27114 -378.256369) (xy 81.271142 -378.323792)
			(xy 81.271142 -378.323793) (xy 84.548676 -378.323793) (xy 84.548678 -378.256368) (xy 84.556756 -378.189429)
			(xy 84.572793 -378.123939) (xy 84.596559 -378.060841) (xy 84.62771 -378.001044) (xy 84.6658 -377.945408)
			(xy 84.687664 -377.919742) (xy 84.693475 -377.912608) (xy 84.699979 -377.895409) (xy 84.700364 -377.886214)
			(xy 84.700364 -377.728734) (xy 84.700855 -377.718607) (xy 84.708576 -377.699882) (xy 84.722862 -377.685523)
			(xy 84.741547 -377.677707) (xy 84.751672 -377.677172) (xy 85.467952 -377.677172) (xy 85.478068 -377.677655)
			(xy 85.496765 -377.685382) (xy 85.51108 -377.699678) (xy 85.518832 -377.718365) (xy 85.51926 -377.72848)
			(xy 85.51926 -377.886214) (xy 85.519672 -377.895401) (xy 85.526185 -377.912585) (xy 85.53196 -377.919742)
			(xy 85.5538 -377.945428) (xy 85.591892 -378.001058) (xy 85.623046 -378.060851) (xy 85.646813 -378.123946)
			(xy 85.662852 -378.189433) (xy 85.67093 -378.256369) (xy 85.670933 -378.323734) (xy 115.349234 -378.323734)
			(xy 115.349237 -378.256427) (xy 115.357283 -378.189603) (xy 115.373258 -378.12422) (xy 115.396932 -378.061215)
			(xy 115.427966 -378.00149) (xy 115.465916 -377.945903) (xy 115.487704 -377.92025) (xy 115.493505 -377.913108)
			(xy 115.500017 -377.895915) (xy 115.500404 -377.886722) (xy 115.500404 -377.728734) (xy 115.500961 -377.718583)
			(xy 115.508717 -377.699821) (xy 115.523064 -377.685456) (xy 115.541815 -377.677674) (xy 115.551966 -377.677172)
			(xy 116.268246 -377.677172) (xy 116.278411 -377.677597) (xy 116.297188 -377.685393) (xy 116.311552 -377.69978)
			(xy 116.319319 -377.718568) (xy 116.319808 -377.728734) (xy 116.319808 -377.886722) (xy 116.320206 -377.895911)
			(xy 116.326728 -377.913095) (xy 116.332508 -377.92025) (xy 116.354272 -377.945922) (xy 116.392225 -378.001505)
			(xy 116.423262 -378.061225) (xy 116.446939 -378.124227) (xy 116.462915 -378.189607) (xy 116.470962 -378.256428)
			(xy 116.470964 -378.323732) (xy 116.470957 -378.323793) (xy 119.749003 -378.323793) (xy 119.749005 -378.256368)
			(xy 119.757084 -378.189428) (xy 119.773122 -378.123937) (xy 119.796889 -378.060839) (xy 119.828043 -378.001042)
			(xy 119.866134 -377.945407) (xy 119.888 -377.919742) (xy 119.893804 -377.912602) (xy 119.900314 -377.895407)
			(xy 119.9007 -377.886214) (xy 119.9007 -377.728734) (xy 119.901253 -377.718614) (xy 119.908963 -377.699902)
			(xy 119.923228 -377.685546) (xy 119.941892 -377.677718) (xy 119.952008 -377.677172) (xy 120.668288 -377.677172)
			(xy 120.678438 -377.677631) (xy 120.697185 -377.685417) (xy 120.711507 -377.699802) (xy 120.719213 -377.718582)
			(xy 120.719596 -377.728734) (xy 120.719596 -377.886214) (xy 120.72 -377.895402) (xy 120.726518 -377.912586)
			(xy 120.732296 -377.919742) (xy 120.754135 -377.945428) (xy 120.792224 -378.00106) (xy 120.823376 -378.060853)
			(xy 120.847142 -378.123947) (xy 120.86318 -378.189434) (xy 120.871258 -378.25637) (xy 120.87126 -378.323734)
			(xy 124.149298 -378.323734) (xy 124.149301 -378.256426) (xy 124.157348 -378.189601) (xy 124.173325 -378.124217)
			(xy 124.197003 -378.061211) (xy 124.228042 -378.001487) (xy 124.265997 -377.945902) (xy 124.287788 -377.92025)
			(xy 124.293587 -377.913106) (xy 124.300101 -377.895915) (xy 124.300488 -377.886722) (xy 124.300488 -377.728734)
			(xy 124.300893 -377.718558) (xy 124.308676 -377.699755) (xy 124.323068 -377.685367) (xy 124.341874 -377.67759)
			(xy 124.35205 -377.677172) (xy 125.06833 -377.677172) (xy 125.078508 -377.67754) (xy 125.09731 -377.685341)
			(xy 125.111695 -377.699744) (xy 125.119473 -377.718556) (xy 125.119892 -377.728734) (xy 125.119892 -377.886722)
			(xy 125.120293 -377.89591) (xy 125.126813 -377.913094) (xy 125.132592 -377.92025) (xy 125.154353 -377.945924)
			(xy 125.192301 -378.001508) (xy 125.223334 -378.061229) (xy 125.247006 -378.12423) (xy 125.26298 -378.189609)
			(xy 125.271026 -378.256429) (xy 125.271028 -378.323732) (xy 125.271028 -378.323734) (xy 128.549089 -378.323734)
			(xy 128.549092 -378.256427) (xy 128.557139 -378.189602) (xy 128.573116 -378.124218) (xy 128.596793 -378.061212)
			(xy 128.627831 -378.001488) (xy 128.665786 -377.945902) (xy 128.687576 -377.92025) (xy 128.693374 -377.913105)
			(xy 128.699888 -377.895915) (xy 128.700276 -377.886722) (xy 128.700276 -377.728734) (xy 128.700693 -377.71856)
			(xy 128.708474 -377.699759) (xy 128.722862 -377.685371) (xy 128.741664 -377.677592) (xy 128.751838 -377.677172)
			(xy 129.468118 -377.677172) (xy 129.478295 -377.67755) (xy 129.497097 -377.685347) (xy 129.511482 -377.699747)
			(xy 129.51926 -377.718557) (xy 129.51968 -377.728734) (xy 129.51968 -377.886722) (xy 129.520084 -377.89591)
			(xy 129.526602 -377.913094) (xy 129.53238 -377.92025) (xy 129.554142 -377.945923) (xy 129.59209 -378.001507)
			(xy 129.623123 -378.061228) (xy 129.646797 -378.12423) (xy 129.662771 -378.189609) (xy 129.670817 -378.256429)
			(xy 129.670819 -378.323732) (xy 129.670819 -378.323734) (xy 159.349143 -378.323734) (xy 159.349146 -378.256427)
			(xy 159.357192 -378.189603) (xy 159.373167 -378.12422) (xy 159.396842 -378.061214) (xy 159.427877 -378.00149)
			(xy 159.465827 -377.945902) (xy 159.487616 -377.92025) (xy 159.493418 -377.913109) (xy 159.499929 -377.895915)
			(xy 159.500316 -377.886722) (xy 159.500316 -377.728734) (xy 159.500791 -377.718567) (xy 159.508561 -377.699778)
			(xy 159.522931 -377.685392) (xy 159.541712 -377.677602) (xy 159.551878 -377.677172) (xy 160.268158 -377.677172)
			(xy 160.278331 -377.677599) (xy 160.297131 -377.685377) (xy 160.311519 -377.699762) (xy 160.319299 -377.718561)
			(xy 160.31972 -377.728734) (xy 160.31972 -377.886722) (xy 160.320115 -377.895911) (xy 160.326639 -377.913095)
			(xy 160.33242 -377.92025) (xy 160.354183 -377.945923) (xy 160.392136 -378.001505) (xy 160.423172 -378.061226)
			(xy 160.446848 -378.124227) (xy 160.462824 -378.189608) (xy 160.470871 -378.256429) (xy 160.470874 -378.323732)
			(xy 160.470867 -378.323793) (xy 163.748912 -378.323793) (xy 163.748914 -378.256367) (xy 163.756993 -378.189427)
			(xy 163.773031 -378.123937) (xy 163.796799 -378.060839) (xy 163.827953 -378.001042) (xy 163.866046 -377.945407)
			(xy 163.887912 -377.919742) (xy 163.893717 -377.912603) (xy 163.900226 -377.895408) (xy 163.900612 -377.886214)
			(xy 163.900612 -377.728734) (xy 163.901154 -377.718613) (xy 163.908865 -377.699898) (xy 163.923134 -377.685542)
			(xy 163.941802 -377.677716) (xy 163.95192 -377.677172) (xy 164.6682 -377.677172) (xy 164.678351 -377.677621)
			(xy 164.697098 -377.685411) (xy 164.71142 -377.699799) (xy 164.719125 -377.718582) (xy 164.719508 -377.728734)
			(xy 164.719508 -377.886214) (xy 164.71991 -377.895402) (xy 164.726429 -377.912586) (xy 164.732208 -377.919742)
			(xy 164.754046 -377.945428) (xy 164.792135 -378.00106) (xy 164.823286 -378.060853) (xy 164.847052 -378.123948)
			(xy 164.863089 -378.189434) (xy 164.871167 -378.25637) (xy 164.871169 -378.323734) (xy 168.149231 -378.323734)
			(xy 168.149234 -378.256427) (xy 168.15728 -378.189604) (xy 168.173254 -378.12422) (xy 168.196928 -378.061215)
			(xy 168.227963 -378.00149) (xy 168.265912 -377.945903) (xy 168.2877 -377.92025) (xy 168.2935 -377.913107)
			(xy 168.300013 -377.895915) (xy 168.3004 -377.886722) (xy 168.3004 -377.728734) (xy 168.30096 -377.718583)
			(xy 168.308717 -377.699822) (xy 168.323062 -377.685457) (xy 168.341812 -377.677675) (xy 168.351962 -377.677172)
			(xy 169.068242 -377.677172) (xy 169.078407 -377.6776) (xy 169.097183 -377.685394) (xy 169.111548 -377.699781)
			(xy 169.119315 -377.718569) (xy 169.119804 -377.728734) (xy 169.119804 -377.886722) (xy 169.120203 -377.89591)
			(xy 169.126724 -377.913095) (xy 169.132504 -377.92025) (xy 169.154265 -377.945924) (xy 169.192212 -378.001508)
			(xy 169.223244 -378.061229) (xy 169.246916 -378.124231) (xy 169.26289 -378.18961) (xy 169.270935 -378.256429)
			(xy 169.270937 -378.323732) (xy 169.270937 -378.323734) (xy 172.548998 -378.323734) (xy 172.549001 -378.256426)
			(xy 172.557048 -378.189601) (xy 172.573025 -378.124217) (xy 172.596703 -378.061211) (xy 172.627742 -378.001487)
			(xy 172.665697 -377.945902) (xy 172.687488 -377.92025) (xy 172.693287 -377.913106) (xy 172.699801 -377.895915)
			(xy 172.700188 -377.886722) (xy 172.700188 -377.728734) (xy 172.700593 -377.718558) (xy 172.708376 -377.699755)
			(xy 172.722768 -377.685367) (xy 172.741574 -377.67759) (xy 172.75175 -377.677172) (xy 173.46803 -377.677172)
			(xy 173.478208 -377.67754) (xy 173.49701 -377.685341) (xy 173.511395 -377.699744) (xy 173.519173 -377.718556)
			(xy 173.519592 -377.728734) (xy 173.519592 -377.886722) (xy 173.519993 -377.89591) (xy 173.526513 -377.913094)
			(xy 173.532292 -377.92025) (xy 173.554053 -377.945924) (xy 173.592001 -378.001508) (xy 173.623034 -378.061229)
			(xy 173.646706 -378.12423) (xy 173.66268 -378.189609) (xy 173.670726 -378.256429) (xy 173.670728 -378.323732)
			(xy 173.662687 -378.390552) (xy 173.646718 -378.455932) (xy 173.623049 -378.518936) (xy 173.592021 -378.578659)
			(xy 173.554077 -378.634245) (xy 173.532292 -378.659898) (xy 173.526513 -378.667056) (xy 173.519988 -378.684237)
			(xy 173.519592 -378.693426) (xy 173.519592 -378.766811) (xy 193.48983 -378.766811) (xy 193.48983 -378.633249)
			(xy 193.497894 -378.499931) (xy 193.513994 -378.367343) (xy 193.538069 -378.235969) (xy 193.570032 -378.106288)
			(xy 193.609767 -377.978774) (xy 193.657129 -377.853891) (xy 193.711944 -377.732096) (xy 193.774014 -377.613833)
			(xy 193.84311 -377.499534) (xy 193.918982 -377.389614) (xy 194.001352 -377.284477) (xy 194.08992 -377.184504)
			(xy 194.184362 -377.090062) (xy 194.284335 -377.001494) (xy 194.389472 -376.919124) (xy 194.499392 -376.843252)
			(xy 194.613691 -376.774156) (xy 194.731954 -376.712086) (xy 194.853749 -376.657271) (xy 194.978632 -376.609909)
			(xy 195.106146 -376.570174) (xy 195.235827 -376.538211) (xy 195.367201 -376.514136) (xy 195.499789 -376.498036)
			(xy 195.633107 -376.489972) (xy 195.766669 -376.489972) (xy 195.899987 -376.498036) (xy 196.032575 -376.514136)
			(xy 196.163949 -376.538211) (xy 196.29363 -376.570174) (xy 196.421144 -376.609909) (xy 196.546027 -376.657271)
			(xy 196.667822 -376.712086) (xy 196.786085 -376.774156) (xy 196.900384 -376.843252) (xy 197.010304 -376.919124)
			(xy 197.115441 -377.001494) (xy 197.215414 -377.090062) (xy 197.309856 -377.184504) (xy 197.398424 -377.284477)
			(xy 197.480794 -377.389614) (xy 197.556666 -377.499534) (xy 197.625762 -377.613833) (xy 197.687832 -377.732096)
			(xy 197.742647 -377.853891) (xy 197.790009 -377.978774) (xy 197.829744 -378.106288) (xy 197.861707 -378.235969)
			(xy 197.862607 -378.240882) (xy 204.068504 -378.240882) (xy 204.076595 -378.185806) (xy 204.092605 -378.132491)
			(xy 204.116196 -378.082071) (xy 204.146866 -378.035615) (xy 204.183964 -377.994111) (xy 204.226701 -377.958442)
			(xy 204.274169 -377.929363) (xy 204.299566 -377.917964) (xy 204.31379 -377.911868) (xy 204.3303 -377.886722)
			(xy 204.3303 -374.878092) (xy 204.329857 -374.868543) (xy 204.322824 -374.850787) (xy 204.316584 -374.843548)
			(xy 204.300697 -374.825797) (xy 204.273817 -374.786469) (xy 204.25311 -374.743569) (xy 204.23904 -374.698059)
			(xy 204.231922 -374.650958) (xy 204.231494 -374.62714) (xy 204.231494 -371.243098) (xy 204.231071 -371.233029)
			(xy 204.223349 -371.214431) (xy 204.216508 -371.20703) (xy 204.18298 -371.173502) (xy 204.165683 -371.155513)
			(xy 204.136361 -371.115135) (xy 204.113715 -371.070668) (xy 204.098302 -371.023206) (xy 204.090502 -370.973917)
			(xy 204.090016 -370.948966) (xy 204.090016 -367.26876) (xy 204.090486 -367.24381) (xy 204.098304 -367.194525)
			(xy 204.113727 -367.147067) (xy 204.136375 -367.102602) (xy 204.165692 -367.062221) (xy 204.18298 -367.044224)
			(xy 204.446632 -366.780572) (xy 204.464604 -366.763255) (xy 204.504984 -366.733927) (xy 204.549455 -366.711277)
			(xy 204.596921 -366.695864) (xy 204.646215 -366.688067) (xy 204.671168 -366.687608) (xy 208.09839 -366.687608)
			(xy 208.123339 -366.688112) (xy 208.172622 -366.695922) (xy 208.220079 -366.711337) (xy 208.264545 -366.733977)
			(xy 208.304928 -366.763287) (xy 208.322926 -366.780572) (xy 208.566512 -367.024158) (xy 208.583789 -367.042165)
			(xy 208.613114 -367.082538) (xy 208.635764 -367.127001) (xy 208.651181 -367.174459) (xy 208.658986 -367.223744)
			(xy 208.659476 -367.248694) (xy 208.659476 -369.788186) (xy 208.659999 -369.79819) (xy 208.667649 -369.816677)
			(xy 208.681791 -369.830829) (xy 208.700273 -369.838494) (xy 208.710276 -369.838986) (xy 208.785968 -369.838986)
			(xy 208.810919 -369.839447) (xy 208.860203 -369.847269) (xy 208.907661 -369.862694) (xy 208.952126 -369.885344)
			(xy 208.992507 -369.914662) (xy 209.010504 -369.93195) (xy 209.67573 -370.597176) (xy 209.683128 -370.604019)
			(xy 209.701729 -370.611738) (xy 209.711798 -370.612162) (xy 210.06562 -370.612162) (xy 210.090569 -370.61266)
			(xy 210.139852 -370.620474) (xy 210.187309 -370.635891) (xy 210.231774 -370.658532) (xy 210.272157 -370.687842)
			(xy 210.290156 -370.705126) (xy 210.516978 -370.931948) (xy 210.534292 -370.949922) (xy 210.563614 -370.990303)
			(xy 210.586257 -371.034774) (xy 210.601666 -371.08224) (xy 210.609459 -371.131532) (xy 210.609942 -371.156484)
			(xy 210.609942 -371.380512) (xy 210.610311 -371.390539) (xy 210.617993 -371.409064) (xy 210.632181 -371.423238)
			(xy 210.650714 -371.4309) (xy 210.660742 -371.431312) (xy 216.45245 -371.431312) (xy 216.462519 -371.430884)
			(xy 216.481119 -371.423168) (xy 216.488518 -371.416326) (xy 217.302334 -370.60251) (xy 217.309167 -370.595105)
			(xy 217.31689 -370.576509) (xy 217.31732 -370.566442) (xy 217.31732 -367.318036) (xy 217.317803 -367.293087)
			(xy 217.325622 -367.243804) (xy 217.341043 -367.196347) (xy 217.363688 -367.151882) (xy 217.392999 -367.111499)
			(xy 217.410284 -367.0935) (xy 217.733118 -366.770666) (xy 217.751095 -366.753355) (xy 217.791474 -366.724026)
			(xy 217.835943 -366.701376) (xy 217.883409 -366.685961) (xy 217.932701 -366.678162) (xy 217.957654 -366.677702)
			(xy 221.342458 -366.677702) (xy 221.367409 -366.678165) (xy 221.416693 -366.685986) (xy 221.464151 -366.70141)
			(xy 221.508616 -366.724059) (xy 221.548997 -366.753378) (xy 221.566994 -366.770666) (xy 221.81058 -367.014252)
			(xy 221.827896 -367.032223) (xy 221.857217 -367.072606) (xy 221.879861 -367.117077) (xy 221.895269 -367.164543)
			(xy 221.903062 -367.213836) (xy 221.903544 -367.238788) (xy 221.903544 -370.592604) (xy 221.903956 -370.602675)
			(xy 221.911685 -370.621273) (xy 221.91853 -370.628672) (xy 222.004382 -370.714524) (xy 222.021685 -370.732507)
			(xy 222.051008 -370.772886) (xy 222.073654 -370.817355) (xy 222.089065 -370.864819) (xy 222.096861 -370.914109)
			(xy 222.097346 -370.93906) (xy 222.097346 -373.42191) (xy 222.097754 -373.431981) (xy 222.105485 -373.45058)
			(xy 222.112332 -373.457978) (xy 223.764602 -375.110248) (xy 223.772013 -375.117074) (xy 223.790604 -375.124804)
			(xy 223.80067 -375.125234) (xy 225.416872 -375.125234) (xy 225.426942 -375.124811) (xy 225.445541 -375.117091)
			(xy 225.45294 -375.110248) (xy 226.51339 -374.049798) (xy 226.520222 -374.042392) (xy 226.527947 -374.023797)
			(xy 226.528376 -374.01373) (xy 226.528376 -372.656862) (xy 226.528859 -372.631912) (xy 226.536676 -372.582629)
			(xy 226.552096 -372.535172) (xy 226.574741 -372.490706) (xy 226.604054 -372.450324) (xy 226.62134 -372.432326)
			(xy 227.816156 -371.23751) (xy 227.822978 -371.230095) (xy 227.83071 -371.211508) (xy 227.831142 -371.201442)
			(xy 227.831142 -370.936012) (xy 227.831666 -370.911064) (xy 227.839474 -370.861783) (xy 227.854885 -370.814326)
			(xy 227.877521 -370.76986) (xy 227.906825 -370.729476) (xy 227.924106 -370.711476) (xy 228.003608 -370.631974)
			(xy 228.010453 -370.624578) (xy 228.01817 -370.605976) (xy 228.018594 -370.595906) (xy 228.018594 -367.245138)
			(xy 228.019057 -367.220188) (xy 228.026878 -367.170903) (xy 228.042302 -367.123445) (xy 228.064952 -367.07898)
			(xy 228.09427 -367.038599) (xy 228.111558 -367.020602) (xy 228.364796 -366.767364) (xy 228.382783 -366.750063)
			(xy 228.423159 -366.720733) (xy 228.467626 -366.698081) (xy 228.515089 -366.682663) (xy 228.56438 -366.674861)
			(xy 228.589332 -366.6744) (xy 232.007156 -366.6744) (xy 232.032106 -366.674865) (xy 232.081391 -366.682685)
			(xy 232.128849 -366.698109) (xy 232.173314 -366.720758) (xy 232.213695 -366.750076) (xy 232.231692 -366.767364)
			(xy 232.48493 -367.020602) (xy 232.502233 -367.038587) (xy 232.531563 -367.078963) (xy 232.554215 -367.123431)
			(xy 232.569632 -367.170894) (xy 232.577433 -367.220186) (xy 232.577894 -367.245138) (xy 232.577894 -370.60251)
			(xy 232.578289 -370.612583) (xy 232.586028 -370.631182) (xy 232.59288 -370.638578) (xy 232.652824 -370.698522)
			(xy 232.670133 -370.716499) (xy 232.699454 -370.756881) (xy 232.722098 -370.801351) (xy 232.737507 -370.848816)
			(xy 232.745303 -370.898106) (xy 232.745788 -370.923058) (xy 232.745788 -371.05971) (xy 232.746185 -371.069783)
			(xy 232.753923 -371.088382) (xy 232.760774 -371.095778) (xy 233.402886 -371.73789) (xy 233.420173 -371.755888)
			(xy 233.449498 -371.796263) (xy 233.472147 -371.840728) (xy 233.487562 -371.888188) (xy 233.495363 -371.937476)
			(xy 233.49585 -371.962426) (xy 233.49585 -375.346214) (xy 233.496255 -375.356286) (xy 233.503988 -375.374884)
			(xy 233.510836 -375.382282) (xy 234.427522 -376.298968) (xy 235.473748 -376.298968) (xy 235.473748 -368.60607)
			(xy 235.474244 -368.581121) (xy 235.482059 -368.531838) (xy 235.497476 -368.484382) (xy 235.520118 -368.439916)
			(xy 235.549428 -368.399533) (xy 235.566712 -368.381534) (xy 235.993178 -367.955068) (xy 236.011173 -367.937776)
			(xy 236.051547 -367.908445) (xy 236.096012 -367.885791) (xy 236.143473 -367.870371) (xy 236.192762 -367.862567)
			(xy 236.217714 -367.862104) (xy 265.631168 -367.862104) (xy 265.656119 -367.86256) (xy 265.705404 -367.870382)
			(xy 265.752862 -367.885808) (xy 265.797327 -367.908459) (xy 265.837707 -367.937779) (xy 265.855704 -367.955068)
			(xy 266.408408 -368.507772) (xy 266.425691 -368.525774) (xy 266.455015 -368.566148) (xy 266.477664 -368.610612)
			(xy 266.49308 -368.658072) (xy 266.500884 -368.707358) (xy 266.501372 -368.732308) (xy 266.501372 -370.523704)
			(xy 286.928752 -370.523704) (xy 286.928753 -370.456278) (xy 286.936831 -370.389338) (xy 286.952869 -370.323848)
			(xy 286.976637 -370.26075) (xy 287.007792 -370.200954) (xy 287.045885 -370.14532) (xy 287.067752 -370.119656)
			(xy 287.073556 -370.112516) (xy 287.080065 -370.095321) (xy 287.080452 -370.086128) (xy 287.080452 -369.928902)
			(xy 287.080929 -369.918774) (xy 287.088658 -369.900051) (xy 287.102947 -369.885694) (xy 287.121634 -369.877877)
			(xy 287.13176 -369.87734) (xy 287.84804 -369.87734) (xy 287.85817 -369.877684) (xy 287.876882 -369.885453)
			(xy 287.891196 -369.899792) (xy 287.898933 -369.918517) (xy 287.899348 -369.928648) (xy 287.899348 -370.086128)
			(xy 287.899756 -370.095315) (xy 287.906273 -370.112499) (xy 287.912048 -370.119656) (xy 287.933902 -370.14533)
			(xy 287.971994 -370.200962) (xy 288.003149 -370.260757) (xy 288.026916 -370.323852) (xy 288.042954 -370.389341)
			(xy 288.051031 -370.456279) (xy 288.051032 -370.523644) (xy 291.329071 -370.523644) (xy 291.329073 -370.456338)
			(xy 291.337118 -370.389515) (xy 291.353092 -370.324132) (xy 291.376766 -370.261127) (xy 291.407801 -370.201403)
			(xy 291.445751 -370.145816) (xy 291.46754 -370.120164) (xy 291.473339 -370.113021) (xy 291.479851 -370.095829)
			(xy 291.48024 -370.086636) (xy 291.48024 -369.928902) (xy 291.480665 -369.91873) (xy 291.48845 -369.899935)
			(xy 291.502835 -369.88555) (xy 291.52163 -369.877765) (xy 291.531802 -369.87734) (xy 292.248082 -369.87734)
			(xy 292.258253 -369.877778) (xy 292.277047 -369.885558) (xy 292.291433 -369.899939) (xy 292.299218 -369.918731)
			(xy 292.299644 -369.928902) (xy 292.299644 -370.086636) (xy 292.30005 -370.095823) (xy 292.306568 -370.113007)
			(xy 292.312344 -370.120164) (xy 292.33412 -370.145826) (xy 292.372071 -370.20141) (xy 292.403105 -370.261132)
			(xy 292.426779 -370.324136) (xy 292.442754 -370.389517) (xy 292.450799 -370.456339) (xy 292.4508 -370.523643)
			(xy 292.450793 -370.523704) (xy 295.72884 -370.523704) (xy 295.728841 -370.456278) (xy 295.736918 -370.389339)
			(xy 295.752956 -370.323848) (xy 295.776723 -370.260751) (xy 295.807878 -370.200955) (xy 295.84597 -370.145321)
			(xy 295.867836 -370.119656) (xy 295.873638 -370.112515) (xy 295.880149 -370.095321) (xy 295.880536 -370.086128)
			(xy 295.880536 -369.928902) (xy 295.881028 -369.918776) (xy 295.888755 -369.900056) (xy 295.903039 -369.885699)
			(xy 295.92172 -369.877879) (xy 295.931844 -369.87734) (xy 296.648124 -369.87734) (xy 296.658285 -369.877703)
			(xy 296.677045 -369.885514) (xy 296.691369 -369.899929) (xy 296.699061 -369.918739) (xy 296.699432 -369.928902)
			(xy 296.699432 -370.086128) (xy 296.699844 -370.095315) (xy 296.706358 -370.112498) (xy 296.712132 -370.119656)
			(xy 296.733983 -370.145332) (xy 296.77207 -370.200965) (xy 296.803219 -370.26076) (xy 296.826983 -370.323856)
			(xy 296.843018 -370.389343) (xy 296.851095 -370.45628) (xy 296.851096 -370.523702) (xy 296.851096 -370.523704)
			(xy 300.128631 -370.523704) (xy 300.128632 -370.456278) (xy 300.136709 -370.389339) (xy 300.152747 -370.323849)
			(xy 300.176513 -370.260751) (xy 300.207667 -370.200955) (xy 300.245758 -370.145321) (xy 300.267624 -370.119656)
			(xy 300.273425 -370.112514) (xy 300.279936 -370.095321) (xy 300.280324 -370.086128) (xy 300.280324 -369.928902)
			(xy 300.280828 -369.918777) (xy 300.288552 -369.900059) (xy 300.302833 -369.885704) (xy 300.32151 -369.877882)
			(xy 300.331632 -369.87734) (xy 301.047912 -369.87734) (xy 301.058072 -369.877712) (xy 301.076832 -369.885519)
			(xy 301.091157 -369.899932) (xy 301.098849 -369.91874) (xy 301.09922 -369.928902) (xy 301.09922 -370.086128)
			(xy 301.099612 -370.095317) (xy 301.106138 -370.112502) (xy 301.11192 -370.119656) (xy 301.133771 -370.145331)
			(xy 301.171859 -370.200965) (xy 301.203009 -370.26076) (xy 301.226773 -370.323855) (xy 301.242809 -370.389343)
			(xy 301.250886 -370.45628) (xy 301.250887 -370.523644) (xy 330.92919 -370.523644) (xy 330.929191 -370.456338)
			(xy 330.937237 -370.389514) (xy 330.953212 -370.324131) (xy 330.976887 -370.261126) (xy 331.007923 -370.201402)
			(xy 331.045875 -370.145816) (xy 331.067664 -370.120164) (xy 331.073466 -370.113023) (xy 331.079976 -370.095829)
			(xy 331.080364 -370.086636) (xy 331.080364 -369.928902) (xy 331.080766 -369.918727) (xy 331.088555 -369.899928)
			(xy 331.102948 -369.885542) (xy 331.121751 -369.877761) (xy 331.131926 -369.87734) (xy 331.848206 -369.87734)
			(xy 331.858364 -369.877829) (xy 331.877134 -369.885605) (xy 331.891499 -369.899973) (xy 331.899273 -369.918744)
			(xy 331.899768 -369.928902) (xy 331.899768 -370.086636) (xy 331.900168 -370.095824) (xy 331.90669 -370.113008)
			(xy 331.912468 -370.120164) (xy 331.934244 -370.145826) (xy 331.972193 -370.201411) (xy 332.003226 -370.261133)
			(xy 332.026899 -370.324137) (xy 332.042873 -370.389518) (xy 332.050918 -370.456339) (xy 332.050919 -370.523643)
			(xy 332.050912 -370.523703) (xy 335.328983 -370.523703) (xy 335.328984 -370.456279) (xy 335.33706 -370.389341)
			(xy 335.353096 -370.323852) (xy 335.376859 -370.260754) (xy 335.408009 -370.200957) (xy 335.446097 -370.145322)
			(xy 335.46796 -370.119656) (xy 335.473765 -370.112517) (xy 335.480273 -370.095322) (xy 335.48066 -370.086128)
			(xy 335.48066 -369.928902) (xy 335.481129 -369.918773) (xy 335.48886 -369.900048) (xy 335.503152 -369.885691)
			(xy 335.521841 -369.877875) (xy 335.531968 -369.87734) (xy 336.248248 -369.87734) (xy 336.25841 -369.877683)
			(xy 336.277171 -369.885502) (xy 336.291494 -369.899923) (xy 336.299185 -369.918737) (xy 336.299556 -369.928902)
			(xy 336.299556 -370.086128) (xy 336.299963 -370.095315) (xy 336.30648 -370.112499) (xy 336.312256 -370.119656)
			(xy 336.33411 -370.14533) (xy 336.372202 -370.200962) (xy 336.403355 -370.260757) (xy 336.427122 -370.323853)
			(xy 336.44316 -370.389341) (xy 336.451237 -370.456279) (xy 336.451238 -370.523644) (xy 339.729277 -370.523644)
			(xy 339.729279 -370.456338) (xy 339.737324 -370.389514) (xy 339.753299 -370.324131) (xy 339.776973 -370.261126)
			(xy 339.808008 -370.201402) (xy 339.845959 -370.145816) (xy 339.867748 -370.120164) (xy 339.873548 -370.113022)
			(xy 339.880059 -370.095829) (xy 339.880448 -370.086636) (xy 339.880448 -369.928902) (xy 339.880866 -369.918729)
			(xy 339.888652 -369.899933) (xy 339.903039 -369.885547) (xy 339.921837 -369.877764) (xy 339.93201 -369.87734)
			(xy 340.64829 -369.87734) (xy 340.658461 -369.877772) (xy 340.677256 -369.885554) (xy 340.691641 -369.899937)
			(xy 340.699426 -369.918731) (xy 340.699852 -369.928902) (xy 340.699852 -370.086636) (xy 340.700256 -370.095824)
			(xy 340.706775 -370.113007) (xy 340.712552 -370.120164) (xy 340.734328 -370.145826) (xy 340.772278 -370.201411)
			(xy 340.803312 -370.261133) (xy 340.826986 -370.324136) (xy 340.84296 -370.389517) (xy 340.851005 -370.456339)
			(xy 340.851006 -370.523643) (xy 340.851006 -370.523644) (xy 344.129068 -370.523644) (xy 344.129069 -370.456338)
			(xy 344.137115 -370.389515) (xy 344.153089 -370.324132) (xy 344.176763 -370.261127) (xy 344.207797 -370.201403)
			(xy 344.245748 -370.145816) (xy 344.267536 -370.120164) (xy 344.273335 -370.113021) (xy 344.279847 -370.095829)
			(xy 344.280236 -370.086636) (xy 344.280236 -369.928902) (xy 344.280735 -369.918745) (xy 344.288508 -369.899976)
			(xy 344.302873 -369.885611) (xy 344.321641 -369.877836) (xy 344.331798 -369.87734) (xy 345.048078 -369.87734)
			(xy 345.058248 -369.877782) (xy 345.077043 -369.88556) (xy 345.091429 -369.89994) (xy 345.099214 -369.918732)
			(xy 345.09964 -369.928902) (xy 345.09964 -370.086636) (xy 345.100046 -370.095823) (xy 345.106564 -370.113007)
			(xy 345.11234 -370.120164) (xy 345.134116 -370.145826) (xy 345.172067 -370.20141) (xy 345.203102 -370.261132)
			(xy 345.226776 -370.324136) (xy 345.242751 -370.389517) (xy 345.250796 -370.456339) (xy 345.250797 -370.523643)
			(xy 345.250797 -370.523644) (xy 374.929099 -370.523644) (xy 374.9291 -370.456338) (xy 374.937146 -370.389514)
			(xy 374.953121 -370.32413) (xy 374.976797 -370.261125) (xy 375.007834 -370.201402) (xy 375.045787 -370.145816)
			(xy 375.067576 -370.120164) (xy 375.073368 -370.113015) (xy 375.079886 -370.095828) (xy 375.080276 -370.086636)
			(xy 375.080276 -369.928902) (xy 375.080666 -369.918726) (xy 375.088458 -369.899924) (xy 375.102854 -369.885538)
			(xy 375.121661 -369.877759) (xy 375.131838 -369.87734) (xy 375.848118 -369.87734) (xy 375.858277 -369.877818)
			(xy 375.877047 -369.885599) (xy 375.891412 -369.89997) (xy 375.899185 -369.918743) (xy 375.89968 -369.928902)
			(xy 375.89968 -370.086636) (xy 375.900077 -370.095824) (xy 375.9066 -370.113008) (xy 375.91238 -370.120164)
			(xy 375.934155 -370.145826) (xy 375.972103 -370.201412) (xy 376.003136 -370.261134) (xy 376.026809 -370.324137)
			(xy 376.042782 -370.389518) (xy 376.050827 -370.456339) (xy 376.050828 -370.523643) (xy 376.050821 -370.523703)
			(xy 379.328892 -370.523703) (xy 379.328893 -370.456279) (xy 379.336969 -370.38934) (xy 379.353005 -370.323851)
			(xy 379.376769 -370.260754) (xy 379.40792 -370.200957) (xy 379.446008 -370.145322) (xy 379.467872 -370.119656)
			(xy 379.473678 -370.112518) (xy 379.480185 -370.095322) (xy 379.480572 -370.086128) (xy 379.480572 -369.928902)
			(xy 379.481029 -369.918772) (xy 379.488762 -369.900044) (xy 379.503058 -369.885687) (xy 379.521752 -369.877873)
			(xy 379.53188 -369.87734) (xy 380.24816 -369.87734) (xy 380.258316 -369.877755) (xy 380.277076 -369.885545)
			(xy 380.291402 -369.899945) (xy 380.299096 -369.918743) (xy 380.299468 -369.928902) (xy 380.299468 -370.086128)
			(xy 380.299872 -370.095316) (xy 380.306391 -370.1125) (xy 380.312168 -370.119656) (xy 380.334021 -370.14533)
			(xy 380.372112 -370.200963) (xy 380.403265 -370.260758) (xy 380.427032 -370.323853) (xy 380.443069 -370.389342)
			(xy 380.451146 -370.456279) (xy 380.451147 -370.523644) (xy 383.729187 -370.523644) (xy 383.729188 -370.456338)
			(xy 383.737234 -370.389514) (xy 383.753209 -370.324131) (xy 383.776884 -370.261126) (xy 383.807919 -370.201402)
			(xy 383.845871 -370.145816) (xy 383.86766 -370.120164) (xy 383.873462 -370.113023) (xy 383.879972 -370.095829)
			(xy 383.88036 -370.086636) (xy 383.88036 -369.928902) (xy 383.880766 -369.918728) (xy 383.888554 -369.899929)
			(xy 383.902946 -369.885543) (xy 383.921748 -369.877762) (xy 383.931922 -369.87734) (xy 384.648202 -369.87734)
			(xy 384.65836 -369.877832) (xy 384.67713 -369.885607) (xy 384.691495 -369.899974) (xy 384.699269 -369.918744)
			(xy 384.699764 -369.928902) (xy 384.699764 -370.086636) (xy 384.700165 -370.095824) (xy 384.706686 -370.113008)
			(xy 384.712464 -370.120164) (xy 384.73424 -370.145826) (xy 384.772189 -370.201411) (xy 384.803222 -370.261133)
			(xy 384.826895 -370.324137) (xy 384.842869 -370.389518) (xy 384.850914 -370.456339) (xy 384.850915 -370.523643)
			(xy 384.850915 -370.523644) (xy 388.128977 -370.523644) (xy 388.128979 -370.456338) (xy 388.137024 -370.389514)
			(xy 388.152999 -370.324131) (xy 388.176673 -370.261126) (xy 388.207708 -370.201402) (xy 388.245659 -370.145816)
			(xy 388.267448 -370.120164) (xy 388.273248 -370.113022) (xy 388.279759 -370.095829) (xy 388.280148 -370.086636)
			(xy 388.280148 -369.928902) (xy 388.280566 -369.918729) (xy 388.288352 -369.899933) (xy 388.302739 -369.885547)
			(xy 388.321537 -369.877764) (xy 388.33171 -369.87734) (xy 389.04799 -369.87734) (xy 389.058161 -369.877772)
			(xy 389.076956 -369.885554) (xy 389.091341 -369.899937) (xy 389.099126 -369.918731) (xy 389.099552 -369.928902)
			(xy 389.099552 -370.086636) (xy 389.099956 -370.095824) (xy 389.106475 -370.113007) (xy 389.112252 -370.120164)
			(xy 389.134028 -370.145826) (xy 389.171978 -370.201411) (xy 389.203012 -370.261133) (xy 389.226686 -370.324136)
			(xy 389.24266 -370.389517) (xy 389.250705 -370.456339) (xy 389.250706 -370.523643) (xy 389.250706 -370.523644)
			(xy 418.929008 -370.523644) (xy 418.929009 -370.456338) (xy 418.937055 -370.389513) (xy 418.953031 -370.32413)
			(xy 418.976707 -370.261125) (xy 419.007745 -370.201401) (xy 419.045698 -370.145816) (xy 419.067488 -370.120164)
			(xy 419.073281 -370.113016) (xy 419.079798 -370.095828) (xy 419.080188 -370.086636) (xy 419.080188 -369.928902)
			(xy 419.080567 -369.918724) (xy 419.08836 -369.89992) (xy 419.10276 -369.885533) (xy 419.121572 -369.877757)
			(xy 419.13175 -369.87734) (xy 419.84803 -369.87734) (xy 419.85819 -369.877809) (xy 419.87696 -369.885593)
			(xy 419.891325 -369.899967) (xy 419.899098 -369.918742) (xy 419.899592 -369.928902) (xy 419.899592 -370.086636)
			(xy 419.899986 -370.095825) (xy 419.906511 -370.113009) (xy 419.912292 -370.120164) (xy 419.934067 -370.145826)
			(xy 419.972014 -370.201412) (xy 420.003046 -370.261134) (xy 420.026718 -370.324138) (xy 420.042691 -370.389518)
			(xy 420.050736 -370.456339) (xy 420.050737 -370.523643) (xy 420.05073 -370.523703) (xy 423.328801 -370.523703)
			(xy 423.328802 -370.456279) (xy 423.336878 -370.38934) (xy 423.352915 -370.323851) (xy 423.37668 -370.260753)
			(xy 423.407831 -370.200957) (xy 423.44592 -370.145322) (xy 423.467784 -370.119656) (xy 423.47358 -370.11251)
			(xy 423.480095 -370.09532) (xy 423.480484 -370.086128) (xy 423.480484 -369.928902) (xy 423.48093 -369.91877)
			(xy 423.488665 -369.900041) (xy 423.502964 -369.885683) (xy 423.521662 -369.877871) (xy 423.531792 -369.87734)
			(xy 424.248072 -369.87734) (xy 424.258198 -369.87774) (xy 424.276908 -369.885486) (xy 424.291225 -369.899808)
			(xy 424.298964 -369.918522) (xy 424.29938 -369.928648) (xy 424.29938 -370.086128) (xy 424.299781 -370.095316)
			(xy 424.306302 -370.1125) (xy 424.31208 -370.119656) (xy 424.333933 -370.145331) (xy 424.372023 -370.200963)
			(xy 424.403176 -370.260758) (xy 424.426941 -370.323854) (xy 424.442978 -370.389342) (xy 424.451055 -370.456279)
			(xy 424.451056 -370.523644) (xy 427.729096 -370.523644) (xy 427.729097 -370.456338) (xy 427.737143 -370.389514)
			(xy 427.753118 -370.32413) (xy 427.776794 -370.261125) (xy 427.80783 -370.201402) (xy 427.845783 -370.145816)
			(xy 427.867572 -370.120164) (xy 427.873375 -370.113024) (xy 427.879884 -370.095829) (xy 427.880272 -370.086636)
			(xy 427.880272 -369.928902) (xy 427.880666 -369.918726) (xy 427.888457 -369.899925) (xy 427.902852 -369.885539)
			(xy 427.921658 -369.87776) (xy 427.931834 -369.87734) (xy 428.648114 -369.87734) (xy 428.658273 -369.877822)
			(xy 428.677043 -369.885602) (xy 428.691407 -369.899971) (xy 428.699181 -369.918743) (xy 428.699676 -369.928902)
			(xy 428.699676 -370.086636) (xy 428.700074 -370.095824) (xy 428.706597 -370.113008) (xy 428.712376 -370.120164)
			(xy 428.734152 -370.145826) (xy 428.7721 -370.201411) (xy 428.803133 -370.261134) (xy 428.826806 -370.324137)
			(xy 428.842779 -370.389518) (xy 428.850824 -370.456339) (xy 428.850825 -370.523643) (xy 428.850825 -370.523644)
			(xy 432.128887 -370.523644) (xy 432.128888 -370.456338) (xy 432.136934 -370.389514) (xy 432.152909 -370.324131)
			(xy 432.176584 -370.261126) (xy 432.207619 -370.201402) (xy 432.245571 -370.145816) (xy 432.26736 -370.120164)
			(xy 432.273162 -370.113023) (xy 432.279672 -370.095829) (xy 432.28006 -370.086636) (xy 432.28006 -369.928902)
			(xy 432.280466 -369.918728) (xy 432.288254 -369.899929) (xy 432.302646 -369.885543) (xy 432.321448 -369.877762)
			(xy 432.331622 -369.87734) (xy 433.047902 -369.87734) (xy 433.05806 -369.877832) (xy 433.07683 -369.885607)
			(xy 433.091195 -369.899974) (xy 433.098969 -369.918744) (xy 433.099464 -369.928902) (xy 433.099464 -370.086636)
			(xy 433.099865 -370.095824) (xy 433.106386 -370.113008) (xy 433.112164 -370.120164) (xy 433.13394 -370.145826)
			(xy 433.171889 -370.201411) (xy 433.202922 -370.261133) (xy 433.226595 -370.324137) (xy 433.242569 -370.389518)
			(xy 433.250614 -370.456339) (xy 433.250615 -370.523643) (xy 433.242572 -370.590465) (xy 433.226601 -370.655846)
			(xy 433.20293 -370.71885) (xy 433.171898 -370.778573) (xy 433.133951 -370.83416) (xy 433.112164 -370.859812)
			(xy 433.106375 -370.866963) (xy 433.099857 -370.884149) (xy 433.099464 -370.89334) (xy 433.099464 -371.386862)
			(xy 433.099901 -371.396046) (xy 433.106397 -371.41323) (xy 433.112164 -371.42039) (xy 433.133966 -371.446031)
			(xy 433.171914 -371.501619) (xy 433.202946 -371.561344) (xy 433.226383 -371.623725) (xy 434.329029 -371.623725)
			(xy 434.329032 -371.556418) (xy 434.33708 -371.489593) (xy 434.353056 -371.424209) (xy 434.376732 -371.361203)
			(xy 434.407768 -371.301478) (xy 434.445719 -371.245891) (xy 434.467508 -371.220238) (xy 434.473314 -371.2131)
			(xy 434.479823 -371.195904) (xy 434.480208 -371.18671) (xy 434.480208 -371.028722) (xy 434.48075 -371.018569)
			(xy 434.488512 -370.999806) (xy 434.502863 -370.985441) (xy 434.521618 -370.977661) (xy 434.53177 -370.97716)
			(xy 435.24805 -370.97716) (xy 435.258221 -370.977605) (xy 435.277019 -370.985378) (xy 435.291406 -370.999758)
			(xy 435.299189 -371.018551) (xy 435.299612 -371.028722) (xy 435.299612 -371.18671) (xy 435.300015 -371.195898)
			(xy 435.306533 -371.213082) (xy 435.312312 -371.220238) (xy 435.334064 -371.24592) (xy 435.372017 -371.301501)
			(xy 435.403055 -371.36122) (xy 435.426732 -371.424221) (xy 435.442709 -371.4896) (xy 435.450757 -371.55642)
			(xy 435.45076 -371.623723) (xy 435.442719 -371.690544) (xy 435.426749 -371.755924) (xy 435.403078 -371.818928)
			(xy 435.372046 -371.87865) (xy 435.334099 -371.934235) (xy 435.312312 -371.959886) (xy 435.306498 -371.967019)
			(xy 435.299993 -371.984219) (xy 435.299612 -371.993414) (xy 435.299612 -372.486682) (xy 435.300028 -372.495869)
			(xy 435.306537 -372.513053) (xy 435.312312 -372.52021) (xy 435.334135 -372.545834) (xy 435.372086 -372.601423)
			(xy 435.40312 -372.66115) (xy 435.426793 -372.724159) (xy 435.442765 -372.789545) (xy 435.450807 -372.856371)
			(xy 435.450804 -372.92368) (xy 435.442756 -372.990506) (xy 435.426778 -373.05589) (xy 435.403099 -373.118896)
			(xy 435.372059 -373.178621) (xy 435.334103 -373.234206) (xy 435.312312 -373.259858) (xy 435.30651 -373.266999)
			(xy 435.299998 -373.284193) (xy 435.299612 -373.293386) (xy 435.299612 -373.451374) (xy 435.299213 -373.46155)
			(xy 435.291428 -373.480354) (xy 435.277034 -373.494741) (xy 435.258226 -373.502518) (xy 435.24805 -373.502936)
			(xy 434.53177 -373.502936) (xy 434.521607 -373.502491) (xy 434.502832 -373.494701) (xy 434.488467 -373.480321)
			(xy 434.480698 -373.461537) (xy 434.480208 -373.451374) (xy 434.480208 -373.293386) (xy 434.479803 -373.284198)
			(xy 434.473286 -373.267014) (xy 434.467508 -373.259858) (xy 434.445755 -373.234178) (xy 434.407807 -373.178595)
			(xy 434.376774 -373.118875) (xy 434.3531 -373.055874) (xy 434.337126 -372.990495) (xy 434.32908 -372.923676)
			(xy 434.329077 -372.856375) (xy 434.337117 -372.789555) (xy 434.353085 -372.724175) (xy 434.376753 -372.661172)
			(xy 434.40778 -372.601449) (xy 434.445723 -372.545863) (xy 434.467508 -372.52021) (xy 434.473326 -372.51308)
			(xy 434.479828 -372.495878) (xy 434.480208 -372.486682) (xy 434.480208 -371.993414) (xy 434.479789 -371.984228)
			(xy 434.473281 -371.967043) (xy 434.467508 -371.959886) (xy 434.445684 -371.934264) (xy 434.407738 -371.878673)
			(xy 434.376708 -371.818945) (xy 434.353039 -371.755936) (xy 434.33707 -371.690551) (xy 434.329029 -371.623725)
			(xy 433.226383 -371.623725) (xy 433.226618 -371.62435) (xy 433.24259 -371.689734) (xy 433.250633 -371.756557)
			(xy 433.250632 -371.823864) (xy 433.242586 -371.890687) (xy 433.226612 -371.95607) (xy 433.202938 -372.019075)
			(xy 433.171903 -372.078799) (xy 433.133953 -372.134386) (xy 433.112164 -372.160038) (xy 433.106364 -372.167181)
			(xy 433.099852 -372.184373) (xy 433.099464 -372.193566) (xy 433.099464 -372.351554) (xy 433.098999 -372.361722)
			(xy 433.091229 -372.380516) (xy 433.076856 -372.394902) (xy 433.05807 -372.402689) (xy 433.047902 -372.403116)
			(xy 432.331622 -372.403116) (xy 432.321446 -372.402717) (xy 432.302643 -372.394931) (xy 432.288256 -372.380537)
			(xy 432.280478 -372.36173) (xy 432.28006 -372.351554) (xy 432.28006 -372.193566) (xy 432.279653 -372.184379)
			(xy 432.273135 -372.167195) (xy 432.26736 -372.160038) (xy 432.245586 -372.134375) (xy 432.207635 -372.07879)
			(xy 432.1766 -372.019069) (xy 432.152925 -371.956065) (xy 432.136951 -371.890684) (xy 432.128905 -371.823863)
			(xy 432.128904 -371.756558) (xy 432.136947 -371.689736) (xy 432.152919 -371.624355) (xy 432.176591 -371.561351)
			(xy 432.207624 -371.501628) (xy 432.245573 -371.446042) (xy 432.26736 -371.42039) (xy 432.273151 -371.413241)
			(xy 432.279667 -371.396053) (xy 432.28006 -371.386862) (xy 432.28006 -370.89334) (xy 432.279617 -370.884157)
			(xy 432.273125 -370.866972) (xy 432.26736 -370.859812) (xy 432.24556 -370.83417) (xy 432.20761 -370.778582)
			(xy 432.176576 -370.718858) (xy 432.152903 -370.655852) (xy 432.136931 -370.590468) (xy 432.128887 -370.523644)
			(xy 428.850825 -370.523644) (xy 428.842782 -370.590464) (xy 428.826811 -370.655846) (xy 428.80314 -370.71885)
			(xy 428.772109 -370.778573) (xy 428.734163 -370.83416) (xy 428.712376 -370.859812) (xy 428.706589 -370.866964)
			(xy 428.700069 -370.884149) (xy 428.699676 -370.89334) (xy 428.699676 -371.386862) (xy 428.70011 -371.396047)
			(xy 428.706608 -371.413231) (xy 428.712376 -371.42039) (xy 428.734177 -371.446031) (xy 428.772125 -371.501619)
			(xy 428.803156 -371.561345) (xy 428.826615 -371.623785) (xy 429.928709 -371.623785) (xy 429.928713 -371.556358)
			(xy 429.936793 -371.489417) (xy 429.952833 -371.423925) (xy 429.976602 -371.360827) (xy 430.007759 -371.30103)
			(xy 430.045853 -371.245395) (xy 430.06772 -371.21973) (xy 430.073531 -371.212595) (xy 430.080036 -371.195397)
			(xy 430.08042 -371.186202) (xy 430.08042 -371.028722) (xy 430.080944 -371.018599) (xy 430.088661 -370.999882)
			(xy 430.102935 -370.985526) (xy 430.121608 -370.977702) (xy 430.131728 -370.97716) (xy 430.848008 -370.97716)
			(xy 430.858158 -370.977614) (xy 430.876902 -370.985405) (xy 430.891224 -370.999791) (xy 430.898931 -371.018571)
			(xy 430.899316 -371.028722) (xy 430.899316 -371.186202) (xy 430.899722 -371.19539) (xy 430.906238 -371.212574)
			(xy 430.912016 -371.21973) (xy 430.933842 -371.245426) (xy 430.971931 -371.301057) (xy 431.003082 -371.360849)
			(xy 431.026848 -371.423942) (xy 431.042886 -371.489427) (xy 431.050964 -371.556361) (xy 431.050968 -371.623782)
			(xy 431.042896 -371.690717) (xy 431.026865 -371.756204) (xy 431.003106 -371.819299) (xy 430.97196 -371.879094)
			(xy 430.933877 -371.934729) (xy 430.912016 -371.960394) (xy 430.906241 -371.967555) (xy 430.899713 -371.984733)
			(xy 430.899316 -371.993922) (xy 430.899316 -372.486174) (xy 430.899735 -372.49536) (xy 430.906242 -372.512545)
			(xy 430.912016 -372.519702) (xy 430.933913 -372.54534) (xy 430.971999 -372.600979) (xy 431.003148 -372.660779)
			(xy 431.026909 -372.723879) (xy 431.042942 -372.789371) (xy 431.051015 -372.856313) (xy 431.051012 -372.923739)
			(xy 431.042933 -372.990679) (xy 431.026894 -373.05617) (xy 431.003127 -373.119268) (xy 430.971973 -373.179065)
			(xy 430.933881 -373.2347) (xy 430.912016 -373.260366) (xy 430.906211 -373.267505) (xy 430.899701 -373.2847)
			(xy 430.899316 -373.293894) (xy 430.899316 -373.451374) (xy 430.898851 -373.461504) (xy 430.891124 -373.480233)
			(xy 430.87683 -373.494592) (xy 430.858136 -373.502405) (xy 430.848008 -373.502936) (xy 430.131728 -373.502936)
			(xy 430.12158 -373.502456) (xy 430.102835 -373.494677) (xy 430.088512 -373.480298) (xy 430.080805 -373.461523)
			(xy 430.08042 -373.451374) (xy 430.08042 -373.293894) (xy 430.080008 -373.284707) (xy 430.073495 -373.267523)
			(xy 430.06772 -373.260366) (xy 430.045889 -373.234674) (xy 430.007798 -373.179043) (xy 429.976644 -373.119251)
			(xy 429.952877 -373.056158) (xy 429.936839 -372.990672) (xy 429.92876 -372.923736) (xy 429.928757 -372.856315)
			(xy 429.93683 -372.789379) (xy 429.952862 -372.723891) (xy 429.976624 -372.660796) (xy 430.007771 -372.601)
			(xy 430.045857 -372.545367) (xy 430.06772 -372.519702) (xy 430.073501 -372.512546) (xy 430.080024 -372.495364)
			(xy 430.08042 -372.486174) (xy 430.08042 -371.993922) (xy 430.079995 -371.984737) (xy 430.073491 -371.967552)
			(xy 430.06772 -371.960394) (xy 430.045818 -371.93476) (xy 430.007729 -371.879121) (xy 429.976579 -371.819321)
			(xy 429.952816 -371.75622) (xy 429.936783 -371.690727) (xy 429.928709 -371.623785) (xy 428.826615 -371.623785)
			(xy 428.826828 -371.624351) (xy 428.842799 -371.689734) (xy 428.850842 -371.756558) (xy 428.850841 -371.823863)
			(xy 428.842795 -371.890687) (xy 428.826821 -371.95607) (xy 428.803148 -372.019075) (xy 428.772114 -372.078799)
			(xy 428.734164 -372.134386) (xy 428.712376 -372.160038) (xy 428.706578 -372.167182) (xy 428.700065 -372.184374)
			(xy 428.699676 -372.193566) (xy 428.699676 -372.351554) (xy 428.699199 -372.361721) (xy 428.691432 -372.380512)
			(xy 428.677062 -372.394898) (xy 428.65828 -372.402687) (xy 428.648114 -372.403116) (xy 427.931834 -372.403116)
			(xy 427.921659 -372.402707) (xy 427.902856 -372.394925) (xy 427.888469 -372.380534) (xy 427.880691 -372.361729)
			(xy 427.880272 -372.351554) (xy 427.880272 -372.193566) (xy 427.879884 -372.184376) (xy 427.873356 -372.167192)
			(xy 427.867572 -372.160038) (xy 427.845797 -372.134375) (xy 427.807846 -372.078791) (xy 427.77681 -372.019069)
			(xy 427.753135 -371.956066) (xy 427.73716 -371.890685) (xy 427.729114 -371.823863) (xy 427.729113 -371.756558)
			(xy 427.737156 -371.689736) (xy 427.753129 -371.624354) (xy 427.776801 -371.56135) (xy 427.807835 -371.501627)
			(xy 427.845784 -371.446042) (xy 427.867572 -371.42039) (xy 427.873364 -371.413242) (xy 427.879879 -371.396053)
			(xy 427.880272 -371.386862) (xy 427.880272 -370.89334) (xy 427.879849 -370.884154) (xy 427.873345 -370.866969)
			(xy 427.867572 -370.859812) (xy 427.845772 -370.83417) (xy 427.807821 -370.778583) (xy 427.776786 -370.718858)
			(xy 427.753113 -370.655852) (xy 427.73714 -370.590468) (xy 427.729096 -370.523644) (xy 424.451056 -370.523644)
			(xy 424.451056 -370.523703) (xy 424.442981 -370.59064) (xy 424.426947 -370.656129) (xy 424.403183 -370.719225)
			(xy 424.372033 -370.779021) (xy 424.333944 -370.834655) (xy 424.31208 -370.86032) (xy 424.30629 -370.86747)
			(xy 424.299772 -370.884657) (xy 424.29938 -370.893848) (xy 424.29938 -371.386354) (xy 424.299817 -371.395538)
			(xy 424.306312 -371.412723) (xy 424.31208 -371.419882) (xy 424.333958 -371.445536) (xy 424.372048 -371.501171)
			(xy 424.403199 -371.560969) (xy 424.426835 -371.623725) (xy 425.528941 -371.623725) (xy 425.528945 -371.556418)
			(xy 425.536992 -371.489593) (xy 425.552969 -371.424208) (xy 425.576645 -371.361202) (xy 425.607682 -371.301478)
			(xy 425.645634 -371.24589) (xy 425.667424 -371.220238) (xy 425.673232 -371.213101) (xy 425.679739 -371.195904)
			(xy 425.680124 -371.18671) (xy 425.680124 -371.028722) (xy 425.680582 -371.018554) (xy 425.688357 -370.999762)
			(xy 425.702732 -370.985377) (xy 425.721518 -370.977589) (xy 425.731686 -370.97716) (xy 426.447966 -370.97716)
			(xy 426.458138 -370.977592) (xy 426.476936 -370.98537) (xy 426.491323 -370.999754) (xy 426.499105 -371.01855)
			(xy 426.499528 -371.028722) (xy 426.499528 -371.18671) (xy 426.499927 -371.195898) (xy 426.506448 -371.213083)
			(xy 426.512228 -371.220238) (xy 426.533979 -371.24592) (xy 426.571931 -371.301502) (xy 426.602968 -371.361221)
			(xy 426.626645 -371.424221) (xy 426.642621 -371.4896) (xy 426.650669 -371.55642) (xy 426.650672 -371.623723)
			(xy 426.642631 -371.690543) (xy 426.626661 -371.755924) (xy 426.602991 -371.818927) (xy 426.571961 -371.878649)
			(xy 426.534014 -371.934234) (xy 426.512228 -371.959886) (xy 426.506404 -371.967011) (xy 426.499908 -371.984217)
			(xy 426.499528 -371.993414) (xy 426.499528 -372.486682) (xy 426.49994 -372.495869) (xy 426.506452 -372.513054)
			(xy 426.512228 -372.52021) (xy 426.53405 -372.545834) (xy 426.572 -372.601424) (xy 426.603034 -372.661151)
			(xy 426.626706 -372.724159) (xy 426.642678 -372.789545) (xy 426.65072 -372.856371) (xy 426.650717 -372.92368)
			(xy 426.642669 -372.990505) (xy 426.626691 -373.05589) (xy 426.603013 -373.118896) (xy 426.571974 -373.17862)
			(xy 426.534019 -373.234206) (xy 426.512228 -373.259858) (xy 426.506416 -373.266992) (xy 426.499912 -373.284191)
			(xy 426.499528 -373.293386) (xy 426.499528 -373.451374) (xy 426.499114 -373.461548) (xy 426.491331 -373.480349)
			(xy 426.476942 -373.494736) (xy 426.45814 -373.502515) (xy 426.447966 -373.502936) (xy 425.731686 -373.502936)
			(xy 425.72151 -373.502547) (xy 425.70271 -373.494752) (xy 425.688325 -373.480356) (xy 425.680545 -373.46155)
			(xy 425.680124 -373.451374) (xy 425.680124 -373.293386) (xy 425.679715 -373.284199) (xy 425.6732 -373.267015)
			(xy 425.667424 -373.259858) (xy 425.64567 -373.234178) (xy 425.607722 -373.178595) (xy 425.576688 -373.118875)
			(xy 425.553014 -373.055874) (xy 425.537039 -372.990496) (xy 425.528992 -372.923677) (xy 425.528989 -372.856375)
			(xy 425.53703 -372.789555) (xy 425.552999 -372.724174) (xy 425.576667 -372.661171) (xy 425.607695 -372.601449)
			(xy 425.645639 -372.545863) (xy 425.667424 -372.52021) (xy 425.673244 -372.513082) (xy 425.679744 -372.495878)
			(xy 425.680124 -372.486682) (xy 425.680124 -371.993414) (xy 425.679702 -371.984228) (xy 425.673196 -371.967044)
			(xy 425.667424 -371.959886) (xy 425.645599 -371.934264) (xy 425.607653 -371.878673) (xy 425.576622 -371.818945)
			(xy 425.552952 -371.755937) (xy 425.536982 -371.690551) (xy 425.528941 -371.623725) (xy 424.426835 -371.623725)
			(xy 424.426964 -371.624067) (xy 424.442999 -371.689558) (xy 424.451074 -371.756498) (xy 424.451072 -371.823923)
			(xy 424.442995 -371.890863) (xy 424.426957 -371.956353) (xy 424.403191 -372.01945) (xy 424.372037 -372.079247)
			(xy 424.333946 -372.134881) (xy 424.31208 -372.160546) (xy 424.306279 -372.167688) (xy 424.299768 -372.184881)
			(xy 424.29938 -372.194074) (xy 424.29938 -372.351554) (xy 424.298836 -372.361675) (xy 424.291127 -372.380392)
			(xy 424.276858 -372.394749) (xy 424.25819 -372.402573) (xy 424.248072 -372.403116) (xy 423.531792 -372.403116)
			(xy 423.521685 -372.402622) (xy 423.50301 -372.394884) (xy 423.488716 -372.38059) (xy 423.480978 -372.361915)
			(xy 423.480484 -372.351808) (xy 423.480484 -372.194074) (xy 423.48009 -372.184885) (xy 423.473565 -372.167701)
			(xy 423.467784 -372.160546) (xy 423.445934 -372.134869) (xy 423.407846 -372.079236) (xy 423.376696 -372.019441)
			(xy 423.352932 -371.956346) (xy 423.336896 -371.890858) (xy 423.328819 -371.823922) (xy 423.328818 -371.756499)
			(xy 423.336892 -371.689562) (xy 423.352925 -371.624074) (xy 423.376687 -371.560978) (xy 423.407835 -371.501182)
			(xy 423.445921 -371.445547) (xy 423.467784 -371.419882) (xy 423.473569 -371.412728) (xy 423.480091 -371.395544)
			(xy 423.480484 -371.386354) (xy 423.480484 -370.893848) (xy 423.480055 -370.884663) (xy 423.473555 -370.867478)
			(xy 423.467784 -370.86032) (xy 423.445909 -370.834664) (xy 423.407821 -370.779028) (xy 423.376672 -370.71923)
			(xy 423.352909 -370.656132) (xy 423.336875 -370.590642) (xy 423.328801 -370.523703) (xy 420.05073 -370.523703)
			(xy 420.042694 -370.590464) (xy 420.026724 -370.655845) (xy 420.003054 -370.718849) (xy 419.972023 -370.778573)
			(xy 419.934078 -370.834159) (xy 419.912292 -370.859812) (xy 419.906507 -370.866965) (xy 419.899986 -370.88415)
			(xy 419.899592 -370.89334) (xy 419.899592 -371.386862) (xy 419.900022 -371.396047) (xy 419.906522 -371.413231)
			(xy 419.912292 -371.42039) (xy 419.934093 -371.446031) (xy 419.972039 -371.50162) (xy 420.00307 -371.561345)
			(xy 420.026528 -371.623785) (xy 421.128621 -371.623785) (xy 421.128625 -371.556358) (xy 421.136705 -371.489416)
			(xy 421.152746 -371.423925) (xy 421.176516 -371.360826) (xy 421.207673 -371.301029) (xy 421.245769 -371.245395)
			(xy 421.267636 -371.21973) (xy 421.273449 -371.212597) (xy 421.279953 -371.195397) (xy 421.280336 -371.186202)
			(xy 421.280336 -371.028722) (xy 421.280844 -371.018597) (xy 421.288564 -370.999877) (xy 421.302844 -370.98552)
			(xy 421.321522 -370.9777) (xy 421.331644 -370.97716) (xy 422.047924 -370.97716) (xy 422.058029 -370.977664)
			(xy 422.076701 -370.985402) (xy 422.090993 -370.999693) (xy 422.098734 -371.018363) (xy 422.099232 -371.028468)
			(xy 422.099232 -371.186202) (xy 422.099656 -371.195387) (xy 422.106162 -371.212571) (xy 422.111932 -371.21973)
			(xy 422.133758 -371.245427) (xy 422.171845 -371.301057) (xy 422.202996 -371.36085) (xy 422.226761 -371.423942)
			(xy 422.242798 -371.489427) (xy 422.250876 -371.556361) (xy 422.25088 -371.623781) (xy 422.242808 -371.690717)
			(xy 422.226778 -371.756203) (xy 422.203019 -371.819298) (xy 422.171875 -371.879094) (xy 422.133793 -371.934728)
			(xy 422.111932 -371.960394) (xy 422.106147 -371.967547) (xy 422.099627 -371.984732) (xy 422.099232 -371.993922)
			(xy 422.099232 -372.486174) (xy 422.09967 -372.495358) (xy 422.106166 -372.512542) (xy 422.111932 -372.519702)
			(xy 422.133828 -372.54534) (xy 422.171914 -372.600979) (xy 422.203061 -372.66078) (xy 422.226822 -372.72388)
			(xy 422.242854 -372.789372) (xy 422.250927 -372.856313) (xy 422.250924 -372.923738) (xy 422.242845 -372.990678)
			(xy 422.226807 -373.056169) (xy 422.20304 -373.119267) (xy 422.171888 -373.179064) (xy 422.133797 -373.2347)
			(xy 422.111932 -373.260366) (xy 422.106117 -373.267498) (xy 422.099615 -373.284699) (xy 422.099232 -373.293894)
			(xy 422.099232 -373.451374) (xy 422.098751 -373.461503) (xy 422.091027 -373.480228) (xy 422.076738 -373.494587)
			(xy 422.05805 -373.502402) (xy 422.047924 -373.502936) (xy 421.331644 -373.502936) (xy 421.321529 -373.502449)
			(xy 421.302833 -373.494722) (xy 421.288519 -373.480427) (xy 421.280765 -373.461743) (xy 421.280336 -373.451628)
			(xy 421.280336 -373.293894) (xy 421.279921 -373.284708) (xy 421.27341 -373.267524) (xy 421.267636 -373.260366)
			(xy 421.245804 -373.234674) (xy 421.207712 -373.179044) (xy 421.176558 -373.119252) (xy 421.15279 -373.056158)
			(xy 421.136751 -372.990672) (xy 421.128672 -372.923736) (xy 421.128669 -372.856315) (xy 421.136742 -372.789378)
			(xy 421.152775 -372.72389) (xy 421.176537 -372.660795) (xy 421.207686 -372.601) (xy 421.245773 -372.545367)
			(xy 421.267636 -372.519702) (xy 421.273419 -372.512547) (xy 421.279941 -372.495364) (xy 421.280336 -372.486174)
			(xy 421.280336 -371.993922) (xy 421.279907 -371.984737) (xy 421.273406 -371.967553) (xy 421.267636 -371.960394)
			(xy 421.245733 -371.93476) (xy 421.207643 -371.879122) (xy 421.176492 -371.819322) (xy 421.152729 -371.756221)
			(xy 421.136695 -371.690727) (xy 421.128621 -371.623785) (xy 420.026528 -371.623785) (xy 420.026741 -371.624351)
			(xy 420.042712 -371.689734) (xy 420.050754 -371.756558) (xy 420.050753 -371.823863) (xy 420.042708 -371.890686)
			(xy 420.026734 -371.956069) (xy 420.003061 -372.019074) (xy 419.972028 -372.078798) (xy 419.93408 -372.134385)
			(xy 419.912292 -372.160038) (xy 419.906496 -372.167183) (xy 419.899981 -372.184374) (xy 419.899592 -372.193566)
			(xy 419.899592 -372.351554) (xy 419.899099 -372.361719) (xy 419.891335 -372.380507) (xy 419.876971 -372.394892)
			(xy 419.858194 -372.402684) (xy 419.84803 -372.403116) (xy 419.13175 -372.403116) (xy 419.121576 -372.402694)
			(xy 419.102773 -372.394917) (xy 419.088385 -372.38053) (xy 419.080607 -372.361728) (xy 419.080188 -372.351554)
			(xy 419.080188 -372.193566) (xy 419.079797 -372.184377) (xy 419.07327 -372.167192) (xy 419.067488 -372.160038)
			(xy 419.045713 -372.134375) (xy 419.00776 -372.078791) (xy 418.976724 -372.01907) (xy 418.953048 -371.956067)
			(xy 418.937072 -371.890685) (xy 418.929026 -371.823863) (xy 418.929025 -371.756558) (xy 418.937069 -371.689736)
			(xy 418.953042 -371.624354) (xy 418.976715 -371.561349) (xy 419.007749 -371.501627) (xy 419.0457 -371.446041)
			(xy 419.067488 -371.42039) (xy 419.07327 -371.413234) (xy 419.079794 -371.396052) (xy 419.080188 -371.386862)
			(xy 419.080188 -370.89334) (xy 419.079761 -370.884154) (xy 419.07326 -370.86697) (xy 419.067488 -370.859812)
			(xy 419.045687 -370.83417) (xy 419.007735 -370.778583) (xy 418.9767 -370.718859) (xy 418.953026 -370.655853)
			(xy 418.937052 -370.590469) (xy 418.929008 -370.523644) (xy 389.250706 -370.523644) (xy 389.242663 -370.590465)
			(xy 389.226691 -370.655847) (xy 389.203019 -370.718851) (xy 389.171987 -370.778574) (xy 389.134039 -370.83416)
			(xy 389.112252 -370.859812) (xy 389.106462 -370.866962) (xy 389.099945 -370.884149) (xy 389.099552 -370.89334)
			(xy 389.099552 -371.386862) (xy 389.099991 -371.396046) (xy 389.106486 -371.41323) (xy 389.112252 -371.42039)
			(xy 389.134054 -371.446031) (xy 389.172003 -371.501618) (xy 389.203036 -371.561344) (xy 389.226474 -371.623725)
			(xy 390.32912 -371.623725) (xy 390.329123 -371.556418) (xy 390.337171 -371.489593) (xy 390.353146 -371.42421)
			(xy 390.376822 -371.361204) (xy 390.407857 -371.301479) (xy 390.445807 -371.245891) (xy 390.467596 -371.220238)
			(xy 390.473401 -371.213099) (xy 390.479911 -371.195904) (xy 390.480296 -371.18671) (xy 390.480296 -371.028722)
			(xy 390.48085 -371.018571) (xy 390.48861 -370.99981) (xy 390.502956 -370.985446) (xy 390.521707 -370.977663)
			(xy 390.531858 -370.97716) (xy 391.248138 -370.97716) (xy 391.258301 -370.977603) (xy 391.277075 -370.985394)
			(xy 391.29144 -370.999775) (xy 391.299209 -371.018558) (xy 391.2997 -371.028722) (xy 391.2997 -371.18671)
			(xy 391.300106 -371.195898) (xy 391.306623 -371.213082) (xy 391.3124 -371.220238) (xy 391.334149 -371.245921)
			(xy 391.372097 -371.301504) (xy 391.403129 -371.361224) (xy 391.426803 -371.424224) (xy 391.442777 -371.489602)
			(xy 391.450824 -371.556421) (xy 391.450827 -371.623722) (xy 391.442787 -371.690541) (xy 391.42682 -371.755921)
			(xy 391.403153 -371.818924) (xy 391.372126 -371.878647) (xy 391.334184 -371.934233) (xy 391.3124 -371.959886)
			(xy 391.306584 -371.967018) (xy 391.300081 -371.984219) (xy 391.2997 -371.993414) (xy 391.2997 -372.486682)
			(xy 391.300119 -372.495868) (xy 391.306627 -372.513053) (xy 391.3124 -372.52021) (xy 391.33422 -372.545835)
			(xy 391.372165 -372.601426) (xy 391.403195 -372.661154) (xy 391.426864 -372.724162) (xy 391.442833 -372.789547)
			(xy 391.450874 -372.856372) (xy 391.450871 -372.923679) (xy 391.442824 -372.990503) (xy 391.426849 -373.055887)
			(xy 391.403174 -373.118893) (xy 391.372139 -373.178617) (xy 391.334189 -373.234205) (xy 391.3124 -373.259858)
			(xy 391.306596 -373.266998) (xy 391.300086 -373.284193) (xy 391.2997 -373.293386) (xy 391.2997 -373.451374)
			(xy 391.299146 -373.461525) (xy 391.291388 -373.480287) (xy 391.277041 -373.494652) (xy 391.258289 -373.502434)
			(xy 391.248138 -373.502936) (xy 390.531858 -373.502936) (xy 390.521694 -373.5025) (xy 390.502919 -373.494707)
			(xy 390.488555 -373.480324) (xy 390.480786 -373.461538) (xy 390.480296 -373.451374) (xy 390.480296 -373.293386)
			(xy 390.479893 -373.284198) (xy 390.473374 -373.267014) (xy 390.467596 -373.259858) (xy 390.445843 -373.234178)
			(xy 390.407896 -373.178594) (xy 390.376864 -373.118874) (xy 390.353191 -373.055874) (xy 390.337217 -372.990495)
			(xy 390.329171 -372.923676) (xy 390.329167 -372.856375) (xy 390.337208 -372.789555) (xy 390.353176 -372.724175)
			(xy 390.376843 -372.661173) (xy 390.40787 -372.60145) (xy 390.445812 -372.545863) (xy 390.467596 -372.52021)
			(xy 390.473413 -372.513079) (xy 390.479916 -372.495878) (xy 390.480296 -372.486682) (xy 390.480296 -371.993414)
			(xy 390.47988 -371.984227) (xy 390.47337 -371.967043) (xy 390.467596 -371.959886) (xy 390.445772 -371.934264)
			(xy 390.407827 -371.878672) (xy 390.376798 -371.818944) (xy 390.353129 -371.755936) (xy 390.33716 -371.69055)
			(xy 390.32912 -371.623725) (xy 389.226474 -371.623725) (xy 389.226709 -371.62435) (xy 389.242681 -371.689733)
			(xy 389.250724 -371.756557) (xy 389.250723 -371.823864) (xy 389.242677 -371.890687) (xy 389.226702 -371.956071)
			(xy 389.203028 -372.019076) (xy 389.171992 -372.0788) (xy 389.134041 -372.134386) (xy 389.112252 -372.160038)
			(xy 389.106451 -372.16718) (xy 389.09994 -372.184373) (xy 389.099552 -372.193566) (xy 389.099552 -372.351554)
			(xy 389.099098 -372.361724) (xy 389.091327 -372.380519) (xy 389.07695 -372.394906) (xy 389.05816 -372.402691)
			(xy 389.04799 -372.403116) (xy 388.33171 -372.403116) (xy 388.321533 -372.402727) (xy 388.30273 -372.394937)
			(xy 388.288343 -372.38054) (xy 388.280566 -372.361731) (xy 388.280148 -372.351554) (xy 388.280148 -372.193566)
			(xy 388.279743 -372.184378) (xy 388.273225 -372.167195) (xy 388.267448 -372.160038) (xy 388.245674 -372.134375)
			(xy 388.207724 -372.07879) (xy 388.17669 -372.019068) (xy 388.153016 -371.956065) (xy 388.137042 -371.890684)
			(xy 388.128996 -371.823863) (xy 388.128995 -371.756558) (xy 388.137038 -371.689737) (xy 388.15301 -371.624355)
			(xy 388.176681 -371.561351) (xy 388.207713 -371.501628) (xy 388.245661 -371.446042) (xy 388.267448 -371.42039)
			(xy 388.273237 -371.41324) (xy 388.279755 -371.396053) (xy 388.280148 -371.386862) (xy 388.280148 -370.89334)
			(xy 388.279708 -370.884156) (xy 388.273214 -370.866972) (xy 388.267448 -370.859812) (xy 388.245648 -370.83417)
			(xy 388.207699 -370.778582) (xy 388.176666 -370.718857) (xy 388.152993 -370.655851) (xy 388.137021 -370.590468)
			(xy 388.128977 -370.523644) (xy 384.850915 -370.523644) (xy 384.842872 -370.590465) (xy 384.826901 -370.655846)
			(xy 384.80323 -370.71885) (xy 384.772198 -370.778573) (xy 384.734251 -370.83416) (xy 384.712464 -370.859812)
			(xy 384.706675 -370.866963) (xy 384.700157 -370.884149) (xy 384.699764 -370.89334) (xy 384.699764 -371.386862)
			(xy 384.700201 -371.396046) (xy 384.706697 -371.41323) (xy 384.712464 -371.42039) (xy 384.734266 -371.446031)
			(xy 384.772214 -371.501619) (xy 384.803246 -371.561344) (xy 384.826706 -371.623785) (xy 385.9288 -371.623785)
			(xy 385.928804 -371.556358) (xy 385.936884 -371.489417) (xy 385.952923 -371.423926) (xy 385.976692 -371.360827)
			(xy 386.007848 -371.30103) (xy 386.045941 -371.245395) (xy 386.067808 -371.21973) (xy 386.073618 -371.212594)
			(xy 386.080124 -371.195396) (xy 386.080508 -371.186202) (xy 386.080508 -371.028722) (xy 386.081044 -371.018601)
			(xy 386.088758 -370.999886) (xy 386.103029 -370.98553) (xy 386.121698 -370.977704) (xy 386.131816 -370.97716)
			(xy 386.848096 -370.97716) (xy 386.858245 -370.977624) (xy 386.876989 -370.985411) (xy 386.891311 -370.999794)
			(xy 386.899019 -371.018571) (xy 386.899404 -371.028722) (xy 386.899404 -371.186202) (xy 386.899812 -371.195389)
			(xy 386.906327 -371.212574) (xy 386.912104 -371.21973) (xy 386.93393 -371.245426) (xy 386.97202 -371.301056)
			(xy 387.003172 -371.360848) (xy 387.026938 -371.423941) (xy 387.042976 -371.489426) (xy 387.051055 -371.556361)
			(xy 387.051059 -371.623782) (xy 387.042987 -371.690717) (xy 387.026955 -371.756204) (xy 387.003196 -371.8193)
			(xy 386.972049 -371.879095) (xy 386.933966 -371.934729) (xy 386.912104 -371.960394) (xy 386.906328 -371.967554)
			(xy 386.899801 -371.984733) (xy 386.899404 -371.993922) (xy 386.899404 -372.486174) (xy 386.899826 -372.49536)
			(xy 386.906331 -372.512545) (xy 386.912104 -372.519702) (xy 386.934001 -372.54534) (xy 386.972089 -372.600978)
			(xy 387.003238 -372.660778) (xy 387.027 -372.723879) (xy 387.043033 -372.789371) (xy 387.051106 -372.856312)
			(xy 387.051103 -372.923739) (xy 387.043024 -372.990679) (xy 387.026985 -373.05617) (xy 387.003217 -373.119268)
			(xy 386.972062 -373.179066) (xy 386.93397 -373.234701) (xy 386.912104 -373.260366) (xy 386.906297 -373.267504)
			(xy 386.899789 -373.2847) (xy 386.899404 -373.293894) (xy 386.899404 -373.451374) (xy 386.898854 -373.461494)
			(xy 386.891142 -373.480206) (xy 386.876876 -373.494562) (xy 386.858212 -373.50239) (xy 386.848096 -373.502936)
			(xy 386.131816 -373.502936) (xy 386.121667 -373.502466) (xy 386.102922 -373.494683) (xy 386.0886 -373.480301)
			(xy 386.080893 -373.461524) (xy 386.080508 -373.451374) (xy 386.080508 -373.293894) (xy 386.080099 -373.284707)
			(xy 386.073584 -373.267523) (xy 386.067808 -373.260366) (xy 386.045977 -373.234673) (xy 386.007887 -373.179043)
			(xy 385.976734 -373.119251) (xy 385.952968 -373.056157) (xy 385.93693 -372.990671) (xy 385.928851 -372.923736)
			(xy 385.928848 -372.856315) (xy 385.936921 -372.789379) (xy 385.952953 -372.723892) (xy 385.976713 -372.660796)
			(xy 386.007861 -372.601001) (xy 386.045946 -372.545367) (xy 386.067808 -372.519702) (xy 386.073587 -372.512544)
			(xy 386.080112 -372.495363) (xy 386.080508 -372.486174) (xy 386.080508 -371.993922) (xy 386.080085 -371.984736)
			(xy 386.07358 -371.967552) (xy 386.067808 -371.960394) (xy 386.045906 -371.93476) (xy 386.007818 -371.879121)
			(xy 385.976669 -371.819321) (xy 385.952906 -371.75622) (xy 385.936873 -371.690727) (xy 385.9288 -371.623785)
			(xy 384.826706 -371.623785) (xy 384.826918 -371.62435) (xy 384.84289 -371.689734) (xy 384.850933 -371.756557)
			(xy 384.850932 -371.823864) (xy 384.842886 -371.890687) (xy 384.826912 -371.95607) (xy 384.803238 -372.019075)
			(xy 384.772203 -372.078799) (xy 384.734253 -372.134386) (xy 384.712464 -372.160038) (xy 384.706664 -372.167181)
			(xy 384.700152 -372.184373) (xy 384.699764 -372.193566) (xy 384.699764 -372.351554) (xy 384.699299 -372.361722)
			(xy 384.691529 -372.380516) (xy 384.677156 -372.394902) (xy 384.65837 -372.402689) (xy 384.648202 -372.403116)
			(xy 383.931922 -372.403116) (xy 383.921746 -372.402717) (xy 383.902943 -372.394931) (xy 383.888556 -372.380537)
			(xy 383.880778 -372.36173) (xy 383.88036 -372.351554) (xy 383.88036 -372.193566) (xy 383.879953 -372.184379)
			(xy 383.873435 -372.167195) (xy 383.86766 -372.160038) (xy 383.845886 -372.134375) (xy 383.807935 -372.07879)
			(xy 383.7769 -372.019069) (xy 383.753225 -371.956065) (xy 383.737251 -371.890684) (xy 383.729205 -371.823863)
			(xy 383.729204 -371.756558) (xy 383.737247 -371.689736) (xy 383.753219 -371.624355) (xy 383.776891 -371.561351)
			(xy 383.807924 -371.501628) (xy 383.845873 -371.446042) (xy 383.86766 -371.42039) (xy 383.873451 -371.413241)
			(xy 383.879967 -371.396053) (xy 383.88036 -371.386862) (xy 383.88036 -370.89334) (xy 383.879917 -370.884157)
			(xy 383.873425 -370.866972) (xy 383.86766 -370.859812) (xy 383.84586 -370.83417) (xy 383.80791 -370.778582)
			(xy 383.776876 -370.718858) (xy 383.753203 -370.655852) (xy 383.737231 -370.590468) (xy 383.729187 -370.523644)
			(xy 380.451147 -370.523644) (xy 380.451147 -370.523703) (xy 380.443072 -370.590641) (xy 380.427037 -370.656129)
			(xy 380.403273 -370.719226) (xy 380.372122 -370.779022) (xy 380.334032 -370.834655) (xy 380.312168 -370.86032)
			(xy 380.306376 -370.867469) (xy 380.299859 -370.884657) (xy 380.299468 -370.893848) (xy 380.299468 -371.386354)
			(xy 380.299908 -371.395538) (xy 380.306402 -371.412722) (xy 380.312168 -371.419882) (xy 380.334047 -371.445535)
			(xy 380.372137 -371.501171) (xy 380.403289 -371.560968) (xy 380.426925 -371.623725) (xy 381.529032 -371.623725)
			(xy 381.529035 -371.556418) (xy 381.537083 -371.489593) (xy 381.553059 -371.424209) (xy 381.576735 -371.361203)
			(xy 381.607771 -371.301478) (xy 381.645723 -371.245891) (xy 381.667512 -371.220238) (xy 381.673319 -371.2131)
			(xy 381.679827 -371.195904) (xy 381.680212 -371.18671) (xy 381.680212 -371.028722) (xy 381.680751 -371.018569)
			(xy 381.688513 -370.999805) (xy 381.702865 -370.98544) (xy 381.721621 -370.97766) (xy 381.731774 -370.97716)
			(xy 382.448054 -370.97716) (xy 382.458225 -370.977602) (xy 382.477023 -370.985376) (xy 382.491411 -370.999757)
			(xy 382.499193 -371.018551) (xy 382.499616 -371.028722) (xy 382.499616 -371.18671) (xy 382.500018 -371.195898)
			(xy 382.506537 -371.213083) (xy 382.512316 -371.220238) (xy 382.534068 -371.24592) (xy 382.572021 -371.301501)
			(xy 382.603058 -371.36122) (xy 382.626735 -371.424221) (xy 382.642712 -371.4896) (xy 382.65076 -371.55642)
			(xy 382.650763 -371.623723) (xy 382.642722 -371.690544) (xy 382.626752 -371.755924) (xy 382.603081 -371.818927)
			(xy 382.57205 -371.87865) (xy 382.534103 -371.934234) (xy 382.512316 -371.959886) (xy 382.506502 -371.967019)
			(xy 382.499997 -371.984219) (xy 382.499616 -371.993414) (xy 382.499616 -372.486682) (xy 382.500031 -372.495869)
			(xy 382.506541 -372.513053) (xy 382.512316 -372.52021) (xy 382.534138 -372.545834) (xy 382.572089 -372.601424)
			(xy 382.603123 -372.661151) (xy 382.626796 -372.724159) (xy 382.642768 -372.789545) (xy 382.65081 -372.856371)
			(xy 382.650807 -372.92368) (xy 382.642759 -372.990506) (xy 382.626781 -373.05589) (xy 382.603103 -373.118896)
			(xy 382.572063 -373.17862) (xy 382.534107 -373.234206) (xy 382.512316 -373.259858) (xy 382.506514 -373.267)
			(xy 382.500002 -373.284193) (xy 382.499616 -373.293386) (xy 382.499616 -373.451374) (xy 382.499214 -373.46155)
			(xy 382.491429 -373.480352) (xy 382.477036 -373.49474) (xy 382.45823 -373.502517) (xy 382.448054 -373.502936)
			(xy 381.731774 -373.502936) (xy 381.721611 -373.502487) (xy 381.702837 -373.4947) (xy 381.688471 -373.48032)
			(xy 381.680702 -373.461537) (xy 381.680212 -373.451374) (xy 381.680212 -373.293386) (xy 381.679806 -373.284198)
			(xy 381.673289 -373.267014) (xy 381.667512 -373.259858) (xy 381.645758 -373.234178) (xy 381.60781 -373.178595)
			(xy 381.576777 -373.118875) (xy 381.553104 -373.055874) (xy 381.537129 -372.990496) (xy 381.529083 -372.923676)
			(xy 381.52908 -372.856375) (xy 381.53712 -372.789555) (xy 381.553088 -372.724175) (xy 381.576756 -372.661172)
			(xy 381.607784 -372.601449) (xy 381.645727 -372.545862) (xy 381.667512 -372.52021) (xy 381.673331 -372.51308)
			(xy 381.679832 -372.495878) (xy 381.680212 -372.486682) (xy 381.680212 -371.993414) (xy 381.679792 -371.984228)
			(xy 381.673285 -371.967044) (xy 381.667512 -371.959886) (xy 381.645688 -371.934264) (xy 381.607742 -371.878673)
			(xy 381.576712 -371.818945) (xy 381.553042 -371.755936) (xy 381.537073 -371.690551) (xy 381.529032 -371.623725)
			(xy 380.426925 -371.623725) (xy 380.427054 -371.624067) (xy 380.443089 -371.689558) (xy 380.451165 -371.756498)
			(xy 380.451163 -371.823923) (xy 380.443086 -371.890863) (xy 380.427048 -371.956353) (xy 380.403281 -372.019451)
			(xy 380.372126 -372.079247) (xy 380.334034 -372.134881) (xy 380.312168 -372.160546) (xy 380.306365 -372.167687)
			(xy 380.299855 -372.184881) (xy 380.299468 -372.194074) (xy 380.299468 -372.351554) (xy 380.298936 -372.361677)
			(xy 380.291225 -372.380395) (xy 380.276952 -372.394753) (xy 380.25828 -372.402575) (xy 380.24816 -372.403116)
			(xy 379.53188 -372.403116) (xy 379.521727 -372.402695) (xy 379.502977 -372.394896) (xy 379.488655 -372.3805)
			(xy 379.480953 -372.36171) (xy 379.480572 -372.351554) (xy 379.480572 -372.194074) (xy 379.480181 -372.184885)
			(xy 379.473655 -372.1677) (xy 379.467872 -372.160546) (xy 379.446023 -372.134869) (xy 379.407935 -372.079235)
			(xy 379.376786 -372.019441) (xy 379.353022 -371.956345) (xy 379.336986 -371.890858) (xy 379.32891 -371.823922)
			(xy 379.328909 -371.7565) (xy 379.336983 -371.689563) (xy 379.353016 -371.624075) (xy 379.376777 -371.560979)
			(xy 379.407925 -371.501183) (xy 379.44601 -371.445548) (xy 379.467872 -371.419882) (xy 379.473667 -371.412736)
			(xy 379.480181 -371.395546) (xy 379.480572 -371.386354) (xy 379.480572 -370.893848) (xy 379.480145 -370.884663)
			(xy 379.473644 -370.867478) (xy 379.467872 -370.86032) (xy 379.445997 -370.834664) (xy 379.407911 -370.779027)
			(xy 379.376762 -370.71923) (xy 379.353 -370.656132) (xy 379.336966 -370.590642) (xy 379.328892 -370.523703)
			(xy 376.050821 -370.523703) (xy 376.042785 -370.590464) (xy 376.026814 -370.655846) (xy 376.003143 -370.71885)
			(xy 375.972113 -370.778573) (xy 375.934166 -370.83416) (xy 375.91238 -370.859812) (xy 375.906594 -370.866964)
			(xy 375.900073 -370.884149) (xy 375.89968 -370.89334) (xy 375.89968 -371.386862) (xy 375.900113 -371.396047)
			(xy 375.906611 -371.413231) (xy 375.91238 -371.42039) (xy 375.934181 -371.446031) (xy 375.972128 -371.50162)
			(xy 376.00316 -371.561345) (xy 376.026618 -371.623785) (xy 377.128712 -371.623785) (xy 377.128716 -371.556358)
			(xy 377.136796 -371.489417) (xy 377.152836 -371.423925) (xy 377.176606 -371.360827) (xy 377.207762 -371.301029)
			(xy 377.245857 -371.245395) (xy 377.267724 -371.21973) (xy 377.273536 -371.212596) (xy 377.28004 -371.195397)
			(xy 377.280424 -371.186202) (xy 377.280424 -371.028722) (xy 377.280944 -371.018599) (xy 377.288662 -370.999881)
			(xy 377.302938 -370.985524) (xy 377.321612 -370.977702) (xy 377.331732 -370.97716) (xy 378.048012 -370.97716)
			(xy 378.058162 -370.977611) (xy 378.076907 -370.985403) (xy 378.091229 -370.99979) (xy 378.098935 -371.01857)
			(xy 378.09932 -371.028722) (xy 378.09932 -371.186202) (xy 378.099725 -371.19539) (xy 378.106242 -371.212574)
			(xy 378.11202 -371.21973) (xy 378.133846 -371.245426) (xy 378.171934 -371.301057) (xy 378.203086 -371.360849)
			(xy 378.226851 -371.423942) (xy 378.242889 -371.489427) (xy 378.250967 -371.556361) (xy 378.250971 -371.623782)
			(xy 378.242899 -371.690717) (xy 378.226868 -371.756204) (xy 378.203109 -371.819299) (xy 378.171964 -371.879094)
			(xy 378.133881 -371.934728) (xy 378.11202 -371.960394) (xy 378.106246 -371.967555) (xy 378.099717 -371.984733)
			(xy 378.09932 -371.993922) (xy 378.09932 -372.486174) (xy 378.099738 -372.49536) (xy 378.106246 -372.512545)
			(xy 378.11202 -372.519702) (xy 378.133917 -372.54534) (xy 378.172003 -372.600979) (xy 378.203151 -372.660779)
			(xy 378.226913 -372.723879) (xy 378.242945 -372.789372) (xy 378.251018 -372.856313) (xy 378.251015 -372.923739)
			(xy 378.242936 -372.990679) (xy 378.226897 -373.056169) (xy 378.20313 -373.119268) (xy 378.171977 -373.179065)
			(xy 378.133885 -373.2347) (xy 378.11202 -373.260366) (xy 378.106215 -373.267506) (xy 378.099705 -373.2847)
			(xy 378.09932 -373.293894) (xy 378.09932 -373.451374) (xy 378.098851 -373.461504) (xy 378.091125 -373.480232)
			(xy 378.076832 -373.494591) (xy 378.05814 -373.502404) (xy 378.048012 -373.502936) (xy 377.331732 -373.502936)
			(xy 377.321584 -373.502453) (xy 377.30284 -373.494675) (xy 377.288516 -373.480297) (xy 377.280809 -373.461523)
			(xy 377.280424 -373.451374) (xy 377.280424 -373.293894) (xy 377.280012 -373.284707) (xy 377.273499 -373.267523)
			(xy 377.267724 -373.260366) (xy 377.245893 -373.234674) (xy 377.207801 -373.179044) (xy 377.176648 -373.119251)
			(xy 377.152881 -373.056158) (xy 377.136842 -372.990672) (xy 377.128763 -372.923736) (xy 377.12876 -372.856315)
			(xy 377.136833 -372.789378) (xy 377.152865 -372.723891) (xy 377.176627 -372.660795) (xy 377.207775 -372.601)
			(xy 377.245861 -372.545367) (xy 377.267724 -372.519702) (xy 377.273505 -372.512546) (xy 377.280028 -372.495364)
			(xy 377.280424 -372.486174) (xy 377.280424 -371.993922) (xy 377.279998 -371.984737) (xy 377.273495 -371.967552)
			(xy 377.267724 -371.960394) (xy 377.245822 -371.93476) (xy 377.207733 -371.879122) (xy 377.176582 -371.819321)
			(xy 377.152819 -371.75622) (xy 377.136786 -371.690727) (xy 377.128712 -371.623785) (xy 376.026618 -371.623785)
			(xy 376.026831 -371.624351) (xy 376.042802 -371.689734) (xy 376.050845 -371.756558) (xy 376.050844 -371.823863)
			(xy 376.042799 -371.890687) (xy 376.026825 -371.956069) (xy 376.003151 -372.019074) (xy 375.972117 -372.078799)
			(xy 375.934168 -372.134386) (xy 375.91238 -372.160038) (xy 375.906582 -372.167182) (xy 375.900069 -372.184374)
			(xy 375.89968 -372.193566) (xy 375.89968 -372.351554) (xy 375.899199 -372.36172) (xy 375.891432 -372.380511)
			(xy 375.877064 -372.394896) (xy 375.858284 -372.402686) (xy 375.848118 -372.403116) (xy 375.131838 -372.403116)
			(xy 375.121663 -372.402704) (xy 375.102861 -372.394923) (xy 375.088473 -372.380533) (xy 375.080695 -372.361729)
			(xy 375.080276 -372.351554) (xy 375.080276 -372.193566) (xy 375.079887 -372.184376) (xy 375.073359 -372.167192)
			(xy 375.067576 -372.160038) (xy 375.045801 -372.134375) (xy 375.007849 -372.078791) (xy 374.976813 -372.019069)
			(xy 374.953138 -371.956066) (xy 374.937163 -371.890685) (xy 374.929117 -371.823863) (xy 374.929116 -371.756558)
			(xy 374.937159 -371.689736) (xy 374.953132 -371.624354) (xy 374.976805 -371.56135) (xy 375.007838 -371.501627)
			(xy 375.045788 -371.446042) (xy 375.067576 -371.42039) (xy 375.073357 -371.413233) (xy 375.079882 -371.396052)
			(xy 375.080276 -371.386862) (xy 375.080276 -370.89334) (xy 375.079852 -370.884154) (xy 375.073349 -370.866969)
			(xy 375.067576 -370.859812) (xy 375.045775 -370.83417) (xy 375.007825 -370.778583) (xy 374.97679 -370.718858)
			(xy 374.953116 -370.655852) (xy 374.937143 -370.590469) (xy 374.929099 -370.523644) (xy 345.250797 -370.523644)
			(xy 345.242754 -370.590465) (xy 345.226782 -370.655847) (xy 345.203109 -370.718851) (xy 345.172076 -370.778574)
			(xy 345.134128 -370.83416) (xy 345.11234 -370.859812) (xy 345.106548 -370.86696) (xy 345.100032 -370.884149)
			(xy 345.09964 -370.89334) (xy 345.09964 -371.386862) (xy 345.100082 -371.396046) (xy 345.106575 -371.41323)
			(xy 345.11234 -371.42039) (xy 345.134142 -371.446031) (xy 345.172092 -371.501618) (xy 345.203126 -371.561343)
			(xy 345.226564 -371.623726) (xy 346.329187 -371.623726) (xy 346.32919 -371.556417) (xy 346.337239 -371.489591)
			(xy 346.353217 -371.424206) (xy 346.376896 -371.3612) (xy 346.407936 -371.301476) (xy 346.445893 -371.24589)
			(xy 346.467684 -371.220238) (xy 346.473488 -371.213098) (xy 346.479999 -371.195904) (xy 346.480384 -371.18671)
			(xy 346.480384 -371.028722) (xy 346.480783 -371.018546) (xy 346.488569 -370.999743) (xy 346.502963 -370.985356)
			(xy 346.52177 -370.977578) (xy 346.531946 -370.97716) (xy 347.248226 -370.97716) (xy 347.258388 -370.977612)
			(xy 347.277162 -370.9854) (xy 347.291527 -370.999778) (xy 347.299297 -371.018559) (xy 347.299788 -371.028722)
			(xy 347.299788 -371.18671) (xy 347.300196 -371.195897) (xy 347.306711 -371.213082) (xy 347.312488 -371.220238)
			(xy 347.334237 -371.245921) (xy 347.372185 -371.301504) (xy 347.403219 -371.361224) (xy 347.426893 -371.424224)
			(xy 347.442867 -371.489602) (xy 347.450914 -371.556421) (xy 347.450918 -371.623722) (xy 347.442878 -371.690542)
			(xy 347.426909 -371.755921) (xy 347.403242 -371.818924) (xy 347.372215 -371.878647) (xy 347.334272 -371.934233)
			(xy 347.312488 -371.959886) (xy 347.306671 -371.967017) (xy 347.300169 -371.984218) (xy 347.299788 -371.993414)
			(xy 347.299788 -372.486682) (xy 347.30021 -372.495868) (xy 347.306716 -372.513052) (xy 347.312488 -372.52021)
			(xy 347.334308 -372.545835) (xy 347.372254 -372.601426) (xy 347.403285 -372.661154) (xy 347.426954 -372.724162)
			(xy 347.442924 -372.789547) (xy 347.450965 -372.856372) (xy 347.450962 -372.923679) (xy 347.442915 -372.990504)
			(xy 347.426939 -373.055887) (xy 347.403264 -373.118893) (xy 347.372228 -373.178618) (xy 347.334277 -373.234205)
			(xy 347.312488 -373.259858) (xy 347.306683 -373.266997) (xy 347.300174 -373.284192) (xy 347.299788 -373.293386)
			(xy 347.299788 -373.451374) (xy 347.299246 -373.461527) (xy 347.291485 -373.480291) (xy 347.277134 -373.494656)
			(xy 347.258378 -373.502436) (xy 347.248226 -373.502936) (xy 346.531946 -373.502936) (xy 346.521774 -373.502498)
			(xy 346.502975 -373.494723) (xy 346.488588 -373.480341) (xy 346.480806 -373.461546) (xy 346.480384 -373.451374)
			(xy 346.480384 -373.293386) (xy 346.479984 -373.284198) (xy 346.473464 -373.267013) (xy 346.467684 -373.259858)
			(xy 346.445928 -373.234179) (xy 346.407976 -373.178597) (xy 346.376938 -373.118878) (xy 346.353262 -373.055877)
			(xy 346.337285 -372.990498) (xy 346.329237 -372.923677) (xy 346.329234 -372.856374) (xy 346.337276 -372.789553)
			(xy 346.353247 -372.724172) (xy 346.376917 -372.661169) (xy 346.407949 -372.601447) (xy 346.445897 -372.545862)
			(xy 346.467684 -372.52021) (xy 346.473499 -372.513078) (xy 346.480003 -372.495877) (xy 346.480384 -372.486682)
			(xy 346.480384 -371.993414) (xy 346.479971 -371.984227) (xy 346.47346 -371.967042) (xy 346.467684 -371.959886)
			(xy 346.445858 -371.934265) (xy 346.407907 -371.878675) (xy 346.376873 -371.818948) (xy 346.3532 -371.755939)
			(xy 346.337229 -371.690553) (xy 346.329187 -371.623726) (xy 345.226564 -371.623726) (xy 345.226798 -371.624349)
			(xy 345.242771 -371.689733) (xy 345.250814 -371.756557) (xy 345.250813 -371.823864) (xy 345.242767 -371.890688)
			(xy 345.226792 -371.956071) (xy 345.203117 -372.019076) (xy 345.172081 -372.0788) (xy 345.134129 -372.134386)
			(xy 345.11234 -372.160038) (xy 345.106537 -372.167179) (xy 345.100028 -372.184373) (xy 345.09964 -372.193566)
			(xy 345.09964 -372.351554) (xy 345.099198 -372.361725) (xy 345.091424 -372.380523) (xy 345.077043 -372.394911)
			(xy 345.058249 -372.402693) (xy 345.048078 -372.403116) (xy 344.331798 -372.403116) (xy 344.321621 -372.402737)
			(xy 344.302817 -372.394942) (xy 344.288431 -372.380543) (xy 344.280654 -372.361732) (xy 344.280236 -372.351554)
			(xy 344.280236 -372.193566) (xy 344.279834 -372.184378) (xy 344.273314 -372.167194) (xy 344.267536 -372.160038)
			(xy 344.245762 -372.134374) (xy 344.207813 -372.078789) (xy 344.17678 -372.019067) (xy 344.153106 -371.956064)
			(xy 344.137132 -371.890684) (xy 344.129087 -371.823862) (xy 344.129086 -371.756559) (xy 344.137129 -371.689737)
			(xy 344.1531 -371.624356) (xy 344.176771 -371.561352) (xy 344.207803 -371.501629) (xy 344.245749 -371.446042)
			(xy 344.267536 -371.42039) (xy 344.273324 -371.413239) (xy 344.279843 -371.396053) (xy 344.280236 -371.386862)
			(xy 344.280236 -370.89334) (xy 344.279798 -370.884156) (xy 344.273303 -370.866972) (xy 344.267536 -370.859812)
			(xy 344.245736 -370.83417) (xy 344.207788 -370.778582) (xy 344.176756 -370.718857) (xy 344.153084 -370.655851)
			(xy 344.137112 -370.590468) (xy 344.129068 -370.523644) (xy 340.851006 -370.523644) (xy 340.842963 -370.590465)
			(xy 340.826991 -370.655847) (xy 340.803319 -370.718851) (xy 340.772287 -370.778574) (xy 340.734339 -370.83416)
			(xy 340.712552 -370.859812) (xy 340.706762 -370.866962) (xy 340.700245 -370.884149) (xy 340.699852 -370.89334)
			(xy 340.699852 -371.386862) (xy 340.700291 -371.396046) (xy 340.706786 -371.41323) (xy 340.712552 -371.42039)
			(xy 340.734354 -371.446031) (xy 340.772303 -371.501618) (xy 340.803336 -371.561344) (xy 340.826797 -371.623785)
			(xy 341.928891 -371.623785) (xy 341.928895 -371.556358) (xy 341.936974 -371.489417) (xy 341.953014 -371.423926)
			(xy 341.976782 -371.360828) (xy 342.007937 -371.301031) (xy 342.04603 -371.245395) (xy 342.067896 -371.21973)
			(xy 342.073704 -371.212593) (xy 342.080212 -371.195396) (xy 342.080596 -371.186202) (xy 342.080596 -371.028722)
			(xy 342.081143 -371.018602) (xy 342.088856 -370.99989) (xy 342.103123 -370.985534) (xy 342.121787 -370.977706)
			(xy 342.131904 -370.97716) (xy 342.848184 -370.97716) (xy 342.858332 -370.977634) (xy 342.877076 -370.985417)
			(xy 342.891399 -370.999797) (xy 342.899106 -371.018572) (xy 342.899492 -371.028722) (xy 342.899492 -371.186202)
			(xy 342.899903 -371.195389) (xy 342.906416 -371.212573) (xy 342.912192 -371.21973) (xy 342.934019 -371.245426)
			(xy 342.972109 -371.301056) (xy 343.003262 -371.360848) (xy 343.027029 -371.423941) (xy 343.043067 -371.489426)
			(xy 343.051146 -371.556361) (xy 343.05115 -371.623782) (xy 343.043077 -371.690718) (xy 343.027046 -371.756205)
			(xy 343.003285 -371.8193) (xy 342.972139 -371.879095) (xy 342.934054 -371.934729) (xy 342.912192 -371.960394)
			(xy 342.906415 -371.967553) (xy 342.899889 -371.984733) (xy 342.899492 -371.993922) (xy 342.899492 -372.486174)
			(xy 342.899917 -372.49536) (xy 342.90642 -372.512544) (xy 342.912192 -372.519702) (xy 342.93409 -372.54534)
			(xy 342.972178 -372.600978) (xy 343.003328 -372.660778) (xy 343.02709 -372.723878) (xy 343.043124 -372.789371)
			(xy 343.051197 -372.856312) (xy 343.051194 -372.923739) (xy 343.043114 -372.99068) (xy 343.027075 -373.056171)
			(xy 343.003307 -373.119269) (xy 342.972152 -373.179066) (xy 342.934058 -373.234701) (xy 342.912192 -373.260366)
			(xy 342.906384 -373.267503) (xy 342.899876 -373.2847) (xy 342.899492 -373.293894) (xy 342.899492 -373.451374)
			(xy 342.898953 -373.461495) (xy 342.89124 -373.48021) (xy 342.87697 -373.494566) (xy 342.858302 -373.502392)
			(xy 342.848184 -373.502936) (xy 342.131904 -373.502936) (xy 342.121755 -373.502476) (xy 342.103009 -373.494688)
			(xy 342.088687 -373.480304) (xy 342.080981 -373.461525) (xy 342.080596 -373.451374) (xy 342.080596 -373.293894)
			(xy 342.080189 -373.284706) (xy 342.073673 -373.267522) (xy 342.067896 -373.260366) (xy 342.046066 -373.234673)
			(xy 342.007976 -373.179042) (xy 341.976824 -373.11925) (xy 341.953058 -373.056157) (xy 341.937021 -372.990671)
			(xy 341.928942 -372.923736) (xy 341.928939 -372.856315) (xy 341.937011 -372.789379) (xy 341.953043 -372.723892)
			(xy 341.976803 -372.660797) (xy 342.00795 -372.601001) (xy 342.046034 -372.545367) (xy 342.067896 -372.519702)
			(xy 342.073674 -372.512543) (xy 342.0802 -372.495363) (xy 342.080596 -372.486174) (xy 342.080596 -371.993922)
			(xy 342.080176 -371.984736) (xy 342.073669 -371.967551) (xy 342.067896 -371.960394) (xy 342.045995 -371.934759)
			(xy 342.007908 -371.87912) (xy 341.976759 -371.81932) (xy 341.952997 -371.756219) (xy 341.936964 -371.690726)
			(xy 341.928891 -371.623785) (xy 340.826797 -371.623785) (xy 340.827009 -371.62435) (xy 340.842981 -371.689733)
			(xy 340.851024 -371.756557) (xy 340.851023 -371.823864) (xy 340.842977 -371.890687) (xy 340.827002 -371.956071)
			(xy 340.803328 -372.019076) (xy 340.772292 -372.0788) (xy 340.734341 -372.134386) (xy 340.712552 -372.160038)
			(xy 340.706751 -372.16718) (xy 340.70024 -372.184373) (xy 340.699852 -372.193566) (xy 340.699852 -372.351554)
			(xy 340.699398 -372.361724) (xy 340.691627 -372.380519) (xy 340.67725 -372.394906) (xy 340.65846 -372.402691)
			(xy 340.64829 -372.403116) (xy 339.93201 -372.403116) (xy 339.921833 -372.402727) (xy 339.90303 -372.394937)
			(xy 339.888643 -372.38054) (xy 339.880866 -372.361731) (xy 339.880448 -372.351554) (xy 339.880448 -372.193566)
			(xy 339.880043 -372.184378) (xy 339.873525 -372.167195) (xy 339.867748 -372.160038) (xy 339.845974 -372.134375)
			(xy 339.808024 -372.07879) (xy 339.77699 -372.019068) (xy 339.753316 -371.956065) (xy 339.737342 -371.890684)
			(xy 339.729296 -371.823863) (xy 339.729295 -371.756558) (xy 339.737338 -371.689737) (xy 339.75331 -371.624355)
			(xy 339.776981 -371.561351) (xy 339.808013 -371.501628) (xy 339.845961 -371.446042) (xy 339.867748 -371.42039)
			(xy 339.873537 -371.41324) (xy 339.880055 -371.396053) (xy 339.880448 -371.386862) (xy 339.880448 -370.89334)
			(xy 339.880008 -370.884156) (xy 339.873514 -370.866972) (xy 339.867748 -370.859812) (xy 339.845948 -370.83417)
			(xy 339.807999 -370.778582) (xy 339.776966 -370.718857) (xy 339.753293 -370.655851) (xy 339.737321 -370.590468)
			(xy 339.729277 -370.523644) (xy 336.451238 -370.523644) (xy 336.451238 -370.523703) (xy 336.443163 -370.590641)
			(xy 336.427128 -370.65613) (xy 336.403363 -370.719227) (xy 336.372211 -370.779022) (xy 336.334121 -370.834656)
			(xy 336.312256 -370.86032) (xy 336.306463 -370.867467) (xy 336.299947 -370.884656) (xy 336.299556 -370.893848)
			(xy 336.299556 -371.386354) (xy 336.299998 -371.395538) (xy 336.306491 -371.412722) (xy 336.312256 -371.419882)
			(xy 336.334135 -371.445535) (xy 336.372226 -371.50117) (xy 336.403379 -371.560968) (xy 336.427016 -371.623725)
			(xy 337.529123 -371.623725) (xy 337.529126 -371.556418) (xy 337.537174 -371.489593) (xy 337.55315 -371.424209)
			(xy 337.576825 -371.361204) (xy 337.60786 -371.301479) (xy 337.645811 -371.245891) (xy 337.6676 -371.220238)
			(xy 337.673405 -371.213099) (xy 337.679915 -371.195904) (xy 337.6803 -371.18671) (xy 337.6803 -371.028722)
			(xy 337.68085 -371.01857) (xy 337.68861 -370.999809) (xy 337.702958 -370.985444) (xy 337.721711 -370.977662)
			(xy 337.731862 -370.97716) (xy 338.448142 -370.97716) (xy 338.458305 -370.9776) (xy 338.477079 -370.985392)
			(xy 338.491444 -370.999774) (xy 338.499213 -371.018558) (xy 338.499704 -371.028722) (xy 338.499704 -371.18671)
			(xy 338.500109 -371.195898) (xy 338.506626 -371.213082) (xy 338.512404 -371.220238) (xy 338.534153 -371.245921)
			(xy 338.5721 -371.301504) (xy 338.603133 -371.361224) (xy 338.626806 -371.424224) (xy 338.64278 -371.489602)
			(xy 338.650827 -371.556421) (xy 338.65083 -371.623722) (xy 338.64279 -371.690541) (xy 338.626823 -371.755921)
			(xy 338.603156 -371.818924) (xy 338.57213 -371.878646) (xy 338.534188 -371.934233) (xy 338.512404 -371.959886)
			(xy 338.506589 -371.967018) (xy 338.500085 -371.984219) (xy 338.499704 -371.993414) (xy 338.499704 -372.486682)
			(xy 338.500122 -372.495868) (xy 338.50663 -372.513053) (xy 338.512404 -372.52021) (xy 338.534224 -372.545835)
			(xy 338.572169 -372.601427) (xy 338.603198 -372.661154) (xy 338.626867 -372.724162) (xy 338.642836 -372.789547)
			(xy 338.650877 -372.856372) (xy 338.650874 -372.923679) (xy 338.642827 -372.990503) (xy 338.626852 -373.055887)
			(xy 338.603177 -373.118892) (xy 338.572142 -373.178617) (xy 338.534192 -373.234205) (xy 338.512404 -373.259858)
			(xy 338.506601 -373.266999) (xy 338.50009 -373.284193) (xy 338.499704 -373.293386) (xy 338.499704 -373.451374)
			(xy 338.499147 -373.461525) (xy 338.491388 -373.480286) (xy 338.477043 -373.49465) (xy 338.458292 -373.502433)
			(xy 338.448142 -373.502936) (xy 337.731862 -373.502936) (xy 337.721699 -373.502497) (xy 337.702924 -373.494705)
			(xy 337.688559 -373.480323) (xy 337.68079 -373.461538) (xy 337.6803 -373.451374) (xy 337.6803 -373.293386)
			(xy 337.679896 -373.284198) (xy 337.673378 -373.267014) (xy 337.6676 -373.259858) (xy 337.645847 -373.234178)
			(xy 337.6079 -373.178595) (xy 337.576867 -373.118874) (xy 337.553194 -373.055874) (xy 337.53722 -372.990495)
			(xy 337.529174 -372.923676) (xy 337.52917 -372.856375) (xy 337.537211 -372.789555) (xy 337.553179 -372.724175)
			(xy 337.576846 -372.661172) (xy 337.607873 -372.601449) (xy 337.645816 -372.545863) (xy 337.6676 -372.52021)
			(xy 337.673417 -372.513079) (xy 337.67992 -372.495878) (xy 337.6803 -372.486682) (xy 337.6803 -371.993414)
			(xy 337.679883 -371.984228) (xy 337.673374 -371.967043) (xy 337.6676 -371.959886) (xy 337.645776 -371.934264)
			(xy 337.607831 -371.878672) (xy 337.576802 -371.818944) (xy 337.553133 -371.755936) (xy 337.537163 -371.69055)
			(xy 337.529123 -371.623725) (xy 336.427016 -371.623725) (xy 336.427144 -371.624066) (xy 336.44318 -371.689557)
			(xy 336.451256 -371.756498) (xy 336.451254 -371.823923) (xy 336.443176 -371.890863) (xy 336.427138 -371.956354)
			(xy 336.40337 -372.019451) (xy 336.372216 -372.079248) (xy 336.334122 -372.134881) (xy 336.312256 -372.160546)
			(xy 336.306452 -372.167686) (xy 336.299943 -372.184881) (xy 336.299556 -372.194074) (xy 336.299556 -372.351554)
			(xy 336.299036 -372.361678) (xy 336.291322 -372.380399) (xy 336.277046 -372.394757) (xy 336.258369 -372.402577)
			(xy 336.248248 -372.403116) (xy 335.531968 -372.403116) (xy 335.521814 -372.402705) (xy 335.503064 -372.394902)
			(xy 335.488742 -372.380502) (xy 335.481041 -372.36171) (xy 335.48066 -372.351554) (xy 335.48066 -372.194074)
			(xy 335.480249 -372.184887) (xy 335.473734 -372.167704) (xy 335.46796 -372.160546) (xy 335.446111 -372.134869)
			(xy 335.408025 -372.079235) (xy 335.376876 -372.01944) (xy 335.353112 -371.956345) (xy 335.337077 -371.890858)
			(xy 335.329001 -371.823921) (xy 335.329 -371.7565) (xy 335.337073 -371.689563) (xy 335.353106 -371.624075)
			(xy 335.376867 -371.560979) (xy 335.408014 -371.501183) (xy 335.446098 -371.445548) (xy 335.46796 -371.419882)
			(xy 335.473754 -371.412735) (xy 335.480269 -371.395546) (xy 335.48066 -371.386354) (xy 335.48066 -370.893848)
			(xy 335.480214 -370.884665) (xy 335.473724 -370.867481) (xy 335.46796 -370.86032) (xy 335.446086 -370.834664)
			(xy 335.408 -370.779027) (xy 335.376852 -370.719229) (xy 335.35309 -370.656131) (xy 335.337057 -370.590642)
			(xy 335.328983 -370.523703) (xy 332.050912 -370.523703) (xy 332.042876 -370.590465) (xy 332.026905 -370.655846)
			(xy 332.003233 -370.71885) (xy 331.972202 -370.778573) (xy 331.934255 -370.83416) (xy 331.912468 -370.859812)
			(xy 331.90668 -370.866963) (xy 331.900161 -370.884149) (xy 331.899768 -370.89334) (xy 331.899768 -371.386862)
			(xy 331.900204 -371.396046) (xy 331.906701 -371.41323) (xy 331.912468 -371.42039) (xy 331.934269 -371.446031)
			(xy 331.972217 -371.501619) (xy 332.00325 -371.561344) (xy 332.026709 -371.623785) (xy 333.128803 -371.623785)
			(xy 333.128807 -371.556358) (xy 333.136887 -371.489417) (xy 333.152927 -371.423926) (xy 333.176696 -371.360827)
			(xy 333.207851 -371.30103) (xy 333.245945 -371.245395) (xy 333.267812 -371.21973) (xy 333.273622 -371.212594)
			(xy 333.280128 -371.195397) (xy 333.280512 -371.186202) (xy 333.280512 -371.028722) (xy 333.281044 -371.0186)
			(xy 333.288759 -370.999885) (xy 333.303031 -370.985529) (xy 333.321701 -370.977704) (xy 333.33182 -370.97716)
			(xy 334.0481 -370.97716) (xy 334.058249 -370.977621) (xy 334.076994 -370.985409) (xy 334.091316 -370.999793)
			(xy 334.099023 -371.018571) (xy 334.099408 -371.028722) (xy 334.099408 -371.186202) (xy 334.099815 -371.195389)
			(xy 334.106331 -371.212574) (xy 334.112108 -371.21973) (xy 334.133934 -371.245426) (xy 334.172024 -371.301056)
			(xy 334.203176 -371.360848) (xy 334.226942 -371.423941) (xy 334.242979 -371.489426) (xy 334.251058 -371.556361)
			(xy 334.251062 -371.623782) (xy 334.24299 -371.690717) (xy 334.226958 -371.756204) (xy 334.203199 -371.819299)
			(xy 334.172053 -371.879095) (xy 334.133969 -371.934729) (xy 334.112108 -371.960394) (xy 334.106332 -371.967554)
			(xy 334.099805 -371.984733) (xy 334.099408 -371.993922) (xy 334.099408 -372.486174) (xy 334.099829 -372.49536)
			(xy 334.106335 -372.512545) (xy 334.112108 -372.519702) (xy 334.134005 -372.54534) (xy 334.172092 -372.600978)
			(xy 334.203241 -372.660779) (xy 334.227003 -372.723879) (xy 334.243036 -372.789371) (xy 334.251109 -372.856312)
			(xy 334.251106 -372.923739) (xy 334.243027 -372.990679) (xy 334.226988 -373.05617) (xy 334.20322 -373.119268)
			(xy 334.172066 -373.179065) (xy 334.133974 -373.234701) (xy 334.112108 -373.260366) (xy 334.106302 -373.267504)
			(xy 334.099793 -373.2847) (xy 334.099408 -373.293894) (xy 334.099408 -373.451374) (xy 334.098854 -373.461493)
			(xy 334.091143 -373.480205) (xy 334.076878 -373.49456) (xy 334.058216 -373.502389) (xy 334.0481 -373.502936)
			(xy 333.33182 -373.502936) (xy 333.321672 -373.502463) (xy 333.302927 -373.494681) (xy 333.288604 -373.4803)
			(xy 333.280897 -373.461524) (xy 333.280512 -373.451374) (xy 333.280512 -373.293894) (xy 333.280102 -373.284707)
			(xy 333.273588 -373.267523) (xy 333.267812 -373.260366) (xy 333.245981 -373.234673) (xy 333.20789 -373.179043)
			(xy 333.176738 -373.119251) (xy 333.152971 -373.056157) (xy 333.136933 -372.990672) (xy 333.128854 -372.923736)
			(xy 333.128851 -372.856315) (xy 333.136924 -372.789379) (xy 333.152956 -372.723891) (xy 333.176717 -372.660796)
			(xy 333.207864 -372.601001) (xy 333.24595 -372.545367) (xy 333.267812 -372.519702) (xy 333.273592 -372.512545)
			(xy 333.280116 -372.495363) (xy 333.280512 -372.486174) (xy 333.280512 -371.993922) (xy 333.280088 -371.984736)
			(xy 333.273584 -371.967552) (xy 333.267812 -371.960394) (xy 333.24591 -371.93476) (xy 333.207822 -371.879121)
			(xy 333.176672 -371.819321) (xy 333.15291 -371.75622) (xy 333.136876 -371.690727) (xy 333.128803 -371.623785)
			(xy 332.026709 -371.623785) (xy 332.026921 -371.62435) (xy 332.042893 -371.689734) (xy 332.050936 -371.756558)
			(xy 332.050935 -371.823864) (xy 332.042889 -371.890687) (xy 332.026915 -371.95607) (xy 332.003241 -372.019075)
			(xy 331.972207 -372.078799) (xy 331.934256 -372.134386) (xy 331.912468 -372.160038) (xy 331.906669 -372.167181)
			(xy 331.900156 -372.184373) (xy 331.899768 -372.193566) (xy 331.899768 -372.351554) (xy 331.899299 -372.361722)
			(xy 331.89153 -372.380514) (xy 331.877158 -372.394901) (xy 331.858373 -372.402688) (xy 331.848206 -372.403116)
			(xy 331.131926 -372.403116) (xy 331.12175 -372.402714) (xy 331.102948 -372.394929) (xy 331.08856 -372.380536)
			(xy 331.080783 -372.36173) (xy 331.080364 -372.351554) (xy 331.080364 -372.193566) (xy 331.079956 -372.184379)
			(xy 331.073439 -372.167195) (xy 331.067664 -372.160038) (xy 331.045889 -372.134375) (xy 331.007939 -372.078791)
			(xy 330.976903 -372.019069) (xy 330.953229 -371.956066) (xy 330.937254 -371.890684) (xy 330.929208 -371.823863)
			(xy 330.929207 -371.756558) (xy 330.93725 -371.689736) (xy 330.953222 -371.624355) (xy 330.976895 -371.561351)
			(xy 331.007928 -371.501628) (xy 331.045876 -371.446042) (xy 331.067664 -371.42039) (xy 331.073455 -371.413241)
			(xy 331.079971 -371.396053) (xy 331.080364 -371.386862) (xy 331.080364 -370.89334) (xy 331.07992 -370.884157)
			(xy 331.073428 -370.866973) (xy 331.067664 -370.859812) (xy 331.045864 -370.83417) (xy 331.007914 -370.778582)
			(xy 330.97688 -370.718858) (xy 330.953206 -370.655852) (xy 330.937234 -370.590468) (xy 330.92919 -370.523644)
			(xy 301.250887 -370.523644) (xy 301.250887 -370.523702) (xy 301.242812 -370.590639) (xy 301.226779 -370.656127)
			(xy 301.203017 -370.719224) (xy 301.171869 -370.77902) (xy 301.133783 -370.834654) (xy 301.11192 -370.86032)
			(xy 301.106135 -370.867473) (xy 301.099613 -370.884658) (xy 301.09922 -370.893848) (xy 301.09922 -371.386354)
			(xy 301.099648 -371.395539) (xy 301.106149 -371.412724) (xy 301.11192 -371.419882) (xy 301.133797 -371.445536)
			(xy 301.171884 -371.501173) (xy 301.203033 -371.560971) (xy 301.226688 -371.623785) (xy 302.328773 -371.623785)
			(xy 302.328777 -371.556358) (xy 302.336856 -371.489418) (xy 302.352895 -371.423927) (xy 302.376662 -371.360829)
			(xy 302.407815 -371.301031) (xy 302.445907 -371.245396) (xy 302.467772 -371.21973) (xy 302.47359 -371.2126)
			(xy 302.48009 -371.195398) (xy 302.480472 -371.186202) (xy 302.480472 -371.028722) (xy 302.480945 -371.018593)
			(xy 302.488672 -370.999866) (xy 302.502963 -370.985508) (xy 302.521653 -370.977693) (xy 302.53178 -370.97716)
			(xy 303.24806 -370.97716) (xy 303.258207 -370.977654) (xy 303.27695 -370.985429) (xy 303.291274 -370.999803)
			(xy 303.298982 -371.018574) (xy 303.299368 -371.028722) (xy 303.299368 -371.186202) (xy 303.299784 -371.195388)
			(xy 303.306294 -371.212572) (xy 303.312068 -371.21973) (xy 303.333896 -371.245425) (xy 303.371988 -371.301055)
			(xy 303.403142 -371.360847) (xy 303.42691 -371.42394) (xy 303.442949 -371.489425) (xy 303.451028 -371.556361)
			(xy 303.451031 -371.623782) (xy 303.442959 -371.690718) (xy 303.426926 -371.756206) (xy 303.403165 -371.819301)
			(xy 303.372017 -371.879096) (xy 303.333931 -371.934729) (xy 303.312068 -371.960394) (xy 303.306287 -371.96755)
			(xy 303.299764 -371.984732) (xy 303.299368 -371.993922) (xy 303.299368 -372.486174) (xy 303.299798 -372.495359)
			(xy 303.306299 -372.512543) (xy 303.312068 -372.519702) (xy 303.333966 -372.545339) (xy 303.372056 -372.600977)
			(xy 303.403207 -372.660777) (xy 303.426971 -372.723877) (xy 303.443005 -372.78937) (xy 303.451079 -372.856312)
			(xy 303.451076 -372.923739) (xy 303.442996 -372.99068) (xy 303.426956 -373.056172) (xy 303.403186 -373.11927)
			(xy 303.37203 -373.179067) (xy 303.333935 -373.234701) (xy 303.312068 -373.260366) (xy 303.306257 -373.267501)
			(xy 303.299752 -373.284699) (xy 303.299368 -373.293894) (xy 303.299368 -373.451374) (xy 303.298853 -373.461498)
			(xy 303.291135 -373.480217) (xy 303.276857 -373.494574) (xy 303.258181 -373.502396) (xy 303.24806 -373.502936)
			(xy 302.53178 -373.502936) (xy 302.521629 -373.502496) (xy 302.502883 -373.4947) (xy 302.488562 -373.48031)
			(xy 302.480856 -373.461527) (xy 302.480472 -373.451374) (xy 302.480472 -373.293894) (xy 302.480071 -373.284706)
			(xy 302.473552 -373.267521) (xy 302.467772 -373.260366) (xy 302.445942 -373.234673) (xy 302.407855 -373.179042)
			(xy 302.376704 -373.119249) (xy 302.352939 -373.056156) (xy 302.336902 -372.99067) (xy 302.328824 -372.923736)
			(xy 302.328821 -372.856315) (xy 302.336893 -372.78938) (xy 302.352924 -372.723893) (xy 302.376683 -372.660798)
			(xy 302.407828 -372.601002) (xy 302.445911 -372.545368) (xy 302.467772 -372.519702) (xy 302.473559 -372.51255)
			(xy 302.480077 -372.495364) (xy 302.480472 -372.486174) (xy 302.480472 -371.993922) (xy 302.480058 -371.984735)
			(xy 302.473548 -371.96755) (xy 302.467772 -371.960394) (xy 302.445872 -371.934759) (xy 302.407786 -371.87912)
			(xy 302.376638 -371.819319) (xy 302.352878 -371.756218) (xy 302.336846 -371.690726) (xy 302.328773 -371.623785)
			(xy 301.226688 -371.623785) (xy 301.226795 -371.624069) (xy 301.242829 -371.689559) (xy 301.250904 -371.756498)
			(xy 301.250903 -371.823923) (xy 301.242826 -371.890862) (xy 301.226789 -371.956351) (xy 301.203024 -372.019449)
			(xy 301.171873 -372.079245) (xy 301.133784 -372.13488) (xy 301.11192 -372.160546) (xy 301.106124 -372.167692)
			(xy 301.099608 -372.184882) (xy 301.09922 -372.194074) (xy 301.09922 -372.351554) (xy 301.098734 -372.361683)
			(xy 301.091014 -372.38041) (xy 301.076727 -372.39477) (xy 301.058038 -372.402583) (xy 301.047912 -372.403116)
			(xy 300.331632 -372.403116) (xy 300.321482 -372.402653) (xy 300.302733 -372.394871) (xy 300.288409 -372.380487)
			(xy 300.280705 -372.361706) (xy 300.280324 -372.351554) (xy 300.280324 -372.194074) (xy 300.279921 -372.184886)
			(xy 300.273402 -372.167702) (xy 300.267624 -372.160546) (xy 300.245773 -372.13487) (xy 300.207682 -372.079237)
			(xy 300.17653 -372.019443) (xy 300.152764 -371.956347) (xy 300.136726 -371.890859) (xy 300.128649 -371.823922)
			(xy 300.128648 -371.756499) (xy 300.136723 -371.689561) (xy 300.152757 -371.624073) (xy 300.176521 -371.560976)
			(xy 300.207671 -371.501181) (xy 300.24576 -371.445547) (xy 300.267624 -371.419882) (xy 300.273413 -371.412732)
			(xy 300.279932 -371.395545) (xy 300.280324 -371.386354) (xy 300.280324 -370.893848) (xy 300.279885 -370.884664)
			(xy 300.273391 -370.86748) (xy 300.267624 -370.86032) (xy 300.245747 -370.834665) (xy 300.207657 -370.779029)
			(xy 300.176506 -370.719232) (xy 300.152741 -370.656134) (xy 300.136706 -370.590643) (xy 300.128631 -370.523704)
			(xy 296.851096 -370.523704) (xy 296.843021 -370.590639) (xy 296.826988 -370.656127) (xy 296.803227 -370.719223)
			(xy 296.772079 -370.779019) (xy 296.733994 -370.834654) (xy 296.712132 -370.86032) (xy 296.706336 -370.867465)
			(xy 296.699823 -370.884656) (xy 296.699432 -370.893848) (xy 296.699432 -371.386354) (xy 296.699879 -371.395537)
			(xy 296.706369 -371.412721) (xy 296.712132 -371.419882) (xy 296.734009 -371.445536) (xy 296.772095 -371.501173)
			(xy 296.803243 -371.560971) (xy 296.826876 -371.623726) (xy 297.92898 -371.623726) (xy 297.928984 -371.556417)
			(xy 297.937032 -371.489591) (xy 297.95301 -371.424206) (xy 297.976689 -371.3612) (xy 298.007729 -371.301476)
			(xy 298.045685 -371.245889) (xy 298.067476 -371.220238) (xy 298.073279 -371.213097) (xy 298.07979 -371.195903)
			(xy 298.080176 -371.18671) (xy 298.080176 -371.028722) (xy 298.080583 -371.018547) (xy 298.088368 -370.999746)
			(xy 298.102759 -370.985359) (xy 298.121563 -370.97758) (xy 298.131738 -370.97716) (xy 298.848018 -370.97716)
			(xy 298.858193 -370.97755) (xy 298.876993 -370.985345) (xy 298.891378 -370.999741) (xy 298.899158 -371.018546)
			(xy 298.89958 -371.028722) (xy 298.89958 -371.18671) (xy 298.89999 -371.195897) (xy 298.906504 -371.213081)
			(xy 298.91228 -371.220238) (xy 298.93403 -371.245921) (xy 298.971978 -371.301504) (xy 299.003012 -371.361223)
			(xy 299.026686 -371.424224) (xy 299.042661 -371.489602) (xy 299.050708 -371.556421) (xy 299.050711 -371.623722)
			(xy 299.042671 -371.690542) (xy 299.026703 -371.755922) (xy 299.003035 -371.818925) (xy 298.972008 -371.878647)
			(xy 298.934065 -371.934233) (xy 298.91228 -371.959886) (xy 298.906462 -371.967016) (xy 298.899961 -371.984218)
			(xy 298.89958 -371.993414) (xy 298.89958 -372.486682) (xy 298.900003 -372.495868) (xy 298.906508 -372.513052)
			(xy 298.91228 -372.52021) (xy 298.934101 -372.545835) (xy 298.972047 -372.601426) (xy 299.003078 -372.661153)
			(xy 299.026748 -372.724161) (xy 299.042718 -372.789547) (xy 299.050759 -372.856372) (xy 299.050756 -372.923679)
			(xy 299.042709 -372.990504) (xy 299.026733 -373.055888) (xy 299.003057 -373.118894) (xy 298.972021 -373.178618)
			(xy 298.934069 -373.234206) (xy 298.91228 -373.259858) (xy 298.906474 -373.266996) (xy 298.899966 -373.284192)
			(xy 298.89958 -373.293386) (xy 298.89958 -373.451374) (xy 298.899115 -373.461542) (xy 298.891342 -373.480332)
			(xy 298.876969 -373.494717) (xy 298.858185 -373.502506) (xy 298.848018 -373.502936) (xy 298.131738 -373.502936)
			(xy 298.121566 -373.502504) (xy 298.102767 -373.494727) (xy 298.08838 -373.480343) (xy 298.080598 -373.461546)
			(xy 298.080176 -373.451374) (xy 298.080176 -373.293386) (xy 298.079778 -373.284197) (xy 298.073256 -373.267013)
			(xy 298.067476 -373.259858) (xy 298.045721 -373.234179) (xy 298.007768 -373.178597) (xy 297.976732 -373.118878)
			(xy 297.953055 -373.055877) (xy 297.937079 -372.990497) (xy 297.929031 -372.923677) (xy 297.929028 -372.856374)
			(xy 297.93707 -372.789553) (xy 297.95304 -372.724172) (xy 297.976711 -372.661169) (xy 298.007742 -372.601447)
			(xy 298.045689 -372.545862) (xy 298.067476 -372.52021) (xy 298.073291 -372.513077) (xy 298.079795 -372.495877)
			(xy 298.080176 -372.486682) (xy 298.080176 -371.993414) (xy 298.079765 -371.984227) (xy 298.073252 -371.967042)
			(xy 298.067476 -371.959886) (xy 298.04565 -371.934265) (xy 298.007699 -371.878675) (xy 297.976666 -371.818948)
			(xy 297.952993 -371.755939) (xy 297.937022 -371.690552) (xy 297.92898 -371.623726) (xy 296.826876 -371.623726)
			(xy 296.827005 -371.624069) (xy 296.843039 -371.689559) (xy 296.851113 -371.756498) (xy 296.851112 -371.823923)
			(xy 296.843035 -371.890861) (xy 296.826999 -371.956351) (xy 296.803235 -372.019448) (xy 296.772084 -372.079245)
			(xy 296.733996 -372.13488) (xy 296.712132 -372.160546) (xy 296.706325 -372.167684) (xy 296.699819 -372.18488)
			(xy 296.699432 -372.194074) (xy 296.699432 -372.351554) (xy 296.698935 -372.361681) (xy 296.691217 -372.380407)
			(xy 296.676933 -372.394765) (xy 296.658249 -372.402581) (xy 296.648124 -372.403116) (xy 295.931844 -372.403116)
			(xy 295.921695 -372.402643) (xy 295.902946 -372.394865) (xy 295.888622 -372.380484) (xy 295.880918 -372.361705)
			(xy 295.880536 -372.351554) (xy 295.880536 -372.194074) (xy 295.88013 -372.184887) (xy 295.873613 -372.167703)
			(xy 295.867836 -372.160546) (xy 295.845985 -372.13487) (xy 295.807893 -372.079238) (xy 295.77674 -372.019444)
			(xy 295.752973 -371.956348) (xy 295.736936 -371.89086) (xy 295.728858 -371.823922) (xy 295.728857 -371.756499)
			(xy 295.736932 -371.689561) (xy 295.752967 -371.624072) (xy 295.776731 -371.560976) (xy 295.807882 -371.50118)
			(xy 295.845972 -371.445547) (xy 295.867836 -371.419882) (xy 295.873627 -371.412733) (xy 295.880144 -371.395545)
			(xy 295.880536 -371.386354) (xy 295.880536 -370.893848) (xy 295.880095 -370.884664) (xy 295.873602 -370.86748)
			(xy 295.867836 -370.86032) (xy 295.845959 -370.834665) (xy 295.807868 -370.77903) (xy 295.776716 -370.719233)
			(xy 295.752951 -370.656134) (xy 295.736915 -370.590644) (xy 295.72884 -370.523704) (xy 292.450793 -370.523704)
			(xy 292.442757 -370.590465) (xy 292.426785 -370.655847) (xy 292.403113 -370.718851) (xy 292.37208 -370.778574)
			(xy 292.334131 -370.83416) (xy 292.312344 -370.859812) (xy 292.306553 -370.866961) (xy 292.300036 -370.884149)
			(xy 292.299644 -370.89334) (xy 292.299644 -371.386862) (xy 292.300085 -371.396046) (xy 292.306578 -371.41323)
			(xy 292.312344 -371.42039) (xy 292.334146 -371.44603) (xy 292.372096 -371.501618) (xy 292.403129 -371.561343)
			(xy 292.42659 -371.623785) (xy 293.528685 -371.623785) (xy 293.528689 -371.556358) (xy 293.536768 -371.489418)
			(xy 293.552807 -371.423927) (xy 293.576575 -371.360828) (xy 293.60773 -371.301031) (xy 293.645822 -371.245395)
			(xy 293.667688 -371.21973) (xy 293.673495 -371.212592) (xy 293.680004 -371.195396) (xy 293.680388 -371.186202)
			(xy 293.680388 -371.028722) (xy 293.680943 -371.018603) (xy 293.688654 -370.999892) (xy 293.702919 -370.985537)
			(xy 293.72158 -370.977708) (xy 293.731696 -370.97716) (xy 294.447976 -370.97716) (xy 294.458078 -370.977704)
			(xy 294.476748 -370.985426) (xy 294.491043 -370.999705) (xy 294.498785 -371.018366) (xy 294.499284 -371.028468)
			(xy 294.499284 -371.186202) (xy 294.499697 -371.195389) (xy 294.506209 -371.212573) (xy 294.511984 -371.21973)
			(xy 294.533811 -371.245426) (xy 294.571902 -371.301056) (xy 294.603055 -371.360847) (xy 294.626822 -371.42394)
			(xy 294.642861 -371.489426) (xy 294.65094 -371.556361) (xy 294.650944 -371.623782) (xy 294.642871 -371.690718)
			(xy 294.626839 -371.756205) (xy 294.603079 -371.8193) (xy 294.571932 -371.879095) (xy 294.533846 -371.934729)
			(xy 294.511984 -371.960394) (xy 294.506206 -371.967552) (xy 294.499681 -371.984733) (xy 294.499284 -371.993922)
			(xy 294.499284 -372.486174) (xy 294.49971 -372.495359) (xy 294.506213 -372.512544) (xy 294.511984 -372.519702)
			(xy 294.533882 -372.545339) (xy 294.571971 -372.600978) (xy 294.603121 -372.660777) (xy 294.626884 -372.723878)
			(xy 294.642917 -372.789371) (xy 294.650991 -372.856312) (xy 294.650988 -372.923739) (xy 294.642908 -372.99068)
			(xy 294.626869 -373.056171) (xy 294.6031 -373.119269) (xy 294.571944 -373.179066) (xy 294.533851 -373.234701)
			(xy 294.511984 -373.260366) (xy 294.506175 -373.267502) (xy 294.499668 -373.2847) (xy 294.499284 -373.293894)
			(xy 294.499284 -373.451374) (xy 294.498753 -373.461496) (xy 294.491038 -373.480212) (xy 294.476766 -373.494569)
			(xy 294.458095 -373.502393) (xy 294.447976 -373.502936) (xy 293.731696 -373.502936) (xy 293.721591 -373.502419)
			(xy 293.70292 -373.494687) (xy 293.688627 -373.4804) (xy 293.680886 -373.461732) (xy 293.680388 -373.451628)
			(xy 293.680388 -373.293894) (xy 293.679983 -373.284706) (xy 293.673466 -373.267522) (xy 293.667688 -373.260366)
			(xy 293.645858 -373.234673) (xy 293.607769 -373.179042) (xy 293.576617 -373.11925) (xy 293.552852 -373.056156)
			(xy 293.536814 -372.990671) (xy 293.528736 -372.923736) (xy 293.528733 -372.856315) (xy 293.536805 -372.789379)
			(xy 293.552837 -372.723892) (xy 293.576597 -372.660797) (xy 293.607743 -372.601002) (xy 293.645826 -372.545367)
			(xy 293.667688 -372.519702) (xy 293.673465 -372.512543) (xy 293.679992 -372.495363) (xy 293.680388 -372.486174)
			(xy 293.680388 -371.993922) (xy 293.67997 -371.984736) (xy 293.673462 -371.967551) (xy 293.667688 -371.960394)
			(xy 293.645787 -371.934759) (xy 293.6077 -371.87912) (xy 293.576552 -371.81932) (xy 293.55279 -371.756219)
			(xy 293.536758 -371.690726) (xy 293.528685 -371.623785) (xy 292.42659 -371.623785) (xy 292.426802 -371.624349)
			(xy 292.442775 -371.689733) (xy 292.450818 -371.756557) (xy 292.450817 -371.823864) (xy 292.442771 -371.890688)
			(xy 292.426796 -371.956071) (xy 292.403121 -372.019076) (xy 292.372085 -372.0788) (xy 292.334133 -372.134386)
			(xy 292.312344 -372.160038) (xy 292.306542 -372.167179) (xy 292.300032 -372.184373) (xy 292.299644 -372.193566)
			(xy 292.299644 -372.351554) (xy 292.299198 -372.361725) (xy 292.291425 -372.380522) (xy 292.277046 -372.394909)
			(xy 292.258253 -372.402693) (xy 292.248082 -372.403116) (xy 291.531802 -372.403116) (xy 291.521625 -372.402733)
			(xy 291.502821 -372.394941) (xy 291.488435 -372.380542) (xy 291.480658 -372.361732) (xy 291.48024 -372.351554)
			(xy 291.48024 -372.193566) (xy 291.479837 -372.184378) (xy 291.473317 -372.167194) (xy 291.46754 -372.160038)
			(xy 291.445766 -372.134374) (xy 291.407817 -372.07879) (xy 291.376783 -372.019068) (xy 291.353109 -371.956065)
			(xy 291.337135 -371.890684) (xy 291.32909 -371.823862) (xy 291.329089 -371.756559) (xy 291.337132 -371.689737)
			(xy 291.353103 -371.624356) (xy 291.376774 -371.561352) (xy 291.407806 -371.501628) (xy 291.445753 -371.446042)
			(xy 291.46754 -371.42039) (xy 291.473328 -371.413239) (xy 291.479847 -371.396053) (xy 291.48024 -371.386862)
			(xy 291.48024 -370.89334) (xy 291.479801 -370.884156) (xy 291.473306 -370.866972) (xy 291.46754 -370.859812)
			(xy 291.44574 -370.83417) (xy 291.407792 -370.778582) (xy 291.376759 -370.718857) (xy 291.353087 -370.655851)
			(xy 291.337115 -370.590468) (xy 291.329071 -370.523644) (xy 288.051032 -370.523644) (xy 288.051032 -370.523703)
			(xy 288.042957 -370.590641) (xy 288.026921 -370.65613) (xy 288.003156 -370.719227) (xy 287.972004 -370.779022)
			(xy 287.933913 -370.834656) (xy 287.912048 -370.86032) (xy 287.906254 -370.867467) (xy 287.899739 -370.884656)
			(xy 287.899348 -370.893848) (xy 287.899348 -371.386354) (xy 287.899792 -371.395537) (xy 287.906284 -371.412721)
			(xy 287.912048 -371.419882) (xy 287.933928 -371.445535) (xy 287.972019 -371.50117) (xy 288.003172 -371.560967)
			(xy 288.02681 -371.623726) (xy 289.128893 -371.623726) (xy 289.128896 -371.556417) (xy 289.136945 -371.489591)
			(xy 289.152924 -371.424206) (xy 289.176603 -371.3612) (xy 289.207644 -371.301475) (xy 289.2456 -371.245889)
			(xy 289.267392 -371.220238) (xy 289.273196 -371.213098) (xy 289.279707 -371.195904) (xy 289.280092 -371.18671)
			(xy 289.280092 -371.028722) (xy 289.28065 -371.018571) (xy 289.288409 -370.999811) (xy 289.302754 -370.985447)
			(xy 289.321504 -370.977663) (xy 289.331654 -370.97716) (xy 290.047934 -370.97716) (xy 290.058097 -370.977606)
			(xy 290.076871 -370.985396) (xy 290.091236 -370.999776) (xy 290.099005 -371.018559) (xy 290.099496 -371.028722)
			(xy 290.099496 -371.18671) (xy 290.099902 -371.195898) (xy 290.106419 -371.213082) (xy 290.112196 -371.220238)
			(xy 290.133945 -371.245921) (xy 290.171893 -371.301504) (xy 290.202926 -371.361224) (xy 290.226599 -371.424224)
			(xy 290.242574 -371.489602) (xy 290.250621 -371.556421) (xy 290.250624 -371.623722) (xy 290.242584 -371.690542)
			(xy 290.226616 -371.755921) (xy 290.202949 -371.818924) (xy 290.171922 -371.878647) (xy 290.13398 -371.934233)
			(xy 290.112196 -371.959886) (xy 290.10638 -371.967017) (xy 290.099877 -371.984218) (xy 290.099496 -371.993414)
			(xy 290.099496 -372.486682) (xy 290.099916 -372.495868) (xy 290.106423 -372.513053) (xy 290.112196 -372.52021)
			(xy 290.134016 -372.545835) (xy 290.171962 -372.601426) (xy 290.202991 -372.661154) (xy 290.226661 -372.724162)
			(xy 290.24263 -372.789547) (xy 290.250671 -372.856372) (xy 290.250668 -372.923679) (xy 290.242621 -372.990503)
			(xy 290.226646 -373.055887) (xy 290.202971 -373.118893) (xy 290.171935 -373.178618) (xy 290.133985 -373.234205)
			(xy 290.112196 -373.259858) (xy 290.106392 -373.266998) (xy 290.099882 -373.284192) (xy 290.099496 -373.293386)
			(xy 290.099496 -373.451374) (xy 290.098946 -373.461526) (xy 290.091187 -373.480288) (xy 290.076838 -373.494653)
			(xy 290.058085 -373.502435) (xy 290.047934 -373.502936) (xy 289.331654 -373.502936) (xy 289.32149 -373.502504)
			(xy 289.302715 -373.494709) (xy 289.28835 -373.480325) (xy 289.280582 -373.461539) (xy 289.280092 -373.451374)
			(xy 289.280092 -373.293386) (xy 289.27969 -373.284198) (xy 289.273171 -373.267014) (xy 289.267392 -373.259858)
			(xy 289.245636 -373.234179) (xy 289.207683 -373.178598) (xy 289.176645 -373.118878) (xy 289.152968 -373.055877)
			(xy 289.136991 -372.990498) (xy 289.128943 -372.923677) (xy 289.12894 -372.856374) (xy 289.136982 -372.789553)
			(xy 289.152953 -372.724172) (xy 289.176624 -372.661168) (xy 289.207656 -372.601446) (xy 289.245605 -372.545861)
			(xy 289.267392 -372.52021) (xy 289.273208 -372.513079) (xy 289.279711 -372.495878) (xy 289.280092 -372.486682)
			(xy 289.280092 -371.993414) (xy 289.279677 -371.984227) (xy 289.273167 -371.967043) (xy 289.267392 -371.959886)
			(xy 289.245565 -371.934265) (xy 289.207614 -371.878676) (xy 289.17658 -371.818948) (xy 289.152907 -371.755939)
			(xy 289.136935 -371.690553) (xy 289.128893 -371.623726) (xy 288.02681 -371.623726) (xy 288.026938 -371.624066)
			(xy 288.042974 -371.689557) (xy 288.05105 -371.756498) (xy 288.051048 -371.823923) (xy 288.04297 -371.890864)
			(xy 288.026932 -371.956354) (xy 288.003164 -372.019452) (xy 287.972008 -372.079248) (xy 287.933915 -372.134882)
			(xy 287.912048 -372.160546) (xy 287.906243 -372.167685) (xy 287.899735 -372.18488) (xy 287.899348 -372.194074)
			(xy 287.899348 -372.351554) (xy 287.898835 -372.361679) (xy 287.89112 -372.380402) (xy 287.876842 -372.39476)
			(xy 287.858162 -372.402579) (xy 287.84804 -372.403116) (xy 287.13176 -372.403116) (xy 287.121651 -372.402648)
			(xy 287.102975 -372.3949) (xy 287.088682 -372.380598) (xy 287.080946 -372.361918) (xy 287.080452 -372.351808)
			(xy 287.080452 -372.194074) (xy 287.080043 -372.184887) (xy 287.073527 -372.167703) (xy 287.067752 -372.160546)
			(xy 287.0459 -372.13487) (xy 287.007807 -372.079238) (xy 286.976653 -372.019444) (xy 286.952886 -371.956349)
			(xy 286.936848 -371.89086) (xy 286.92877 -371.823922) (xy 286.928769 -371.756499) (xy 286.936844 -371.68956)
			(xy 286.95288 -371.624072) (xy 286.976645 -371.560975) (xy 287.007797 -371.50118) (xy 287.045887 -371.445546)
			(xy 287.067752 -371.419882) (xy 287.073545 -371.412735) (xy 287.08006 -371.395546) (xy 287.080452 -371.386354)
			(xy 287.080452 -370.893848) (xy 287.080007 -370.884665) (xy 287.073516 -370.867481) (xy 287.067752 -370.86032)
			(xy 287.045874 -370.834665) (xy 287.007783 -370.779031) (xy 286.97663 -370.719233) (xy 286.952864 -370.656135)
			(xy 286.936828 -370.590644) (xy 286.928752 -370.523704) (xy 266.501372 -370.523704) (xy 266.501372 -374.423882)
			(xy 286.928731 -374.423882) (xy 286.928735 -374.356454) (xy 286.936815 -374.289512) (xy 286.952857 -374.22402)
			(xy 286.976628 -374.160921) (xy 287.007787 -374.101124) (xy 287.045884 -374.04549) (xy 287.067752 -374.019826)
			(xy 287.073569 -374.012695) (xy 287.08007 -373.995494) (xy 287.080452 -373.986298) (xy 287.080452 -373.828818)
			(xy 287.080942 -373.818691) (xy 287.088666 -373.799968) (xy 287.102951 -373.785611) (xy 287.121636 -373.777793)
			(xy 287.13176 -373.777256) (xy 287.84804 -373.777256) (xy 287.858146 -373.777751) (xy 287.876817 -373.785494)
			(xy 287.891108 -373.799787) (xy 287.898849 -373.818458) (xy 287.899348 -373.828564) (xy 287.899348 -373.986298)
			(xy 287.899771 -373.995484) (xy 287.906277 -374.012667) (xy 287.912048 -374.019826) (xy 287.933873 -374.045524)
			(xy 287.971966 -374.101153) (xy 288.003121 -374.160944) (xy 288.02689 -374.224037) (xy 288.04293 -374.289522)
			(xy 288.05101 -374.356458) (xy 288.051014 -374.423823) (xy 291.32905 -374.423823) (xy 291.329054 -374.356514)
			(xy 291.337102 -374.289689) (xy 291.35308 -374.224304) (xy 291.376757 -374.161298) (xy 291.407796 -374.101573)
			(xy 291.44575 -374.045986) (xy 291.46754 -374.020334) (xy 291.473352 -374.0132) (xy 291.479857 -373.996001)
			(xy 291.48024 -373.986806) (xy 291.48024 -373.828818) (xy 291.480678 -373.818647) (xy 291.488458 -373.799853)
			(xy 291.502839 -373.785467) (xy 291.521631 -373.777682) (xy 291.531802 -373.777256) (xy 292.248082 -373.777256)
			(xy 292.258255 -373.777679) (xy 292.277053 -373.785461) (xy 292.291439 -373.799847) (xy 292.299221 -373.818645)
			(xy 292.299644 -373.828818) (xy 292.299644 -373.986806) (xy 292.300064 -373.995992) (xy 292.306572 -374.013176)
			(xy 292.312344 -374.020334) (xy 292.334091 -374.04602) (xy 292.372042 -374.101601) (xy 292.403078 -374.16132)
			(xy 292.426754 -374.22432) (xy 292.44273 -374.289698) (xy 292.450778 -374.356517) (xy 292.450782 -374.423819)
			(xy 292.450774 -374.423882) (xy 295.728819 -374.423882) (xy 295.728822 -374.356455) (xy 295.736903 -374.289513)
			(xy 295.752944 -374.224021) (xy 295.776715 -374.160922) (xy 295.807872 -374.101125) (xy 295.845968 -374.045491)
			(xy 295.867836 -374.019826) (xy 295.873651 -374.012694) (xy 295.880154 -373.995493) (xy 295.880536 -373.986298)
			(xy 295.880536 -373.828818) (xy 295.881041 -373.818693) (xy 295.888762 -373.799973) (xy 295.903043 -373.785616)
			(xy 295.921722 -373.777796) (xy 295.931844 -373.777256) (xy 296.648124 -373.777256) (xy 296.658274 -373.777701)
			(xy 296.677019 -373.785496) (xy 296.69134 -373.799885) (xy 296.699046 -373.818666) (xy 296.699432 -373.828818)
			(xy 296.699432 -373.986298) (xy 296.699858 -373.995483) (xy 296.706362 -374.012667) (xy 296.712132 -374.019826)
			(xy 296.733954 -374.045526) (xy 296.772041 -374.101156) (xy 296.803192 -374.160948) (xy 296.826957 -374.22404)
			(xy 296.842995 -374.289525) (xy 296.851073 -374.356459) (xy 296.851077 -374.423878) (xy 296.851077 -374.423882)
			(xy 300.12861 -374.423882) (xy 300.128613 -374.356455) (xy 300.136694 -374.289513) (xy 300.152734 -374.224021)
			(xy 300.176504 -374.160923) (xy 300.207661 -374.101126) (xy 300.245757 -374.045491) (xy 300.267624 -374.019826)
			(xy 300.273437 -374.012693) (xy 300.279941 -373.995493) (xy 300.280324 -373.986298) (xy 300.280324 -373.828818)
			(xy 300.280841 -373.818694) (xy 300.28856 -373.799977) (xy 300.302837 -373.78562) (xy 300.321511 -373.777798)
			(xy 300.331632 -373.777256) (xy 301.047912 -373.777256) (xy 301.058061 -373.777711) (xy 301.076806 -373.785502)
			(xy 301.091127 -373.799888) (xy 301.098834 -373.818667) (xy 301.09922 -373.828818) (xy 301.09922 -373.986298)
			(xy 301.099627 -373.995486) (xy 301.106142 -374.01267) (xy 301.11192 -374.019826) (xy 301.133742 -374.045526)
			(xy 301.171831 -374.101156) (xy 301.202982 -374.160947) (xy 301.226748 -374.22404) (xy 301.242785 -374.289524)
			(xy 301.250864 -374.356458) (xy 301.250868 -374.423823) (xy 330.929168 -374.423823) (xy 330.929172 -374.356514)
			(xy 330.937221 -374.289688) (xy 330.953199 -374.224303) (xy 330.976878 -374.161297) (xy 331.007917 -374.101572)
			(xy 331.045873 -374.045986) (xy 331.067664 -374.020334) (xy 331.073479 -374.013202) (xy 331.079981 -373.996001)
			(xy 331.080364 -373.986806) (xy 331.080364 -373.828818) (xy 331.080779 -373.818644) (xy 331.088563 -373.799845)
			(xy 331.102952 -373.785458) (xy 331.121752 -373.777677) (xy 331.131926 -373.777256) (xy 331.848206 -373.777256)
			(xy 331.85838 -373.777659) (xy 331.877178 -373.78545) (xy 331.891564 -373.799842) (xy 331.899345 -373.818644)
			(xy 331.899768 -373.828818) (xy 331.899768 -373.986806) (xy 331.900182 -373.995993) (xy 331.906694 -374.013177)
			(xy 331.912468 -374.020334) (xy 331.934214 -374.04602) (xy 331.972164 -374.101602) (xy 332.003198 -374.161321)
			(xy 332.026873 -374.224321) (xy 332.042849 -374.289699) (xy 332.050896 -374.356518) (xy 332.0509 -374.423819)
			(xy 332.050892 -374.423882) (xy 335.328961 -374.423882) (xy 335.328965 -374.356455) (xy 335.337045 -374.289515)
			(xy 335.353083 -374.224024) (xy 335.37685 -374.160926) (xy 335.408004 -374.101128) (xy 335.446095 -374.045492)
			(xy 335.46796 -374.019826) (xy 335.473778 -374.012696) (xy 335.480278 -373.995494) (xy 335.48066 -373.986298)
			(xy 335.48066 -373.828818) (xy 335.481142 -373.81869) (xy 335.488867 -373.799965) (xy 335.503156 -373.785608)
			(xy 335.521842 -373.777791) (xy 335.531968 -373.777256) (xy 336.248248 -373.777256) (xy 336.2584 -373.777682)
			(xy 336.277145 -373.785485) (xy 336.291465 -373.799879) (xy 336.299171 -373.818664) (xy 336.299556 -373.828818)
			(xy 336.299556 -373.986298) (xy 336.299977 -373.995484) (xy 336.306484 -374.012668) (xy 336.312256 -374.019826)
			(xy 336.33408 -374.045525) (xy 336.372173 -374.101153) (xy 336.403328 -374.160944) (xy 336.427097 -374.224037)
			(xy 336.443136 -374.289523) (xy 336.451216 -374.356458) (xy 336.45122 -374.423823) (xy 339.729256 -374.423823)
			(xy 339.72926 -374.356514) (xy 339.737309 -374.289689) (xy 339.753286 -374.224304) (xy 339.776964 -374.161298)
			(xy 339.808003 -374.101573) (xy 339.845957 -374.045986) (xy 339.867748 -374.020334) (xy 339.873561 -374.013201)
			(xy 339.880065 -373.996001) (xy 339.880448 -373.986806) (xy 339.880448 -373.828818) (xy 339.880879 -373.818646)
			(xy 339.88866 -373.79985) (xy 339.903043 -373.785464) (xy 339.921838 -373.77768) (xy 339.93201 -373.777256)
			(xy 340.64829 -373.777256) (xy 340.658463 -373.777672) (xy 340.677261 -373.785457) (xy 340.691647 -373.799846)
			(xy 340.699429 -373.818645) (xy 340.699852 -373.828818) (xy 340.699852 -373.986806) (xy 340.70027 -373.995992)
			(xy 340.706779 -374.013176) (xy 340.712552 -374.020334) (xy 340.734299 -374.04602) (xy 340.772249 -374.101601)
			(xy 340.803285 -374.16132) (xy 340.82696 -374.22432) (xy 340.842936 -374.289699) (xy 340.850984 -374.356517)
			(xy 340.850988 -374.423819) (xy 340.850988 -374.423823) (xy 344.129047 -374.423823) (xy 344.129051 -374.356514)
			(xy 344.137099 -374.289689) (xy 344.153077 -374.224304) (xy 344.176754 -374.161298) (xy 344.207792 -374.101573)
			(xy 344.245746 -374.045986) (xy 344.267536 -374.020334) (xy 344.273348 -374.0132) (xy 344.279852 -373.996001)
			(xy 344.280236 -373.986806) (xy 344.280236 -373.828818) (xy 344.280678 -373.818648) (xy 344.288457 -373.799854)
			(xy 344.302837 -373.785468) (xy 344.321628 -373.777682) (xy 344.331798 -373.777256) (xy 345.048078 -373.777256)
			(xy 345.05825 -373.777683) (xy 345.077048 -373.785464) (xy 345.091434 -373.799849) (xy 345.099217 -373.818646)
			(xy 345.09964 -373.828818) (xy 345.09964 -373.986806) (xy 345.100061 -373.995992) (xy 345.106569 -374.013175)
			(xy 345.11234 -374.020334) (xy 345.134087 -374.04602) (xy 345.172038 -374.101601) (xy 345.203075 -374.16132)
			(xy 345.226751 -374.22432) (xy 345.242727 -374.289698) (xy 345.250775 -374.356517) (xy 345.250779 -374.423819)
			(xy 345.250779 -374.423823) (xy 374.929078 -374.423823) (xy 374.929081 -374.356514) (xy 374.93713 -374.289688)
			(xy 374.953109 -374.224303) (xy 374.976788 -374.161296) (xy 375.007828 -374.101572) (xy 375.045784 -374.045985)
			(xy 375.067576 -374.020334) (xy 375.07338 -374.013194) (xy 375.079891 -373.996) (xy 375.080276 -373.986806)
			(xy 375.080276 -373.828818) (xy 375.080679 -373.818643) (xy 375.088465 -373.799841) (xy 375.102858 -373.785454)
			(xy 375.121663 -373.777675) (xy 375.131838 -373.777256) (xy 375.848118 -373.777256) (xy 375.858279 -373.777719)
			(xy 375.877052 -373.785503) (xy 375.891418 -373.799878) (xy 375.899188 -373.818656) (xy 375.89968 -373.828818)
			(xy 375.89968 -373.986806) (xy 375.900092 -373.995993) (xy 375.906605 -374.013177) (xy 375.91238 -374.020334)
			(xy 375.934126 -374.046021) (xy 375.972074 -374.101603) (xy 376.003108 -374.161322) (xy 376.026783 -374.224321)
			(xy 376.042758 -374.289699) (xy 376.050805 -374.356518) (xy 376.050809 -374.423819) (xy 376.050801 -374.423882)
			(xy 379.32887 -374.423882) (xy 379.328874 -374.356455) (xy 379.336954 -374.289515) (xy 379.352993 -374.224024)
			(xy 379.376761 -374.160925) (xy 379.407915 -374.101127) (xy 379.446007 -374.045492) (xy 379.467872 -374.019826)
			(xy 379.473691 -374.012697) (xy 379.48019 -373.995494) (xy 379.480572 -373.986298) (xy 379.480572 -373.828818)
			(xy 379.481042 -373.818688) (xy 379.48877 -373.799962) (xy 379.503062 -373.785604) (xy 379.521753 -373.777789)
			(xy 379.53188 -373.777256) (xy 380.24816 -373.777256) (xy 380.258306 -373.777754) (xy 380.277049 -373.785528)
			(xy 380.291372 -373.799901) (xy 380.299081 -373.818671) (xy 380.299468 -373.828818) (xy 380.299468 -373.986298)
			(xy 380.299886 -373.995484) (xy 380.306395 -374.012668) (xy 380.312168 -374.019826) (xy 380.333992 -374.045525)
			(xy 380.372084 -374.101154) (xy 380.403238 -374.160945) (xy 380.427006 -374.224038) (xy 380.443046 -374.289523)
			(xy 380.451125 -374.356458) (xy 380.451129 -374.423823) (xy 383.729165 -374.423823) (xy 383.729169 -374.356514)
			(xy 383.737218 -374.289688) (xy 383.753196 -374.224303) (xy 383.776874 -374.161297) (xy 383.807914 -374.101572)
			(xy 383.845869 -374.045986) (xy 383.86766 -374.020334) (xy 383.873474 -374.013202) (xy 383.879977 -373.996001)
			(xy 383.88036 -373.986806) (xy 383.88036 -373.828818) (xy 383.880779 -373.818645) (xy 383.888562 -373.799846)
			(xy 383.90295 -373.78546) (xy 383.921749 -373.777678) (xy 383.931922 -373.777256) (xy 384.648202 -373.777256)
			(xy 384.658376 -373.777663) (xy 384.677174 -373.785452) (xy 384.69156 -373.799843) (xy 384.699341 -373.818644)
			(xy 384.699764 -373.828818) (xy 384.699764 -373.986806) (xy 384.700179 -373.995992) (xy 384.70669 -374.013176)
			(xy 384.712464 -374.020334) (xy 384.73421 -374.04602) (xy 384.77216 -374.101602) (xy 384.803195 -374.161321)
			(xy 384.82687 -374.224321) (xy 384.842846 -374.289699) (xy 384.850893 -374.356518) (xy 384.850897 -374.423819)
			(xy 384.850897 -374.423823) (xy 388.128956 -374.423823) (xy 388.12896 -374.356514) (xy 388.137009 -374.289689)
			(xy 388.152986 -374.224304) (xy 388.176664 -374.161298) (xy 388.207703 -374.101573) (xy 388.245657 -374.045986)
			(xy 388.267448 -374.020334) (xy 388.273261 -374.013201) (xy 388.279765 -373.996001) (xy 388.280148 -373.986806)
			(xy 388.280148 -373.828818) (xy 388.280579 -373.818646) (xy 388.28836 -373.79985) (xy 388.302743 -373.785464)
			(xy 388.321538 -373.77768) (xy 388.33171 -373.777256) (xy 389.04799 -373.777256) (xy 389.058163 -373.777672)
			(xy 389.076961 -373.785457) (xy 389.091347 -373.799846) (xy 389.099129 -373.818645) (xy 389.099552 -373.828818)
			(xy 389.099552 -373.986806) (xy 389.09997 -373.995992) (xy 389.106479 -374.013176) (xy 389.112252 -374.020334)
			(xy 389.133999 -374.04602) (xy 389.171949 -374.101601) (xy 389.202985 -374.16132) (xy 389.22666 -374.22432)
			(xy 389.242636 -374.289699) (xy 389.250684 -374.356517) (xy 389.250688 -374.423819) (xy 389.250688 -374.423823)
			(xy 418.928987 -374.423823) (xy 418.928991 -374.356514) (xy 418.93704 -374.289688) (xy 418.953019 -374.224302)
			(xy 418.976698 -374.161296) (xy 419.007739 -374.101572) (xy 419.045696 -374.045986) (xy 419.067488 -374.020334)
			(xy 419.073294 -374.013195) (xy 419.079803 -373.996) (xy 419.080188 -373.986806) (xy 419.080188 -373.828818)
			(xy 419.08058 -373.818641) (xy 419.088368 -373.799837) (xy 419.102764 -373.78545) (xy 419.121573 -373.777673)
			(xy 419.13175 -373.777256) (xy 419.84803 -373.777256) (xy 419.858192 -373.777709) (xy 419.876965 -373.785497)
			(xy 419.89133 -373.799875) (xy 419.8991 -373.818656) (xy 419.899592 -373.828818) (xy 419.899592 -373.986806)
			(xy 419.900001 -373.995993) (xy 419.906516 -374.013177) (xy 419.912292 -374.020334) (xy 419.934038 -374.04602)
			(xy 419.971986 -374.101603) (xy 420.003019 -374.161322) (xy 420.026693 -374.224322) (xy 420.042668 -374.2897)
			(xy 420.050715 -374.356518) (xy 420.050719 -374.423819) (xy 420.050711 -374.423882) (xy 423.328779 -374.423882)
			(xy 423.328783 -374.356455) (xy 423.336863 -374.289514) (xy 423.352903 -374.224023) (xy 423.376671 -374.160925)
			(xy 423.407825 -374.101127) (xy 423.445918 -374.045492) (xy 423.467784 -374.019826) (xy 423.473593 -374.012689)
			(xy 423.480101 -373.995492) (xy 423.480484 -373.986298) (xy 423.480484 -373.828818) (xy 423.480942 -373.818687)
			(xy 423.488672 -373.799958) (xy 423.502968 -373.785599) (xy 423.521663 -373.777787) (xy 423.531792 -373.777256)
			(xy 424.248072 -373.777256) (xy 424.258174 -373.777807) (xy 424.276843 -373.785527) (xy 424.291137 -373.799803)
			(xy 424.298881 -373.818463) (xy 424.29938 -373.828564) (xy 424.29938 -373.986298) (xy 424.299795 -373.995485)
			(xy 424.306306 -374.012669) (xy 424.31208 -374.019826) (xy 424.333903 -374.045525) (xy 424.371995 -374.101154)
			(xy 424.403148 -374.160946) (xy 424.426916 -374.224038) (xy 424.442955 -374.289523) (xy 424.451034 -374.356458)
			(xy 424.451038 -374.423823) (xy 427.729074 -374.423823) (xy 427.729078 -374.356514) (xy 427.737127 -374.289688)
			(xy 427.753106 -374.224303) (xy 427.776784 -374.161296) (xy 427.807824 -374.101572) (xy 427.84578 -374.045986)
			(xy 427.867572 -374.020334) (xy 427.873388 -374.013203) (xy 427.879889 -373.996001) (xy 427.880272 -373.986806)
			(xy 427.880272 -373.828818) (xy 427.880679 -373.818643) (xy 427.888465 -373.799842) (xy 427.902856 -373.785456)
			(xy 427.921659 -373.777676) (xy 427.931834 -373.777256) (xy 428.648114 -373.777256) (xy 428.658289 -373.777653)
			(xy 428.677087 -373.785446) (xy 428.691472 -373.79984) (xy 428.699253 -373.818643) (xy 428.699676 -373.828818)
			(xy 428.699676 -373.986806) (xy 428.700088 -373.995993) (xy 428.706601 -374.013177) (xy 428.712376 -374.020334)
			(xy 428.734122 -374.04602) (xy 428.772071 -374.101602) (xy 428.803105 -374.161321) (xy 428.82678 -374.224321)
			(xy 428.842755 -374.289699) (xy 428.850802 -374.356518) (xy 428.850806 -374.423819) (xy 428.850806 -374.423823)
			(xy 432.128865 -374.423823) (xy 432.128869 -374.356514) (xy 432.136918 -374.289688) (xy 432.152896 -374.224303)
			(xy 432.176574 -374.161297) (xy 432.207614 -374.101572) (xy 432.245569 -374.045986) (xy 432.26736 -374.020334)
			(xy 432.273174 -374.013202) (xy 432.279677 -373.996001) (xy 432.28006 -373.986806) (xy 432.28006 -373.828818)
			(xy 432.280479 -373.818645) (xy 432.288262 -373.799846) (xy 432.30265 -373.78546) (xy 432.321449 -373.777678)
			(xy 432.331622 -373.777256) (xy 433.047902 -373.777256) (xy 433.058076 -373.777663) (xy 433.076874 -373.785452)
			(xy 433.09126 -373.799843) (xy 433.099041 -373.818644) (xy 433.099464 -373.828818) (xy 433.099464 -373.986806)
			(xy 433.099879 -373.995992) (xy 433.10639 -374.013176) (xy 433.112164 -374.020334) (xy 433.13391 -374.04602)
			(xy 433.17186 -374.101602) (xy 433.202895 -374.161321) (xy 433.22657 -374.224321) (xy 433.242546 -374.289699)
			(xy 433.250593 -374.356518) (xy 433.250597 -374.423819) (xy 433.242557 -374.490639) (xy 433.226589 -374.556019)
			(xy 433.202921 -374.619021) (xy 433.171892 -374.678744) (xy 433.133949 -374.73433) (xy 433.112164 -374.759982)
			(xy 433.106346 -374.767112) (xy 433.099845 -374.784314) (xy 433.099464 -374.79351) (xy 433.099464 -375.286778)
			(xy 433.099893 -375.295963) (xy 433.106394 -375.313147) (xy 433.112164 -375.320306) (xy 433.133981 -375.345934)
			(xy 433.171929 -375.401524) (xy 433.202961 -375.461251) (xy 433.226632 -375.524259) (xy 433.242603 -375.589644)
			(xy 433.250644 -375.656469) (xy 433.250642 -375.723776) (xy 433.242594 -375.790601) (xy 433.226618 -375.855985)
			(xy 433.202942 -375.91899) (xy 433.171906 -375.978715) (xy 433.133954 -376.034302) (xy 433.112164 -376.059954)
			(xy 433.106357 -376.067092) (xy 433.09985 -376.084288) (xy 433.099464 -376.093482) (xy 433.099464 -376.25147)
			(xy 433.099011 -376.261639) (xy 433.091237 -376.280433) (xy 433.07686 -376.294819) (xy 433.058071 -376.302605)
			(xy 433.047902 -376.303032) (xy 432.331622 -376.303032) (xy 432.321448 -376.302617) (xy 432.302648 -376.294834)
			(xy 432.288262 -376.280445) (xy 432.280481 -376.261644) (xy 432.28006 -376.25147) (xy 432.28006 -376.093482)
			(xy 432.279645 -376.084296) (xy 432.273133 -376.067112) (xy 432.26736 -376.059954) (xy 432.245601 -376.034278)
			(xy 432.20765 -375.978695) (xy 432.176614 -375.918975) (xy 432.152939 -375.855974) (xy 432.136963 -375.790594)
			(xy 432.128917 -375.723774) (xy 432.128914 -375.656471) (xy 432.136955 -375.58965) (xy 432.152926 -375.524269)
			(xy 432.176596 -375.461266) (xy 432.207627 -375.401543) (xy 432.245574 -375.345958) (xy 432.26736 -375.320306)
			(xy 432.273144 -375.313152) (xy 432.279664 -375.295968) (xy 432.28006 -375.286778) (xy 432.28006 -374.79351)
			(xy 432.279632 -374.784325) (xy 432.273129 -374.767141) (xy 432.26736 -374.759982) (xy 432.24553 -374.734364)
			(xy 432.207581 -374.678773) (xy 432.176549 -374.619045) (xy 432.152877 -374.556036) (xy 432.136907 -374.49065)
			(xy 432.128865 -374.423823) (xy 428.850806 -374.423823) (xy 428.842766 -374.490639) (xy 428.826798 -374.556018)
			(xy 428.803131 -374.619021) (xy 428.772103 -374.678743) (xy 428.73416 -374.734329) (xy 428.712376 -374.759982)
			(xy 428.706559 -374.767113) (xy 428.700057 -374.784314) (xy 428.699676 -374.79351) (xy 428.699676 -375.286778)
			(xy 428.700102 -375.295963) (xy 428.706605 -375.313148) (xy 428.712376 -375.320306) (xy 428.734193 -375.345934)
			(xy 428.77214 -375.401524) (xy 428.803171 -375.461251) (xy 428.826841 -375.524259) (xy 428.842812 -375.589644)
			(xy 428.850853 -375.656469) (xy 428.850851 -375.723776) (xy 428.842804 -375.790601) (xy 428.826828 -375.855984)
			(xy 428.803152 -375.91899) (xy 428.772117 -375.978714) (xy 428.734165 -376.034302) (xy 428.712376 -376.059954)
			(xy 428.706571 -376.067093) (xy 428.700062 -376.084288) (xy 428.699676 -376.093482) (xy 428.699676 -376.25147)
			(xy 428.699212 -376.261638) (xy 428.691439 -376.280429) (xy 428.677066 -376.294815) (xy 428.658282 -376.302603)
			(xy 428.648114 -376.303032) (xy 427.931834 -376.303032) (xy 427.921661 -376.302607) (xy 427.902861 -376.294828)
			(xy 427.888474 -376.280442) (xy 427.880693 -376.261643) (xy 427.880272 -376.25147) (xy 427.880272 -376.093482)
			(xy 427.879877 -376.084293) (xy 427.873353 -376.067109) (xy 427.867572 -376.059954) (xy 427.845813 -376.034278)
			(xy 427.807861 -375.978696) (xy 427.776825 -375.918976) (xy 427.753149 -375.855974) (xy 427.737173 -375.790595)
			(xy 427.729126 -375.723774) (xy 427.729123 -375.656471) (xy 427.737165 -375.58965) (xy 427.753135 -375.524269)
			(xy 427.776806 -375.461266) (xy 427.807838 -375.401543) (xy 427.845785 -375.345958) (xy 427.867572 -375.320306)
			(xy 427.873357 -375.313153) (xy 427.879877 -375.295968) (xy 427.880272 -375.286778) (xy 427.880272 -374.79351)
			(xy 427.879863 -374.784323) (xy 427.873349 -374.767138) (xy 427.867572 -374.759982) (xy 427.845742 -374.734364)
			(xy 427.807792 -374.678774) (xy 427.776759 -374.619046) (xy 427.753087 -374.556037) (xy 427.737116 -374.49065)
			(xy 427.729074 -374.423823) (xy 424.451038 -374.423823) (xy 424.451038 -374.423879) (xy 424.442966 -374.490815)
			(xy 424.426934 -374.556302) (xy 424.403174 -374.619397) (xy 424.372027 -374.679192) (xy 424.333942 -374.734825)
			(xy 424.31208 -374.76049) (xy 424.30626 -374.767619) (xy 424.29976 -374.784822) (xy 424.29938 -374.794018)
			(xy 424.29938 -375.28627) (xy 424.299809 -375.295455) (xy 424.30631 -375.312639) (xy 424.31208 -375.319798)
			(xy 424.333974 -375.345439) (xy 424.372063 -375.401076) (xy 424.403214 -375.460876) (xy 424.426977 -375.523976)
			(xy 424.443011 -375.589468) (xy 424.451085 -375.656409) (xy 424.451082 -375.723836) (xy 424.443003 -375.790776)
			(xy 424.426964 -375.856267) (xy 424.403195 -375.919366) (xy 424.37204 -375.979163) (xy 424.333946 -376.034797)
			(xy 424.31208 -376.060462) (xy 424.306272 -376.067599) (xy 424.299765 -376.084796) (xy 424.29938 -376.09399)
			(xy 424.29938 -376.25147) (xy 424.29885 -376.261592) (xy 424.291135 -376.280309) (xy 424.276863 -376.294666)
			(xy 424.258191 -376.30249) (xy 424.248072 -376.303032) (xy 423.531792 -376.303032) (xy 423.521687 -376.302522)
			(xy 423.503015 -376.294788) (xy 423.488721 -376.280499) (xy 423.480981 -376.261829) (xy 423.480484 -376.251724)
			(xy 423.480484 -376.09399) (xy 423.480082 -376.084802) (xy 423.473563 -376.067617) (xy 423.467784 -376.060462)
			(xy 423.44595 -376.034772) (xy 423.407862 -375.979141) (xy 423.37671 -375.919348) (xy 423.352945 -375.856254)
			(xy 423.336908 -375.790768) (xy 423.32883 -375.723833) (xy 423.328827 -375.656412) (xy 423.3369 -375.589476)
			(xy 423.352932 -375.523989) (xy 423.376692 -375.460893) (xy 423.407838 -375.401098) (xy 423.445922 -375.345463)
			(xy 423.467784 -375.319798) (xy 423.473562 -375.31264) (xy 423.480088 -375.295459) (xy 423.480484 -375.28627)
			(xy 423.480484 -374.794018) (xy 423.480069 -374.784831) (xy 423.473559 -374.767647) (xy 423.467784 -374.76049)
			(xy 423.445879 -374.734859) (xy 423.407793 -374.679219) (xy 423.376645 -374.619418) (xy 423.352884 -374.556317)
			(xy 423.336852 -374.490824) (xy 423.328779 -374.423882) (xy 420.050711 -374.423882) (xy 420.042679 -374.490638)
			(xy 420.026712 -374.556018) (xy 420.003045 -374.61902) (xy 419.972018 -374.678743) (xy 419.934076 -374.73433)
			(xy 419.912292 -374.759982) (xy 419.906477 -374.767114) (xy 419.899974 -374.784315) (xy 419.899592 -374.79351)
			(xy 419.899592 -375.286778) (xy 419.900015 -375.295964) (xy 419.90652 -375.313148) (xy 419.912292 -375.320306)
			(xy 419.934108 -375.345934) (xy 419.972054 -375.401525) (xy 420.003084 -375.461252) (xy 420.026754 -375.52426)
			(xy 420.042724 -375.589644) (xy 420.050765 -375.656469) (xy 420.050763 -375.723776) (xy 420.042716 -375.7906)
			(xy 420.026741 -375.855984) (xy 420.003066 -375.918989) (xy 419.972031 -375.978714) (xy 419.934081 -376.034301)
			(xy 419.912292 -376.059954) (xy 419.906489 -376.067095) (xy 419.899978 -376.084289) (xy 419.899592 -376.093482)
			(xy 419.899592 -376.25147) (xy 419.899043 -376.261622) (xy 419.891284 -376.280385) (xy 419.876935 -376.29475)
			(xy 419.858182 -376.302531) (xy 419.84803 -376.303032) (xy 419.13175 -376.303032) (xy 419.121578 -376.302595)
			(xy 419.102779 -376.29482) (xy 419.088391 -376.280438) (xy 419.080609 -376.261642) (xy 419.080188 -376.25147)
			(xy 419.080188 -376.093482) (xy 419.079789 -376.084294) (xy 419.073268 -376.067109) (xy 419.067488 -376.059954)
			(xy 419.045728 -376.034278) (xy 419.007775 -375.978696) (xy 418.976738 -375.918976) (xy 418.953061 -375.855975)
			(xy 418.937085 -375.790595) (xy 418.929038 -375.723774) (xy 418.929035 -375.656471) (xy 418.937077 -375.589649)
			(xy 418.953048 -375.524268) (xy 418.97672 -375.461265) (xy 419.007752 -375.401542) (xy 419.045701 -375.345957)
			(xy 419.067488 -375.320306) (xy 419.073263 -375.313145) (xy 419.079791 -375.295967) (xy 419.080188 -375.286778)
			(xy 419.080188 -374.79351) (xy 419.079776 -374.784323) (xy 419.073264 -374.767138) (xy 419.067488 -374.759982)
			(xy 419.045658 -374.734364) (xy 419.007707 -374.678774) (xy 418.976673 -374.619046) (xy 418.953 -374.556037)
			(xy 418.937029 -374.49065) (xy 418.928987 -374.423823) (xy 389.250688 -374.423823) (xy 389.242648 -374.490639)
			(xy 389.226679 -374.556019) (xy 389.203011 -374.619022) (xy 389.171982 -374.678744) (xy 389.134037 -374.73433)
			(xy 389.112252 -374.759982) (xy 389.106432 -374.76711) (xy 389.099933 -374.784314) (xy 389.099552 -374.79351)
			(xy 389.099552 -375.286778) (xy 389.099983 -375.295963) (xy 389.106483 -375.313147) (xy 389.112252 -375.320306)
			(xy 389.13407 -375.345934) (xy 389.172018 -375.401523) (xy 389.203051 -375.46125) (xy 389.226722 -375.524258)
			(xy 389.242693 -375.589643) (xy 389.250735 -375.656469) (xy 389.250732 -375.723776) (xy 389.242685 -375.790601)
			(xy 389.226709 -375.855985) (xy 389.203032 -375.918991) (xy 389.171995 -375.978715) (xy 389.134042 -376.034302)
			(xy 389.112252 -376.059954) (xy 389.106444 -376.067091) (xy 389.099937 -376.084288) (xy 389.099552 -376.093482)
			(xy 389.099552 -376.25147) (xy 389.099111 -376.261641) (xy 389.091334 -376.280437) (xy 389.076954 -376.294823)
			(xy 389.058161 -376.302607) (xy 389.04799 -376.303032) (xy 388.33171 -376.303032) (xy 388.321535 -376.302627)
			(xy 388.302735 -376.29484) (xy 388.288349 -376.280448) (xy 388.280569 -376.261645) (xy 388.280148 -376.25147)
			(xy 388.280148 -376.093482) (xy 388.279736 -376.084295) (xy 388.273222 -376.067111) (xy 388.267448 -376.059954)
			(xy 388.24569 -376.034278) (xy 388.207739 -375.978695) (xy 388.176704 -375.918975) (xy 388.153029 -375.855973)
			(xy 388.137054 -375.790594) (xy 388.129007 -375.723774) (xy 388.129005 -375.656471) (xy 388.137046 -375.58965)
			(xy 388.153016 -375.52427) (xy 388.176686 -375.461267) (xy 388.207716 -375.401544) (xy 388.245662 -375.345958)
			(xy 388.267448 -375.320306) (xy 388.273231 -375.313151) (xy 388.279752 -375.295968) (xy 388.280148 -375.286778)
			(xy 388.280148 -374.79351) (xy 388.279722 -374.784325) (xy 388.273218 -374.767141) (xy 388.267448 -374.759982)
			(xy 388.245619 -374.734364) (xy 388.20767 -374.678773) (xy 388.176638 -374.619045) (xy 388.152968 -374.556036)
			(xy 388.136997 -374.490649) (xy 388.128956 -374.423823) (xy 384.850897 -374.423823) (xy 384.842857 -374.490639)
			(xy 384.826889 -374.556019) (xy 384.803221 -374.619021) (xy 384.772192 -374.678744) (xy 384.734249 -374.73433)
			(xy 384.712464 -374.759982) (xy 384.706646 -374.767112) (xy 384.700145 -374.784314) (xy 384.699764 -374.79351)
			(xy 384.699764 -375.286778) (xy 384.700193 -375.295963) (xy 384.706694 -375.313147) (xy 384.712464 -375.320306)
			(xy 384.734281 -375.345934) (xy 384.772229 -375.401524) (xy 384.803261 -375.461251) (xy 384.826932 -375.524259)
			(xy 384.842903 -375.589644) (xy 384.850944 -375.656469) (xy 384.850942 -375.723776) (xy 384.842894 -375.790601)
			(xy 384.826918 -375.855985) (xy 384.803242 -375.91899) (xy 384.772206 -375.978715) (xy 384.734254 -376.034302)
			(xy 384.712464 -376.059954) (xy 384.706657 -376.067092) (xy 384.70015 -376.084288) (xy 384.699764 -376.093482)
			(xy 384.699764 -376.25147) (xy 384.699311 -376.261639) (xy 384.691537 -376.280433) (xy 384.67716 -376.294819)
			(xy 384.658371 -376.302605) (xy 384.648202 -376.303032) (xy 383.931922 -376.303032) (xy 383.921748 -376.302617)
			(xy 383.902948 -376.294834) (xy 383.888562 -376.280445) (xy 383.880781 -376.261644) (xy 383.88036 -376.25147)
			(xy 383.88036 -376.093482) (xy 383.879945 -376.084296) (xy 383.873433 -376.067112) (xy 383.86766 -376.059954)
			(xy 383.845901 -376.034278) (xy 383.80795 -375.978695) (xy 383.776914 -375.918975) (xy 383.753239 -375.855974)
			(xy 383.737263 -375.790594) (xy 383.729217 -375.723774) (xy 383.729214 -375.656471) (xy 383.737255 -375.58965)
			(xy 383.753226 -375.524269) (xy 383.776896 -375.461266) (xy 383.807927 -375.401543) (xy 383.845874 -375.345958)
			(xy 383.86766 -375.320306) (xy 383.873444 -375.313152) (xy 383.879964 -375.295968) (xy 383.88036 -375.286778)
			(xy 383.88036 -374.79351) (xy 383.879932 -374.784325) (xy 383.873429 -374.767141) (xy 383.86766 -374.759982)
			(xy 383.84583 -374.734364) (xy 383.807881 -374.678773) (xy 383.776849 -374.619045) (xy 383.753177 -374.556036)
			(xy 383.737207 -374.49065) (xy 383.729165 -374.423823) (xy 380.451129 -374.423823) (xy 380.451129 -374.423879)
			(xy 380.443057 -374.490815) (xy 380.427025 -374.556302) (xy 380.403264 -374.619397) (xy 380.372116 -374.679192)
			(xy 380.334031 -374.734825) (xy 380.312168 -374.76049) (xy 380.306347 -374.767617) (xy 380.299847 -374.784822)
			(xy 380.299468 -374.794018) (xy 380.299468 -375.28627) (xy 380.2999 -375.295455) (xy 380.306399 -375.312639)
			(xy 380.312168 -375.319798) (xy 380.334063 -375.345438) (xy 380.372152 -375.401076) (xy 380.403304 -375.460875)
			(xy 380.427068 -375.523975) (xy 380.443102 -375.589468) (xy 380.451176 -375.656409) (xy 380.451173 -375.723836)
			(xy 380.443094 -375.790777) (xy 380.427054 -375.856268) (xy 380.403285 -375.919366) (xy 380.372129 -375.979163)
			(xy 380.334035 -376.034797) (xy 380.312168 -376.060462) (xy 380.306358 -376.067598) (xy 380.299852 -376.084796)
			(xy 380.299468 -376.09399) (xy 380.299468 -376.25147) (xy 380.298949 -376.261594) (xy 380.291233 -376.280313)
			(xy 380.276956 -376.29467) (xy 380.258281 -376.302492) (xy 380.24816 -376.303032) (xy 379.53188 -376.303032)
			(xy 379.521729 -376.302596) (xy 379.502982 -376.294799) (xy 379.48866 -376.280408) (xy 379.480955 -376.261623)
			(xy 379.480572 -376.25147) (xy 379.480572 -376.09399) (xy 379.480173 -376.084802) (xy 379.473652 -376.067617)
			(xy 379.467872 -376.060462) (xy 379.446038 -376.034772) (xy 379.407951 -375.97914) (xy 379.3768 -375.919347)
			(xy 379.353036 -375.856254) (xy 379.336999 -375.790768) (xy 379.328921 -375.723833) (xy 379.328918 -375.656412)
			(xy 379.336991 -375.589476) (xy 379.353022 -375.523989) (xy 379.376782 -375.460894) (xy 379.407928 -375.401098)
			(xy 379.446011 -375.345464) (xy 379.467872 -375.319798) (xy 379.473661 -375.312648) (xy 379.480178 -375.295461)
			(xy 379.480572 -375.28627) (xy 379.480572 -374.794018) (xy 379.48016 -374.784831) (xy 379.473648 -374.767646)
			(xy 379.467872 -374.76049) (xy 379.445968 -374.734858) (xy 379.407882 -374.679218) (xy 379.376735 -374.619417)
			(xy 379.352974 -374.556316) (xy 379.336943 -374.490823) (xy 379.32887 -374.423882) (xy 376.050801 -374.423882)
			(xy 376.042769 -374.490638) (xy 376.026801 -374.556018) (xy 376.003134 -374.619021) (xy 375.972107 -374.678743)
			(xy 375.934164 -374.734329) (xy 375.91238 -374.759982) (xy 375.906564 -374.767113) (xy 375.900062 -374.784315)
			(xy 375.89968 -374.79351) (xy 375.89968 -375.286778) (xy 375.900105 -375.295963) (xy 375.906609 -375.313148)
			(xy 375.91238 -375.320306) (xy 375.934197 -375.345934) (xy 375.972143 -375.401524) (xy 376.003174 -375.461252)
			(xy 376.026845 -375.524259) (xy 376.042815 -375.589644) (xy 376.050856 -375.656469) (xy 376.050854 -375.723776)
			(xy 376.042807 -375.7906) (xy 376.026831 -375.855984) (xy 376.003156 -375.91899) (xy 375.97212 -375.978714)
			(xy 375.934169 -376.034302) (xy 375.91238 -376.059954) (xy 375.906576 -376.067094) (xy 375.900066 -376.084288)
			(xy 375.89968 -376.093482) (xy 375.89968 -376.25147) (xy 375.899212 -376.261637) (xy 375.89144 -376.280428)
			(xy 375.877068 -376.294813) (xy 375.858285 -376.302602) (xy 375.848118 -376.303032) (xy 375.131838 -376.303032)
			(xy 375.121665 -376.302604) (xy 375.102866 -376.294826) (xy 375.088478 -376.280441) (xy 375.080697 -376.261643)
			(xy 375.080276 -376.25147) (xy 375.080276 -376.093482) (xy 375.07988 -376.084293) (xy 375.073357 -376.067109)
			(xy 375.067576 -376.059954) (xy 375.045817 -376.034278) (xy 375.007865 -375.978696) (xy 374.976828 -375.918976)
			(xy 374.953152 -375.855974) (xy 374.937176 -375.790595) (xy 374.929129 -375.723774) (xy 374.929126 -375.656471)
			(xy 374.937168 -375.58965) (xy 374.953138 -375.524269) (xy 374.97681 -375.461265) (xy 375.007841 -375.401543)
			(xy 375.045789 -375.345958) (xy 375.067576 -375.320306) (xy 375.07335 -375.313144) (xy 375.079879 -375.295967)
			(xy 375.080276 -375.286778) (xy 375.080276 -374.79351) (xy 375.079866 -374.784323) (xy 375.073353 -374.767138)
			(xy 375.067576 -374.759982) (xy 375.045746 -374.734365) (xy 375.007796 -374.678774) (xy 374.976762 -374.619046)
			(xy 374.95309 -374.556037) (xy 374.937119 -374.49065) (xy 374.929078 -374.423823) (xy 345.250779 -374.423823)
			(xy 345.242739 -374.49064) (xy 345.226769 -374.55602) (xy 345.2031 -374.619022) (xy 345.172071 -374.678745)
			(xy 345.134126 -374.73433) (xy 345.11234 -374.759982) (xy 345.106519 -374.767109) (xy 345.10002 -374.784314)
			(xy 345.09964 -374.79351) (xy 345.09964 -375.286778) (xy 345.100074 -375.295962) (xy 345.106573 -375.313146)
			(xy 345.11234 -375.320306) (xy 345.134158 -375.345933) (xy 345.172107 -375.401523) (xy 345.203141 -375.46125)
			(xy 345.226813 -375.524258) (xy 345.242784 -375.589643) (xy 345.250826 -375.656469) (xy 345.250823 -375.723776)
			(xy 345.242776 -375.790602) (xy 345.226799 -375.855986) (xy 345.203122 -375.918992) (xy 345.172084 -375.978716)
			(xy 345.13413 -376.034302) (xy 345.11234 -376.059954) (xy 345.106531 -376.06709) (xy 345.100025 -376.084288)
			(xy 345.09964 -376.093482) (xy 345.09964 -376.25147) (xy 345.099211 -376.261642) (xy 345.091432 -376.280441)
			(xy 345.077047 -376.294827) (xy 345.05825 -376.302609) (xy 345.048078 -376.303032) (xy 344.331798 -376.303032)
			(xy 344.321623 -376.302637) (xy 344.302822 -376.294846) (xy 344.288436 -376.280451) (xy 344.280657 -376.261646)
			(xy 344.280236 -376.25147) (xy 344.280236 -376.093482) (xy 344.279826 -376.084295) (xy 344.273311 -376.067111)
			(xy 344.267536 -376.059954) (xy 344.245778 -376.034277) (xy 344.207829 -375.978694) (xy 344.176794 -375.918974)
			(xy 344.15312 -375.855973) (xy 344.137145 -375.790594) (xy 344.129098 -375.723774) (xy 344.129096 -375.656471)
			(xy 344.137137 -375.589651) (xy 344.153106 -375.52427) (xy 344.176776 -375.461267) (xy 344.207805 -375.401544)
			(xy 344.24575 -375.345958) (xy 344.267536 -375.320306) (xy 344.273317 -375.31315) (xy 344.27984 -375.295968)
			(xy 344.280236 -375.286778) (xy 344.280236 -374.79351) (xy 344.279813 -374.784324) (xy 344.273308 -374.76714)
			(xy 344.267536 -374.759982) (xy 344.245707 -374.734364) (xy 344.20776 -374.678772) (xy 344.176728 -374.619044)
			(xy 344.153058 -374.556035) (xy 344.137088 -374.490649) (xy 344.129047 -374.423823) (xy 340.850988 -374.423823)
			(xy 340.842948 -374.490639) (xy 340.826979 -374.556019) (xy 340.803311 -374.619022) (xy 340.772282 -374.678744)
			(xy 340.734337 -374.73433) (xy 340.712552 -374.759982) (xy 340.706732 -374.76711) (xy 340.700233 -374.784314)
			(xy 340.699852 -374.79351) (xy 340.699852 -375.286778) (xy 340.700283 -375.295963) (xy 340.706783 -375.313147)
			(xy 340.712552 -375.320306) (xy 340.73437 -375.345934) (xy 340.772318 -375.401523) (xy 340.803351 -375.46125)
			(xy 340.827022 -375.524258) (xy 340.842993 -375.589643) (xy 340.851035 -375.656469) (xy 340.851032 -375.723776)
			(xy 340.842985 -375.790601) (xy 340.827009 -375.855985) (xy 340.803332 -375.918991) (xy 340.772295 -375.978715)
			(xy 340.734342 -376.034302) (xy 340.712552 -376.059954) (xy 340.706744 -376.067091) (xy 340.700237 -376.084288)
			(xy 340.699852 -376.093482) (xy 340.699852 -376.25147) (xy 340.699411 -376.261641) (xy 340.691634 -376.280437)
			(xy 340.677254 -376.294823) (xy 340.658461 -376.302607) (xy 340.64829 -376.303032) (xy 339.93201 -376.303032)
			(xy 339.921835 -376.302627) (xy 339.903035 -376.29484) (xy 339.888649 -376.280448) (xy 339.880869 -376.261645)
			(xy 339.880448 -376.25147) (xy 339.880448 -376.093482) (xy 339.880036 -376.084295) (xy 339.873522 -376.067111)
			(xy 339.867748 -376.059954) (xy 339.84599 -376.034278) (xy 339.808039 -375.978695) (xy 339.777004 -375.918975)
			(xy 339.753329 -375.855973) (xy 339.737354 -375.790594) (xy 339.729307 -375.723774) (xy 339.729305 -375.656471)
			(xy 339.737346 -375.58965) (xy 339.753316 -375.52427) (xy 339.776986 -375.461267) (xy 339.808016 -375.401544)
			(xy 339.845962 -375.345958) (xy 339.867748 -375.320306) (xy 339.873531 -375.313151) (xy 339.880052 -375.295968)
			(xy 339.880448 -375.286778) (xy 339.880448 -374.79351) (xy 339.880022 -374.784325) (xy 339.873518 -374.767141)
			(xy 339.867748 -374.759982) (xy 339.845919 -374.734364) (xy 339.80797 -374.678773) (xy 339.776938 -374.619045)
			(xy 339.753268 -374.556036) (xy 339.737297 -374.490649) (xy 339.729256 -374.423823) (xy 336.45122 -374.423823)
			(xy 336.45122 -374.423879) (xy 336.443148 -374.490815) (xy 336.427115 -374.556303) (xy 336.403354 -374.619398)
			(xy 336.372206 -374.679193) (xy 336.334119 -374.734826) (xy 336.312256 -374.76049) (xy 336.306433 -374.767616)
			(xy 336.299935 -374.784821) (xy 336.299556 -374.794018) (xy 336.299556 -375.28627) (xy 336.29999 -375.295454)
			(xy 336.306488 -375.312639) (xy 336.312256 -375.319798) (xy 336.334151 -375.345438) (xy 336.372242 -375.401075)
			(xy 336.403394 -375.460875) (xy 336.427158 -375.523975) (xy 336.443193 -375.589467) (xy 336.451267 -375.656409)
			(xy 336.451264 -375.723836) (xy 336.443185 -375.790777) (xy 336.427145 -375.856268) (xy 336.403375 -375.919367)
			(xy 336.372218 -375.979163) (xy 336.334123 -376.034797) (xy 336.312256 -376.060462) (xy 336.306445 -376.067597)
			(xy 336.29994 -376.084795) (xy 336.299556 -376.09399) (xy 336.299556 -376.25147) (xy 336.299049 -376.261595)
			(xy 336.29133 -376.280317) (xy 336.27705 -376.294674) (xy 336.258371 -376.302494) (xy 336.248248 -376.303032)
			(xy 335.531968 -376.303032) (xy 335.521816 -376.302605) (xy 335.503069 -376.294805) (xy 335.488748 -376.280411)
			(xy 335.481043 -376.261624) (xy 335.48066 -376.25147) (xy 335.48066 -376.09399) (xy 335.480241 -376.084804)
			(xy 335.473732 -376.06762) (xy 335.46796 -376.060462) (xy 335.446127 -376.034772) (xy 335.40804 -375.97914)
			(xy 335.37689 -375.919347) (xy 335.353126 -375.856253) (xy 335.33709 -375.790768) (xy 335.329012 -375.723833)
			(xy 335.329009 -375.656412) (xy 335.337082 -375.589477) (xy 335.353113 -375.52399) (xy 335.376872 -375.460894)
			(xy 335.408017 -375.401099) (xy 335.446099 -375.345464) (xy 335.46796 -375.319798) (xy 335.473747 -375.312647)
			(xy 335.480266 -375.295461) (xy 335.48066 -375.28627) (xy 335.48066 -374.794018) (xy 335.480228 -374.784833)
			(xy 335.473728 -374.76765) (xy 335.46796 -374.76049) (xy 335.446056 -374.734858) (xy 335.407971 -374.679218)
			(xy 335.376825 -374.619417) (xy 335.353065 -374.556316) (xy 335.337033 -374.490823) (xy 335.328961 -374.423882)
			(xy 332.050892 -374.423882) (xy 332.04286 -374.490639) (xy 332.026892 -374.556019) (xy 332.003224 -374.619021)
			(xy 331.972196 -374.678744) (xy 331.934253 -374.73433) (xy 331.912468 -374.759982) (xy 331.90665 -374.767112)
			(xy 331.900149 -374.784314) (xy 331.899768 -374.79351) (xy 331.899768 -375.286778) (xy 331.900196 -375.295963)
			(xy 331.906698 -375.313147) (xy 331.912468 -375.320306) (xy 331.934285 -375.345934) (xy 331.972233 -375.401524)
			(xy 332.003264 -375.461251) (xy 332.026935 -375.524259) (xy 332.042906 -375.589644) (xy 332.050947 -375.656469)
			(xy 332.050945 -375.723776) (xy 332.042898 -375.790601) (xy 332.026922 -375.855985) (xy 332.003246 -375.91899)
			(xy 331.972209 -375.978715) (xy 331.934257 -376.034302) (xy 331.912468 -376.059954) (xy 331.906662 -376.067092)
			(xy 331.900154 -376.084288) (xy 331.899768 -376.093482) (xy 331.899768 -376.25147) (xy 331.899312 -376.261639)
			(xy 331.891538 -376.280432) (xy 331.877162 -376.294817) (xy 331.858375 -376.302604) (xy 331.848206 -376.303032)
			(xy 331.131926 -376.303032) (xy 331.121752 -376.302614) (xy 331.102953 -376.294832) (xy 331.088566 -376.280444)
			(xy 331.080785 -376.261644) (xy 331.080364 -376.25147) (xy 331.080364 -376.093482) (xy 331.079948 -376.084296)
			(xy 331.073437 -376.067112) (xy 331.067664 -376.059954) (xy 331.045905 -376.034278) (xy 331.007954 -375.978695)
			(xy 330.976918 -375.918975) (xy 330.953242 -375.855974) (xy 330.937266 -375.790594) (xy 330.92922 -375.723774)
			(xy 330.929217 -375.656471) (xy 330.937258 -375.58965) (xy 330.953229 -375.524269) (xy 330.976899 -375.461266)
			(xy 331.007931 -375.401543) (xy 331.045877 -375.345958) (xy 331.067664 -375.320306) (xy 331.073448 -375.313152)
			(xy 331.079969 -375.295968) (xy 331.080364 -375.286778) (xy 331.080364 -374.79351) (xy 331.079935 -374.784325)
			(xy 331.073433 -374.767141) (xy 331.067664 -374.759982) (xy 331.045834 -374.734364) (xy 331.007885 -374.678773)
			(xy 330.976852 -374.619045) (xy 330.95318 -374.556036) (xy 330.93721 -374.49065) (xy 330.929168 -374.423823)
			(xy 301.250868 -374.423823) (xy 301.250868 -374.423878) (xy 301.242797 -374.490814) (xy 301.226766 -374.5563)
			(xy 301.203008 -374.619395) (xy 301.171863 -374.67919) (xy 301.133781 -374.734824) (xy 301.11192 -374.76049)
			(xy 301.106105 -374.767622) (xy 301.099601 -374.784823) (xy 301.09922 -374.794018) (xy 301.09922 -375.28627)
			(xy 301.09964 -375.295456) (xy 301.106146 -375.312641) (xy 301.11192 -375.319798) (xy 301.133813 -375.345439)
			(xy 301.171899 -375.401078) (xy 301.203048 -375.460877) (xy 301.226809 -375.523977) (xy 301.242842 -375.589469)
			(xy 301.250915 -375.65641) (xy 301.250912 -375.723835) (xy 301.242834 -375.790775) (xy 301.226796 -375.856266)
			(xy 301.203029 -375.919364) (xy 301.171876 -375.979161) (xy 301.133785 -376.034796) (xy 301.11192 -376.060462)
			(xy 301.106117 -376.067603) (xy 301.099605 -376.084797) (xy 301.09922 -376.09399) (xy 301.09922 -376.25147)
			(xy 301.098748 -376.2616) (xy 301.091023 -376.280328) (xy 301.076731 -376.294687) (xy 301.058039 -376.3025)
			(xy 301.047912 -376.303032) (xy 300.331632 -376.303032) (xy 300.321484 -376.302553) (xy 300.302738 -376.294774)
			(xy 300.288415 -376.280395) (xy 300.280708 -376.26162) (xy 300.280324 -376.25147) (xy 300.280324 -376.09399)
			(xy 300.279913 -376.084803) (xy 300.2734 -376.067619) (xy 300.267624 -376.060462) (xy 300.245789 -376.034773)
			(xy 300.207697 -375.979142) (xy 300.176544 -375.91935) (xy 300.152777 -375.856256) (xy 300.136739 -375.790769)
			(xy 300.12866 -375.723833) (xy 300.128658 -375.656412) (xy 300.136731 -375.589475) (xy 300.152764 -375.523987)
			(xy 300.176526 -375.460892) (xy 300.207674 -375.401096) (xy 300.245761 -375.345463) (xy 300.267624 -375.319798)
			(xy 300.273407 -375.312643) (xy 300.279929 -375.29546) (xy 300.280324 -375.28627) (xy 300.280324 -374.794018)
			(xy 300.2799 -374.784832) (xy 300.273395 -374.767648) (xy 300.267624 -374.76049) (xy 300.245718 -374.734859)
			(xy 300.207629 -374.67922) (xy 300.176479 -374.61942) (xy 300.152716 -374.556318) (xy 300.136683 -374.490825)
			(xy 300.12861 -374.423882) (xy 296.851077 -374.423882) (xy 296.843006 -374.490813) (xy 296.826976 -374.556299)
			(xy 296.803218 -374.619394) (xy 296.772074 -374.67919) (xy 296.733992 -374.734824) (xy 296.712132 -374.76049)
			(xy 296.706306 -374.767614) (xy 296.699811 -374.784821) (xy 296.699432 -374.794018) (xy 296.699432 -375.28627)
			(xy 296.699872 -375.295454) (xy 296.706366 -375.312638) (xy 296.712132 -375.319798) (xy 296.734024 -375.345439)
			(xy 296.77211 -375.401078) (xy 296.803258 -375.460878) (xy 296.827019 -375.523978) (xy 296.843051 -375.589469)
			(xy 296.851124 -375.65641) (xy 296.851121 -375.723835) (xy 296.843043 -375.790775) (xy 296.827005 -375.856265)
			(xy 296.803239 -375.919363) (xy 296.772087 -375.979161) (xy 296.733997 -376.034796) (xy 296.712132 -376.060462)
			(xy 296.706318 -376.067595) (xy 296.699816 -376.084795) (xy 296.699432 -376.09399) (xy 296.699432 -376.25147)
			(xy 296.698948 -376.261598) (xy 296.691225 -376.280324) (xy 296.676937 -376.294683) (xy 296.65825 -376.302498)
			(xy 296.648124 -376.303032) (xy 295.931844 -376.303032) (xy 295.921697 -376.302543) (xy 295.902951 -376.294768)
			(xy 295.888628 -376.280392) (xy 295.880921 -376.261619) (xy 295.880536 -376.25147) (xy 295.880536 -376.09399)
			(xy 295.880123 -376.084803) (xy 295.87361 -376.067619) (xy 295.867836 -376.060462) (xy 295.846 -376.034773)
			(xy 295.807908 -375.979143) (xy 295.776754 -375.91935) (xy 295.752987 -375.856256) (xy 295.736948 -375.79077)
			(xy 295.728869 -375.723834) (xy 295.728867 -375.656412) (xy 295.73694 -375.589475) (xy 295.752973 -375.523987)
			(xy 295.776736 -375.460891) (xy 295.807885 -375.401096) (xy 295.845973 -375.345463) (xy 295.867836 -375.319798)
			(xy 295.873621 -375.312644) (xy 295.880142 -375.29546) (xy 295.880536 -375.28627) (xy 295.880536 -374.794018)
			(xy 295.880109 -374.784833) (xy 295.873606 -374.767649) (xy 295.867836 -374.76049) (xy 295.84593 -374.734859)
			(xy 295.80784 -374.679221) (xy 295.776689 -374.61942) (xy 295.752925 -374.556319) (xy 295.736892 -374.490825)
			(xy 295.728819 -374.423882) (xy 292.450774 -374.423882) (xy 292.442742 -374.490639) (xy 292.426773 -374.55602)
			(xy 292.403104 -374.619022) (xy 292.372075 -374.678745) (xy 292.33413 -374.73433) (xy 292.312344 -374.759982)
			(xy 292.306523 -374.76711) (xy 292.300025 -374.784314) (xy 292.299644 -374.79351) (xy 292.299644 -375.286778)
			(xy 292.300077 -375.295962) (xy 292.306576 -375.313146) (xy 292.312344 -375.320306) (xy 292.334162 -375.345934)
			(xy 292.372111 -375.401523) (xy 292.403144 -375.46125) (xy 292.426816 -375.524258) (xy 292.442787 -375.589643)
			(xy 292.450829 -375.656469) (xy 292.450826 -375.723776) (xy 292.442779 -375.790601) (xy 292.426802 -375.855985)
			(xy 292.403125 -375.918991) (xy 292.372088 -375.978716) (xy 292.334134 -376.034302) (xy 292.312344 -376.059954)
			(xy 292.306535 -376.06709) (xy 292.300029 -376.084288) (xy 292.299644 -376.093482) (xy 292.299644 -376.25147)
			(xy 292.299211 -376.261642) (xy 292.291433 -376.280439) (xy 292.277049 -376.294826) (xy 292.258254 -376.302609)
			(xy 292.248082 -376.303032) (xy 291.531802 -376.303032) (xy 291.521627 -376.302634) (xy 291.502826 -376.294844)
			(xy 291.48844 -376.28045) (xy 291.480661 -376.261645) (xy 291.48024 -376.25147) (xy 291.48024 -376.093482)
			(xy 291.47983 -376.084295) (xy 291.473315 -376.067111) (xy 291.46754 -376.059954) (xy 291.445782 -376.034277)
			(xy 291.407832 -375.978695) (xy 291.376798 -375.918974) (xy 291.353123 -375.855973) (xy 291.337148 -375.790594)
			(xy 291.329101 -375.723774) (xy 291.329099 -375.656471) (xy 291.33714 -375.589651) (xy 291.35311 -375.52427)
			(xy 291.376779 -375.461267) (xy 291.407809 -375.401544) (xy 291.445754 -375.345958) (xy 291.46754 -375.320306)
			(xy 291.473322 -375.31315) (xy 291.479844 -375.295968) (xy 291.48024 -375.286778) (xy 291.48024 -374.79351)
			(xy 291.479816 -374.784324) (xy 291.473311 -374.76714) (xy 291.46754 -374.759982) (xy 291.445711 -374.734364)
			(xy 291.407763 -374.678773) (xy 291.376732 -374.619044) (xy 291.353061 -374.556035) (xy 291.337091 -374.490649)
			(xy 291.32905 -374.423823) (xy 288.051014 -374.423823) (xy 288.051014 -374.423879) (xy 288.042941 -374.490816)
			(xy 288.026909 -374.556303) (xy 288.003147 -374.619398) (xy 287.971998 -374.679193) (xy 287.933911 -374.734826)
			(xy 287.912048 -374.76049) (xy 287.906224 -374.767616) (xy 287.899727 -374.784821) (xy 287.899348 -374.794018)
			(xy 287.899348 -375.28627) (xy 287.899784 -375.295454) (xy 287.906281 -375.312638) (xy 287.912048 -375.319798)
			(xy 287.933943 -375.345438) (xy 287.972035 -375.401075) (xy 288.003187 -375.460874) (xy 288.026952 -375.523974)
			(xy 288.042987 -375.589467) (xy 288.051061 -375.656409) (xy 288.051058 -375.723836) (xy 288.042978 -375.790777)
			(xy 288.026938 -375.856269) (xy 288.003168 -375.919367) (xy 287.972011 -375.979164) (xy 287.933916 -376.034798)
			(xy 287.912048 -376.060462) (xy 287.906236 -376.067596) (xy 287.899732 -376.084795) (xy 287.899348 -376.09399)
			(xy 287.899348 -376.25147) (xy 287.898849 -376.261596) (xy 287.891129 -376.280319) (xy 287.876846 -376.294677)
			(xy 287.858164 -376.302495) (xy 287.84804 -376.303032) (xy 287.13176 -376.303032) (xy 287.121653 -376.302548)
			(xy 287.10298 -376.294804) (xy 287.088687 -376.280507) (xy 287.080948 -376.261831) (xy 287.080452 -376.251724)
			(xy 287.080452 -376.09399) (xy 287.080035 -376.084804) (xy 287.073525 -376.06762) (xy 287.067752 -376.060462)
			(xy 287.045916 -376.034773) (xy 287.007823 -375.979143) (xy 286.976668 -375.919351) (xy 286.9529 -375.856257)
			(xy 286.93686 -375.79077) (xy 286.928781 -375.723834) (xy 286.928779 -375.656411) (xy 286.936852 -375.589474)
			(xy 286.952886 -375.523986) (xy 286.976649 -375.46089) (xy 287.007799 -375.401095) (xy 287.045888 -375.345462)
			(xy 287.067752 -375.319798) (xy 287.073538 -375.312646) (xy 287.080058 -375.29546) (xy 287.080452 -375.28627)
			(xy 287.080452 -374.794018) (xy 287.080022 -374.784833) (xy 287.073521 -374.767649) (xy 287.067752 -374.76049)
			(xy 287.045845 -374.73486) (xy 287.007754 -374.679221) (xy 286.976602 -374.619421) (xy 286.952838 -374.556319)
			(xy 286.936804 -374.490825) (xy 286.928731 -374.423882) (xy 266.501372 -374.423882) (xy 266.501372 -377.582176)
			(xy 266.500836 -377.607123) (xy 266.49303 -377.656404) (xy 266.477622 -377.70386) (xy 266.454989 -377.748327)
			(xy 266.425688 -377.788712) (xy 266.408408 -377.806712) (xy 265.993118 -378.222002) (xy 265.975119 -378.239288)
			(xy 265.934744 -378.268613) (xy 265.890279 -378.291261) (xy 265.842819 -378.306676) (xy 265.793532 -378.314478)
			(xy 265.768582 -378.314966) (xy 243.004086 -378.314966) (xy 242.979138 -378.314456) (xy 242.929856 -378.306644)
			(xy 242.882399 -378.291229) (xy 242.837933 -378.268591) (xy 242.797549 -378.239285) (xy 242.77955 -378.222002)
			(xy 242.203732 -377.646184) (xy 242.186435 -377.628195) (xy 242.157111 -377.587818) (xy 242.134464 -377.543351)
			(xy 242.119051 -377.495888) (xy 242.111253 -377.446599) (xy 242.110768 -377.421648) (xy 242.110768 -377.180602)
			(xy 242.11035 -377.170532) (xy 242.102625 -377.151933) (xy 242.095782 -377.144534) (xy 242.00104 -377.049792)
			(xy 241.993621 -377.042976) (xy 241.975036 -377.035243) (xy 241.964972 -377.034806) (xy 236.209586 -377.034806)
			(xy 236.184637 -377.034313) (xy 236.135353 -377.026499) (xy 236.087896 -377.011082) (xy 236.04343 -376.988439)
			(xy 236.003048 -376.959128) (xy 235.98505 -376.941842) (xy 235.566712 -376.523504) (xy 235.549421 -376.505509)
			(xy 235.520097 -376.465133) (xy 235.497449 -376.420668) (xy 235.482035 -376.373206) (xy 235.474235 -376.323919)
			(xy 235.473748 -376.298968) (xy 234.427522 -376.298968) (xy 237.245652 -379.117098) (xy 237.253075 -379.123909)
			(xy 237.271657 -379.131646) (xy 237.28172 -379.132084) (xy 239.621314 -379.132084) (xy 239.631385 -379.13167)
			(xy 239.649982 -379.123942) (xy 239.657382 -379.117098) (xy 240.207292 -378.567188) (xy 240.225285 -378.549895)
			(xy 240.265662 -378.520572) (xy 240.310128 -378.497925) (xy 240.357589 -378.482511) (xy 240.406877 -378.474711)
			(xy 240.431828 -378.474224) (xy 262.084058 -378.474224) (xy 262.109007 -378.474709) (xy 262.15829 -378.482528)
			(xy 262.205747 -378.497948) (xy 262.250212 -378.520592) (xy 262.290595 -378.549903) (xy 262.308594 -378.567188)
			(xy 262.508217 -378.766811) (xy 269.68983 -378.766811) (xy 269.68983 -378.633249) (xy 269.697894 -378.499931)
			(xy 269.713994 -378.367343) (xy 269.738069 -378.235969) (xy 269.770032 -378.106288) (xy 269.809767 -377.978774)
			(xy 269.857129 -377.853891) (xy 269.911944 -377.732096) (xy 269.974014 -377.613833) (xy 270.04311 -377.499534)
			(xy 270.118982 -377.389614) (xy 270.201352 -377.284477) (xy 270.28992 -377.184504) (xy 270.384362 -377.090062)
			(xy 270.484335 -377.001494) (xy 270.589472 -376.919124) (xy 270.699392 -376.843252) (xy 270.813691 -376.774156)
			(xy 270.931954 -376.712086) (xy 271.053749 -376.657271) (xy 271.178632 -376.609909) (xy 271.306146 -376.570174)
			(xy 271.435827 -376.538211) (xy 271.567201 -376.514136) (xy 271.699789 -376.498036) (xy 271.833107 -376.489972)
			(xy 271.966669 -376.489972) (xy 272.099987 -376.498036) (xy 272.232575 -376.514136) (xy 272.363949 -376.538211)
			(xy 272.49363 -376.570174) (xy 272.621144 -376.609909) (xy 272.746027 -376.657271) (xy 272.867822 -376.712086)
			(xy 272.986085 -376.774156) (xy 273.068299 -376.823856) (xy 289.128922 -376.823856) (xy 289.128922 -376.75655)
			(xy 289.136967 -376.689727) (xy 289.152941 -376.624344) (xy 289.176615 -376.56134) (xy 289.207651 -376.501617)
			(xy 289.245603 -376.446031) (xy 289.267392 -376.42038) (xy 289.273179 -376.413228) (xy 289.2797 -376.396043)
			(xy 289.280092 -376.386852) (xy 289.280092 -375.893584) (xy 289.279691 -375.884396) (xy 289.273171 -375.867212)
			(xy 289.267392 -375.860056) (xy 289.245634 -375.834379) (xy 289.207681 -375.778797) (xy 289.176643 -375.719078)
			(xy 289.152966 -375.656076) (xy 289.13699 -375.590696) (xy 289.128942 -375.523876) (xy 289.128939 -375.456572)
			(xy 289.136981 -375.389751) (xy 289.152952 -375.32437) (xy 289.176624 -375.261367) (xy 289.207656 -375.201644)
			(xy 289.245605 -375.146059) (xy 289.267392 -375.120408) (xy 289.273167 -375.113247) (xy 289.279695 -375.096069)
			(xy 289.280092 -375.08688) (xy 289.280092 -374.928638) (xy 289.280664 -374.918488) (xy 289.288417 -374.899729)
			(xy 289.302758 -374.885364) (xy 289.321505 -374.87758) (xy 289.331654 -374.877076) (xy 290.047934 -374.877076)
			(xy 290.058113 -374.877437) (xy 290.076915 -374.88524) (xy 290.0913 -374.899645) (xy 290.099077 -374.918459)
			(xy 290.099496 -374.928638) (xy 290.099496 -375.08688) (xy 290.099917 -375.096066) (xy 290.106423 -375.11325)
			(xy 290.112196 -375.120408) (xy 290.134014 -375.146035) (xy 290.17196 -375.201626) (xy 290.20299 -375.261353)
			(xy 290.226659 -375.324361) (xy 290.242629 -375.389746) (xy 290.25067 -375.456571) (xy 290.250667 -375.523878)
			(xy 290.24262 -375.590702) (xy 290.226645 -375.656085) (xy 290.20297 -375.719091) (xy 290.171935 -375.778816)
			(xy 290.133985 -375.834403) (xy 290.112196 -375.860056) (xy 290.106393 -375.867196) (xy 290.099882 -375.884391)
			(xy 290.099496 -375.893584) (xy 290.099496 -376.386852) (xy 290.09993 -376.396037) (xy 290.106427 -376.413221)
			(xy 290.112196 -376.42038) (xy 290.133987 -376.446029) (xy 290.171933 -376.501617) (xy 290.202964 -376.561341)
			(xy 290.226635 -376.624346) (xy 290.242607 -376.689728) (xy 290.25065 -376.756551) (xy 290.25065 -376.823855)
			(xy 290.250643 -376.823915) (xy 293.528715 -376.823915) (xy 293.528715 -376.756491) (xy 293.53679 -376.689554)
			(xy 293.552824 -376.624065) (xy 293.576588 -376.560968) (xy 293.607737 -376.501172) (xy 293.645825 -376.445537)
			(xy 293.667688 -376.419872) (xy 293.673478 -376.412722) (xy 293.679997 -376.395535) (xy 293.680388 -376.386344)
			(xy 293.680388 -375.894092) (xy 293.679984 -375.884904) (xy 293.673466 -375.86772) (xy 293.667688 -375.860564)
			(xy 293.645856 -375.834873) (xy 293.607767 -375.779242) (xy 293.576616 -375.719449) (xy 293.55285 -375.656355)
			(xy 293.536813 -375.59087) (xy 293.528735 -375.523934) (xy 293.528732 -375.456514) (xy 293.536804 -375.389578)
			(xy 293.552836 -375.324091) (xy 293.576596 -375.260995) (xy 293.607742 -375.2012) (xy 293.645826 -375.145565)
			(xy 293.667688 -375.1199) (xy 293.673466 -375.112741) (xy 293.679992 -375.095561) (xy 293.680388 -375.086372)
			(xy 293.680388 -374.928638) (xy 293.680956 -374.91852) (xy 293.688662 -374.89981) (xy 293.702923 -374.885454)
			(xy 293.721582 -374.877624) (xy 293.731696 -374.877076) (xy 294.447976 -374.877076) (xy 294.458094 -374.877535)
			(xy 294.476793 -374.885271) (xy 294.491107 -374.899574) (xy 294.498857 -374.918266) (xy 294.499284 -374.928384)
			(xy 294.499284 -375.086372) (xy 294.499711 -375.095557) (xy 294.506214 -375.112742) (xy 294.511984 -375.1199)
			(xy 294.53388 -375.145539) (xy 294.571969 -375.201177) (xy 294.603119 -375.260977) (xy 294.626882 -375.324077)
			(xy 294.642916 -375.389569) (xy 294.650989 -375.456511) (xy 294.650986 -375.523937) (xy 294.642907 -375.590878)
			(xy 294.626868 -375.656369) (xy 294.603099 -375.719467) (xy 294.571944 -375.779264) (xy 294.53385 -375.834899)
			(xy 294.511984 -375.860564) (xy 294.506176 -375.867701) (xy 294.499669 -375.884898) (xy 294.499284 -375.894092)
			(xy 294.499284 -376.386344) (xy 294.499677 -376.395533) (xy 294.506203 -376.412717) (xy 294.511984 -376.419872)
			(xy 294.533852 -376.445534) (xy 294.571942 -376.501168) (xy 294.603094 -376.560965) (xy 294.626858 -376.624062)
			(xy 294.642894 -376.689552) (xy 294.65097 -376.756491) (xy 294.650969 -376.823856) (xy 297.92901 -376.823856)
			(xy 297.92901 -376.75655) (xy 297.937054 -376.689727) (xy 297.953028 -376.624345) (xy 297.976702 -376.56134)
			(xy 298.007737 -376.501617) (xy 298.045687 -376.446032) (xy 298.067476 -376.42038) (xy 298.073261 -376.413226)
			(xy 298.079783 -376.396042) (xy 298.080176 -376.386852) (xy 298.080176 -375.893584) (xy 298.079779 -375.884395)
			(xy 298.073257 -375.867211) (xy 298.067476 -375.860056) (xy 298.045719 -375.834378) (xy 298.007766 -375.778797)
			(xy 297.97673 -375.719077) (xy 297.953054 -375.656076) (xy 297.937077 -375.590696) (xy 297.92903 -375.523876)
			(xy 297.929027 -375.456572) (xy 297.937069 -375.389751) (xy 297.953039 -375.324371) (xy 297.97671 -375.261367)
			(xy 298.007742 -375.201645) (xy 298.045689 -375.14606) (xy 298.067476 -375.120408) (xy 298.073249 -375.113246)
			(xy 298.079778 -375.096068) (xy 298.080176 -375.08688) (xy 298.080176 -374.928638) (xy 298.080596 -374.918464)
			(xy 298.088376 -374.899663) (xy 298.102763 -374.885276) (xy 298.121564 -374.877496) (xy 298.131738 -374.877076)
			(xy 298.848018 -374.877076) (xy 298.858195 -374.87745) (xy 298.876998 -374.885248) (xy 298.891383 -374.899649)
			(xy 298.899161 -374.91846) (xy 298.89958 -374.928638) (xy 298.89958 -375.08688) (xy 298.900004 -375.096066)
			(xy 298.906509 -375.11325) (xy 298.91228 -375.120408) (xy 298.934099 -375.146035) (xy 298.972045 -375.201625)
			(xy 299.003076 -375.261352) (xy 299.026746 -375.32436) (xy 299.042716 -375.389745) (xy 299.050758 -375.45657)
			(xy 299.050755 -375.523878) (xy 299.042708 -375.590702) (xy 299.026732 -375.656086) (xy 299.003056 -375.719092)
			(xy 298.972021 -375.778816) (xy 298.934069 -375.834404) (xy 298.91228 -375.860056) (xy 298.906475 -375.867195)
			(xy 298.899966 -375.88439) (xy 298.89958 -375.893584) (xy 298.89958 -376.386852) (xy 298.900018 -376.396036)
			(xy 298.906513 -376.413221) (xy 298.91228 -376.42038) (xy 298.934071 -376.446029) (xy 298.972019 -376.501616)
			(xy 299.003051 -376.561341) (xy 299.026722 -376.624345) (xy 299.042695 -376.689728) (xy 299.050731 -376.756492)
			(xy 302.328802 -376.756492) (xy 302.336877 -376.689554) (xy 302.352912 -376.624066) (xy 302.376674 -376.560969)
			(xy 302.407823 -376.501173) (xy 302.445909 -376.445538) (xy 302.467772 -376.419872) (xy 302.473572 -376.412729)
			(xy 302.480082 -376.395537) (xy 302.480472 -376.386344) (xy 302.480472 -375.894092) (xy 302.480072 -375.884904)
			(xy 302.473552 -375.867719) (xy 302.467772 -375.860564) (xy 302.44594 -375.834872) (xy 302.407853 -375.779241)
			(xy 302.376702 -375.719448) (xy 302.352937 -375.656355) (xy 302.336901 -375.590869) (xy 302.328823 -375.523934)
			(xy 302.32882 -375.456514) (xy 302.336892 -375.389578) (xy 302.352923 -375.324091) (xy 302.376682 -375.260996)
			(xy 302.407828 -375.2012) (xy 302.445911 -375.145566) (xy 302.467772 -375.1199) (xy 302.47356 -375.112749)
			(xy 302.480078 -375.095563) (xy 302.480472 -375.086372) (xy 302.480472 -374.928638) (xy 302.480959 -374.91851)
			(xy 302.48868 -374.899784) (xy 302.502967 -374.885425) (xy 302.521654 -374.87761) (xy 302.53178 -374.877076)
			(xy 303.24806 -374.877076) (xy 303.258209 -374.877554) (xy 303.276955 -374.885332) (xy 303.291279 -374.899711)
			(xy 303.298985 -374.918488) (xy 303.299368 -374.928638) (xy 303.299368 -375.086372) (xy 303.299799 -375.095557)
			(xy 303.306299 -375.112741) (xy 303.312068 -375.1199) (xy 303.333965 -375.145539) (xy 303.372054 -375.201176)
			(xy 303.403205 -375.260976) (xy 303.426969 -375.324076) (xy 303.443004 -375.389569) (xy 303.451077 -375.456511)
			(xy 303.451074 -375.523937) (xy 303.442995 -375.590878) (xy 303.426955 -375.65637) (xy 303.403186 -375.719468)
			(xy 303.37203 -375.779265) (xy 303.333935 -375.834899) (xy 303.312068 -375.860564) (xy 303.306258 -375.867699)
			(xy 303.299752 -375.884898) (xy 303.299368 -375.894092) (xy 303.299368 -376.386344) (xy 303.299764 -376.395533)
			(xy 303.306288 -376.412716) (xy 303.312068 -376.419872) (xy 303.333937 -376.445533) (xy 303.372028 -376.501168)
			(xy 303.40318 -376.560964) (xy 303.426945 -376.624062) (xy 303.442982 -376.689551) (xy 303.451058 -376.756491)
			(xy 303.451057 -376.823915) (xy 333.128833 -376.823915) (xy 333.128833 -376.756491) (xy 333.136908 -376.689553)
			(xy 333.152944 -376.624064) (xy 333.176708 -376.560967) (xy 333.207859 -376.501171) (xy 333.245948 -376.445537)
			(xy 333.267812 -376.419872) (xy 333.273604 -376.412724) (xy 333.280121 -376.395536) (xy 333.280512 -376.386344)
			(xy 333.280512 -375.894092) (xy 333.280103 -375.884905) (xy 333.273588 -375.86772) (xy 333.267812 -375.860564)
			(xy 333.245979 -375.834873) (xy 333.207889 -375.779242) (xy 333.176736 -375.71945) (xy 333.152969 -375.656356)
			(xy 333.136931 -375.59087) (xy 333.128853 -375.523935) (xy 333.12885 -375.456513) (xy 333.136923 -375.389577)
			(xy 333.152955 -375.32409) (xy 333.176716 -375.260994) (xy 333.207864 -375.201199) (xy 333.24595 -375.145565)
			(xy 333.267812 -375.1199) (xy 333.273592 -375.112743) (xy 333.280116 -375.095562) (xy 333.280512 -375.086372)
			(xy 333.280512 -374.928638) (xy 333.281057 -374.918517) (xy 333.288767 -374.899802) (xy 333.303035 -374.885446)
			(xy 333.321702 -374.87762) (xy 333.33182 -374.877076) (xy 334.0481 -374.877076) (xy 334.058251 -374.877521)
			(xy 334.076999 -374.885312) (xy 334.091321 -374.899701) (xy 334.099025 -374.918485) (xy 334.099408 -374.928638)
			(xy 334.099408 -375.086372) (xy 334.09983 -375.095558) (xy 334.106335 -375.112743) (xy 334.112108 -375.1199)
			(xy 334.134003 -375.145539) (xy 334.17209 -375.201178) (xy 334.203239 -375.260978) (xy 334.227001 -375.324078)
			(xy 334.243034 -375.38957) (xy 334.251107 -375.456511) (xy 334.251105 -375.523937) (xy 334.243026 -375.590877)
			(xy 334.226987 -375.656368) (xy 334.20322 -375.719466) (xy 334.172066 -375.779263) (xy 334.133974 -375.834899)
			(xy 334.112108 -375.860564) (xy 334.106303 -375.867703) (xy 334.099793 -375.884898) (xy 334.099408 -375.894092)
			(xy 334.099408 -376.386344) (xy 334.099795 -376.395534) (xy 334.106324 -376.412718) (xy 334.112108 -376.419872)
			(xy 334.133976 -376.445534) (xy 334.172064 -376.501169) (xy 334.203214 -376.560966) (xy 334.226977 -376.624063)
			(xy 334.243012 -376.689553) (xy 334.251088 -376.756491) (xy 334.251087 -376.823855) (xy 337.529152 -376.823855)
			(xy 337.529152 -376.756551) (xy 337.537195 -376.689729) (xy 337.553167 -376.624348) (xy 337.576837 -376.561344)
			(xy 337.607868 -376.50162) (xy 337.645814 -376.446033) (xy 337.6676 -376.42038) (xy 337.673388 -376.413228)
			(xy 337.679908 -376.396043) (xy 337.6803 -376.386852) (xy 337.6803 -375.893584) (xy 337.679897 -375.884396)
			(xy 337.673378 -375.867212) (xy 337.6676 -375.860056) (xy 337.645845 -375.834377) (xy 337.607898 -375.778794)
			(xy 337.576865 -375.719074) (xy 337.553192 -375.656073) (xy 337.537218 -375.590694) (xy 337.529172 -375.523875)
			(xy 337.529169 -375.456573) (xy 337.53721 -375.389753) (xy 337.553178 -375.324373) (xy 337.576846 -375.26137)
			(xy 337.607873 -375.201647) (xy 337.645815 -375.146061) (xy 337.6676 -375.120408) (xy 337.673376 -375.113248)
			(xy 337.679903 -375.096069) (xy 337.6803 -375.08688) (xy 337.6803 -374.928638) (xy 337.680864 -374.918487)
			(xy 337.688619 -374.899726) (xy 337.702963 -374.885361) (xy 337.721712 -374.877579) (xy 337.731862 -374.877076)
			(xy 338.448142 -374.877076) (xy 338.458307 -374.8775) (xy 338.477085 -374.885295) (xy 338.49145 -374.899683)
			(xy 338.499216 -374.918472) (xy 338.499704 -374.928638) (xy 338.499704 -375.08688) (xy 338.500123 -375.096066)
			(xy 338.50663 -375.113251) (xy 338.512404 -375.120408) (xy 338.534222 -375.146035) (xy 338.572167 -375.201626)
			(xy 338.603196 -375.261353) (xy 338.626865 -375.324361) (xy 338.642835 -375.389746) (xy 338.650876 -375.456571)
			(xy 338.650873 -375.523877) (xy 338.642826 -375.590701) (xy 338.626851 -375.656085) (xy 338.603177 -375.719091)
			(xy 338.572142 -375.778815) (xy 338.534192 -375.834403) (xy 338.512404 -375.860056) (xy 338.506602 -375.867197)
			(xy 338.50009 -375.884391) (xy 338.499704 -375.893584) (xy 338.499704 -376.386852) (xy 338.500136 -376.396037)
			(xy 338.506634 -376.413222) (xy 338.512404 -376.42038) (xy 338.534194 -376.44603) (xy 338.57214 -376.501617)
			(xy 338.603171 -376.561342) (xy 338.626842 -376.624346) (xy 338.642813 -376.689729) (xy 338.650856 -376.756551)
			(xy 338.650856 -376.823855) (xy 338.650849 -376.823915) (xy 341.928921 -376.823915) (xy 341.928921 -376.756491)
			(xy 341.936996 -376.689553) (xy 341.953031 -376.624065) (xy 341.976794 -376.560968) (xy 342.007944 -376.501172)
			(xy 342.046032 -376.445537) (xy 342.067896 -376.419872) (xy 342.073686 -376.412722) (xy 342.080205 -376.395535)
			(xy 342.080596 -376.386344) (xy 342.080596 -375.894092) (xy 342.08019 -375.884904) (xy 342.073674 -375.86772)
			(xy 342.067896 -375.860564) (xy 342.046064 -375.834873) (xy 342.007974 -375.779242) (xy 341.976822 -375.719449)
			(xy 341.953057 -375.656356) (xy 341.937019 -375.59087) (xy 341.928941 -375.523935) (xy 341.928938 -375.456513)
			(xy 341.93701 -375.389577) (xy 341.953042 -375.32409) (xy 341.976803 -375.260995) (xy 342.007949 -375.201199)
			(xy 342.046034 -375.145565) (xy 342.067896 -375.1199) (xy 342.073675 -375.112742) (xy 342.0802 -375.095561)
			(xy 342.080596 -375.086372) (xy 342.080596 -374.928638) (xy 342.081157 -374.918519) (xy 342.088864 -374.899807)
			(xy 342.103127 -374.885451) (xy 342.121789 -374.877623) (xy 342.131904 -374.877076) (xy 342.848184 -374.877076)
			(xy 342.858334 -374.877534) (xy 342.877082 -374.88532) (xy 342.891405 -374.899705) (xy 342.899109 -374.918486)
			(xy 342.899492 -374.928638) (xy 342.899492 -375.086372) (xy 342.899917 -375.095558) (xy 342.906421 -375.112742)
			(xy 342.912192 -375.1199) (xy 342.934088 -375.145539) (xy 342.972176 -375.201177) (xy 343.003326 -375.260977)
			(xy 343.027088 -375.324077) (xy 343.043122 -375.38957) (xy 343.051195 -375.456511) (xy 343.051193 -375.523937)
			(xy 343.043113 -375.590878) (xy 343.027074 -375.656369) (xy 343.003306 -375.719467) (xy 342.972151 -375.779264)
			(xy 342.934058 -375.834899) (xy 342.912192 -375.860564) (xy 342.906385 -375.867702) (xy 342.899877 -375.884898)
			(xy 342.899492 -375.894092) (xy 342.899492 -376.386344) (xy 342.899883 -376.395533) (xy 342.90641 -376.412717)
			(xy 342.912192 -376.419872) (xy 342.93406 -376.445534) (xy 342.972149 -376.501169) (xy 343.0033 -376.560965)
			(xy 343.027065 -376.624063) (xy 343.0431 -376.689552) (xy 343.051176 -376.756491) (xy 343.051175 -376.823856)
			(xy 346.329216 -376.823856) (xy 346.329216 -376.75655) (xy 346.33726 -376.689727) (xy 346.353234 -376.624345)
			(xy 346.376909 -376.56134) (xy 346.407944 -376.501617) (xy 346.445895 -376.446032) (xy 346.467684 -376.42038)
			(xy 346.47347 -376.413227) (xy 346.479991 -376.396043) (xy 346.480384 -376.386852) (xy 346.480384 -375.893584)
			(xy 346.479985 -375.884396) (xy 346.473464 -375.867211) (xy 346.467684 -375.860056) (xy 346.445926 -375.834379)
			(xy 346.407974 -375.778797) (xy 346.376937 -375.719077) (xy 346.35326 -375.656076) (xy 346.337283 -375.590696)
			(xy 346.329236 -375.523876) (xy 346.329233 -375.456572) (xy 346.337275 -375.389751) (xy 346.353246 -375.32437)
			(xy 346.376917 -375.261367) (xy 346.407949 -375.201645) (xy 346.445897 -375.14606) (xy 346.467684 -375.120408)
			(xy 346.473458 -375.113247) (xy 346.479987 -375.096069) (xy 346.480384 -375.08688) (xy 346.480384 -374.928638)
			(xy 346.480796 -374.918463) (xy 346.488577 -374.899661) (xy 346.502967 -374.885273) (xy 346.521771 -374.877495)
			(xy 346.531946 -374.877076) (xy 347.248226 -374.877076) (xy 347.258404 -374.877443) (xy 347.277207 -374.885244)
			(xy 347.291592 -374.899647) (xy 347.299369 -374.918459) (xy 347.299788 -374.928638) (xy 347.299788 -375.08688)
			(xy 347.300211 -375.096066) (xy 347.306716 -375.11325) (xy 347.312488 -375.120408) (xy 347.334306 -375.146035)
			(xy 347.372252 -375.201625) (xy 347.403283 -375.261353) (xy 347.426953 -375.324361) (xy 347.442923 -375.389746)
			(xy 347.450964 -375.456571) (xy 347.450961 -375.523878) (xy 347.442914 -375.590702) (xy 347.426938 -375.656086)
			(xy 347.403263 -375.719091) (xy 347.372228 -375.778816) (xy 347.334277 -375.834403) (xy 347.312488 -375.860056)
			(xy 347.306684 -375.867196) (xy 347.300174 -375.88439) (xy 347.299788 -375.893584) (xy 347.299788 -376.386852)
			(xy 347.300224 -376.396036) (xy 347.30672 -376.413221) (xy 347.312488 -376.42038) (xy 347.334279 -376.446029)
			(xy 347.372226 -376.501617) (xy 347.403257 -376.561341) (xy 347.426929 -376.624346) (xy 347.442901 -376.689728)
			(xy 347.450944 -376.756551) (xy 347.450944 -376.823855) (xy 347.450937 -376.823915) (xy 377.128742 -376.823915)
			(xy 377.128742 -376.756491) (xy 377.136817 -376.689553) (xy 377.152853 -376.624064) (xy 377.176618 -376.560967)
			(xy 377.20777 -376.501171) (xy 377.245859 -376.445537) (xy 377.267724 -376.419872) (xy 377.273518 -376.412725)
			(xy 377.280033 -376.395536) (xy 377.280424 -376.386344) (xy 377.280424 -375.894092) (xy 377.280012 -375.884905)
			(xy 377.273499 -375.867721) (xy 377.267724 -375.860564) (xy 377.245891 -375.834873) (xy 377.207799 -375.779243)
			(xy 377.176646 -375.71945) (xy 377.152879 -375.656357) (xy 377.136841 -375.590871) (xy 377.128762 -375.523935)
			(xy 377.128759 -375.456513) (xy 377.136832 -375.389577) (xy 377.152865 -375.324089) (xy 377.176626 -375.260993)
			(xy 377.207775 -375.201198) (xy 377.245861 -375.145565) (xy 377.267724 -375.1199) (xy 377.273506 -375.112744)
			(xy 377.280029 -375.095562) (xy 377.280424 -375.086372) (xy 377.280424 -374.928638) (xy 377.280957 -374.918516)
			(xy 377.28867 -374.899799) (xy 377.302942 -374.885442) (xy 377.321613 -374.877618) (xy 377.331732 -374.877076)
			(xy 378.048012 -374.877076) (xy 378.058164 -374.877511) (xy 378.076912 -374.885306) (xy 378.091234 -374.899698)
			(xy 378.098938 -374.918484) (xy 378.09932 -374.928638) (xy 378.09932 -375.086372) (xy 378.099739 -375.095558)
			(xy 378.106246 -375.112743) (xy 378.11202 -375.1199) (xy 378.133915 -375.14554) (xy 378.172001 -375.201178)
			(xy 378.203149 -375.260978) (xy 378.226911 -375.324078) (xy 378.242943 -375.38957) (xy 378.251016 -375.456511)
			(xy 378.251014 -375.523937) (xy 378.242935 -375.590877) (xy 378.226897 -375.656368) (xy 378.20313 -375.719466)
			(xy 378.171976 -375.779263) (xy 378.133885 -375.834898) (xy 378.11202 -375.860564) (xy 378.106216 -375.867704)
			(xy 378.099705 -375.884898) (xy 378.09932 -375.894092) (xy 378.09932 -376.386344) (xy 378.099704 -376.395534)
			(xy 378.106235 -376.412718) (xy 378.11202 -376.419872) (xy 378.133887 -376.445534) (xy 378.171974 -376.50117)
			(xy 378.203124 -376.560967) (xy 378.226887 -376.624064) (xy 378.242922 -376.689553) (xy 378.250997 -376.756491)
			(xy 378.250997 -376.756551) (xy 381.529061 -376.756551) (xy 381.537105 -376.689729) (xy 381.553076 -376.624347)
			(xy 381.576747 -376.561343) (xy 381.607779 -376.501619) (xy 381.645725 -376.446032) (xy 381.667512 -376.42038)
			(xy 381.673301 -376.413229) (xy 381.67982 -376.396043) (xy 381.680212 -376.386852) (xy 381.680212 -375.893584)
			(xy 381.679807 -375.884396) (xy 381.67329 -375.867212) (xy 381.667512 -375.860056) (xy 381.645756 -375.834378)
			(xy 381.607808 -375.778794) (xy 381.576775 -375.719074) (xy 381.553102 -375.656073) (xy 381.537127 -375.590694)
			(xy 381.529081 -375.523875) (xy 381.529078 -375.456573) (xy 381.537119 -375.389753) (xy 381.553088 -375.324373)
			(xy 381.576756 -375.26137) (xy 381.607784 -375.201647) (xy 381.645727 -375.14606) (xy 381.667512 -375.120408)
			(xy 381.673289 -375.113249) (xy 381.679815 -375.096069) (xy 381.680212 -375.08688) (xy 381.680212 -374.928638)
			(xy 381.680694 -374.918472) (xy 381.688462 -374.899683) (xy 381.702829 -374.885298) (xy 381.721609 -374.877507)
			(xy 381.731774 -374.877076) (xy 382.448054 -374.877076) (xy 382.458227 -374.877502) (xy 382.477028 -374.885279)
			(xy 382.491416 -374.899665) (xy 382.499196 -374.918465) (xy 382.499616 -374.928638) (xy 382.499616 -375.08688)
			(xy 382.500032 -375.096067) (xy 382.506541 -375.113251) (xy 382.512316 -375.120408) (xy 382.534136 -375.146034)
			(xy 382.572087 -375.201623) (xy 382.603122 -375.26135) (xy 382.626795 -375.324358) (xy 382.642767 -375.389744)
			(xy 382.650809 -375.45657) (xy 382.650806 -375.523878) (xy 382.642758 -375.590704) (xy 382.62678 -375.656088)
			(xy 382.603102 -375.719094) (xy 382.572063 -375.778818) (xy 382.534107 -375.834404) (xy 382.512316 -375.860056)
			(xy 382.506515 -375.867198) (xy 382.500002 -375.884391) (xy 382.499616 -375.893584) (xy 382.499616 -376.386852)
			(xy 382.500045 -376.396037) (xy 382.506545 -376.413222) (xy 382.512316 -376.42038) (xy 382.534109 -376.446028)
			(xy 382.572061 -376.501614) (xy 382.603096 -376.561338) (xy 382.626771 -376.624343) (xy 382.642745 -376.689726)
			(xy 382.650789 -376.75655) (xy 382.650789 -376.823856) (xy 382.650782 -376.823915) (xy 385.92883 -376.823915)
			(xy 385.92883 -376.756491) (xy 385.936905 -376.689553) (xy 385.95294 -376.624064) (xy 385.976705 -376.560967)
			(xy 386.007855 -376.501171) (xy 386.045944 -376.445537) (xy 386.067808 -376.419872) (xy 386.0736 -376.412724)
			(xy 386.080117 -376.395535) (xy 386.080508 -376.386344) (xy 386.080508 -375.894092) (xy 386.0801 -375.884905)
			(xy 386.073584 -375.867721) (xy 386.067808 -375.860564) (xy 386.045975 -375.834873) (xy 386.007885 -375.779242)
			(xy 385.976732 -375.71945) (xy 385.952966 -375.656356) (xy 385.936928 -375.59087) (xy 385.92885 -375.523935)
			(xy 385.928847 -375.456513) (xy 385.93692 -375.389577) (xy 385.952952 -375.32409) (xy 385.976713 -375.260994)
			(xy 386.00786 -375.201199) (xy 386.045946 -375.145565) (xy 386.067808 -375.1199) (xy 386.073588 -375.112743)
			(xy 386.080112 -375.095562) (xy 386.080508 -375.086372) (xy 386.080508 -374.928638) (xy 386.081057 -374.918518)
			(xy 386.088766 -374.899804) (xy 386.103033 -374.885447) (xy 386.121699 -374.877621) (xy 386.131816 -374.877076)
			(xy 386.848096 -374.877076) (xy 386.858247 -374.877524) (xy 386.876995 -374.885314) (xy 386.891317 -374.899702)
			(xy 386.899021 -374.918485) (xy 386.899404 -374.928638) (xy 386.899404 -375.086372) (xy 386.899827 -375.095558)
			(xy 386.906332 -375.112742) (xy 386.912104 -375.1199) (xy 386.933999 -375.145539) (xy 386.972087 -375.201178)
			(xy 387.003236 -375.260978) (xy 387.026998 -375.324078) (xy 387.043031 -375.38957) (xy 387.051104 -375.456511)
			(xy 387.051102 -375.523937) (xy 387.043023 -375.590877) (xy 387.026984 -375.656368) (xy 387.003216 -375.719466)
			(xy 386.972062 -375.779264) (xy 386.93397 -375.834899) (xy 386.912104 -375.860564) (xy 386.906298 -375.867703)
			(xy 386.899789 -375.884898) (xy 386.899404 -375.894092) (xy 386.899404 -376.386344) (xy 386.899792 -376.395534)
			(xy 386.906321 -376.412718) (xy 386.912104 -376.419872) (xy 386.933972 -376.445534) (xy 386.97206 -376.501169)
			(xy 387.00321 -376.560966) (xy 387.026974 -376.624063) (xy 387.043009 -376.689552) (xy 387.051085 -376.756491)
			(xy 387.051084 -376.823855) (xy 390.329149 -376.823855) (xy 390.329149 -376.756551) (xy 390.337192 -376.689729)
			(xy 390.353163 -376.624348) (xy 390.376834 -376.561344) (xy 390.407864 -376.50162) (xy 390.44581 -376.446033)
			(xy 390.467596 -376.42038) (xy 390.473383 -376.413228) (xy 390.479904 -376.396043) (xy 390.480296 -376.386852)
			(xy 390.480296 -375.893584) (xy 390.479894 -375.884396) (xy 390.473375 -375.867212) (xy 390.467596 -375.860056)
			(xy 390.445841 -375.834377) (xy 390.407894 -375.778794) (xy 390.376862 -375.719073) (xy 390.353189 -375.656072)
			(xy 390.337215 -375.590694) (xy 390.329169 -375.523875) (xy 390.329166 -375.456573) (xy 390.337207 -375.389754)
			(xy 390.353175 -375.324374) (xy 390.376842 -375.261371) (xy 390.407869 -375.201648) (xy 390.445812 -375.146061)
			(xy 390.467596 -375.120408) (xy 390.473371 -375.113248) (xy 390.479899 -375.096069) (xy 390.480296 -375.08688)
			(xy 390.480296 -374.928638) (xy 390.480864 -374.918488) (xy 390.488618 -374.899728) (xy 390.502961 -374.885363)
			(xy 390.521709 -374.877579) (xy 390.531858 -374.877076) (xy 391.248138 -374.877076) (xy 391.258303 -374.877503)
			(xy 391.27708 -374.885297) (xy 391.291445 -374.899684) (xy 391.299212 -374.918472) (xy 391.2997 -374.928638)
			(xy 391.2997 -375.08688) (xy 391.30012 -375.096066) (xy 391.306627 -375.113251) (xy 391.3124 -375.120408)
			(xy 391.334218 -375.146035) (xy 391.372163 -375.201626) (xy 391.403193 -375.261353) (xy 391.426862 -375.324361)
			(xy 391.442832 -375.389746) (xy 391.450873 -375.456571) (xy 391.45087 -375.523877) (xy 391.442823 -375.590702)
			(xy 391.426848 -375.656085) (xy 391.403173 -375.719091) (xy 391.372139 -375.778816) (xy 391.334188 -375.834403)
			(xy 391.3124 -375.860056) (xy 391.306597 -375.867197) (xy 391.300086 -375.884391) (xy 391.2997 -375.893584)
			(xy 391.2997 -376.386852) (xy 391.300133 -376.396037) (xy 391.306631 -376.413221) (xy 391.3124 -376.42038)
			(xy 391.33419 -376.446029) (xy 391.372137 -376.501617) (xy 391.403168 -376.561342) (xy 391.426838 -376.624346)
			(xy 391.44281 -376.689728) (xy 391.450853 -376.756551) (xy 391.450853 -376.823855) (xy 391.450846 -376.823915)
			(xy 421.128651 -376.823915) (xy 421.128651 -376.756491) (xy 421.136727 -376.689552) (xy 421.152763 -376.624063)
			(xy 421.176528 -376.560966) (xy 421.20768 -376.50117) (xy 421.245771 -376.445537) (xy 421.267636 -376.419872)
			(xy 421.273432 -376.412726) (xy 421.279946 -376.395536) (xy 421.280336 -376.386344) (xy 421.280336 -375.894092)
			(xy 421.279922 -375.884905) (xy 421.27341 -375.867721) (xy 421.267636 -375.860564) (xy 421.245802 -375.834873)
			(xy 421.20771 -375.779243) (xy 421.176556 -375.719451) (xy 421.152788 -375.656357) (xy 421.13675 -375.590871)
			(xy 421.128671 -375.523935) (xy 421.128668 -375.456513) (xy 421.136741 -375.389576) (xy 421.152774 -375.324089)
			(xy 421.176536 -375.260993) (xy 421.207685 -375.201198) (xy 421.245773 -375.145565) (xy 421.267636 -375.1199)
			(xy 421.27342 -375.112746) (xy 421.279941 -375.095562) (xy 421.280336 -375.086372) (xy 421.280336 -374.928638)
			(xy 421.280858 -374.918514) (xy 421.288572 -374.899795) (xy 421.302848 -374.885437) (xy 421.321523 -374.877616)
			(xy 421.331644 -374.877076) (xy 422.047924 -374.877076) (xy 422.058031 -374.877565) (xy 422.076706 -374.885306)
			(xy 422.090999 -374.899601) (xy 422.098737 -374.918277) (xy 422.099232 -374.928384) (xy 422.099232 -375.086372)
			(xy 422.099671 -375.095556) (xy 422.106166 -375.11274) (xy 422.111932 -375.1199) (xy 422.133826 -375.14554)
			(xy 422.171912 -375.201179) (xy 422.203059 -375.260979) (xy 422.22682 -375.324079) (xy 422.242853 -375.389571)
			(xy 422.250926 -375.456511) (xy 422.250923 -375.523937) (xy 422.242844 -375.590877) (xy 422.226806 -375.656367)
			(xy 422.20304 -375.719465) (xy 422.171887 -375.779263) (xy 422.133797 -375.834898) (xy 422.111932 -375.860564)
			(xy 422.106117 -375.867696) (xy 422.099615 -375.884897) (xy 422.099232 -375.894092) (xy 422.099232 -376.386344)
			(xy 422.099636 -376.395532) (xy 422.106156 -376.412715) (xy 422.111932 -376.419872) (xy 422.133799 -376.445535)
			(xy 422.171885 -376.50117) (xy 422.203034 -376.560967) (xy 422.226797 -376.624064) (xy 422.242831 -376.689553)
			(xy 422.250906 -376.756491) (xy 422.250906 -376.756551) (xy 425.52897 -376.756551) (xy 425.537014 -376.689729)
			(xy 425.552986 -376.624347) (xy 425.576658 -376.561343) (xy 425.607689 -376.501619) (xy 425.645637 -376.446032)
			(xy 425.667424 -376.42038) (xy 425.673214 -376.413231) (xy 425.679732 -376.396043) (xy 425.680124 -376.386852)
			(xy 425.680124 -375.893584) (xy 425.679716 -375.884397) (xy 425.6732 -375.867213) (xy 425.667424 -375.860056)
			(xy 425.645668 -375.834378) (xy 425.60772 -375.778795) (xy 425.576686 -375.719074) (xy 425.553012 -375.656073)
			(xy 425.537037 -375.590695) (xy 425.528991 -375.523875) (xy 425.528988 -375.456573) (xy 425.537029 -375.389753)
			(xy 425.552998 -375.324373) (xy 425.576666 -375.26137) (xy 425.607695 -375.201647) (xy 425.645639 -375.146061)
			(xy 425.667424 -375.120408) (xy 425.673202 -375.11325) (xy 425.679727 -375.096069) (xy 425.680124 -375.08688)
			(xy 425.680124 -374.928638) (xy 425.680595 -374.918471) (xy 425.688365 -374.899679) (xy 425.702736 -374.885294)
			(xy 425.721519 -374.877505) (xy 425.731686 -374.877076) (xy 426.447966 -374.877076) (xy 426.45814 -374.877493)
			(xy 426.476941 -374.885274) (xy 426.491329 -374.899662) (xy 426.499108 -374.918464) (xy 426.499528 -374.928638)
			(xy 426.499528 -375.08688) (xy 426.499941 -375.096067) (xy 426.506452 -375.113252) (xy 426.512228 -375.120408)
			(xy 426.534048 -375.146034) (xy 426.571998 -375.201623) (xy 426.603032 -375.26135) (xy 426.626705 -375.324358)
			(xy 426.642676 -375.389744) (xy 426.650718 -375.45657) (xy 426.650716 -375.523878) (xy 426.642668 -375.590704)
			(xy 426.62669 -375.656088) (xy 426.603013 -375.719094) (xy 426.571974 -375.778818) (xy 426.534019 -375.834404)
			(xy 426.512228 -375.860056) (xy 426.506416 -375.86719) (xy 426.499913 -375.884389) (xy 426.499528 -375.893584)
			(xy 426.499528 -376.386852) (xy 426.499955 -376.396037) (xy 426.506456 -376.413222) (xy 426.512228 -376.42038)
			(xy 426.534021 -376.446029) (xy 426.571971 -376.501615) (xy 426.603006 -376.561338) (xy 426.62668 -376.624344)
			(xy 426.642654 -376.689727) (xy 426.650698 -376.75655) (xy 426.650698 -376.823856) (xy 426.650691 -376.823915)
			(xy 429.928739 -376.823915) (xy 429.928739 -376.756491) (xy 429.936814 -376.689553) (xy 429.95285 -376.624064)
			(xy 429.976615 -376.560967) (xy 430.007766 -376.501171) (xy 430.045856 -376.445537) (xy 430.06772 -376.419872)
			(xy 430.073513 -376.412725) (xy 430.080029 -376.395536) (xy 430.08042 -376.386344) (xy 430.08042 -375.894092)
			(xy 430.080009 -375.884905) (xy 430.073496 -375.867721) (xy 430.06772 -375.860564) (xy 430.045887 -375.834873)
			(xy 430.007796 -375.779243) (xy 429.976643 -375.71945) (xy 429.952876 -375.656357) (xy 429.936837 -375.590871)
			(xy 429.928759 -375.523935) (xy 429.928756 -375.456513) (xy 429.936829 -375.389577) (xy 429.952861 -375.324089)
			(xy 429.976623 -375.260994) (xy 430.007771 -375.201199) (xy 430.045857 -375.145565) (xy 430.06772 -375.1199)
			(xy 430.073501 -375.112744) (xy 430.080024 -375.095562) (xy 430.08042 -375.086372) (xy 430.08042 -374.928638)
			(xy 430.080957 -374.918516) (xy 430.088669 -374.8998) (xy 430.10294 -374.885443) (xy 430.121609 -374.877619)
			(xy 430.131728 -374.877076) (xy 430.848008 -374.877076) (xy 430.85816 -374.877515) (xy 430.876907 -374.885308)
			(xy 430.89123 -374.899699) (xy 430.898933 -374.918484) (xy 430.899316 -374.928638) (xy 430.899316 -375.086372)
			(xy 430.899736 -375.095558) (xy 430.906242 -375.112743) (xy 430.912016 -375.1199) (xy 430.933911 -375.14554)
			(xy 430.971998 -375.201178) (xy 431.003146 -375.260978) (xy 431.026908 -375.324078) (xy 431.04294 -375.38957)
			(xy 431.051013 -375.456511) (xy 431.051011 -375.523937) (xy 431.042932 -375.590877) (xy 431.026893 -375.656368)
			(xy 431.003126 -375.719466) (xy 430.971973 -375.779263) (xy 430.933881 -375.834898) (xy 430.912016 -375.860564)
			(xy 430.906212 -375.867704) (xy 430.899701 -375.884898) (xy 430.899316 -375.894092) (xy 430.899316 -376.386344)
			(xy 430.899701 -376.395534) (xy 430.906232 -376.412718) (xy 430.912016 -376.419872) (xy 430.933883 -376.445534)
			(xy 430.971971 -376.50117) (xy 431.003121 -376.560966) (xy 431.026884 -376.624064) (xy 431.042918 -376.689553)
			(xy 431.050994 -376.756491) (xy 431.050994 -376.756551) (xy 434.329058 -376.756551) (xy 434.337101 -376.689729)
			(xy 434.353073 -376.624348) (xy 434.376744 -376.561343) (xy 434.407775 -376.50162) (xy 434.445721 -376.446033)
			(xy 434.467508 -376.42038) (xy 434.473296 -376.413229) (xy 434.479816 -376.396043) (xy 434.480208 -376.386852)
			(xy 434.480208 -375.893584) (xy 434.479804 -375.884396) (xy 434.473286 -375.867212) (xy 434.467508 -375.860056)
			(xy 434.445753 -375.834378) (xy 434.407805 -375.778794) (xy 434.376772 -375.719074) (xy 434.353099 -375.656073)
			(xy 434.337124 -375.590694) (xy 434.329078 -375.523875) (xy 434.329075 -375.456573) (xy 434.337116 -375.389753)
			(xy 434.353084 -375.324373) (xy 434.376752 -375.26137) (xy 434.40778 -375.201647) (xy 434.445723 -375.146061)
			(xy 434.467508 -375.120408) (xy 434.473285 -375.113249) (xy 434.479811 -375.096069) (xy 434.480208 -375.08688)
			(xy 434.480208 -374.928638) (xy 434.480694 -374.918473) (xy 434.488461 -374.899684) (xy 434.502827 -374.885299)
			(xy 434.521605 -374.877508) (xy 434.53177 -374.877076) (xy 435.24805 -374.877076) (xy 435.258223 -374.877506)
			(xy 435.277024 -374.885281) (xy 435.291412 -374.899666) (xy 435.299192 -374.918465) (xy 435.299612 -374.928638)
			(xy 435.299612 -375.08688) (xy 435.300029 -375.096067) (xy 435.306538 -375.113251) (xy 435.312312 -375.120408)
			(xy 435.334133 -375.146034) (xy 435.372084 -375.201623) (xy 435.403118 -375.26135) (xy 435.426791 -375.324358)
			(xy 435.442764 -375.389744) (xy 435.450806 -375.45657) (xy 435.450803 -375.523878) (xy 435.442755 -375.590704)
			(xy 435.426777 -375.656088) (xy 435.403099 -375.719094) (xy 435.372059 -375.778819) (xy 435.334103 -375.834404)
			(xy 435.312312 -375.860056) (xy 435.306511 -375.867198) (xy 435.299998 -375.884391) (xy 435.299612 -375.893584)
			(xy 435.299612 -376.386852) (xy 435.300042 -376.396037) (xy 435.306542 -376.413222) (xy 435.312312 -376.42038)
			(xy 435.334105 -376.446028) (xy 435.372057 -376.501614) (xy 435.403093 -376.561338) (xy 435.426768 -376.624343)
			(xy 435.442742 -376.689726) (xy 435.450786 -376.75655) (xy 435.450786 -376.823856) (xy 435.442741 -376.89068)
			(xy 435.426766 -376.956063) (xy 435.40309 -377.019068) (xy 435.372054 -377.078791) (xy 435.334101 -377.134376)
			(xy 435.312312 -377.160028) (xy 435.306522 -377.167178) (xy 435.300003 -377.184365) (xy 435.299612 -377.193556)
			(xy 435.299612 -377.35129) (xy 435.299227 -377.361467) (xy 435.291436 -377.380271) (xy 435.277038 -377.394658)
			(xy 435.258228 -377.402435) (xy 435.24805 -377.402852) (xy 434.53177 -377.402852) (xy 434.521609 -377.402391)
			(xy 434.502837 -377.394605) (xy 434.488473 -377.380229) (xy 434.480701 -377.361451) (xy 434.480208 -377.35129)
			(xy 434.480208 -377.193556) (xy 434.479817 -377.184367) (xy 434.47329 -377.167183) (xy 434.467508 -377.160028)
			(xy 434.445725 -377.134372) (xy 434.407778 -377.078786) (xy 434.376746 -377.019062) (xy 434.353075 -376.956058)
			(xy 434.337103 -376.890677) (xy 434.329059 -376.823855) (xy 434.329058 -376.756551) (xy 431.050994 -376.756551)
			(xy 431.050993 -376.823915) (xy 431.042917 -376.890853) (xy 431.026882 -376.956342) (xy 431.003118 -377.019439)
			(xy 430.971968 -377.079236) (xy 430.93388 -377.13487) (xy 430.912016 -377.160536) (xy 430.906223 -377.167684)
			(xy 430.899706 -377.184872) (xy 430.899316 -377.194064) (xy 430.899316 -377.35129) (xy 430.898864 -377.361421)
			(xy 430.891131 -377.380151) (xy 430.876834 -377.394509) (xy 430.858137 -377.402321) (xy 430.848008 -377.402852)
			(xy 430.131728 -377.402852) (xy 430.121582 -377.402357) (xy 430.10284 -377.39458) (xy 430.088518 -377.380207)
			(xy 430.080808 -377.361437) (xy 430.08042 -377.35129) (xy 430.08042 -377.194064) (xy 430.080023 -377.184876)
			(xy 430.0735 -377.167692) (xy 430.06772 -377.160536) (xy 430.045859 -377.134868) (xy 430.007769 -377.079234)
			(xy 429.976617 -377.019439) (xy 429.952852 -376.956342) (xy 429.936815 -376.890853) (xy 429.928739 -376.823915)
			(xy 426.650691 -376.823915) (xy 426.642653 -376.890679) (xy 426.626679 -376.956062) (xy 426.603004 -377.019067)
			(xy 426.571968 -377.07879) (xy 426.534017 -377.134376) (xy 426.512228 -377.160028) (xy 426.506428 -377.167171)
			(xy 426.499918 -377.184363) (xy 426.499528 -377.193556) (xy 426.499528 -377.35129) (xy 426.499127 -377.361465)
			(xy 426.491339 -377.380266) (xy 426.476946 -377.394653) (xy 426.458141 -377.402432) (xy 426.447966 -377.402852)
			(xy 425.731686 -377.402852) (xy 425.721526 -377.402378) (xy 425.702755 -377.394597) (xy 425.68839 -377.380225)
			(xy 425.680618 -377.36145) (xy 425.680124 -377.35129) (xy 425.680124 -377.193556) (xy 425.67973 -377.184367)
			(xy 425.673204 -377.167183) (xy 425.667424 -377.160028) (xy 425.645641 -377.134372) (xy 425.607693 -377.078786)
			(xy 425.57666 -377.019063) (xy 425.552988 -376.956059) (xy 425.537015 -376.890677) (xy 425.528971 -376.823855)
			(xy 425.52897 -376.756551) (xy 422.250906 -376.756551) (xy 422.250905 -376.823915) (xy 422.24283 -376.890853)
			(xy 422.226795 -376.956342) (xy 422.203032 -377.019438) (xy 422.171882 -377.079235) (xy 422.133795 -377.13487)
			(xy 422.111932 -377.160536) (xy 422.106129 -377.167677) (xy 422.09962 -377.184871) (xy 422.099232 -377.194064)
			(xy 422.099232 -377.35129) (xy 422.098764 -377.36142) (xy 422.091035 -377.380146) (xy 422.076742 -377.394503)
			(xy 422.058051 -377.402318) (xy 422.047924 -377.402852) (xy 421.331644 -377.402852) (xy 421.321544 -377.40228)
			(xy 421.302877 -377.394567) (xy 421.288583 -377.380297) (xy 421.280837 -377.361643) (xy 421.280336 -377.351544)
			(xy 421.280336 -377.194064) (xy 421.279935 -377.184876) (xy 421.273414 -377.167692) (xy 421.267636 -377.160536)
			(xy 421.245775 -377.134868) (xy 421.207684 -377.079235) (xy 421.176531 -377.019439) (xy 421.152765 -376.956343)
			(xy 421.136728 -376.890854) (xy 421.128651 -376.823915) (xy 391.450846 -376.823915) (xy 391.442809 -376.890678)
			(xy 391.426837 -376.956059) (xy 391.403165 -377.019064) (xy 391.372134 -377.078788) (xy 391.334187 -377.134375)
			(xy 391.3124 -377.160028) (xy 391.306609 -377.167177) (xy 391.300091 -377.184365) (xy 391.2997 -377.193556)
			(xy 391.2997 -377.35129) (xy 391.299159 -377.361442) (xy 391.291395 -377.380204) (xy 391.277044 -377.394568)
			(xy 391.25829 -377.40235) (xy 391.248138 -377.402852) (xy 390.531858 -377.402852) (xy 390.521696 -377.402401)
			(xy 390.502924 -377.394611) (xy 390.48856 -377.380232) (xy 390.480789 -377.361452) (xy 390.480296 -377.35129)
			(xy 390.480296 -377.193556) (xy 390.479908 -377.184366) (xy 390.473379 -377.167182) (xy 390.467596 -377.160028)
			(xy 390.445814 -377.134372) (xy 390.407867 -377.078785) (xy 390.376836 -377.019062) (xy 390.353165 -376.956058)
			(xy 390.337193 -376.890676) (xy 390.329149 -376.823855) (xy 387.051084 -376.823855) (xy 387.051084 -376.823915)
			(xy 387.043008 -376.890853) (xy 387.026972 -376.956343) (xy 387.003208 -377.01944) (xy 386.972057 -377.079236)
			(xy 386.933968 -377.134871) (xy 386.912104 -377.160536) (xy 386.90631 -377.167683) (xy 386.899794 -377.184872)
			(xy 386.899404 -377.194064) (xy 386.899404 -377.35129) (xy 386.898867 -377.361411) (xy 386.89115 -377.380123)
			(xy 386.87688 -377.394478) (xy 386.858214 -377.402306) (xy 386.848096 -377.402852) (xy 386.131816 -377.402852)
			(xy 386.121669 -377.402366) (xy 386.102927 -377.394586) (xy 386.088605 -377.380209) (xy 386.080896 -377.361438)
			(xy 386.080508 -377.35129) (xy 386.080508 -377.194064) (xy 386.080114 -377.184875) (xy 386.073589 -377.167691)
			(xy 386.067808 -377.160536) (xy 386.045948 -377.134868) (xy 386.007858 -377.079234) (xy 385.976707 -377.019438)
			(xy 385.952942 -376.956342) (xy 385.936906 -376.890853) (xy 385.92883 -376.823915) (xy 382.650782 -376.823915)
			(xy 382.642744 -376.89068) (xy 382.626769 -376.956063) (xy 382.603094 -377.019068) (xy 382.572058 -377.078791)
			(xy 382.534105 -377.134376) (xy 382.512316 -377.160028) (xy 382.506527 -377.167179) (xy 382.500007 -377.184365)
			(xy 382.499616 -377.193556) (xy 382.499616 -377.35129) (xy 382.499227 -377.361467) (xy 382.491437 -377.38027)
			(xy 382.47704 -377.394657) (xy 382.458231 -377.402434) (xy 382.448054 -377.402852) (xy 381.731774 -377.402852)
			(xy 381.721613 -377.402388) (xy 381.702842 -377.394603) (xy 381.688477 -377.380228) (xy 381.680705 -377.361451)
			(xy 381.680212 -377.35129) (xy 381.680212 -377.193556) (xy 381.67982 -377.184367) (xy 381.673294 -377.167183)
			(xy 381.667512 -377.160028) (xy 381.645729 -377.134372) (xy 381.607782 -377.078786) (xy 381.57675 -377.019062)
			(xy 381.553078 -376.956058) (xy 381.537106 -376.890677) (xy 381.529062 -376.823855) (xy 381.529061 -376.756551)
			(xy 378.250997 -376.756551) (xy 378.250996 -376.823915) (xy 378.24292 -376.890853) (xy 378.226885 -376.956342)
			(xy 378.203121 -377.019439) (xy 378.171971 -377.079235) (xy 378.133884 -377.13487) (xy 378.11202 -377.160536)
			(xy 378.106228 -377.167685) (xy 378.09971 -377.184872) (xy 378.09932 -377.194064) (xy 378.09932 -377.35129)
			(xy 378.098864 -377.361421) (xy 378.091132 -377.38015) (xy 378.076836 -377.394508) (xy 378.058141 -377.40232)
			(xy 378.048012 -377.402852) (xy 377.331732 -377.402852) (xy 377.321586 -377.402353) (xy 377.302845 -377.394578)
			(xy 377.288522 -377.380206) (xy 377.280812 -377.361437) (xy 377.280424 -377.35129) (xy 377.280424 -377.194064)
			(xy 377.280026 -377.184876) (xy 377.273503 -377.167692) (xy 377.267724 -377.160536) (xy 377.245863 -377.134868)
			(xy 377.207773 -377.079234) (xy 377.17662 -377.019439) (xy 377.152855 -376.956342) (xy 377.136819 -376.890853)
			(xy 377.128742 -376.823915) (xy 347.450937 -376.823915) (xy 347.4429 -376.890678) (xy 347.426927 -376.95606)
			(xy 347.403255 -377.019065) (xy 347.372223 -377.078788) (xy 347.334275 -377.134376) (xy 347.312488 -377.160028)
			(xy 347.306696 -377.167176) (xy 347.300179 -377.184364) (xy 347.299788 -377.193556) (xy 347.299788 -377.35129)
			(xy 347.299259 -377.361444) (xy 347.291493 -377.380208) (xy 347.277138 -377.394573) (xy 347.25838 -377.402352)
			(xy 347.248226 -377.402852) (xy 346.531946 -377.402852) (xy 346.521776 -377.402398) (xy 346.502981 -377.394627)
			(xy 346.488594 -377.38025) (xy 346.480809 -377.36146) (xy 346.480384 -377.35129) (xy 346.480384 -377.193556)
			(xy 346.479999 -377.184366) (xy 346.473468 -377.167182) (xy 346.467684 -377.160028) (xy 346.445899 -377.134373)
			(xy 346.407947 -377.078788) (xy 346.376911 -377.019065) (xy 346.353236 -376.956061) (xy 346.337262 -376.890679)
			(xy 346.329216 -376.823856) (xy 343.051175 -376.823856) (xy 343.051175 -376.823915) (xy 343.043099 -376.890854)
			(xy 343.027063 -376.956343) (xy 343.003298 -377.01944) (xy 342.972146 -377.079236) (xy 342.934056 -377.134871)
			(xy 342.912192 -377.160536) (xy 342.906397 -377.167682) (xy 342.899882 -377.184872) (xy 342.899492 -377.194064)
			(xy 342.899492 -377.35129) (xy 342.898966 -377.361412) (xy 342.891248 -377.380127) (xy 342.876974 -377.394483)
			(xy 342.858303 -377.402308) (xy 342.848184 -377.402852) (xy 342.131904 -377.402852) (xy 342.121757 -377.402376)
			(xy 342.103014 -377.394592) (xy 342.088693 -377.380212) (xy 342.080984 -377.361439) (xy 342.080596 -377.35129)
			(xy 342.080596 -377.194064) (xy 342.080204 -377.184875) (xy 342.073678 -377.167691) (xy 342.067896 -377.160536)
			(xy 342.046036 -377.134867) (xy 342.007948 -377.079233) (xy 341.976797 -377.019438) (xy 341.953033 -376.956341)
			(xy 341.936997 -376.890852) (xy 341.928921 -376.823915) (xy 338.650849 -376.823915) (xy 338.642812 -376.890677)
			(xy 338.62684 -376.956059) (xy 338.603168 -377.019064) (xy 338.572137 -377.078788) (xy 338.534191 -377.134375)
			(xy 338.512404 -377.160028) (xy 338.506614 -377.167178) (xy 338.500095 -377.184365) (xy 338.499704 -377.193556)
			(xy 338.499704 -377.35129) (xy 338.49916 -377.361442) (xy 338.491396 -377.380203) (xy 338.477047 -377.394567)
			(xy 338.458293 -377.402349) (xy 338.448142 -377.402852) (xy 337.731862 -377.402852) (xy 337.721701 -377.402397)
			(xy 337.702929 -377.394609) (xy 337.688564 -377.380231) (xy 337.680793 -377.361452) (xy 337.6803 -377.35129)
			(xy 337.6803 -377.193556) (xy 337.679911 -377.184367) (xy 337.673383 -377.167182) (xy 337.6676 -377.160028)
			(xy 337.645817 -377.134372) (xy 337.607871 -377.078785) (xy 337.57684 -377.019062) (xy 337.553168 -376.956058)
			(xy 337.537196 -376.890677) (xy 337.529152 -376.823855) (xy 334.251087 -376.823855) (xy 334.251087 -376.823915)
			(xy 334.243011 -376.890853) (xy 334.226976 -376.956342) (xy 334.203211 -377.019439) (xy 334.172061 -377.079236)
			(xy 334.133972 -377.134871) (xy 334.112108 -377.160536) (xy 334.106315 -377.167684) (xy 334.099798 -377.184872)
			(xy 334.099408 -377.194064) (xy 334.099408 -377.35129) (xy 334.098867 -377.36141) (xy 334.091151 -377.380122)
			(xy 334.076882 -377.394477) (xy 334.058217 -377.402305) (xy 334.0481 -377.402852) (xy 333.33182 -377.402852)
			(xy 333.321674 -377.402363) (xy 333.302932 -377.394584) (xy 333.288609 -377.380209) (xy 333.2809 -377.361438)
			(xy 333.280512 -377.35129) (xy 333.280512 -377.194064) (xy 333.280117 -377.184875) (xy 333.273592 -377.167691)
			(xy 333.267812 -377.160536) (xy 333.245952 -377.134868) (xy 333.207862 -377.079234) (xy 333.17671 -377.019438)
			(xy 333.152945 -376.956342) (xy 333.136909 -376.890853) (xy 333.128833 -376.823915) (xy 303.451057 -376.823915)
			(xy 303.44298 -376.890854) (xy 303.426944 -376.956344) (xy 303.403178 -377.019441) (xy 303.372025 -377.079237)
			(xy 303.333933 -377.134871) (xy 303.312068 -377.160536) (xy 303.30627 -377.16768) (xy 303.299757 -377.184871)
			(xy 303.299368 -377.194064) (xy 303.299368 -377.35129) (xy 303.298865 -377.361415) (xy 303.291142 -377.380135)
			(xy 303.276861 -377.394491) (xy 303.258182 -377.402312) (xy 303.24806 -377.402852) (xy 302.53178 -377.402852)
			(xy 302.521631 -377.402396) (xy 302.502888 -377.394604) (xy 302.488567 -377.380218) (xy 302.480859 -377.361441)
			(xy 302.480472 -377.35129) (xy 302.480472 -377.194064) (xy 302.480085 -377.184874) (xy 302.473556 -377.16769)
			(xy 302.467772 -377.160536) (xy 302.445913 -377.134867) (xy 302.407826 -377.079232) (xy 302.376677 -377.019436)
			(xy 302.352913 -376.95634) (xy 302.336879 -376.890852) (xy 302.328803 -376.823914) (xy 302.328802 -376.756492)
			(xy 299.050731 -376.756492) (xy 299.050738 -376.756551) (xy 299.050738 -376.823856) (xy 299.042693 -376.890678)
			(xy 299.026721 -376.95606) (xy 299.003048 -377.019065) (xy 298.972016 -377.078789) (xy 298.934067 -377.134376)
			(xy 298.91228 -377.160028) (xy 298.906487 -377.167175) (xy 298.899971 -377.184364) (xy 298.89958 -377.193556)
			(xy 298.89958 -377.35129) (xy 298.899059 -377.361445) (xy 298.891291 -377.38021) (xy 298.876934 -377.394575)
			(xy 298.858173 -377.402353) (xy 298.848018 -377.402852) (xy 298.131738 -377.402852) (xy 298.121568 -377.402405)
			(xy 298.102772 -377.39463) (xy 298.088385 -377.380252) (xy 298.080601 -377.36146) (xy 298.080176 -377.35129)
			(xy 298.080176 -377.193556) (xy 298.079792 -377.184366) (xy 298.073261 -377.167182) (xy 298.067476 -377.160028)
			(xy 298.045691 -377.134373) (xy 298.00774 -377.078788) (xy 297.976704 -377.019065) (xy 297.95303 -376.956061)
			(xy 297.937055 -376.890679) (xy 297.92901 -376.823856) (xy 294.650969 -376.823856) (xy 294.650969 -376.823915)
			(xy 294.642893 -376.890854) (xy 294.626856 -376.956343) (xy 294.603091 -377.019441) (xy 294.571939 -377.079237)
			(xy 294.533849 -377.134871) (xy 294.511984 -377.160536) (xy 294.506188 -377.167681) (xy 294.499673 -377.184872)
			(xy 294.499284 -377.194064) (xy 294.499284 -377.35129) (xy 294.498766 -377.361413) (xy 294.491046 -377.38013)
			(xy 294.47677 -377.394485) (xy 294.458096 -377.402309) (xy 294.447976 -377.402852) (xy 293.731696 -377.402852)
			(xy 293.721593 -377.402319) (xy 293.702925 -377.39459) (xy 293.688632 -377.380308) (xy 293.680889 -377.361646)
			(xy 293.680388 -377.351544) (xy 293.680388 -377.194064) (xy 293.679998 -377.184875) (xy 293.673471 -377.16769)
			(xy 293.667688 -377.160536) (xy 293.645828 -377.134867) (xy 293.60774 -377.079233) (xy 293.57659 -377.019437)
			(xy 293.552826 -376.956341) (xy 293.536791 -376.890852) (xy 293.528715 -376.823915) (xy 290.250643 -376.823915)
			(xy 290.242606 -376.890678) (xy 290.226633 -376.95606) (xy 290.202962 -377.019064) (xy 290.17193 -377.078788)
			(xy 290.133983 -377.134375) (xy 290.112196 -377.160028) (xy 290.106405 -377.167177) (xy 290.099887 -377.184365)
			(xy 290.099496 -377.193556) (xy 290.099496 -377.35129) (xy 290.098959 -377.361443) (xy 290.091194 -377.380205)
			(xy 290.076842 -377.39457) (xy 290.058087 -377.402351) (xy 290.047934 -377.402852) (xy 289.331654 -377.402852)
			(xy 289.321492 -377.402404) (xy 289.30272 -377.394613) (xy 289.288356 -377.380233) (xy 289.280585 -377.361452)
			(xy 289.280092 -377.35129) (xy 289.280092 -377.193556) (xy 289.279705 -377.184366) (xy 289.273176 -377.167182)
			(xy 289.267392 -377.160028) (xy 289.245607 -377.134373) (xy 289.207654 -377.078788) (xy 289.176618 -377.019066)
			(xy 289.152942 -376.956061) (xy 289.136968 -376.890679) (xy 289.128922 -376.823856) (xy 273.068299 -376.823856)
			(xy 273.100384 -376.843252) (xy 273.210304 -376.919124) (xy 273.315441 -377.001494) (xy 273.415414 -377.090062)
			(xy 273.509856 -377.184504) (xy 273.598424 -377.284477) (xy 273.680794 -377.389614) (xy 273.756666 -377.499534)
			(xy 273.825762 -377.613833) (xy 273.887832 -377.732096) (xy 273.942647 -377.853891) (xy 273.990009 -377.978774)
			(xy 274.029744 -378.106288) (xy 274.061707 -378.235969) (xy 274.077801 -378.323794) (xy 286.928742 -378.323794)
			(xy 286.928744 -378.256367) (xy 286.936824 -378.189426) (xy 286.952863 -378.123935) (xy 286.976633 -378.060837)
			(xy 287.007789 -378.00104) (xy 287.045885 -377.945406) (xy 287.067752 -377.919742) (xy 287.073562 -377.912607)
			(xy 287.080067 -377.895408) (xy 287.080452 -377.886214) (xy 287.080452 -377.728734) (xy 287.080955 -377.718608)
			(xy 287.088674 -377.699885) (xy 287.102955 -377.685528) (xy 287.121637 -377.677709) (xy 287.13176 -377.677172)
			(xy 287.84804 -377.677172) (xy 287.858148 -377.677652) (xy 287.876822 -377.685397) (xy 287.891114 -377.699695)
			(xy 287.898852 -377.718372) (xy 287.899348 -377.72848) (xy 287.899348 -377.886214) (xy 287.899763 -377.8954)
			(xy 287.906275 -377.912584) (xy 287.912048 -377.919742) (xy 287.933888 -377.945427) (xy 287.971981 -378.001058)
			(xy 288.003136 -378.060851) (xy 288.026904 -378.123945) (xy 288.042943 -378.189432) (xy 288.051021 -378.256369)
			(xy 288.051024 -378.323734) (xy 291.329062 -378.323734) (xy 291.329064 -378.256427) (xy 291.337111 -378.189602)
			(xy 291.353086 -378.124219) (xy 291.376762 -378.061213) (xy 291.407799 -378.001489) (xy 291.445751 -377.945902)
			(xy 291.46754 -377.92025) (xy 291.473345 -377.913111) (xy 291.479854 -377.895916) (xy 291.48024 -377.886722)
			(xy 291.48024 -377.728734) (xy 291.480692 -377.718564) (xy 291.488466 -377.69977) (xy 291.502843 -377.685384)
			(xy 291.521633 -377.677598) (xy 291.531802 -377.677172) (xy 292.248082 -377.677172) (xy 292.258257 -377.677579)
			(xy 292.277058 -377.685365) (xy 292.291444 -377.699756) (xy 292.299224 -377.718559) (xy 292.299644 -377.728734)
			(xy 292.299644 -377.886722) (xy 292.300056 -377.895909) (xy 292.30657 -377.913092) (xy 292.312344 -377.92025)
			(xy 292.334107 -377.945923) (xy 292.372057 -378.001506) (xy 292.403093 -378.061227) (xy 292.426768 -378.124228)
			(xy 292.442743 -378.189608) (xy 292.450789 -378.256429) (xy 292.450792 -378.323732) (xy 292.450785 -378.323794)
			(xy 295.72883 -378.323794) (xy 295.728832 -378.256367) (xy 295.736911 -378.189427) (xy 295.752951 -378.123936)
			(xy 295.776719 -378.060837) (xy 295.807875 -378.001041) (xy 295.845969 -377.945407) (xy 295.867836 -377.919742)
			(xy 295.873644 -377.912605) (xy 295.880151 -377.895408) (xy 295.880536 -377.886214) (xy 295.880536 -377.728734)
			(xy 295.881055 -377.71861) (xy 295.88877 -377.69989) (xy 295.903047 -377.685533) (xy 295.921723 -377.677712)
			(xy 295.931844 -377.677172) (xy 296.648124 -377.677172) (xy 296.658276 -377.677601) (xy 296.677024 -377.6854)
			(xy 296.691345 -377.699793) (xy 296.699049 -377.71858) (xy 296.699432 -377.728734) (xy 296.699432 -377.886214)
			(xy 296.699851 -377.8954) (xy 296.70636 -377.912584) (xy 296.712132 -377.919742) (xy 296.733969 -377.945429)
			(xy 296.772057 -378.001061) (xy 296.803207 -378.060855) (xy 296.826971 -378.123949) (xy 296.843007 -378.189435)
			(xy 296.851085 -378.25637) (xy 296.851087 -378.323791) (xy 296.851087 -378.323794) (xy 300.128621 -378.323794)
			(xy 300.128623 -378.256367) (xy 300.136702 -378.189427) (xy 300.152741 -378.123936) (xy 300.176509 -378.060838)
			(xy 300.207664 -378.001041) (xy 300.245758 -377.945407) (xy 300.267624 -377.919742) (xy 300.27343 -377.912604)
			(xy 300.279938 -377.895408) (xy 300.280324 -377.886214) (xy 300.280324 -377.728734) (xy 300.280854 -377.718611)
			(xy 300.288568 -377.699894) (xy 300.302841 -377.685537) (xy 300.321512 -377.677714) (xy 300.331632 -377.677172)
			(xy 301.047912 -377.677172) (xy 301.058063 -377.677611) (xy 301.076811 -377.685405) (xy 301.091133 -377.699796)
			(xy 301.098837 -377.718581) (xy 301.09922 -377.728734) (xy 301.09922 -377.886214) (xy 301.099619 -377.895402)
			(xy 301.10614 -377.912587) (xy 301.11192 -377.919742) (xy 301.133758 -377.945429) (xy 301.171846 -378.001061)
			(xy 301.202997 -378.060854) (xy 301.226761 -378.123948) (xy 301.242798 -378.189434) (xy 301.250876 -378.25637)
			(xy 301.250878 -378.323734) (xy 330.92918 -378.323734) (xy 330.929182 -378.256427) (xy 330.937229 -378.189602)
			(xy 330.953206 -378.124218) (xy 330.976882 -378.061212) (xy 331.00792 -378.001488) (xy 331.045874 -377.945902)
			(xy 331.067664 -377.92025) (xy 331.073472 -377.913113) (xy 331.079978 -377.895916) (xy 331.080364 -377.886722)
			(xy 331.080364 -377.728734) (xy 331.080792 -377.718561) (xy 331.088571 -377.699763) (xy 331.102956 -377.685376)
			(xy 331.121753 -377.677594) (xy 331.131926 -377.677172) (xy 331.848206 -377.677172) (xy 331.858382 -377.67756)
			(xy 331.877184 -377.685353) (xy 331.891569 -377.69975) (xy 331.899348 -377.718557) (xy 331.899768 -377.728734)
			(xy 331.899768 -377.886722) (xy 331.900175 -377.895909) (xy 331.906692 -377.913093) (xy 331.912468 -377.92025)
			(xy 331.93423 -377.945923) (xy 331.972179 -378.001507) (xy 332.003213 -378.061228) (xy 332.026887 -378.124229)
			(xy 332.042861 -378.189609) (xy 332.050907 -378.256429) (xy 332.05091 -378.323732) (xy 332.050903 -378.323793)
			(xy 335.328973 -378.323793) (xy 335.328975 -378.256368) (xy 335.337053 -378.189429) (xy 335.35309 -378.123939)
			(xy 335.376855 -378.060841) (xy 335.408007 -378.001044) (xy 335.446096 -377.945408) (xy 335.46796 -377.919742)
			(xy 335.473771 -377.912607) (xy 335.480275 -377.895409) (xy 335.48066 -377.886214) (xy 335.48066 -377.728734)
			(xy 335.481155 -377.718607) (xy 335.488875 -377.699883) (xy 335.50316 -377.685525) (xy 335.521844 -377.677708)
			(xy 335.531968 -377.677172) (xy 336.248248 -377.677172) (xy 336.258402 -377.677582) (xy 336.27715 -377.685388)
			(xy 336.29147 -377.699787) (xy 336.299173 -377.718578) (xy 336.299556 -377.728734) (xy 336.299556 -377.886214)
			(xy 336.299969 -377.895401) (xy 336.306482 -377.912585) (xy 336.312256 -377.919742) (xy 336.334096 -377.945428)
			(xy 336.372188 -378.001058) (xy 336.403343 -378.060851) (xy 336.42711 -378.123945) (xy 336.443149 -378.189433)
			(xy 336.451227 -378.256369) (xy 336.45123 -378.323734) (xy 339.729268 -378.323734) (xy 339.72927 -378.256427)
			(xy 339.737317 -378.189602) (xy 339.753293 -378.124218) (xy 339.776969 -378.061213) (xy 339.808006 -378.001489)
			(xy 339.845958 -377.945902) (xy 339.867748 -377.92025) (xy 339.873554 -377.913112) (xy 339.880062 -377.895916)
			(xy 339.880448 -377.886722) (xy 339.880448 -377.728734) (xy 339.880892 -377.718563) (xy 339.888668 -377.699768)
			(xy 339.903047 -377.685381) (xy 339.92184 -377.677597) (xy 339.93201 -377.677172) (xy 340.64829 -377.677172)
			(xy 340.658465 -377.677573) (xy 340.677266 -377.685361) (xy 340.691653 -377.699754) (xy 340.699432 -377.718559)
			(xy 340.699852 -377.728734) (xy 340.699852 -377.886722) (xy 340.700262 -377.895909) (xy 340.706777 -377.913093)
			(xy 340.712552 -377.92025) (xy 340.734314 -377.945923) (xy 340.772264 -378.001506) (xy 340.803299 -378.061227)
			(xy 340.826974 -378.124229) (xy 340.842949 -378.189608) (xy 340.850995 -378.256429) (xy 340.850998 -378.323732)
			(xy 340.850998 -378.323734) (xy 344.129059 -378.323734) (xy 344.129061 -378.256427) (xy 344.137108 -378.189603)
			(xy 344.153083 -378.124219) (xy 344.176759 -378.061213) (xy 344.207795 -378.001489) (xy 344.245747 -377.945902)
			(xy 344.267536 -377.92025) (xy 344.273341 -377.913111) (xy 344.27985 -377.895916) (xy 344.280236 -377.886722)
			(xy 344.280236 -377.728734) (xy 344.280692 -377.718565) (xy 344.288465 -377.699771) (xy 344.302841 -377.685385)
			(xy 344.321629 -377.677599) (xy 344.331798 -377.677172) (xy 345.048078 -377.677172) (xy 345.058252 -377.677583)
			(xy 345.077053 -377.685367) (xy 345.09144 -377.699757) (xy 345.099219 -377.71856) (xy 345.09964 -377.728734)
			(xy 345.09964 -377.886722) (xy 345.100053 -377.895909) (xy 345.106566 -377.913092) (xy 345.11234 -377.92025)
			(xy 345.134103 -377.945923) (xy 345.172054 -378.001506) (xy 345.203089 -378.061226) (xy 345.226764 -378.124228)
			(xy 345.24274 -378.189608) (xy 345.250786 -378.256429) (xy 345.250789 -378.323732) (xy 345.250789 -378.323734)
			(xy 374.929089 -378.323734) (xy 374.929092 -378.256427) (xy 374.937139 -378.189602) (xy 374.953116 -378.124218)
			(xy 374.976793 -378.061212) (xy 375.007831 -378.001488) (xy 375.045786 -377.945902) (xy 375.067576 -377.92025)
			(xy 375.073374 -377.913105) (xy 375.079888 -377.895915) (xy 375.080276 -377.886722) (xy 375.080276 -377.728734)
			(xy 375.080693 -377.71856) (xy 375.088474 -377.699759) (xy 375.102862 -377.685371) (xy 375.121664 -377.677592)
			(xy 375.131838 -377.677172) (xy 375.848118 -377.677172) (xy 375.858295 -377.67755) (xy 375.877097 -377.685347)
			(xy 375.891482 -377.699747) (xy 375.89926 -377.718557) (xy 375.89968 -377.728734) (xy 375.89968 -377.886722)
			(xy 375.900084 -377.89591) (xy 375.906602 -377.913094) (xy 375.91238 -377.92025) (xy 375.934142 -377.945923)
			(xy 375.97209 -378.001507) (xy 376.003123 -378.061228) (xy 376.026797 -378.12423) (xy 376.042771 -378.189609)
			(xy 376.050817 -378.256429) (xy 376.050819 -378.323732) (xy 376.050812 -378.323793) (xy 379.328882 -378.323793)
			(xy 379.328884 -378.256368) (xy 379.336962 -378.189428) (xy 379.352999 -378.123938) (xy 379.376765 -378.06084)
			(xy 379.407917 -378.001043) (xy 379.446007 -377.945408) (xy 379.467872 -377.919742) (xy 379.473684 -377.912608)
			(xy 379.480188 -377.895409) (xy 379.480572 -377.886214) (xy 379.480572 -377.728734) (xy 379.481056 -377.718606)
			(xy 379.488778 -377.699879) (xy 379.503066 -377.685521) (xy 379.521754 -377.677706) (xy 379.53188 -377.677172)
			(xy 380.24816 -377.677172) (xy 380.258308 -377.677654) (xy 380.277054 -377.685431) (xy 380.291378 -377.699809)
			(xy 380.299084 -377.718584) (xy 380.299468 -377.728734) (xy 380.299468 -377.886214) (xy 380.299878 -377.895401)
			(xy 380.306393 -377.912585) (xy 380.312168 -377.919742) (xy 380.334008 -377.945428) (xy 380.372099 -378.001059)
			(xy 380.403253 -378.060852) (xy 380.42702 -378.123946) (xy 380.443058 -378.189433) (xy 380.451137 -378.256369)
			(xy 380.451139 -378.323734) (xy 383.729177 -378.323734) (xy 383.729179 -378.256427) (xy 383.737226 -378.189602)
			(xy 383.753202 -378.124218) (xy 383.776879 -378.061212) (xy 383.807917 -378.001488) (xy 383.84587 -377.945902)
			(xy 383.86766 -377.92025) (xy 383.873468 -377.913113) (xy 383.879974 -377.895916) (xy 383.88036 -377.886722)
			(xy 383.88036 -377.728734) (xy 383.880792 -377.718562) (xy 383.88857 -377.699764) (xy 383.902954 -377.685377)
			(xy 383.92175 -377.677595) (xy 383.931922 -377.677172) (xy 384.648202 -377.677172) (xy 384.658378 -377.677563)
			(xy 384.677179 -377.685355) (xy 384.691565 -377.699751) (xy 384.699344 -377.718558) (xy 384.699764 -377.728734)
			(xy 384.699764 -377.886722) (xy 384.700172 -377.895909) (xy 384.706688 -377.913093) (xy 384.712464 -377.92025)
			(xy 384.734226 -377.945923) (xy 384.772175 -378.001507) (xy 384.803209 -378.061228) (xy 384.826884 -378.124229)
			(xy 384.842858 -378.189609) (xy 384.850904 -378.256429) (xy 384.850907 -378.323732) (xy 384.850907 -378.323734)
			(xy 388.128968 -378.323734) (xy 388.12897 -378.256427) (xy 388.137017 -378.189602) (xy 388.152993 -378.124218)
			(xy 388.176669 -378.061213) (xy 388.207706 -378.001489) (xy 388.245658 -377.945902) (xy 388.267448 -377.92025)
			(xy 388.273254 -377.913112) (xy 388.279762 -377.895916) (xy 388.280148 -377.886722) (xy 388.280148 -377.728734)
			(xy 388.280592 -377.718563) (xy 388.288368 -377.699768) (xy 388.302747 -377.685381) (xy 388.32154 -377.677597)
			(xy 388.33171 -377.677172) (xy 389.04799 -377.677172) (xy 389.058165 -377.677573) (xy 389.076966 -377.685361)
			(xy 389.091353 -377.699754) (xy 389.099132 -377.718559) (xy 389.099552 -377.728734) (xy 389.099552 -377.886722)
			(xy 389.099962 -377.895909) (xy 389.106477 -377.913093) (xy 389.112252 -377.92025) (xy 389.134014 -377.945923)
			(xy 389.171964 -378.001506) (xy 389.202999 -378.061227) (xy 389.226674 -378.124229) (xy 389.242649 -378.189608)
			(xy 389.250695 -378.256429) (xy 389.250698 -378.323732) (xy 389.250698 -378.323734) (xy 418.928998 -378.323734)
			(xy 418.929001 -378.256426) (xy 418.937048 -378.189601) (xy 418.953025 -378.124217) (xy 418.976703 -378.061211)
			(xy 419.007742 -378.001487) (xy 419.045697 -377.945902) (xy 419.067488 -377.92025) (xy 419.073287 -377.913106)
			(xy 419.079801 -377.895915) (xy 419.080188 -377.886722) (xy 419.080188 -377.728734) (xy 419.080593 -377.718558)
			(xy 419.088376 -377.699755) (xy 419.102768 -377.685367) (xy 419.121574 -377.67759) (xy 419.13175 -377.677172)
			(xy 419.84803 -377.677172) (xy 419.858208 -377.67754) (xy 419.87701 -377.685341) (xy 419.891395 -377.699744)
			(xy 419.899173 -377.718556) (xy 419.899592 -377.728734) (xy 419.899592 -377.886722) (xy 419.899993 -377.89591)
			(xy 419.906513 -377.913094) (xy 419.912292 -377.92025) (xy 419.934053 -377.945924) (xy 419.972001 -378.001508)
			(xy 420.003034 -378.061229) (xy 420.026706 -378.12423) (xy 420.04268 -378.189609) (xy 420.050726 -378.256429)
			(xy 420.050728 -378.323732) (xy 420.050721 -378.323793) (xy 423.328791 -378.323793) (xy 423.328793 -378.256368)
			(xy 423.336871 -378.189428) (xy 423.352909 -378.123938) (xy 423.376675 -378.06084) (xy 423.407828 -378.001043)
			(xy 423.445919 -377.945408) (xy 423.467784 -377.919742) (xy 423.473586 -377.9126) (xy 423.480098 -377.895407)
			(xy 423.480484 -377.886214) (xy 423.480484 -377.728734) (xy 423.480956 -377.718604) (xy 423.488681 -377.699875)
			(xy 423.502972 -377.685516) (xy 423.521664 -377.677704) (xy 423.531792 -377.677172) (xy 424.248072 -377.677172)
			(xy 424.258189 -377.677638) (xy 424.276887 -377.685372) (xy 424.291201 -377.699673) (xy 424.298953 -377.718363)
			(xy 424.29938 -377.72848) (xy 424.29938 -377.886214) (xy 424.299788 -377.895401) (xy 424.306303 -377.912585)
			(xy 424.31208 -377.919742) (xy 424.333919 -377.945428) (xy 424.37201 -378.001059) (xy 424.403163 -378.060852)
			(xy 424.426929 -378.123946) (xy 424.442967 -378.189433) (xy 424.451046 -378.256369) (xy 424.451048 -378.323734)
			(xy 427.729086 -378.323734) (xy 427.729089 -378.256427) (xy 427.737136 -378.189602) (xy 427.753113 -378.124218)
			(xy 427.77679 -378.061212) (xy 427.807828 -378.001488) (xy 427.845782 -377.945902) (xy 427.867572 -377.92025)
			(xy 427.873381 -377.913114) (xy 427.879886 -377.895916) (xy 427.880272 -377.886722) (xy 427.880272 -377.728734)
			(xy 427.880693 -377.71856) (xy 427.888473 -377.69976) (xy 427.90286 -377.685373) (xy 427.92166 -377.677593)
			(xy 427.931834 -377.677172) (xy 428.648114 -377.677172) (xy 428.658291 -377.677553) (xy 428.677092 -377.685349)
			(xy 428.691478 -377.699748) (xy 428.699256 -377.718557) (xy 428.699676 -377.728734) (xy 428.699676 -377.886722)
			(xy 428.700081 -377.89591) (xy 428.706599 -377.913094) (xy 428.712376 -377.92025) (xy 428.734137 -377.945924)
			(xy 428.772086 -378.001507) (xy 428.80312 -378.061228) (xy 428.826793 -378.12423) (xy 428.842767 -378.189609)
			(xy 428.850813 -378.256429) (xy 428.850816 -378.323732) (xy 428.850816 -378.323734) (xy 432.128877 -378.323734)
			(xy 432.128879 -378.256427) (xy 432.136926 -378.189602) (xy 432.152902 -378.124218) (xy 432.176579 -378.061212)
			(xy 432.207617 -378.001488) (xy 432.24557 -377.945902) (xy 432.26736 -377.92025) (xy 432.273168 -377.913113)
			(xy 432.279674 -377.895916) (xy 432.28006 -377.886722) (xy 432.28006 -377.728734) (xy 432.280492 -377.718562)
			(xy 432.28827 -377.699764) (xy 432.302654 -377.685377) (xy 432.32145 -377.677595) (xy 432.331622 -377.677172)
			(xy 433.047902 -377.677172) (xy 433.058078 -377.677563) (xy 433.076879 -377.685355) (xy 433.091265 -377.699751)
			(xy 433.099044 -377.718558) (xy 433.099464 -377.728734) (xy 433.099464 -377.886722) (xy 433.099872 -377.895909)
			(xy 433.106388 -377.913093) (xy 433.112164 -377.92025) (xy 433.133926 -377.945923) (xy 433.171875 -378.001507)
			(xy 433.202909 -378.061228) (xy 433.226584 -378.124229) (xy 433.242558 -378.189609) (xy 433.250604 -378.256429)
			(xy 433.250607 -378.323732) (xy 433.242565 -378.390553) (xy 433.226595 -378.455933) (xy 433.202925 -378.518937)
			(xy 433.171895 -378.57866) (xy 433.13395 -378.634246) (xy 433.112164 -378.659898) (xy 433.106381 -378.667053)
			(xy 433.099859 -378.684236) (xy 433.099464 -378.693426) (xy 433.099464 -379.186694) (xy 433.099885 -379.19588)
			(xy 433.106392 -379.213064) (xy 433.112164 -379.220222) (xy 433.133997 -379.245837) (xy 433.171944 -379.301429)
			(xy 433.202975 -379.361158) (xy 433.226645 -379.424167) (xy 433.242615 -379.489554) (xy 433.250655 -379.55638)
			(xy 433.250651 -379.623689) (xy 433.242603 -379.690515) (xy 433.226625 -379.755899) (xy 433.202947 -379.818906)
			(xy 433.171909 -379.878631) (xy 433.133955 -379.934218) (xy 433.112164 -379.95987) (xy 433.106351 -379.967003)
			(xy 433.099847 -379.984203) (xy 433.099464 -379.993398) (xy 433.099464 -380.151386) (xy 433.099025 -380.161556)
			(xy 433.091245 -380.180351) (xy 433.076864 -380.194736) (xy 433.058072 -380.202522) (xy 433.047902 -380.202948)
			(xy 432.331622 -380.202948) (xy 432.32145 -380.202518) (xy 432.302653 -380.194737) (xy 432.288267 -380.180353)
			(xy 432.280484 -380.161558) (xy 432.28006 -380.151386) (xy 432.28006 -379.993398) (xy 432.279637 -379.984212)
			(xy 432.273131 -379.967029) (xy 432.26736 -379.95987) (xy 432.245617 -379.934181) (xy 432.207665 -379.8786)
			(xy 432.176629 -379.818882) (xy 432.152953 -379.755882) (xy 432.136976 -379.690504) (xy 432.128928 -379.623685)
			(xy 432.128924 -379.556384) (xy 432.136964 -379.489564) (xy 432.152932 -379.424184) (xy 432.176601 -379.361181)
			(xy 432.20763 -379.301459) (xy 432.245575 -379.245874) (xy 432.26736 -379.220222) (xy 432.27318 -379.213093)
			(xy 432.279679 -379.19589) (xy 432.28006 -379.186694) (xy 432.28006 -378.693426) (xy 432.279624 -378.684242)
			(xy 432.273127 -378.667058) (xy 432.26736 -378.659898) (xy 432.245546 -378.634267) (xy 432.207596 -378.578678)
			(xy 432.176563 -378.518952) (xy 432.152891 -378.455945) (xy 432.136919 -378.39056) (xy 432.128877 -378.323734)
			(xy 428.850816 -378.323734) (xy 428.842774 -378.390552) (xy 428.826805 -378.455933) (xy 428.803136 -378.518936)
			(xy 428.772106 -378.578659) (xy 428.734161 -378.634245) (xy 428.712376 -378.659898) (xy 428.706595 -378.667054)
			(xy 428.700072 -378.684236) (xy 428.699676 -378.693426) (xy 428.699676 -379.186694) (xy 428.700094 -379.19588)
			(xy 428.706603 -379.213064) (xy 428.712376 -379.220222) (xy 428.734209 -379.245837) (xy 428.772155 -379.301429)
			(xy 428.803185 -379.361158) (xy 428.826855 -379.424167) (xy 428.842824 -379.489554) (xy 428.850865 -379.55638)
			(xy 428.85086 -379.623689) (xy 428.842812 -379.690514) (xy 428.826835 -379.755899) (xy 428.803157 -379.818905)
			(xy 428.772119 -379.87863) (xy 428.734166 -379.934218) (xy 428.712376 -379.95987) (xy 428.706564 -379.967004)
			(xy 428.70006 -379.984203) (xy 428.699676 -379.993398) (xy 428.699676 -380.151386) (xy 428.699156 -380.161541)
			(xy 428.691388 -380.180307) (xy 428.677031 -380.194673) (xy 428.658269 -380.20245) (xy 428.648114 -380.202948)
			(xy 427.931834 -380.202948) (xy 427.921663 -380.202508) (xy 427.902866 -380.194731) (xy 427.88848 -380.180351)
			(xy 427.880696 -380.161557) (xy 427.880272 -380.151386) (xy 427.880272 -379.993398) (xy 427.879869 -379.98421)
			(xy 427.873351 -379.967025) (xy 427.867572 -379.95987) (xy 427.845829 -379.934181) (xy 427.807876 -379.878601)
			(xy 427.776839 -379.818882) (xy 427.753162 -379.755883) (xy 427.737185 -379.690505) (xy 427.729137 -379.623686)
			(xy 427.729133 -379.556384) (xy 427.737173 -379.489564) (xy 427.753142 -379.424183) (xy 427.776811 -379.361181)
			(xy 427.807841 -379.301459) (xy 427.845786 -379.245874) (xy 427.867572 -379.220222) (xy 427.873393 -379.213094)
			(xy 427.879891 -379.19589) (xy 427.880272 -379.186694) (xy 427.880272 -378.693426) (xy 427.879856 -378.684239)
			(xy 427.873347 -378.667055) (xy 427.867572 -378.659898) (xy 427.845758 -378.634267) (xy 427.807808 -378.578678)
			(xy 427.776774 -378.518952) (xy 427.753101 -378.455945) (xy 427.737129 -378.39056) (xy 427.729086 -378.323734)
			(xy 424.451048 -378.323734) (xy 424.451048 -378.323791) (xy 424.442974 -378.390728) (xy 424.426941 -378.456216)
			(xy 424.403179 -378.519312) (xy 424.37203 -378.579107) (xy 424.333943 -378.634741) (xy 424.31208 -378.660406)
			(xy 424.306296 -378.66756) (xy 424.299775 -378.684744) (xy 424.29938 -378.693934) (xy 424.29938 -379.186186)
			(xy 424.299802 -379.195372) (xy 424.306308 -379.212556) (xy 424.31208 -379.219714) (xy 424.33399 -379.245342)
			(xy 424.372079 -379.300981) (xy 424.403228 -379.360782) (xy 424.426991 -379.423884) (xy 424.443024 -379.489378)
			(xy 424.451096 -379.556321) (xy 424.451092 -379.623748) (xy 424.443011 -379.69069) (xy 424.42697 -379.756182)
			(xy 424.4032 -379.819281) (xy 424.372043 -379.879078) (xy 424.333947 -379.934713) (xy 424.31208 -379.960378)
			(xy 424.306266 -379.96751) (xy 424.299762 -379.984711) (xy 424.29938 -379.993906) (xy 424.29938 -380.151386)
			(xy 424.298863 -380.161509) (xy 424.291143 -380.180226) (xy 424.276866 -380.194583) (xy 424.258193 -380.202406)
			(xy 424.248072 -380.202948) (xy 423.531792 -380.202948) (xy 423.521689 -380.202422) (xy 423.50302 -380.194691)
			(xy 423.488727 -380.180407) (xy 423.480984 -380.161743) (xy 423.480484 -380.15164) (xy 423.480484 -379.993906)
			(xy 423.480075 -379.984719) (xy 423.473561 -379.967534) (xy 423.467784 -379.960378) (xy 423.445966 -379.934675)
			(xy 423.407877 -379.879046) (xy 423.376725 -379.819255) (xy 423.352959 -379.756163) (xy 423.336921 -379.690678)
			(xy 423.328841 -379.623744) (xy 423.328837 -379.556325) (xy 423.336908 -379.48939) (xy 423.352938 -379.423904)
			(xy 423.376697 -379.360809) (xy 423.407841 -379.301014) (xy 423.445923 -379.245379) (xy 423.467784 -379.219714)
			(xy 423.473598 -379.212581) (xy 423.480103 -379.195381) (xy 423.480484 -379.186186) (xy 423.480484 -378.693934)
			(xy 423.480061 -378.684748) (xy 423.473557 -378.667563) (xy 423.467784 -378.660406) (xy 423.445895 -378.634762)
			(xy 423.407808 -378.579124) (xy 423.376659 -378.519324) (xy 423.352897 -378.456225) (xy 423.336864 -378.390733)
			(xy 423.328791 -378.323793) (xy 420.050721 -378.323793) (xy 420.042687 -378.390552) (xy 420.026718 -378.455932)
			(xy 420.003049 -378.518936) (xy 419.972021 -378.578659) (xy 419.934077 -378.634245) (xy 419.912292 -378.659898)
			(xy 419.906513 -378.667056) (xy 419.899988 -378.684237) (xy 419.899592 -378.693426) (xy 419.899592 -379.186694)
			(xy 419.900007 -379.195881) (xy 419.906518 -379.213065) (xy 419.912292 -379.220222) (xy 419.934124 -379.245837)
			(xy 419.972069 -379.30143) (xy 420.003099 -379.361159) (xy 420.026768 -379.424168) (xy 420.042737 -379.489554)
			(xy 420.050777 -379.556381) (xy 420.050772 -379.623689) (xy 420.042724 -379.690514) (xy 420.026747 -379.755898)
			(xy 420.003071 -379.818905) (xy 419.972034 -379.87863) (xy 419.934082 -379.934217) (xy 419.912292 -379.95987)
			(xy 419.906482 -379.967006) (xy 419.899976 -379.984204) (xy 419.899592 -379.993398) (xy 419.899592 -380.151386)
			(xy 419.899056 -380.161539) (xy 419.891292 -380.180302) (xy 419.876939 -380.194667) (xy 419.858183 -380.202447)
			(xy 419.84803 -380.202948) (xy 419.13175 -380.202948) (xy 419.12158 -380.202495) (xy 419.102784 -380.194724)
			(xy 419.088396 -380.180347) (xy 419.080612 -380.161556) (xy 419.080188 -380.151386) (xy 419.080188 -379.993398)
			(xy 419.079781 -379.98421) (xy 419.073266 -379.967026) (xy 419.067488 -379.95987) (xy 419.045744 -379.934181)
			(xy 419.007791 -379.878601) (xy 418.976753 -379.818883) (xy 418.953075 -379.755883) (xy 418.937097 -379.690505)
			(xy 418.929049 -379.623686) (xy 418.929045 -379.556383) (xy 418.937085 -379.489563) (xy 418.953055 -379.424183)
			(xy 418.976724 -379.36118) (xy 419.007755 -379.301458) (xy 419.045702 -379.245873) (xy 419.067488 -379.220222)
			(xy 419.073299 -379.213087) (xy 419.079805 -379.195889) (xy 419.080188 -379.186694) (xy 419.080188 -378.693426)
			(xy 419.079768 -378.68424) (xy 419.073262 -378.667055) (xy 419.067488 -378.659898) (xy 419.045673 -378.634268)
			(xy 419.007722 -378.578679) (xy 418.976687 -378.518953) (xy 418.953014 -378.455946) (xy 418.937041 -378.39056)
			(xy 418.928998 -378.323734) (xy 389.250698 -378.323734) (xy 389.242656 -378.390553) (xy 389.226686 -378.455934)
			(xy 389.203015 -378.518937) (xy 389.171985 -378.57866) (xy 389.134038 -378.634246) (xy 389.112252 -378.659898)
			(xy 389.106468 -378.667052) (xy 389.099947 -378.684236) (xy 389.099552 -378.693426) (xy 389.099552 -379.186694)
			(xy 389.099976 -379.19588) (xy 389.106481 -379.213063) (xy 389.112252 -379.220222) (xy 389.134085 -379.245837)
			(xy 389.172033 -379.301428) (xy 389.203065 -379.361157) (xy 389.226736 -379.424166) (xy 389.242706 -379.489553)
			(xy 389.250746 -379.55638) (xy 389.250742 -379.623689) (xy 389.242693 -379.690515) (xy 389.226715 -379.7559)
			(xy 389.203037 -379.818906) (xy 389.171998 -379.878631) (xy 389.134043 -379.934218) (xy 389.112252 -379.95987)
			(xy 389.106437 -379.967002) (xy 389.099935 -379.984203) (xy 389.099552 -379.993398) (xy 389.099552 -380.151386)
			(xy 389.099125 -380.161558) (xy 389.091342 -380.180354) (xy 389.076958 -380.19474) (xy 389.058162 -380.202524)
			(xy 389.04799 -380.202948) (xy 388.33171 -380.202948) (xy 388.321537 -380.202528) (xy 388.30274 -380.194743)
			(xy 388.288354 -380.180357) (xy 388.280571 -380.161559) (xy 388.280148 -380.151386) (xy 388.280148 -379.993398)
			(xy 388.279728 -379.984212) (xy 388.27322 -379.967028) (xy 388.267448 -379.95987) (xy 388.245705 -379.934181)
			(xy 388.207755 -379.8786) (xy 388.176719 -379.818881) (xy 388.153043 -379.755882) (xy 388.137067 -379.690504)
			(xy 388.129019 -379.623685) (xy 388.129015 -379.556384) (xy 388.137054 -379.489564) (xy 388.153023 -379.424184)
			(xy 388.176691 -379.361182) (xy 388.207719 -379.30146) (xy 388.245663 -379.245874) (xy 388.267448 -379.220222)
			(xy 388.273266 -379.213092) (xy 388.279767 -379.19589) (xy 388.280148 -379.186694) (xy 388.280148 -378.693426)
			(xy 388.279715 -378.684241) (xy 388.273216 -378.667057) (xy 388.267448 -378.659898) (xy 388.245634 -378.634267)
			(xy 388.207686 -378.578678) (xy 388.176653 -378.518951) (xy 388.152981 -378.455944) (xy 388.13701 -378.390559)
			(xy 388.128968 -378.323734) (xy 384.850907 -378.323734) (xy 384.842865 -378.390553) (xy 384.826895 -378.455933)
			(xy 384.803225 -378.518937) (xy 384.772195 -378.57866) (xy 384.73425 -378.634246) (xy 384.712464 -378.659898)
			(xy 384.706681 -378.667053) (xy 384.700159 -378.684236) (xy 384.699764 -378.693426) (xy 384.699764 -379.186694)
			(xy 384.700185 -379.19588) (xy 384.706692 -379.213064) (xy 384.712464 -379.220222) (xy 384.734297 -379.245837)
			(xy 384.772244 -379.301429) (xy 384.803275 -379.361158) (xy 384.826945 -379.424167) (xy 384.842915 -379.489554)
			(xy 384.850955 -379.55638) (xy 384.850951 -379.623689) (xy 384.842903 -379.690515) (xy 384.826925 -379.755899)
			(xy 384.803247 -379.818906) (xy 384.772209 -379.878631) (xy 384.734255 -379.934218) (xy 384.712464 -379.95987)
			(xy 384.706651 -379.967003) (xy 384.700147 -379.984203) (xy 384.699764 -379.993398) (xy 384.699764 -380.151386)
			(xy 384.699325 -380.161556) (xy 384.691545 -380.180351) (xy 384.677164 -380.194736) (xy 384.658372 -380.202522)
			(xy 384.648202 -380.202948) (xy 383.931922 -380.202948) (xy 383.92175 -380.202518) (xy 383.902953 -380.194737)
			(xy 383.888567 -380.180353) (xy 383.880784 -380.161558) (xy 383.88036 -380.151386) (xy 383.88036 -379.993398)
			(xy 383.879937 -379.984212) (xy 383.873431 -379.967029) (xy 383.86766 -379.95987) (xy 383.845917 -379.934181)
			(xy 383.807965 -379.8786) (xy 383.776929 -379.818882) (xy 383.753253 -379.755882) (xy 383.737276 -379.690504)
			(xy 383.729228 -379.623685) (xy 383.729224 -379.556384) (xy 383.737264 -379.489564) (xy 383.753232 -379.424184)
			(xy 383.776901 -379.361181) (xy 383.80793 -379.301459) (xy 383.845875 -379.245874) (xy 383.86766 -379.220222)
			(xy 383.87348 -379.213093) (xy 383.879979 -379.19589) (xy 383.88036 -379.186694) (xy 383.88036 -378.693426)
			(xy 383.879924 -378.684242) (xy 383.873427 -378.667058) (xy 383.86766 -378.659898) (xy 383.845846 -378.634267)
			(xy 383.807896 -378.578678) (xy 383.776863 -378.518952) (xy 383.753191 -378.455945) (xy 383.737219 -378.39056)
			(xy 383.729177 -378.323734) (xy 380.451139 -378.323734) (xy 380.451139 -378.323792) (xy 380.443065 -378.390729)
			(xy 380.427031 -378.456217) (xy 380.403269 -378.519313) (xy 380.372119 -378.579108) (xy 380.334032 -378.634741)
			(xy 380.312168 -378.660406) (xy 380.306382 -378.667559) (xy 380.299862 -378.684744) (xy 380.299468 -378.693934)
			(xy 380.299468 -379.186186) (xy 380.299892 -379.195372) (xy 380.306397 -379.212556) (xy 380.312168 -379.219714)
			(xy 380.334078 -379.245341) (xy 380.372168 -379.300981) (xy 380.403318 -379.360782) (xy 380.427081 -379.423884)
			(xy 380.443114 -379.489378) (xy 380.451187 -379.556321) (xy 380.451183 -379.623749) (xy 380.443102 -379.69069)
			(xy 380.427061 -379.756182) (xy 380.40329 -379.819281) (xy 380.372132 -379.879079) (xy 380.334036 -379.934713)
			(xy 380.312168 -379.960378) (xy 380.306352 -379.967509) (xy 380.29985 -379.984711) (xy 380.299468 -379.993906)
			(xy 380.299468 -380.151386) (xy 380.298962 -380.161511) (xy 380.291241 -380.18023) (xy 380.27696 -380.194587)
			(xy 380.258282 -380.202408) (xy 380.24816 -380.202948) (xy 379.53188 -380.202948) (xy 379.521731 -380.202496)
			(xy 379.502987 -380.194703) (xy 379.488666 -380.180316) (xy 379.480958 -380.161537) (xy 379.480572 -380.151386)
			(xy 379.480572 -379.993906) (xy 379.480165 -379.984718) (xy 379.47365 -379.967534) (xy 379.467872 -379.960378)
			(xy 379.446054 -379.934675) (xy 379.407966 -379.879045) (xy 379.376815 -379.819254) (xy 379.353049 -379.756162)
			(xy 379.337011 -379.690678) (xy 379.328932 -379.623744) (xy 379.328928 -379.556325) (xy 379.336999 -379.48939)
			(xy 379.353029 -379.423904) (xy 379.376787 -379.360809) (xy 379.40793 -379.301014) (xy 379.446012 -379.24538)
			(xy 379.467872 -379.219714) (xy 379.473696 -379.212589) (xy 379.480192 -379.195383) (xy 379.480572 -379.186186)
			(xy 379.480572 -378.693934) (xy 379.480152 -378.684748) (xy 379.473646 -378.667563) (xy 379.467872 -378.660406)
			(xy 379.445983 -378.634761) (xy 379.407897 -378.579123) (xy 379.376749 -378.519324) (xy 379.352988 -378.456224)
			(xy 379.336955 -378.390733) (xy 379.328882 -378.323793) (xy 376.050812 -378.323793) (xy 376.042778 -378.390552)
			(xy 376.026808 -378.455933) (xy 376.003139 -378.518936) (xy 375.97211 -378.578659) (xy 375.934166 -378.634246)
			(xy 375.91238 -378.659898) (xy 375.906599 -378.667054) (xy 375.900076 -378.684236) (xy 375.89968 -378.693426)
			(xy 375.89968 -379.186694) (xy 375.900098 -379.19588) (xy 375.906607 -379.213064) (xy 375.91238 -379.220222)
			(xy 375.934212 -379.245837) (xy 375.972159 -379.301429) (xy 376.003189 -379.361158) (xy 376.026858 -379.424168)
			(xy 376.042827 -379.489554) (xy 376.050868 -379.55638) (xy 376.050863 -379.623689) (xy 376.042815 -379.690514)
			(xy 376.026838 -379.755899) (xy 376.003161 -379.818905) (xy 375.972123 -379.87863) (xy 375.93417 -379.934218)
			(xy 375.91238 -379.95987) (xy 375.906569 -379.967005) (xy 375.900064 -379.984203) (xy 375.89968 -379.993398)
			(xy 375.89968 -380.151386) (xy 375.899156 -380.161541) (xy 375.891389 -380.180306) (xy 375.877033 -380.194671)
			(xy 375.858272 -380.202449) (xy 375.848118 -380.202948) (xy 375.131838 -380.202948) (xy 375.121667 -380.202505)
			(xy 375.102871 -380.19473) (xy 375.088484 -380.18035) (xy 375.0807 -380.161557) (xy 375.080276 -380.151386)
			(xy 375.080276 -379.993398) (xy 375.079872 -379.98421) (xy 375.073355 -379.967025) (xy 375.067576 -379.95987)
			(xy 375.045832 -379.934181) (xy 375.00788 -379.878601) (xy 374.976842 -379.818883) (xy 374.953165 -379.755883)
			(xy 374.937188 -379.690505) (xy 374.92914 -379.623686) (xy 374.929136 -379.556384) (xy 374.937176 -379.489563)
			(xy 374.953145 -379.424183) (xy 374.976814 -379.361181) (xy 375.007844 -379.301459) (xy 375.04579 -379.245874)
			(xy 375.067576 -379.220222) (xy 375.073385 -379.213086) (xy 375.079893 -379.195889) (xy 375.080276 -379.186694)
			(xy 375.080276 -378.693426) (xy 375.079859 -378.684239) (xy 375.073351 -378.667055) (xy 375.067576 -378.659898)
			(xy 375.045762 -378.634267) (xy 375.007811 -378.578679) (xy 374.976777 -378.518952) (xy 374.953104 -378.455945)
			(xy 374.937132 -378.39056) (xy 374.929089 -378.323734) (xy 345.250789 -378.323734) (xy 345.242747 -378.390553)
			(xy 345.226776 -378.455934) (xy 345.203105 -378.518938) (xy 345.172074 -378.57866) (xy 345.134127 -378.634246)
			(xy 345.11234 -378.659898) (xy 345.106554 -378.667051) (xy 345.100035 -378.684236) (xy 345.09964 -378.693426)
			(xy 345.09964 -379.186694) (xy 345.100066 -379.195879) (xy 345.10657 -379.213063) (xy 345.11234 -379.220222)
			(xy 345.134174 -379.245837) (xy 345.172123 -379.301428) (xy 345.203155 -379.361156) (xy 345.226826 -379.424166)
			(xy 345.242797 -379.489553) (xy 345.250837 -379.55638) (xy 345.250833 -379.623689) (xy 345.242784 -379.690515)
			(xy 345.226806 -379.7559) (xy 345.203127 -379.818907) (xy 345.172087 -379.878632) (xy 345.134131 -379.934218)
			(xy 345.11234 -379.95987) (xy 345.106524 -379.967001) (xy 345.100023 -379.984203) (xy 345.09964 -379.993398)
			(xy 345.09964 -380.151386) (xy 345.099224 -380.161559) (xy 345.09144 -380.180358) (xy 345.077051 -380.194744)
			(xy 345.058252 -380.202526) (xy 345.048078 -380.202948) (xy 344.331798 -380.202948) (xy 344.321625 -380.202537)
			(xy 344.302827 -380.194749) (xy 344.288442 -380.180359) (xy 344.280659 -380.16156) (xy 344.280236 -380.151386)
			(xy 344.280236 -379.993398) (xy 344.279819 -379.984212) (xy 344.273309 -379.967028) (xy 344.267536 -379.95987)
			(xy 344.245794 -379.93418) (xy 344.207844 -379.878599) (xy 344.176809 -379.818881) (xy 344.153133 -379.755881)
			(xy 344.137157 -379.690504) (xy 344.12911 -379.623685) (xy 344.129106 -379.556384) (xy 344.137145 -379.489565)
			(xy 344.153113 -379.424185) (xy 344.17678 -379.361182) (xy 344.207808 -379.30146) (xy 344.245751 -379.245874)
			(xy 344.267536 -379.220222) (xy 344.273353 -379.213091) (xy 344.279855 -379.19589) (xy 344.280236 -379.186694)
			(xy 344.280236 -378.693426) (xy 344.279805 -378.684241) (xy 344.273305 -378.667057) (xy 344.267536 -378.659898)
			(xy 344.245723 -378.634267) (xy 344.207775 -378.578677) (xy 344.176743 -378.518951) (xy 344.153072 -378.455944)
			(xy 344.137101 -378.390559) (xy 344.129059 -378.323734) (xy 340.850998 -378.323734) (xy 340.842956 -378.390553)
			(xy 340.826986 -378.455934) (xy 340.803315 -378.518937) (xy 340.772285 -378.57866) (xy 340.734338 -378.634246)
			(xy 340.712552 -378.659898) (xy 340.706768 -378.667052) (xy 340.700247 -378.684236) (xy 340.699852 -378.693426)
			(xy 340.699852 -379.186694) (xy 340.700276 -379.19588) (xy 340.706781 -379.213063) (xy 340.712552 -379.220222)
			(xy 340.734385 -379.245837) (xy 340.772333 -379.301428) (xy 340.803365 -379.361157) (xy 340.827036 -379.424166)
			(xy 340.843006 -379.489553) (xy 340.851046 -379.55638) (xy 340.851042 -379.623689) (xy 340.842993 -379.690515)
			(xy 340.827015 -379.7559) (xy 340.803337 -379.818906) (xy 340.772298 -379.878631) (xy 340.734343 -379.934218)
			(xy 340.712552 -379.95987) (xy 340.706737 -379.967002) (xy 340.700235 -379.984203) (xy 340.699852 -379.993398)
			(xy 340.699852 -380.151386) (xy 340.699425 -380.161558) (xy 340.691642 -380.180354) (xy 340.677258 -380.19474)
			(xy 340.658462 -380.202524) (xy 340.64829 -380.202948) (xy 339.93201 -380.202948) (xy 339.921837 -380.202528)
			(xy 339.90304 -380.194743) (xy 339.888654 -380.180357) (xy 339.880871 -380.161559) (xy 339.880448 -380.151386)
			(xy 339.880448 -379.993398) (xy 339.880028 -379.984212) (xy 339.87352 -379.967028) (xy 339.867748 -379.95987)
			(xy 339.846005 -379.934181) (xy 339.808055 -379.8786) (xy 339.777019 -379.818881) (xy 339.753343 -379.755882)
			(xy 339.737367 -379.690504) (xy 339.729319 -379.623685) (xy 339.729315 -379.556384) (xy 339.737354 -379.489564)
			(xy 339.753323 -379.424184) (xy 339.776991 -379.361182) (xy 339.808019 -379.30146) (xy 339.845963 -379.245874)
			(xy 339.867748 -379.220222) (xy 339.873566 -379.213092) (xy 339.880067 -379.19589) (xy 339.880448 -379.186694)
			(xy 339.880448 -378.693426) (xy 339.880015 -378.684241) (xy 339.873516 -378.667057) (xy 339.867748 -378.659898)
			(xy 339.845934 -378.634267) (xy 339.807986 -378.578678) (xy 339.776953 -378.518951) (xy 339.753281 -378.455944)
			(xy 339.73731 -378.390559) (xy 339.729268 -378.323734) (xy 336.45123 -378.323734) (xy 336.45123 -378.323792)
			(xy 336.443156 -378.390729) (xy 336.427122 -378.456217) (xy 336.403359 -378.519313) (xy 336.372208 -378.579108)
			(xy 336.33412 -378.634742) (xy 336.312256 -378.660406) (xy 336.306469 -378.667558) (xy 336.29995 -378.684743)
			(xy 336.299556 -378.693934) (xy 336.299556 -379.186186) (xy 336.299983 -379.195371) (xy 336.306486 -379.212555)
			(xy 336.312256 -379.219714) (xy 336.334167 -379.245341) (xy 336.372257 -379.30098) (xy 336.403408 -379.360781)
			(xy 336.427172 -379.423883) (xy 336.443205 -379.489377) (xy 336.451278 -379.55632) (xy 336.451274 -379.623749)
			(xy 336.443193 -379.690691) (xy 336.427151 -379.756183) (xy 336.40338 -379.819282) (xy 336.372221 -379.879079)
			(xy 336.334124 -379.934713) (xy 336.312256 -379.960378) (xy 336.306438 -379.967508) (xy 336.299937 -379.98471)
			(xy 336.299556 -379.993906) (xy 336.299556 -380.151386) (xy 336.299062 -380.161512) (xy 336.291338 -380.180234)
			(xy 336.277054 -380.194591) (xy 336.258372 -380.20241) (xy 336.248248 -380.202948) (xy 335.531968 -380.202948)
			(xy 335.521818 -380.202506) (xy 335.503074 -380.194708) (xy 335.488753 -380.180319) (xy 335.481046 -380.161538)
			(xy 335.48066 -380.151386) (xy 335.48066 -379.993906) (xy 335.480234 -379.984721) (xy 335.47373 -379.967537)
			(xy 335.46796 -379.960378) (xy 335.446143 -379.934675) (xy 335.408055 -379.879045) (xy 335.376905 -379.819253)
			(xy 335.35314 -379.756162) (xy 335.337102 -379.690678) (xy 335.329023 -379.623744) (xy 335.329019 -379.556325)
			(xy 335.33709 -379.48939) (xy 335.353119 -379.423904) (xy 335.376876 -379.36081) (xy 335.40802 -379.301015)
			(xy 335.4461 -379.24538) (xy 335.46796 -379.219714) (xy 335.473783 -379.212588) (xy 335.48028 -379.195382)
			(xy 335.48066 -379.186186) (xy 335.48066 -378.693934) (xy 335.48022 -378.68475) (xy 335.473726 -378.667566)
			(xy 335.46796 -378.660406) (xy 335.446072 -378.634761) (xy 335.407987 -378.579123) (xy 335.376839 -378.519323)
			(xy 335.353078 -378.456224) (xy 335.337046 -378.390733) (xy 335.328973 -378.323793) (xy 332.050903 -378.323793)
			(xy 332.042868 -378.390553) (xy 332.026898 -378.455933) (xy 332.003229 -378.518937) (xy 331.972199 -378.578659)
			(xy 331.934254 -378.634246) (xy 331.912468 -378.659898) (xy 331.906686 -378.667053) (xy 331.900163 -378.684236)
			(xy 331.899768 -378.693426) (xy 331.899768 -379.186694) (xy 331.900188 -379.19588) (xy 331.906696 -379.213064)
			(xy 331.912468 -379.220222) (xy 331.934301 -379.245837) (xy 331.972248 -379.301429) (xy 332.003279 -379.361158)
			(xy 332.026949 -379.424167) (xy 332.042918 -379.489554) (xy 332.050958 -379.55638) (xy 332.050954 -379.623689)
			(xy 332.042906 -379.690514) (xy 332.026928 -379.755899) (xy 332.00325 -379.818906) (xy 331.972212 -379.878631)
			(xy 331.934258 -379.934218) (xy 331.912468 -379.95987) (xy 331.906655 -379.967003) (xy 331.900151 -379.984203)
			(xy 331.899768 -379.993398) (xy 331.899768 -380.151386) (xy 331.899325 -380.161556) (xy 331.891546 -380.180349)
			(xy 331.877166 -380.194734) (xy 331.858376 -380.202521) (xy 331.848206 -380.202948) (xy 331.131926 -380.202948)
			(xy 331.121754 -380.202514) (xy 331.102958 -380.194735) (xy 331.088571 -380.180352) (xy 331.080788 -380.161558)
			(xy 331.080364 -380.151386) (xy 331.080364 -379.993398) (xy 331.07994 -379.984213) (xy 331.073434 -379.967029)
			(xy 331.067664 -379.95987) (xy 331.045921 -379.934181) (xy 331.007969 -379.8786) (xy 330.976932 -379.818882)
			(xy 330.953256 -379.755882) (xy 330.937279 -379.690504) (xy 330.929231 -379.623686) (xy 330.929227 -379.556384)
			(xy 330.937267 -379.489564) (xy 330.953235 -379.424184) (xy 330.976904 -379.361181) (xy 331.007933 -379.301459)
			(xy 331.045878 -379.245874) (xy 331.067664 -379.220222) (xy 331.073484 -379.213094) (xy 331.079983 -379.19589)
			(xy 331.080364 -379.186694) (xy 331.080364 -378.693426) (xy 331.079927 -378.684242) (xy 331.07343 -378.667058)
			(xy 331.067664 -378.659898) (xy 331.04585 -378.634267) (xy 331.0079 -378.578678) (xy 330.976866 -378.518952)
			(xy 330.953194 -378.455945) (xy 330.937222 -378.39056) (xy 330.92918 -378.323734) (xy 301.250878 -378.323734)
			(xy 301.250878 -378.323791) (xy 301.242805 -378.390727) (xy 301.226773 -378.456215) (xy 301.203013 -378.51931)
			(xy 301.171866 -378.579106) (xy 301.133782 -378.63474) (xy 301.11192 -378.660406) (xy 301.106141 -378.667564)
			(xy 301.099615 -378.684745) (xy 301.09922 -378.693934) (xy 301.09922 -379.186186) (xy 301.099632 -379.195373)
			(xy 301.106144 -379.212558) (xy 301.11192 -379.219714) (xy 301.133828 -379.245342) (xy 301.171914 -379.300983)
			(xy 301.203062 -379.360784) (xy 301.226823 -379.423886) (xy 301.242854 -379.489379) (xy 301.250926 -379.556321)
			(xy 301.250922 -379.623748) (xy 301.242842 -379.690689) (xy 301.226802 -379.75618) (xy 301.203034 -379.819279)
			(xy 301.171879 -379.879077) (xy 301.133786 -379.934712) (xy 301.11192 -379.960378) (xy 301.10611 -379.967514)
			(xy 301.099603 -379.984711) (xy 301.09922 -379.993906) (xy 301.09922 -380.151386) (xy 301.098761 -380.161517)
			(xy 301.09103 -380.180245) (xy 301.076735 -380.194603) (xy 301.058041 -380.202416) (xy 301.047912 -380.202948)
			(xy 300.331632 -380.202948) (xy 300.321486 -380.202453) (xy 300.302743 -380.194677) (xy 300.28842 -380.180304)
			(xy 300.280711 -380.161534) (xy 300.280324 -380.151386) (xy 300.280324 -379.993906) (xy 300.279906 -379.98472)
			(xy 300.273397 -379.967536) (xy 300.267624 -379.960378) (xy 300.245804 -379.934676) (xy 300.207713 -379.879047)
			(xy 300.176559 -379.819256) (xy 300.152791 -379.756164) (xy 300.136751 -379.690679) (xy 300.128672 -379.623745)
			(xy 300.128667 -379.556324) (xy 300.136739 -379.489389) (xy 300.15277 -379.423902) (xy 300.17653 -379.360807)
			(xy 300.207677 -379.301012) (xy 300.245762 -379.245379) (xy 300.267624 -379.219714) (xy 300.273442 -379.212584)
			(xy 300.279943 -379.195382) (xy 300.280324 -379.186186) (xy 300.280324 -378.693934) (xy 300.279892 -378.684749)
			(xy 300.273393 -378.667565) (xy 300.267624 -378.660406) (xy 300.245734 -378.634762) (xy 300.207644 -378.579125)
			(xy 300.176493 -378.519326) (xy 300.152729 -378.456227) (xy 300.136695 -378.390735) (xy 300.128621 -378.323794)
			(xy 296.851087 -378.323794) (xy 296.843014 -378.390727) (xy 296.826983 -378.456214) (xy 296.803223 -378.51931)
			(xy 296.772077 -378.579105) (xy 296.733993 -378.63474) (xy 296.712132 -378.660406) (xy 296.706342 -378.667556)
			(xy 296.699825 -378.684743) (xy 296.699432 -378.693934) (xy 296.699432 -379.186186) (xy 296.699864 -379.195371)
			(xy 296.706364 -379.212554) (xy 296.712132 -379.219714) (xy 296.73404 -379.245342) (xy 296.772125 -379.300983)
			(xy 296.803272 -379.360785) (xy 296.827032 -379.423886) (xy 296.843064 -379.489379) (xy 296.851135 -379.556321)
			(xy 296.851131 -379.623748) (xy 296.843051 -379.690689) (xy 296.827012 -379.75618) (xy 296.803244 -379.819279)
			(xy 296.77209 -379.879076) (xy 296.733998 -379.934712) (xy 296.712132 -379.960378) (xy 296.706312 -379.967506)
			(xy 296.699813 -379.98471) (xy 296.699432 -379.993906) (xy 296.699432 -380.151386) (xy 296.698961 -380.161515)
			(xy 296.691233 -380.180241) (xy 296.676941 -380.194599) (xy 296.658251 -380.202414) (xy 296.648124 -380.202948)
			(xy 295.931844 -380.202948) (xy 295.921699 -380.202443) (xy 295.902957 -380.194671) (xy 295.888633 -380.1803)
			(xy 295.880924 -380.161533) (xy 295.880536 -380.151386) (xy 295.880536 -379.993906) (xy 295.880115 -379.98472)
			(xy 295.873608 -379.967536) (xy 295.867836 -379.960378) (xy 295.846016 -379.934676) (xy 295.807924 -379.879048)
			(xy 295.776769 -379.819257) (xy 295.753 -379.756165) (xy 295.736961 -379.69068) (xy 295.728881 -379.623745)
			(xy 295.728876 -379.556324) (xy 295.736948 -379.489388) (xy 295.75298 -379.423901) (xy 295.776741 -379.360806)
			(xy 295.807888 -379.301012) (xy 295.845974 -379.245379) (xy 295.867836 -379.219714) (xy 295.873656 -379.212586)
			(xy 295.880156 -379.195382) (xy 295.880536 -379.186186) (xy 295.880536 -378.693934) (xy 295.880101 -378.68475)
			(xy 295.873604 -378.667565) (xy 295.867836 -378.660406) (xy 295.845945 -378.634762) (xy 295.807855 -378.579126)
			(xy 295.776703 -378.519327) (xy 295.752939 -378.456227) (xy 295.736904 -378.390735) (xy 295.72883 -378.323794)
			(xy 292.450785 -378.323794) (xy 292.44275 -378.390553) (xy 292.426779 -378.455934) (xy 292.403109 -378.518938)
			(xy 292.372077 -378.57866) (xy 292.334131 -378.634246) (xy 292.312344 -378.659898) (xy 292.306559 -378.667051)
			(xy 292.300039 -378.684236) (xy 292.299644 -378.693426) (xy 292.299644 -379.186694) (xy 292.30007 -379.195879)
			(xy 292.306574 -379.213063) (xy 292.312344 -379.220222) (xy 292.334178 -379.245837) (xy 292.372126 -379.301428)
			(xy 292.403158 -379.361157) (xy 292.426829 -379.424166) (xy 292.4428 -379.489553) (xy 292.45084 -379.55638)
			(xy 292.450836 -379.623689) (xy 292.442787 -379.690515) (xy 292.426809 -379.7559) (xy 292.40313 -379.818907)
			(xy 292.372091 -379.878631) (xy 292.334135 -379.934218) (xy 292.312344 -379.95987) (xy 292.306528 -379.967001)
			(xy 292.300027 -379.984203) (xy 292.299644 -379.993398) (xy 292.299644 -380.151386) (xy 292.299224 -380.161559)
			(xy 292.291441 -380.180357) (xy 292.277054 -380.194743) (xy 292.258255 -380.202525) (xy 292.248082 -380.202948)
			(xy 291.531802 -380.202948) (xy 291.521629 -380.202534) (xy 291.502831 -380.194747) (xy 291.488446 -380.180358)
			(xy 291.480663 -380.161559) (xy 291.48024 -380.151386) (xy 291.48024 -379.993398) (xy 291.479822 -379.984212)
			(xy 291.473313 -379.967028) (xy 291.46754 -379.95987) (xy 291.445798 -379.934181) (xy 291.407847 -379.878599)
			(xy 291.376812 -379.818881) (xy 291.353137 -379.755881) (xy 291.337161 -379.690504) (xy 291.329113 -379.623685)
			(xy 291.329109 -379.556384) (xy 291.337148 -379.489564) (xy 291.353116 -379.424185) (xy 291.376784 -379.361182)
			(xy 291.407812 -379.30146) (xy 291.445755 -379.245874) (xy 291.46754 -379.220222) (xy 291.473357 -379.213092)
			(xy 291.479859 -379.19589) (xy 291.48024 -379.186694) (xy 291.48024 -378.693426) (xy 291.479809 -378.684241)
			(xy 291.473309 -378.667057) (xy 291.46754 -378.659898) (xy 291.445727 -378.634267) (xy 291.407778 -378.578678)
			(xy 291.376746 -378.518951) (xy 291.353075 -378.455944) (xy 291.337104 -378.390559) (xy 291.329062 -378.323734)
			(xy 288.051024 -378.323734) (xy 288.051024 -378.323792) (xy 288.04295 -378.390729) (xy 288.026915 -378.456218)
			(xy 288.003152 -378.519314) (xy 287.972001 -378.579109) (xy 287.933912 -378.634742) (xy 287.912048 -378.660406)
			(xy 287.90626 -378.667557) (xy 287.899742 -378.684743) (xy 287.899348 -378.693934) (xy 287.899348 -379.186186)
			(xy 287.899776 -379.195371) (xy 287.906279 -379.212555) (xy 287.912048 -379.219714) (xy 287.933959 -379.245341)
			(xy 287.97205 -379.30098) (xy 288.003201 -379.360781) (xy 288.026965 -379.423883) (xy 288.042999 -379.489377)
			(xy 288.051072 -379.55632) (xy 288.051068 -379.623749) (xy 288.042987 -379.690691) (xy 288.026945 -379.756183)
			(xy 288.003173 -379.819282) (xy 287.972014 -379.879079) (xy 287.933917 -379.934714) (xy 287.912048 -379.960378)
			(xy 287.906229 -379.967507) (xy 287.899729 -379.98471) (xy 287.899348 -379.993906) (xy 287.899348 -380.151386)
			(xy 287.898862 -380.161513) (xy 287.891136 -380.180236) (xy 287.87685 -380.194594) (xy 287.858165 -380.202411)
			(xy 287.84804 -380.202948) (xy 287.13176 -380.202948) (xy 287.121655 -380.202449) (xy 287.102985 -380.194707)
			(xy 287.088693 -380.180415) (xy 287.080951 -380.161745) (xy 287.080452 -380.15164) (xy 287.080452 -379.993906)
			(xy 287.080027 -379.984721) (xy 287.073523 -379.967537) (xy 287.067752 -379.960378) (xy 287.045931 -379.934676)
			(xy 287.007838 -379.879048) (xy 286.976682 -379.819258) (xy 286.952913 -379.756165) (xy 286.936873 -379.69068)
			(xy 286.928793 -379.623745) (xy 286.928788 -379.556324) (xy 286.936861 -379.489388) (xy 286.952893 -379.423901)
			(xy 286.976654 -379.360806) (xy 287.007802 -379.301011) (xy 287.045889 -379.245378) (xy 287.067752 -379.219714)
			(xy 287.073574 -379.212587) (xy 287.080072 -379.195382) (xy 287.080452 -379.186186) (xy 287.080452 -378.693934)
			(xy 287.080014 -378.68475) (xy 287.073519 -378.667566) (xy 287.067752 -378.660406) (xy 287.045861 -378.634763)
			(xy 287.007769 -378.579126) (xy 286.976617 -378.519328) (xy 286.952852 -378.456228) (xy 286.936817 -378.390735)
			(xy 286.928742 -378.323794) (xy 274.077801 -378.323794) (xy 274.085782 -378.367343) (xy 274.101882 -378.499931)
			(xy 274.109946 -378.633249) (xy 274.11045 -378.70003) (xy 274.109946 -378.766811) (xy 274.101882 -378.900129)
			(xy 274.085782 -379.032717) (xy 274.061707 -379.164091) (xy 274.029744 -379.293772) (xy 273.990009 -379.421286)
			(xy 273.942647 -379.546169) (xy 273.887832 -379.667964) (xy 273.825762 -379.786227) (xy 273.756666 -379.900526)
			(xy 273.680794 -380.010446) (xy 273.598424 -380.115583) (xy 273.509856 -380.215556) (xy 273.415414 -380.309998)
			(xy 273.315441 -380.398566) (xy 273.210304 -380.480936) (xy 273.100384 -380.556808) (xy 272.986085 -380.625904)
			(xy 272.92786 -380.656463) (xy 289.128932 -380.656463) (xy 289.136975 -380.589641) (xy 289.152947 -380.524259)
			(xy 289.17662 -380.461255) (xy 289.207654 -380.401532) (xy 289.245604 -380.345947) (xy 289.267392 -380.320296)
			(xy 289.273172 -380.313139) (xy 289.279697 -380.295958) (xy 289.280092 -380.286768) (xy 289.280092 -379.7935)
			(xy 289.279684 -379.784313) (xy 289.273169 -379.767128) (xy 289.267392 -379.759972) (xy 289.24565 -379.734282)
			(xy 289.207696 -379.678702) (xy 289.176658 -379.618984) (xy 289.15298 -379.555985) (xy 289.137002 -379.490606)
			(xy 289.128953 -379.423787) (xy 289.128949 -379.356485) (xy 289.136989 -379.289665) (xy 289.152959 -379.224284)
			(xy 289.176628 -379.161282) (xy 289.207659 -379.10156) (xy 289.245606 -379.045975) (xy 289.267392 -379.020324)
			(xy 289.273202 -379.013189) (xy 289.279709 -378.995991) (xy 289.280092 -378.986796) (xy 289.280092 -378.828554)
			(xy 289.280595 -378.818399) (xy 289.288376 -378.799638) (xy 289.302738 -378.785276) (xy 289.321499 -378.777495)
			(xy 289.331654 -378.776992) (xy 290.047934 -378.776992) (xy 290.058088 -378.777504) (xy 290.076849 -378.785281)
			(xy 290.091212 -378.799641) (xy 290.098993 -378.8184) (xy 290.099496 -378.828554) (xy 290.099496 -378.986796)
			(xy 290.099909 -378.995983) (xy 290.106421 -379.013167) (xy 290.112196 -379.020324) (xy 290.13403 -379.045938)
			(xy 290.171975 -379.101531) (xy 290.203004 -379.16126) (xy 290.226673 -379.224269) (xy 290.242641 -379.289656)
			(xy 290.250681 -379.356482) (xy 290.250677 -379.42379) (xy 290.242628 -379.490615) (xy 290.226651 -379.556)
			(xy 290.202975 -379.619006) (xy 290.171938 -379.678731) (xy 290.133986 -379.734319) (xy 290.112196 -379.759972)
			(xy 290.106386 -379.767108) (xy 290.099879 -379.784305) (xy 290.099496 -379.7935) (xy 290.099496 -380.286768)
			(xy 290.099922 -380.295953) (xy 290.106425 -380.313138) (xy 290.112196 -380.320296) (xy 290.134002 -380.345932)
			(xy 290.171948 -380.401522) (xy 290.202979 -380.461248) (xy 290.226649 -380.524255) (xy 290.242619 -380.589638)
			(xy 290.250654 -380.656404) (xy 293.528724 -380.656404) (xy 293.536798 -380.589467) (xy 293.552831 -380.52398)
			(xy 293.576592 -380.460884) (xy 293.60774 -380.401088) (xy 293.645826 -380.345453) (xy 293.667688 -380.319788)
			(xy 293.673471 -380.312633) (xy 293.679994 -380.29545) (xy 293.680388 -380.28626) (xy 293.680388 -379.794008)
			(xy 293.679977 -379.784821) (xy 293.673464 -379.767636) (xy 293.667688 -379.76048) (xy 293.645872 -379.734776)
			(xy 293.607782 -379.679146) (xy 293.57663 -379.619356) (xy 293.552864 -379.556264) (xy 293.536825 -379.49078)
			(xy 293.528746 -379.423846) (xy 293.528741 -379.356426) (xy 293.536812 -379.289491) (xy 293.552842 -379.224005)
			(xy 293.576601 -379.16091) (xy 293.607745 -379.101115) (xy 293.645827 -379.045481) (xy 293.667688 -379.019816)
			(xy 293.673501 -379.012683) (xy 293.680006 -378.995483) (xy 293.680388 -378.986288) (xy 293.680388 -378.828554)
			(xy 293.680887 -378.818431) (xy 293.688621 -378.799718) (xy 293.702902 -378.785366) (xy 293.721575 -378.777539)
			(xy 293.731696 -378.776992) (xy 294.447976 -378.776992) (xy 294.458096 -378.777435) (xy 294.476798 -378.785174)
			(xy 294.491112 -378.799482) (xy 294.49886 -378.81818) (xy 294.499284 -378.8283) (xy 294.499284 -378.986288)
			(xy 294.499704 -378.995474) (xy 294.506211 -379.012658) (xy 294.511984 -379.019816) (xy 294.533896 -379.045442)
			(xy 294.571984 -379.101082) (xy 294.603134 -379.160883) (xy 294.626896 -379.223985) (xy 294.642928 -379.289479)
			(xy 294.651001 -379.356422) (xy 294.650996 -379.42385) (xy 294.642915 -379.490792) (xy 294.626874 -379.556284)
			(xy 294.603104 -379.619383) (xy 294.571947 -379.67918) (xy 294.533851 -379.734815) (xy 294.511984 -379.76048)
			(xy 294.506169 -379.767612) (xy 294.499666 -379.784813) (xy 294.499284 -379.794008) (xy 294.499284 -380.28626)
			(xy 294.499717 -380.295445) (xy 294.506215 -380.312629) (xy 294.511984 -380.319788) (xy 294.533868 -380.345437)
			(xy 294.571957 -380.401073) (xy 294.603108 -380.460872) (xy 294.626872 -380.523971) (xy 294.642906 -380.589462)
			(xy 294.650981 -380.656402) (xy 294.650981 -380.656463) (xy 297.92902 -380.656463) (xy 297.937062 -380.589641)
			(xy 297.953034 -380.52426) (xy 297.976707 -380.461256) (xy 298.00774 -380.401533) (xy 298.045688 -380.345948)
			(xy 298.067476 -380.320296) (xy 298.073254 -380.313137) (xy 298.079781 -380.295957) (xy 298.080176 -380.286768)
			(xy 298.080176 -379.7935) (xy 298.079771 -379.784312) (xy 298.073254 -379.767128) (xy 298.067476 -379.759972)
			(xy 298.045734 -379.734282) (xy 298.007782 -379.678701) (xy 297.976744 -379.618984) (xy 297.953067 -379.555984)
			(xy 297.93709 -379.490606) (xy 297.929041 -379.423787) (xy 297.929037 -379.356485) (xy 297.937077 -379.289665)
			(xy 297.953046 -379.224285) (xy 297.976715 -379.161283) (xy 298.007745 -379.101561) (xy 298.04569 -379.045976)
			(xy 298.067476 -379.020324) (xy 298.073285 -379.013187) (xy 298.079793 -378.99599) (xy 298.080176 -378.986796)
			(xy 298.080176 -378.828554) (xy 298.080597 -378.818389) (xy 298.088393 -378.799611) (xy 298.102782 -378.785246)
			(xy 298.121572 -378.77748) (xy 298.131738 -378.776992) (xy 298.848018 -378.776992) (xy 298.858171 -378.777517)
			(xy 298.876932 -378.785289) (xy 298.891295 -378.799644) (xy 298.899077 -378.818401) (xy 298.89958 -378.828554)
			(xy 298.89958 -378.986796) (xy 298.899996 -378.995982) (xy 298.906506 -379.013167) (xy 298.91228 -379.020324)
			(xy 298.934114 -379.045938) (xy 298.972061 -379.10153) (xy 299.003091 -379.161259) (xy 299.02676 -379.224269)
			(xy 299.042729 -379.289655) (xy 299.050769 -379.356482) (xy 299.050765 -379.42379) (xy 299.042716 -379.490616)
			(xy 299.026739 -379.556) (xy 299.003061 -379.619007) (xy 298.972023 -379.678732) (xy 298.93407 -379.73432)
			(xy 298.91228 -379.759972) (xy 298.906468 -379.767106) (xy 298.899963 -379.784305) (xy 298.89958 -379.7935)
			(xy 298.89958 -380.286768) (xy 298.90001 -380.295953) (xy 298.90651 -380.313137) (xy 298.91228 -380.320296)
			(xy 298.934087 -380.345932) (xy 298.972034 -380.401521) (xy 299.003065 -380.461247) (xy 299.026736 -380.524254)
			(xy 299.042707 -380.589638) (xy 299.050742 -380.656404) (xy 302.328812 -380.656404) (xy 302.336886 -380.589468)
			(xy 302.352918 -380.52398) (xy 302.376679 -380.460884) (xy 302.407826 -380.401089) (xy 302.44591 -380.345454)
			(xy 302.467772 -380.319788) (xy 302.473565 -380.312641) (xy 302.48008 -380.295451) (xy 302.480472 -380.28626)
			(xy 302.480472 -379.794008) (xy 302.480064 -379.78482) (xy 302.47355 -379.767636) (xy 302.467772 -379.76048)
			(xy 302.445956 -379.734775) (xy 302.407868 -379.679146) (xy 302.376717 -379.619355) (xy 302.352951 -379.556263)
			(xy 302.336913 -379.490779) (xy 302.328834 -379.423846) (xy 302.328829 -379.356426) (xy 302.3369 -379.289492)
			(xy 302.35293 -379.224006) (xy 302.376687 -379.160911) (xy 302.407831 -379.101116) (xy 302.445912 -379.045482)
			(xy 302.467772 -379.019816) (xy 302.473595 -379.01269) (xy 302.480092 -378.995485) (xy 302.480472 -378.986288)
			(xy 302.480472 -378.828554) (xy 302.48089 -378.81842) (xy 302.488639 -378.799692) (xy 302.502946 -378.785336)
			(xy 302.521648 -378.777525) (xy 302.53178 -378.776992) (xy 303.24806 -378.776992) (xy 303.258211 -378.777454)
			(xy 303.27696 -378.785235) (xy 303.291285 -378.79962) (xy 303.298987 -378.818402) (xy 303.299368 -378.828554)
			(xy 303.299368 -378.986288) (xy 303.299791 -378.995474) (xy 303.306296 -379.012658) (xy 303.312068 -379.019816)
			(xy 303.33398 -379.045442) (xy 303.37207 -379.101081) (xy 303.40322 -379.160883) (xy 303.426983 -379.223985)
			(xy 303.443016 -379.289479) (xy 303.451089 -379.356422) (xy 303.451084 -379.42385) (xy 303.443003 -379.490792)
			(xy 303.426962 -379.556284) (xy 303.403191 -379.619383) (xy 303.372032 -379.679181) (xy 303.333936 -379.734815)
			(xy 303.312068 -379.76048) (xy 303.306251 -379.76761) (xy 303.299749 -379.784812) (xy 303.299368 -379.794008)
			(xy 303.299368 -380.28626) (xy 303.299805 -380.295444) (xy 303.306301 -380.312628) (xy 303.312068 -380.319788)
			(xy 303.333953 -380.345436) (xy 303.372043 -380.401073) (xy 303.403195 -380.460871) (xy 303.426959 -380.52397)
			(xy 303.442994 -380.589461) (xy 303.451069 -380.656402) (xy 303.451069 -380.656404) (xy 333.128842 -380.656404)
			(xy 333.136916 -380.589467) (xy 333.15295 -380.523979) (xy 333.176713 -380.460883) (xy 333.207862 -380.401087)
			(xy 333.245949 -380.345453) (xy 333.267812 -380.319788) (xy 333.273598 -380.312635) (xy 333.280118 -380.29545)
			(xy 333.280512 -380.28626) (xy 333.280512 -379.794008) (xy 333.280095 -379.784822) (xy 333.273586 -379.767637)
			(xy 333.267812 -379.76048) (xy 333.245995 -379.734776) (xy 333.207904 -379.679147) (xy 333.17675 -379.619357)
			(xy 333.152983 -379.556265) (xy 333.136944 -379.49078) (xy 333.128864 -379.423846) (xy 333.12886 -379.356426)
			(xy 333.136931 -379.289491) (xy 333.152962 -379.224004) (xy 333.176721 -379.160909) (xy 333.207867 -379.101115)
			(xy 333.24595 -379.045481) (xy 333.267812 -379.019816) (xy 333.273628 -379.012685) (xy 333.280131 -378.995483)
			(xy 333.280512 -378.986288) (xy 333.280512 -378.828554) (xy 333.280988 -378.818428) (xy 333.288726 -378.799711)
			(xy 333.303015 -378.785357) (xy 333.321696 -378.777535) (xy 333.33182 -378.776992) (xy 334.0481 -378.776992)
			(xy 334.058253 -378.777422) (xy 334.077004 -378.785216) (xy 334.091327 -378.79961) (xy 334.099028 -378.818399)
			(xy 334.099408 -378.828554) (xy 334.099408 -378.986288) (xy 334.099822 -378.995475) (xy 334.106333 -379.012659)
			(xy 334.112108 -379.019816) (xy 334.134019 -379.045442) (xy 334.172106 -379.101083) (xy 334.203254 -379.160884)
			(xy 334.227015 -379.223986) (xy 334.243047 -379.28948) (xy 334.251119 -379.356422) (xy 334.251114 -379.42385)
			(xy 334.243034 -379.490791) (xy 334.226994 -379.556283) (xy 334.203224 -379.619382) (xy 334.172068 -379.679179)
			(xy 334.133975 -379.734815) (xy 334.112108 -379.76048) (xy 334.106296 -379.767614) (xy 334.09979 -379.784813)
			(xy 334.099408 -379.794008) (xy 334.099408 -380.28626) (xy 334.099836 -380.295445) (xy 334.106337 -380.31263)
			(xy 334.112108 -380.319788) (xy 334.133991 -380.345437) (xy 334.172079 -380.401074) (xy 334.203228 -380.460873)
			(xy 334.226991 -380.523972) (xy 334.243025 -380.589463) (xy 334.251099 -380.656402) (xy 334.251099 -380.656464)
			(xy 337.529162 -380.656464) (xy 337.537203 -380.589643) (xy 337.553173 -380.524262) (xy 337.576842 -380.461259)
			(xy 337.607871 -380.401536) (xy 337.645815 -380.345949) (xy 337.6676 -380.320296) (xy 337.673381 -380.31314)
			(xy 337.679905 -380.295958) (xy 337.6803 -380.286768) (xy 337.6803 -379.7935) (xy 337.67989 -379.784313)
			(xy 337.673376 -379.767129) (xy 337.6676 -379.759972) (xy 337.645861 -379.734281) (xy 337.607913 -379.678699)
			(xy 337.57688 -379.61898) (xy 337.553206 -379.555981) (xy 337.537231 -379.490604) (xy 337.529183 -379.423786)
			(xy 337.529179 -379.356486) (xy 337.537218 -379.289667) (xy 337.553185 -379.224288) (xy 337.57685 -379.161286)
			(xy 337.607876 -379.101563) (xy 337.645816 -379.045977) (xy 337.6676 -379.020324) (xy 337.673411 -379.013189)
			(xy 337.679917 -378.995991) (xy 337.6803 -378.986796) (xy 337.6803 -378.828554) (xy 337.680795 -378.818398)
			(xy 337.688577 -378.799635) (xy 337.702942 -378.785273) (xy 337.721706 -378.777493) (xy 337.731862 -378.776992)
			(xy 338.448142 -378.776992) (xy 338.458297 -378.777498) (xy 338.477058 -378.785278) (xy 338.49142 -378.799639)
			(xy 338.499201 -378.818399) (xy 338.499704 -378.828554) (xy 338.499704 -378.986796) (xy 338.500115 -378.995983)
			(xy 338.506628 -379.013167) (xy 338.512404 -379.020324) (xy 338.534237 -379.045938) (xy 338.572182 -379.101531)
			(xy 338.603211 -379.16126) (xy 338.626879 -379.22427) (xy 338.642847 -379.289656) (xy 338.650887 -379.356482)
			(xy 338.650883 -379.42379) (xy 338.642834 -379.490615) (xy 338.626858 -379.556) (xy 338.603181 -379.619006)
			(xy 338.572145 -379.678731) (xy 338.534193 -379.734319) (xy 338.512404 -379.759972) (xy 338.506595 -379.767108)
			(xy 338.500088 -379.784306) (xy 338.499704 -379.7935) (xy 338.499704 -380.286768) (xy 338.500129 -380.295954)
			(xy 338.506632 -380.313138) (xy 338.512404 -380.320296) (xy 338.53421 -380.345933) (xy 338.572155 -380.401522)
			(xy 338.603185 -380.461248) (xy 338.626855 -380.524255) (xy 338.642826 -380.589639) (xy 338.65086 -380.656404)
			(xy 341.92893 -380.656404) (xy 341.937004 -380.589467) (xy 341.953037 -380.523979) (xy 341.976799 -380.460883)
			(xy 342.007947 -380.401088) (xy 342.046033 -380.345453) (xy 342.067896 -380.319788) (xy 342.07368 -380.312634)
			(xy 342.080202 -380.29545) (xy 342.080596 -380.28626) (xy 342.080596 -379.794008) (xy 342.080183 -379.784821)
			(xy 342.073671 -379.767637) (xy 342.067896 -379.76048) (xy 342.046079 -379.734776) (xy 342.007989 -379.679147)
			(xy 341.976837 -379.619356) (xy 341.95307 -379.556264) (xy 341.937032 -379.49078) (xy 341.928952 -379.423846)
			(xy 341.928948 -379.356426) (xy 341.937019 -379.289491) (xy 341.953049 -379.224005) (xy 341.976807 -379.16091)
			(xy 342.007952 -379.101115) (xy 342.046035 -379.045481) (xy 342.067896 -379.019816) (xy 342.07371 -379.012683)
			(xy 342.080215 -378.995483) (xy 342.080596 -378.986288) (xy 342.080596 -378.828554) (xy 342.081088 -378.81843)
			(xy 342.088822 -378.799716) (xy 342.103106 -378.785363) (xy 342.121782 -378.777538) (xy 342.131904 -378.776992)
			(xy 342.848184 -378.776992) (xy 342.858336 -378.777434) (xy 342.877087 -378.785223) (xy 342.89141 -378.799614)
			(xy 342.899112 -378.8184) (xy 342.899492 -378.828554) (xy 342.899492 -378.986288) (xy 342.89991 -378.995474)
			(xy 342.906418 -379.012659) (xy 342.912192 -379.019816) (xy 342.934103 -379.045442) (xy 342.972191 -379.101082)
			(xy 343.00334 -379.160884) (xy 343.027102 -379.223986) (xy 343.043135 -379.28948) (xy 343.051207 -379.356422)
			(xy 343.051202 -379.42385) (xy 343.043122 -379.490792) (xy 343.027081 -379.556283) (xy 343.003311 -379.619382)
			(xy 342.972154 -379.67918) (xy 342.934059 -379.734815) (xy 342.912192 -379.76048) (xy 342.906378 -379.767613)
			(xy 342.899874 -379.784813) (xy 342.899492 -379.794008) (xy 342.899492 -380.28626) (xy 342.899923 -380.295445)
			(xy 342.906422 -380.312629) (xy 342.912192 -380.319788) (xy 342.934076 -380.345437) (xy 342.972165 -380.401074)
			(xy 343.003315 -380.460872) (xy 343.027078 -380.523971) (xy 343.043113 -380.589462) (xy 343.051187 -380.656402)
			(xy 343.051187 -380.656463) (xy 346.329226 -380.656463) (xy 346.337269 -380.589641) (xy 346.353241 -380.524259)
			(xy 346.376913 -380.461255) (xy 346.407947 -380.401533) (xy 346.445896 -380.345948) (xy 346.467684 -380.320296)
			(xy 346.473463 -380.313138) (xy 346.479989 -380.295957) (xy 346.480384 -380.286768) (xy 346.480384 -379.7935)
			(xy 346.479977 -379.784312) (xy 346.473462 -379.767128) (xy 346.467684 -379.759972) (xy 346.445942 -379.734282)
			(xy 346.407989 -379.678702) (xy 346.376951 -379.618984) (xy 346.353274 -379.555984) (xy 346.337296 -379.490606)
			(xy 346.329247 -379.423787) (xy 346.329243 -379.356485) (xy 346.337283 -379.289665) (xy 346.353252 -379.224285)
			(xy 346.376922 -379.161282) (xy 346.407952 -379.10156) (xy 346.445898 -379.045976) (xy 346.467684 -379.020324)
			(xy 346.473493 -379.013188) (xy 346.480001 -378.99599) (xy 346.480384 -378.986796) (xy 346.480384 -378.828554)
			(xy 346.480797 -378.818388) (xy 346.488595 -378.799609) (xy 346.502986 -378.785243) (xy 346.521779 -378.777479)
			(xy 346.531946 -378.776992) (xy 347.248226 -378.776992) (xy 347.25838 -378.777511) (xy 347.277141 -378.785285)
			(xy 347.291504 -378.799642) (xy 347.299285 -378.8184) (xy 347.299788 -378.828554) (xy 347.299788 -378.986796)
			(xy 347.300203 -378.995983) (xy 347.306714 -379.013167) (xy 347.312488 -379.020324) (xy 347.334322 -379.045938)
			(xy 347.372268 -379.10153) (xy 347.403297 -379.161259) (xy 347.426966 -379.224269) (xy 347.442935 -379.289656)
			(xy 347.450975 -379.356482) (xy 347.450971 -379.42379) (xy 347.442922 -379.490616) (xy 347.426945 -379.556)
			(xy 347.403268 -379.619007) (xy 347.372231 -379.678732) (xy 347.334278 -379.734319) (xy 347.312488 -379.759972)
			(xy 347.306677 -379.767107) (xy 347.300171 -379.784305) (xy 347.299788 -379.7935) (xy 347.299788 -380.286768)
			(xy 347.300216 -380.295953) (xy 347.306718 -380.313138) (xy 347.312488 -380.320296) (xy 347.334295 -380.345932)
			(xy 347.372241 -380.401522) (xy 347.403272 -380.461248) (xy 347.426942 -380.524254) (xy 347.442913 -380.589638)
			(xy 347.450948 -380.656404) (xy 377.128751 -380.656404) (xy 377.136826 -380.589466) (xy 377.15286 -380.523978)
			(xy 377.176623 -380.460882) (xy 377.207772 -380.401087) (xy 377.24586 -380.345453) (xy 377.267724 -380.319788)
			(xy 377.273511 -380.312636) (xy 377.280031 -380.295451) (xy 377.280424 -380.28626) (xy 377.280424 -379.794008)
			(xy 377.280005 -379.784822) (xy 377.273497 -379.767638) (xy 377.267724 -379.76048) (xy 377.245906 -379.734776)
			(xy 377.207815 -379.679148) (xy 377.17666 -379.619357) (xy 377.152893 -379.556265) (xy 377.136853 -379.490781)
			(xy 377.128773 -379.423846) (xy 377.128769 -379.356426) (xy 377.13684 -379.28949) (xy 377.152871 -379.224004)
			(xy 377.176631 -379.160909) (xy 377.207777 -379.101114) (xy 377.245862 -379.045481) (xy 377.267724 -379.019816)
			(xy 377.273542 -379.012686) (xy 377.280043 -378.995484) (xy 377.280424 -378.986288) (xy 377.280424 -378.828554)
			(xy 377.280888 -378.818426) (xy 377.288628 -378.799707) (xy 377.302921 -378.785353) (xy 377.321607 -378.777533)
			(xy 377.331732 -378.776992) (xy 378.048012 -378.776992) (xy 378.058166 -378.777411) (xy 378.076917 -378.785209)
			(xy 378.09124 -378.799607) (xy 378.098941 -378.818398) (xy 378.09932 -378.828554) (xy 378.09932 -378.986288)
			(xy 378.099731 -378.995475) (xy 378.106244 -379.01266) (xy 378.11202 -379.019816) (xy 378.13393 -379.045443)
			(xy 378.172016 -379.101083) (xy 378.203164 -379.160885) (xy 378.226924 -379.223987) (xy 378.242956 -379.28948)
			(xy 378.251028 -379.356423) (xy 378.251023 -379.42385) (xy 378.242943 -379.490791) (xy 378.226903 -379.556282)
			(xy 378.203134 -379.619381) (xy 378.171979 -379.679179) (xy 378.133886 -379.734814) (xy 378.11202 -379.76048)
			(xy 378.106209 -379.767615) (xy 378.099702 -379.784813) (xy 378.09932 -379.794008) (xy 378.09932 -380.28626)
			(xy 378.099745 -380.295446) (xy 378.106248 -380.312631) (xy 378.11202 -380.319788) (xy 378.133903 -380.345437)
			(xy 378.17199 -380.401075) (xy 378.203138 -380.460873) (xy 378.226901 -380.523972) (xy 378.242934 -380.589463)
			(xy 378.251008 -380.656403) (xy 378.251008 -380.656464) (xy 381.529071 -380.656464) (xy 381.537113 -380.589643)
			(xy 381.553083 -380.524262) (xy 381.576752 -380.461258) (xy 381.607782 -380.401535) (xy 381.645726 -380.345948)
			(xy 381.667512 -380.320296) (xy 381.673294 -380.313141) (xy 381.679817 -380.295958) (xy 381.680212 -380.286768)
			(xy 381.680212 -379.7935) (xy 381.679799 -379.784313) (xy 381.673287 -379.767129) (xy 381.667512 -379.759972)
			(xy 381.645773 -379.73428) (xy 381.607824 -379.678699) (xy 381.57679 -379.618981) (xy 381.553116 -379.555981)
			(xy 381.537141 -379.490604) (xy 381.529093 -379.423786) (xy 381.529089 -379.356486) (xy 381.537128 -379.289667)
			(xy 381.553095 -379.224288) (xy 381.576761 -379.161285) (xy 381.607787 -379.101563) (xy 381.645728 -379.045977)
			(xy 381.667512 -379.020324) (xy 381.673325 -379.01319) (xy 381.679829 -378.995991) (xy 381.680212 -378.986796)
			(xy 381.680212 -378.828554) (xy 381.680695 -378.818397) (xy 381.68848 -378.799631) (xy 381.702848 -378.785269)
			(xy 381.721616 -378.777491) (xy 381.731774 -378.776992) (xy 382.448054 -378.776992) (xy 382.458203 -378.77757)
			(xy 382.476962 -378.785321) (xy 382.491328 -378.79966) (xy 382.499112 -378.818406) (xy 382.499616 -378.828554)
			(xy 382.499616 -378.986796) (xy 382.500025 -378.995983) (xy 382.506539 -379.013168) (xy 382.512316 -379.020324)
			(xy 382.534153 -379.045936) (xy 382.572103 -379.101528) (xy 382.603137 -379.161256) (xy 382.626809 -379.224266)
			(xy 382.64278 -379.289654) (xy 382.650821 -379.356481) (xy 382.650816 -379.423791) (xy 382.642767 -379.490618)
			(xy 382.626787 -379.556003) (xy 382.603107 -379.61901) (xy 382.572066 -379.678734) (xy 382.534108 -379.734321)
			(xy 382.512316 -379.759972) (xy 382.506508 -379.767109) (xy 382.5 -379.784306) (xy 382.499616 -379.7935)
			(xy 382.499616 -380.286768) (xy 382.500038 -380.295954) (xy 382.506543 -380.313139) (xy 382.512316 -380.320296)
			(xy 382.534125 -380.345931) (xy 382.572076 -380.401519) (xy 382.603111 -380.461245) (xy 382.626784 -380.524251)
			(xy 382.642757 -380.589636) (xy 382.650793 -380.656404) (xy 385.928839 -380.656404) (xy 385.936913 -380.589467)
			(xy 385.952947 -380.523979) (xy 385.976709 -380.460883) (xy 386.007858 -380.401087) (xy 386.045945 -380.345453)
			(xy 386.067808 -380.319788) (xy 386.073593 -380.312635) (xy 386.080114 -380.29545) (xy 386.080508 -380.28626)
			(xy 386.080508 -379.794008) (xy 386.080092 -379.784821) (xy 386.073582 -379.767637) (xy 386.067808 -379.76048)
			(xy 386.045991 -379.734776) (xy 386.0079 -379.679147) (xy 385.976747 -379.619356) (xy 385.95298 -379.556265)
			(xy 385.936941 -379.49078) (xy 385.928861 -379.423846) (xy 385.928857 -379.356426) (xy 385.936928 -379.289491)
			(xy 385.952958 -379.224004) (xy 385.976718 -379.160909) (xy 386.007863 -379.101115) (xy 386.045947 -379.045481)
			(xy 386.067808 -379.019816) (xy 386.073624 -379.012684) (xy 386.080127 -378.995483) (xy 386.080508 -378.986288)
			(xy 386.080508 -378.828554) (xy 386.080988 -378.818428) (xy 386.088725 -378.799712) (xy 386.103012 -378.785359)
			(xy 386.121693 -378.777535) (xy 386.131816 -378.776992) (xy 386.848096 -378.776992) (xy 386.858249 -378.777425)
			(xy 386.877 -378.785218) (xy 386.891323 -378.799611) (xy 386.899024 -378.818399) (xy 386.899404 -378.828554)
			(xy 386.899404 -378.986288) (xy 386.899819 -378.995475) (xy 386.906329 -379.012659) (xy 386.912104 -379.019816)
			(xy 386.934015 -379.045442) (xy 386.972102 -379.101083) (xy 387.00325 -379.160884) (xy 387.027012 -379.223986)
			(xy 387.043044 -379.28948) (xy 387.051116 -379.356422) (xy 387.051111 -379.42385) (xy 387.043031 -379.490791)
			(xy 387.02699 -379.556283) (xy 387.003221 -379.619382) (xy 386.972065 -379.679179) (xy 386.933971 -379.734815)
			(xy 386.912104 -379.76048) (xy 386.906291 -379.767614) (xy 386.899786 -379.784813) (xy 386.899404 -379.794008)
			(xy 386.899404 -380.28626) (xy 386.899832 -380.295445) (xy 386.906333 -380.31263) (xy 386.912104 -380.319788)
			(xy 386.933987 -380.345437) (xy 386.972075 -380.401074) (xy 387.003225 -380.460872) (xy 387.026988 -380.523971)
			(xy 387.043022 -380.589462) (xy 387.051096 -380.656402) (xy 387.051096 -380.656464) (xy 390.329159 -380.656464)
			(xy 390.3372 -380.589643) (xy 390.35317 -380.524263) (xy 390.376839 -380.461259) (xy 390.407867 -380.401536)
			(xy 390.445811 -380.345949) (xy 390.467596 -380.320296) (xy 390.473376 -380.313139) (xy 390.479901 -380.295958)
			(xy 390.480296 -380.286768) (xy 390.480296 -379.7935) (xy 390.479887 -379.784313) (xy 390.473372 -379.767128)
			(xy 390.467596 -379.759972) (xy 390.445857 -379.73428) (xy 390.407909 -379.678699) (xy 390.376876 -379.61898)
			(xy 390.353203 -379.555981) (xy 390.337228 -379.490604) (xy 390.32918 -379.423786) (xy 390.329176 -379.356486)
			(xy 390.337215 -379.289667) (xy 390.353181 -379.224288) (xy 390.376847 -379.161286) (xy 390.407872 -379.101563)
			(xy 390.445812 -379.045977) (xy 390.467596 -379.020324) (xy 390.473407 -379.013189) (xy 390.479913 -378.995991)
			(xy 390.480296 -378.986796) (xy 390.480296 -378.828554) (xy 390.480795 -378.818398) (xy 390.488576 -378.799636)
			(xy 390.50294 -378.785274) (xy 390.521702 -378.777494) (xy 390.531858 -378.776992) (xy 391.248138 -378.776992)
			(xy 391.258293 -378.777501) (xy 391.277054 -378.785279) (xy 391.291416 -378.79964) (xy 391.299197 -378.8184)
			(xy 391.2997 -378.828554) (xy 391.2997 -378.986796) (xy 391.300112 -378.995983) (xy 391.306625 -379.013167)
			(xy 391.3124 -379.020324) (xy 391.334234 -379.045938) (xy 391.372178 -379.101531) (xy 391.403207 -379.16126)
			(xy 391.426876 -379.224269) (xy 391.442844 -379.289656) (xy 391.450884 -379.356482) (xy 391.45088 -379.42379)
			(xy 391.442831 -379.490615) (xy 391.426855 -379.556) (xy 391.403178 -379.619006) (xy 391.372141 -379.678731)
			(xy 391.334189 -379.734319) (xy 391.3124 -379.759972) (xy 391.30659 -379.767108) (xy 391.300083 -379.784306)
			(xy 391.2997 -379.7935) (xy 391.2997 -380.286768) (xy 391.300126 -380.295954) (xy 391.306629 -380.313138)
			(xy 391.3124 -380.320296) (xy 391.334206 -380.345933) (xy 391.372152 -380.401522) (xy 391.403182 -380.461248)
			(xy 391.426852 -380.524255) (xy 391.442822 -380.589638) (xy 391.450857 -380.656404) (xy 421.12866 -380.656404)
			(xy 421.136735 -380.589466) (xy 421.152769 -380.523978) (xy 421.176533 -380.460881) (xy 421.207683 -380.401086)
			(xy 421.245772 -380.345453) (xy 421.267636 -380.319788) (xy 421.273425 -380.312637) (xy 421.279943 -380.295451)
			(xy 421.280336 -380.28626) (xy 421.280336 -379.794008) (xy 421.279914 -379.784822) (xy 421.273408 -379.767638)
			(xy 421.267636 -379.76048) (xy 421.245818 -379.734776) (xy 421.207725 -379.679148) (xy 421.176571 -379.619358)
			(xy 421.152802 -379.556266) (xy 421.136762 -379.490781) (xy 421.128682 -379.423846) (xy 421.128678 -379.356426)
			(xy 421.136749 -379.28949) (xy 421.152781 -379.224003) (xy 421.176541 -379.160908) (xy 421.207688 -379.101114)
			(xy 421.245774 -379.045481) (xy 421.267636 -379.019816) (xy 421.273455 -379.012687) (xy 421.279956 -378.995484)
			(xy 421.280336 -378.986288) (xy 421.280336 -378.828554) (xy 421.280789 -378.818425) (xy 421.288531 -378.799703)
			(xy 421.302827 -378.785349) (xy 421.321517 -378.777531) (xy 421.331644 -378.776992) (xy 422.047924 -378.776992)
			(xy 422.058033 -378.777465) (xy 422.076711 -378.785209) (xy 422.091004 -378.79951) (xy 422.09874 -378.81819)
			(xy 422.099232 -378.8283) (xy 422.099232 -378.986288) (xy 422.099663 -378.995473) (xy 422.106164 -379.012656)
			(xy 422.111932 -379.019816) (xy 422.133842 -379.045443) (xy 422.171927 -379.101084) (xy 422.203074 -379.160885)
			(xy 422.226834 -379.223987) (xy 422.242865 -379.289481) (xy 422.250937 -379.356423) (xy 422.250932 -379.423849)
			(xy 422.242852 -379.49079) (xy 422.226813 -379.556282) (xy 422.203045 -379.61938) (xy 422.17189 -379.679178)
			(xy 422.133798 -379.734814) (xy 422.111932 -379.76048) (xy 422.106111 -379.767607) (xy 422.099613 -379.784812)
			(xy 422.099232 -379.794008) (xy 422.099232 -380.28626) (xy 422.099677 -380.295443) (xy 422.106168 -380.312627)
			(xy 422.111932 -380.319788) (xy 422.133814 -380.345438) (xy 422.171901 -380.401075) (xy 422.203049 -380.460874)
			(xy 422.22681 -380.523973) (xy 422.242843 -380.589463) (xy 422.250917 -380.656403) (xy 422.250917 -380.656463)
			(xy 425.52898 -380.656463) (xy 425.537022 -380.589642) (xy 425.552992 -380.524262) (xy 425.576662 -380.461258)
			(xy 425.607692 -380.401535) (xy 425.645638 -380.345948) (xy 425.667424 -380.320296) (xy 425.673208 -380.313142)
			(xy 425.679729 -380.295958) (xy 425.680124 -380.286768) (xy 425.680124 -379.7935) (xy 425.679709 -379.784313)
			(xy 425.673198 -379.767129) (xy 425.667424 -379.759972) (xy 425.645684 -379.734281) (xy 425.607735 -379.678699)
			(xy 425.5767 -379.618981) (xy 425.553026 -379.555982) (xy 425.53705 -379.490605) (xy 425.529002 -379.423787)
			(xy 425.528998 -379.356486) (xy 425.537037 -379.289667) (xy 425.553004 -379.224287) (xy 425.576671 -379.161285)
			(xy 425.607698 -379.101563) (xy 425.64564 -379.045977) (xy 425.667424 -379.020324) (xy 425.673238 -379.013191)
			(xy 425.679742 -378.995991) (xy 425.680124 -378.986796) (xy 425.680124 -378.828554) (xy 425.680595 -378.818395)
			(xy 425.688382 -378.799628) (xy 425.702754 -378.785264) (xy 425.721527 -378.777489) (xy 425.731686 -378.776992)
			(xy 426.447966 -378.776992) (xy 426.458116 -378.77756) (xy 426.476875 -378.785315) (xy 426.49124 -378.799657)
			(xy 426.499024 -378.818405) (xy 426.499528 -378.828554) (xy 426.499528 -378.986796) (xy 426.499934 -378.995984)
			(xy 426.50645 -379.013168) (xy 426.512228 -379.020324) (xy 426.534064 -379.045937) (xy 426.572014 -379.101528)
			(xy 426.603047 -379.161257) (xy 426.626718 -379.224267) (xy 426.642689 -379.289654) (xy 426.65073 -379.356481)
			(xy 426.650725 -379.423791) (xy 426.642676 -379.490617) (xy 426.626697 -379.556003) (xy 426.603017 -379.619009)
			(xy 426.571977 -379.678734) (xy 426.53402 -379.73432) (xy 426.512228 -379.759972) (xy 426.50641 -379.767101)
			(xy 426.49991 -379.784304) (xy 426.499528 -379.7935) (xy 426.499528 -380.286768) (xy 426.499947 -380.295954)
			(xy 426.506454 -380.313139) (xy 426.512228 -380.320296) (xy 426.534036 -380.345932) (xy 426.571987 -380.40152)
			(xy 426.603021 -380.461245) (xy 426.626694 -380.524252) (xy 426.642667 -380.589636) (xy 426.650703 -380.656404)
			(xy 429.928748 -380.656404) (xy 429.936823 -380.589467) (xy 429.952857 -380.523978) (xy 429.976619 -380.460882)
			(xy 430.007769 -380.401087) (xy 430.045857 -380.345453) (xy 430.06772 -380.319788) (xy 430.073506 -380.312636)
			(xy 430.080027 -380.295451) (xy 430.08042 -380.28626) (xy 430.08042 -379.794008) (xy 430.080001 -379.784822)
			(xy 430.073493 -379.767638) (xy 430.06772 -379.76048) (xy 430.045902 -379.734776) (xy 430.007811 -379.679148)
			(xy 429.976657 -379.619357) (xy 429.952889 -379.556265) (xy 429.93685 -379.490781) (xy 429.92877 -379.423846)
			(xy 429.928766 -379.356426) (xy 429.936837 -379.289491) (xy 429.952868 -379.224004) (xy 429.976628 -379.160909)
			(xy 430.007774 -379.101114) (xy 430.045858 -379.045481) (xy 430.06772 -379.019816) (xy 430.073537 -379.012685)
			(xy 430.080039 -378.995484) (xy 430.08042 -378.986288) (xy 430.08042 -378.828554) (xy 430.080888 -378.818427)
			(xy 430.088628 -378.799708) (xy 430.102919 -378.785354) (xy 430.121603 -378.777533) (xy 430.131728 -378.776992)
			(xy 430.848008 -378.776992) (xy 430.858162 -378.777415) (xy 430.876913 -378.785212) (xy 430.891235 -378.799608)
			(xy 430.898936 -378.818398) (xy 430.899316 -378.828554) (xy 430.899316 -378.986288) (xy 430.899728 -378.995475)
			(xy 430.90624 -379.01266) (xy 430.912016 -379.019816) (xy 430.933927 -379.045443) (xy 430.972013 -379.101083)
			(xy 431.003161 -379.160885) (xy 431.026921 -379.223987) (xy 431.042953 -379.28948) (xy 431.051025 -379.356422)
			(xy 431.05102 -379.42385) (xy 431.04294 -379.490791) (xy 431.0269 -379.556282) (xy 431.003131 -379.619381)
			(xy 430.971976 -379.679179) (xy 430.933882 -379.734814) (xy 430.912016 -379.76048) (xy 430.906205 -379.767615)
			(xy 430.899698 -379.784813) (xy 430.899316 -379.794008) (xy 430.899316 -380.28626) (xy 430.899742 -380.295446)
			(xy 430.906244 -380.31263) (xy 430.912016 -380.319788) (xy 430.933899 -380.345437) (xy 430.971986 -380.401074)
			(xy 431.003135 -380.460873) (xy 431.026897 -380.523972) (xy 431.042931 -380.589463) (xy 431.051005 -380.656403)
			(xy 431.051005 -380.656464) (xy 434.329068 -380.656464) (xy 434.33711 -380.589643) (xy 434.35308 -380.524262)
			(xy 434.376749 -380.461259) (xy 434.407778 -380.401535) (xy 434.445722 -380.345949) (xy 434.467508 -380.320296)
			(xy 434.47329 -380.31314) (xy 434.479813 -380.295958) (xy 434.480208 -380.286768) (xy 434.480208 -379.7935)
			(xy 434.479796 -379.784313) (xy 434.473283 -379.767129) (xy 434.467508 -379.759972) (xy 434.445769 -379.73428)
			(xy 434.407821 -379.678699) (xy 434.376787 -379.61898) (xy 434.353113 -379.555981) (xy 434.337137 -379.490604)
			(xy 434.32909 -379.423786) (xy 434.329086 -379.356486) (xy 434.337125 -379.289667) (xy 434.353091 -379.224288)
			(xy 434.376757 -379.161286) (xy 434.407783 -379.101563) (xy 434.445724 -379.045977) (xy 434.467508 -379.020324)
			(xy 434.47332 -379.01319) (xy 434.479825 -378.995991) (xy 434.480208 -378.986796) (xy 434.480208 -378.828554)
			(xy 434.480695 -378.818397) (xy 434.488479 -378.799633) (xy 434.502846 -378.78527) (xy 434.521613 -378.777492)
			(xy 434.53177 -378.776992) (xy 435.24805 -378.776992) (xy 435.258213 -378.777504) (xy 435.276998 -378.785264)
			(xy 435.291383 -378.799622) (xy 435.299177 -378.818392) (xy 435.299612 -378.828554) (xy 435.299612 -378.986796)
			(xy 435.300021 -378.995983) (xy 435.306535 -379.013168) (xy 435.312312 -379.020324) (xy 435.334148 -379.045937)
			(xy 435.372099 -379.101528) (xy 435.403133 -379.161256) (xy 435.426805 -379.224266) (xy 435.442776 -379.289654)
			(xy 435.450817 -379.356481) (xy 435.450813 -379.423791) (xy 435.442763 -379.490618) (xy 435.426784 -379.556003)
			(xy 435.403103 -379.61901) (xy 435.372062 -379.678734) (xy 435.334104 -379.73432) (xy 435.312312 -379.759972)
			(xy 435.306504 -379.767109) (xy 435.299996 -379.784306) (xy 435.299612 -379.7935) (xy 435.299612 -380.286768)
			(xy 435.300035 -380.295954) (xy 435.306539 -380.313139) (xy 435.312312 -380.320296) (xy 435.334121 -380.345931)
			(xy 435.372072 -380.401519) (xy 435.403107 -380.461244) (xy 435.426781 -380.524251) (xy 435.442754 -380.589636)
			(xy 435.450797 -380.656461) (xy 435.450796 -380.723769) (xy 435.442749 -380.790594) (xy 435.426772 -380.855977)
			(xy 435.403095 -380.918983) (xy 435.372057 -380.978707) (xy 435.334102 -381.034292) (xy 435.312312 -381.059944)
			(xy 435.306516 -381.067089) (xy 435.3 -381.08428) (xy 435.299612 -381.093472) (xy 435.299612 -381.251206)
			(xy 435.29924 -381.261384) (xy 435.291444 -381.280189) (xy 435.277041 -381.294575) (xy 435.258229 -381.302351)
			(xy 435.24805 -381.302768) (xy 434.53177 -381.302768) (xy 434.521611 -381.302291) (xy 434.502842 -381.294508)
			(xy 434.488478 -381.280138) (xy 434.480704 -381.261365) (xy 434.480208 -381.251206) (xy 434.480208 -381.093472)
			(xy 434.47981 -381.084284) (xy 434.473288 -381.067099) (xy 434.467508 -381.059944) (xy 434.445741 -381.034275)
			(xy 434.407793 -380.97869) (xy 434.376761 -380.918969) (xy 434.353088 -380.855967) (xy 434.337115 -380.790587)
			(xy 434.32907 -380.723766) (xy 434.329068 -380.656464) (xy 431.051005 -380.656464) (xy 431.051003 -380.723827)
			(xy 431.042926 -380.790767) (xy 431.026889 -380.856257) (xy 431.003123 -380.919354) (xy 430.971971 -380.979151)
			(xy 430.933881 -381.034786) (xy 430.912016 -381.060452) (xy 430.906217 -381.067595) (xy 430.899703 -381.084787)
			(xy 430.899316 -381.09398) (xy 430.899316 -381.251206) (xy 430.898877 -381.261338) (xy 430.891139 -381.280068)
			(xy 430.876838 -381.294426) (xy 430.858138 -381.302237) (xy 430.848008 -381.302768) (xy 430.131728 -381.302768)
			(xy 430.121572 -381.302355) (xy 430.102814 -381.294563) (xy 430.088488 -381.280163) (xy 430.080793 -381.261364)
			(xy 430.08042 -381.251206) (xy 430.08042 -381.09398) (xy 430.080015 -381.084792) (xy 430.073497 -381.067608)
			(xy 430.06772 -381.060452) (xy 430.045875 -381.034771) (xy 430.007784 -380.979139) (xy 429.976632 -380.919345)
			(xy 429.952865 -380.85625) (xy 429.936828 -380.790763) (xy 429.92875 -380.723826) (xy 429.928748 -380.656404)
			(xy 426.650703 -380.656404) (xy 426.65071 -380.656461) (xy 426.650708 -380.723769) (xy 426.642661 -380.790593)
			(xy 426.626685 -380.855977) (xy 426.603009 -380.918982) (xy 426.571971 -380.978706) (xy 426.534018 -381.034292)
			(xy 426.512228 -381.059944) (xy 426.506422 -381.067082) (xy 426.499915 -381.084278) (xy 426.499528 -381.093472)
			(xy 426.499528 -381.251206) (xy 426.49914 -381.261382) (xy 426.491347 -381.280184) (xy 426.47695 -381.294569)
			(xy 426.458143 -381.302348) (xy 426.447966 -381.302768) (xy 425.731686 -381.302768) (xy 425.721528 -381.302278)
			(xy 425.70276 -381.2945) (xy 425.688395 -381.280133) (xy 425.68062 -381.261364) (xy 425.680124 -381.251206)
			(xy 425.680124 -381.093472) (xy 425.679722 -381.084284) (xy 425.673202 -381.0671) (xy 425.667424 -381.059944)
			(xy 425.645656 -381.034276) (xy 425.607708 -380.978691) (xy 425.576675 -380.91897) (xy 425.553001 -380.855967)
			(xy 425.537027 -380.790587) (xy 425.528982 -380.723767) (xy 425.52898 -380.656463) (xy 422.250917 -380.656463)
			(xy 422.250915 -380.723827) (xy 422.242838 -380.790766) (xy 422.226801 -380.856256) (xy 422.203036 -380.919354)
			(xy 422.171885 -380.979151) (xy 422.133796 -381.034786) (xy 422.111932 -381.060452) (xy 422.106123 -381.067588)
			(xy 422.099618 -381.084786) (xy 422.099232 -381.09398) (xy 422.099232 -381.251206) (xy 422.098777 -381.261337)
			(xy 422.091042 -381.280063) (xy 422.076746 -381.29442) (xy 422.058052 -381.302234) (xy 422.047924 -381.302768)
			(xy 421.331644 -381.302768) (xy 421.32152 -381.302347) (xy 421.302812 -381.294608) (xy 421.288495 -381.280292)
			(xy 421.280754 -381.261584) (xy 421.280336 -381.25146) (xy 421.280336 -381.09398) (xy 421.279927 -381.084793)
			(xy 421.273412 -381.067609) (xy 421.267636 -381.060452) (xy 421.24579 -381.034771) (xy 421.207699 -380.97914)
			(xy 421.176545 -380.919346) (xy 421.152778 -380.856251) (xy 421.13674 -380.790764) (xy 421.128662 -380.723826)
			(xy 421.12866 -380.656404) (xy 391.450857 -380.656404) (xy 391.450864 -380.656462) (xy 391.450863 -380.723768)
			(xy 391.442817 -380.790591) (xy 391.426843 -380.855974) (xy 391.40317 -380.918979) (xy 391.372136 -380.978704)
			(xy 391.334188 -381.034291) (xy 391.3124 -381.059944) (xy 391.306602 -381.067088) (xy 391.300088 -381.08428)
			(xy 391.2997 -381.093472) (xy 391.2997 -381.251206) (xy 391.299172 -381.261359) (xy 391.291403 -381.280121)
			(xy 391.277048 -381.294485) (xy 391.258291 -381.302266) (xy 391.248138 -381.302768) (xy 390.531858 -381.302768)
			(xy 390.521698 -381.302301) (xy 390.502929 -381.294514) (xy 390.488566 -381.28014) (xy 390.480792 -381.261366)
			(xy 390.480296 -381.251206) (xy 390.480296 -381.093472) (xy 390.4799 -381.084283) (xy 390.473377 -381.067099)
			(xy 390.467596 -381.059944) (xy 390.445829 -381.034275) (xy 390.407883 -380.97869) (xy 390.376851 -380.918968)
			(xy 390.353179 -380.855966) (xy 390.337206 -380.790586) (xy 390.329161 -380.723766) (xy 390.329159 -380.656464)
			(xy 387.051096 -380.656464) (xy 387.051094 -380.723828) (xy 387.043016 -380.790767) (xy 387.026979 -380.856257)
			(xy 387.003213 -380.919355) (xy 386.97206 -380.979152) (xy 386.933969 -381.034787) (xy 386.912104 -381.060452)
			(xy 386.906303 -381.067594) (xy 386.899791 -381.084787) (xy 386.899404 -381.09398) (xy 386.899404 -381.251206)
			(xy 386.89888 -381.261328) (xy 386.891158 -381.280041) (xy 386.876884 -381.294395) (xy 386.858215 -381.302222)
			(xy 386.848096 -381.302768) (xy 386.131816 -381.302768) (xy 386.121659 -381.302365) (xy 386.102901 -381.294568)
			(xy 386.088576 -381.280166) (xy 386.080881 -381.261365) (xy 386.080508 -381.251206) (xy 386.080508 -381.09398)
			(xy 386.080106 -381.084792) (xy 386.073587 -381.067608) (xy 386.067808 -381.060452) (xy 386.045963 -381.034771)
			(xy 386.007874 -380.979139) (xy 385.976722 -380.919345) (xy 385.952956 -380.85625) (xy 385.936919 -380.790763)
			(xy 385.928841 -380.723826) (xy 385.928839 -380.656404) (xy 382.650793 -380.656404) (xy 382.6508 -380.656461)
			(xy 382.650799 -380.723769) (xy 382.642752 -380.790593) (xy 382.626775 -380.855977) (xy 382.603098 -380.918983)
			(xy 382.57206 -380.978707) (xy 382.534106 -381.034292) (xy 382.512316 -381.059944) (xy 382.50652 -381.06709)
			(xy 382.500005 -381.08428) (xy 382.499616 -381.093472) (xy 382.499616 -381.251206) (xy 382.49924 -381.261384)
			(xy 382.491444 -381.280187) (xy 382.477044 -381.294574) (xy 382.458232 -381.30235) (xy 382.448054 -381.302768)
			(xy 381.731774 -381.302768) (xy 381.721615 -381.302288) (xy 381.702847 -381.294506) (xy 381.688482 -381.280137)
			(xy 381.680708 -381.261365) (xy 381.680212 -381.251206) (xy 381.680212 -381.093472) (xy 381.679813 -381.084284)
			(xy 381.673291 -381.0671) (xy 381.667512 -381.059944) (xy 381.645745 -381.034275) (xy 381.607797 -380.978691)
			(xy 381.576764 -380.918969) (xy 381.553092 -380.855967) (xy 381.537118 -380.790587) (xy 381.529073 -380.723767)
			(xy 381.529071 -380.656464) (xy 378.251008 -380.656464) (xy 378.251006 -380.723827) (xy 378.242929 -380.790767)
			(xy 378.226892 -380.856257) (xy 378.203126 -380.919354) (xy 378.171974 -380.979151) (xy 378.133884 -381.034786)
			(xy 378.11202 -381.060452) (xy 378.106221 -381.067596) (xy 378.099707 -381.084787) (xy 378.09932 -381.09398)
			(xy 378.09932 -381.251206) (xy 378.098877 -381.261338) (xy 378.09114 -381.280067) (xy 378.07684 -381.294424)
			(xy 378.058142 -381.302236) (xy 378.048012 -381.302768) (xy 377.331732 -381.302768) (xy 377.321576 -381.302352)
			(xy 377.302818 -381.294561) (xy 377.288492 -381.280162) (xy 377.280797 -381.261364) (xy 377.280424 -381.251206)
			(xy 377.280424 -381.09398) (xy 377.280018 -381.084792) (xy 377.273501 -381.067608) (xy 377.267724 -381.060452)
			(xy 377.245879 -381.034771) (xy 377.207788 -380.979139) (xy 377.176635 -380.919345) (xy 377.152869 -380.856251)
			(xy 377.136831 -380.790763) (xy 377.128753 -380.723826) (xy 377.128751 -380.656404) (xy 347.450948 -380.656404)
			(xy 347.450955 -380.656462) (xy 347.450954 -380.723768) (xy 347.442908 -380.790592) (xy 347.426934 -380.855975)
			(xy 347.40326 -380.91898) (xy 347.372226 -380.978704) (xy 347.334276 -381.034291) (xy 347.312488 -381.059944)
			(xy 347.306689 -381.067087) (xy 347.300176 -381.084279) (xy 347.299788 -381.093472) (xy 347.299788 -381.251206)
			(xy 347.299272 -381.261361) (xy 347.2915 -381.280125) (xy 347.277142 -381.294489) (xy 347.258381 -381.302268)
			(xy 347.248226 -381.302768) (xy 346.531946 -381.302768) (xy 346.521778 -381.302299) (xy 346.502986 -381.29453)
			(xy 346.488599 -381.280158) (xy 346.480812 -381.261373) (xy 346.480384 -381.251206) (xy 346.480384 -381.093472)
			(xy 346.479991 -381.084283) (xy 346.473466 -381.067099) (xy 346.467684 -381.059944) (xy 346.445915 -381.034276)
			(xy 346.407962 -380.978693) (xy 346.376926 -380.918972) (xy 346.35325 -380.85597) (xy 346.337274 -380.790589)
			(xy 346.329228 -380.723767) (xy 346.329226 -380.656463) (xy 343.051187 -380.656463) (xy 343.051185 -380.723828)
			(xy 343.043107 -380.790767) (xy 343.027069 -380.856258) (xy 343.003303 -380.919356) (xy 342.972149 -380.979152)
			(xy 342.934057 -381.034787) (xy 342.912192 -381.060452) (xy 342.90639 -381.067593) (xy 342.899879 -381.084787)
			(xy 342.899492 -381.09398) (xy 342.899492 -381.251206) (xy 342.898979 -381.261329) (xy 342.891255 -381.280044)
			(xy 342.876978 -381.294399) (xy 342.858304 -381.302224) (xy 342.848184 -381.302768) (xy 342.131904 -381.302768)
			(xy 342.121746 -381.302374) (xy 342.102988 -381.294574) (xy 342.088663 -381.280168) (xy 342.080969 -381.261366)
			(xy 342.080596 -381.251206) (xy 342.080596 -381.09398) (xy 342.080196 -381.084792) (xy 342.073675 -381.067608)
			(xy 342.067896 -381.060452) (xy 342.046052 -381.03477) (xy 342.007963 -380.979138) (xy 341.976811 -380.919344)
			(xy 341.953046 -380.856249) (xy 341.93701 -380.790762) (xy 341.928932 -380.723826) (xy 341.92893 -380.656404)
			(xy 338.65086 -380.656404) (xy 338.650867 -380.656462) (xy 338.650866 -380.723768) (xy 338.64282 -380.790591)
			(xy 338.626846 -380.855974) (xy 338.603173 -380.918979) (xy 338.57214 -380.978704) (xy 338.534192 -381.034291)
			(xy 338.512404 -381.059944) (xy 338.506607 -381.067089) (xy 338.500092 -381.08428) (xy 338.499704 -381.093472)
			(xy 338.499704 -381.251206) (xy 338.499172 -381.261359) (xy 338.491404 -381.28012) (xy 338.47705 -381.294484)
			(xy 338.458295 -381.302265) (xy 338.448142 -381.302768) (xy 337.731862 -381.302768) (xy 337.721703 -381.302298)
			(xy 337.702934 -381.294512) (xy 337.68857 -381.280139) (xy 337.680796 -381.261366) (xy 337.6803 -381.251206)
			(xy 337.6803 -381.093472) (xy 337.679904 -381.084283) (xy 337.67338 -381.067099) (xy 337.6676 -381.059944)
			(xy 337.645833 -381.034275) (xy 337.607886 -380.97869) (xy 337.576854 -380.918969) (xy 337.553182 -380.855966)
			(xy 337.537209 -380.790587) (xy 337.529164 -380.723766) (xy 337.529162 -380.656464) (xy 334.251099 -380.656464)
			(xy 334.251097 -380.723828) (xy 334.243019 -380.790767) (xy 334.226982 -380.856257) (xy 334.203216 -380.919355)
			(xy 334.172063 -380.979152) (xy 334.133973 -381.034787) (xy 334.112108 -381.060452) (xy 334.106308 -381.067595)
			(xy 334.099795 -381.084787) (xy 334.099408 -381.09398) (xy 334.099408 -381.251206) (xy 334.09888 -381.261327)
			(xy 334.091159 -381.280039) (xy 334.076886 -381.294394) (xy 334.058218 -381.302221) (xy 334.0481 -381.302768)
			(xy 333.33182 -381.302768) (xy 333.321663 -381.302362) (xy 333.302905 -381.294567) (xy 333.28858 -381.280165)
			(xy 333.280885 -381.261365) (xy 333.280512 -381.251206) (xy 333.280512 -381.09398) (xy 333.280109 -381.084792)
			(xy 333.27359 -381.067608) (xy 333.267812 -381.060452) (xy 333.245967 -381.034771) (xy 333.207877 -380.979139)
			(xy 333.176725 -380.919345) (xy 333.152959 -380.85625) (xy 333.136922 -380.790763) (xy 333.128844 -380.723826)
			(xy 333.128842 -380.656404) (xy 303.451069 -380.656404) (xy 303.451067 -380.723828) (xy 303.442989 -380.790768)
			(xy 303.42695 -380.856259) (xy 303.403182 -380.919357) (xy 303.372027 -380.979153) (xy 303.333934 -381.034787)
			(xy 303.312068 -381.060452) (xy 303.306263 -381.067591) (xy 303.299754 -381.084786) (xy 303.299368 -381.09398)
			(xy 303.299368 -381.251206) (xy 303.298878 -381.261332) (xy 303.29115 -381.280052) (xy 303.276865 -381.294408)
			(xy 303.258184 -381.302228) (xy 303.24806 -381.302768) (xy 302.53178 -381.302768) (xy 302.521621 -381.302394)
			(xy 302.502861 -381.294586) (xy 302.488538 -381.280174) (xy 302.480844 -381.261368) (xy 302.480472 -381.251206)
			(xy 302.480472 -381.09398) (xy 302.480078 -381.084791) (xy 302.473554 -381.067607) (xy 302.467772 -381.060452)
			(xy 302.445929 -381.03477) (xy 302.407841 -380.979137) (xy 302.376691 -380.919343) (xy 302.352927 -380.856248)
			(xy 302.336891 -380.790762) (xy 302.328814 -380.723826) (xy 302.328812 -380.656404) (xy 299.050742 -380.656404)
			(xy 299.050749 -380.656462) (xy 299.050747 -380.723768) (xy 299.042702 -380.790592) (xy 299.026727 -380.855975)
			(xy 299.003053 -380.91898) (xy 298.972018 -380.978704) (xy 298.934068 -381.034292) (xy 298.91228 -381.059944)
			(xy 298.90648 -381.067087) (xy 298.899968 -381.084279) (xy 298.89958 -381.093472) (xy 298.89958 -381.251206)
			(xy 298.899072 -381.261362) (xy 298.891299 -381.280128) (xy 298.876938 -381.294492) (xy 298.858174 -381.302269)
			(xy 298.848018 -381.302768) (xy 298.131738 -381.302768) (xy 298.12157 -381.302305) (xy 298.102777 -381.294534)
			(xy 298.088391 -381.28016) (xy 298.080604 -381.261374) (xy 298.080176 -381.251206) (xy 298.080176 -381.093472)
			(xy 298.079785 -381.084283) (xy 298.073258 -381.067098) (xy 298.067476 -381.059944) (xy 298.045707 -381.034276)
			(xy 298.007755 -380.978693) (xy 297.976719 -380.918972) (xy 297.953043 -380.855969) (xy 297.937068 -380.790589)
			(xy 297.929022 -380.723767) (xy 297.92902 -380.656463) (xy 294.650981 -380.656463) (xy 294.650979 -380.723828)
			(xy 294.642901 -380.790768) (xy 294.626863 -380.856258) (xy 294.603096 -380.919356) (xy 294.571942 -380.979153)
			(xy 294.53385 -381.034787) (xy 294.511984 -381.060452) (xy 294.506181 -381.067593) (xy 294.499671 -381.084787)
			(xy 294.499284 -381.09398) (xy 294.499284 -381.251206) (xy 294.498779 -381.26133) (xy 294.491054 -381.280047)
			(xy 294.476773 -381.294402) (xy 294.458097 -381.302225) (xy 294.447976 -381.302768) (xy 293.731696 -381.302768)
			(xy 293.721569 -381.302386) (xy 293.70286 -381.294631) (xy 293.688544 -381.280303) (xy 293.680805 -381.261587)
			(xy 293.680388 -381.25146) (xy 293.680388 -381.09398) (xy 293.67999 -381.084791) (xy 293.673468 -381.067607)
			(xy 293.667688 -381.060452) (xy 293.645844 -381.03477) (xy 293.607756 -380.979138) (xy 293.576605 -380.919344)
			(xy 293.55284 -380.856249) (xy 293.536803 -380.790762) (xy 293.528726 -380.723826) (xy 293.528724 -380.656404)
			(xy 290.250654 -380.656404) (xy 290.250661 -380.656462) (xy 290.25066 -380.723768) (xy 290.242614 -380.790591)
			(xy 290.22664 -380.855974) (xy 290.202966 -380.918979) (xy 290.171933 -380.978704) (xy 290.133984 -381.034291)
			(xy 290.112196 -381.059944) (xy 290.106398 -381.067088) (xy 290.099884 -381.084279) (xy 290.099496 -381.093472)
			(xy 290.099496 -381.251206) (xy 290.098972 -381.26136) (xy 290.091202 -381.280123) (xy 290.076846 -381.294486)
			(xy 290.058088 -381.302267) (xy 290.047934 -381.302768) (xy 289.331654 -381.302768) (xy 289.321494 -381.302304)
			(xy 289.302725 -381.294516) (xy 289.288362 -381.280141) (xy 289.280588 -381.261366) (xy 289.280092 -381.251206)
			(xy 289.280092 -381.093472) (xy 289.279697 -381.084283) (xy 289.273173 -381.067099) (xy 289.267392 -381.059944)
			(xy 289.245622 -381.034276) (xy 289.207669 -380.978693) (xy 289.176632 -380.918972) (xy 289.152956 -380.85597)
			(xy 289.13698 -380.790589) (xy 289.128934 -380.723767) (xy 289.128932 -380.656463) (xy 272.92786 -380.656463)
			(xy 272.867822 -380.687974) (xy 272.746027 -380.742789) (xy 272.621144 -380.790151) (xy 272.49363 -380.829886)
			(xy 272.363949 -380.861849) (xy 272.232575 -380.885924) (xy 272.099987 -380.902024) (xy 271.966669 -380.910088)
			(xy 271.833107 -380.910088) (xy 271.699789 -380.902024) (xy 271.567201 -380.885924) (xy 271.435827 -380.861849)
			(xy 271.306146 -380.829886) (xy 271.178632 -380.790151) (xy 271.053749 -380.742789) (xy 270.931954 -380.687974)
			(xy 270.813691 -380.625904) (xy 270.699392 -380.556808) (xy 270.589472 -380.480936) (xy 270.484335 -380.398566)
			(xy 270.384362 -380.309998) (xy 270.28992 -380.215556) (xy 270.201352 -380.115583) (xy 270.118982 -380.010446)
			(xy 270.04311 -379.900526) (xy 269.974014 -379.786227) (xy 269.911944 -379.667964) (xy 269.857129 -379.546169)
			(xy 269.809767 -379.421286) (xy 269.770032 -379.293772) (xy 269.738069 -379.164091) (xy 269.713994 -379.032717)
			(xy 269.697894 -378.900129) (xy 269.68983 -378.766811) (xy 262.508217 -378.766811) (xy 262.561832 -378.820426)
			(xy 262.579147 -378.8384) (xy 262.608475 -378.878779) (xy 262.631125 -378.92325) (xy 262.646539 -378.970716)
			(xy 262.654337 -379.020009) (xy 262.654796 -379.044962) (xy 262.654796 -382.223705) (xy 286.928753 -382.223705)
			(xy 286.928754 -382.15628) (xy 286.936832 -382.08934) (xy 286.95287 -382.02385) (xy 286.976638 -381.960752)
			(xy 287.007792 -381.900956) (xy 287.045886 -381.845322) (xy 287.067752 -381.819658) (xy 287.073555 -381.812518)
			(xy 287.080065 -381.795323) (xy 287.080452 -381.78613) (xy 287.080452 -381.628904) (xy 287.080987 -381.618801)
			(xy 287.088715 -381.600133) (xy 287.102996 -381.585839) (xy 287.121658 -381.578096) (xy 287.13176 -381.577596)
			(xy 287.84804 -381.577596) (xy 287.858151 -381.578052) (xy 287.876829 -381.585802) (xy 287.891122 -381.600108)
			(xy 287.898856 -381.618793) (xy 287.899348 -381.628904) (xy 287.899348 -381.78613) (xy 287.899755 -381.795317)
			(xy 287.906272 -381.812501) (xy 287.912048 -381.819658) (xy 287.933904 -381.84533) (xy 287.971996 -381.900963)
			(xy 288.00315 -381.960757) (xy 288.026917 -382.023853) (xy 288.042955 -382.089342) (xy 288.051033 -382.156281)
			(xy 288.051034 -382.223645) (xy 291.329073 -382.223645) (xy 291.329074 -382.15634) (xy 291.337119 -382.089516)
			(xy 291.353093 -382.024133) (xy 291.376767 -381.961128) (xy 291.407801 -381.901405) (xy 291.445751 -381.845818)
			(xy 291.46754 -381.820166) (xy 291.473339 -381.813022) (xy 291.479851 -381.795831) (xy 291.48024 -381.786638)
			(xy 291.48024 -381.628904) (xy 291.48062 -381.618777) (xy 291.488375 -381.600066) (xy 291.502703 -381.58575)
			(xy 291.52142 -381.578012) (xy 291.531548 -381.577596) (xy 292.248082 -381.577596) (xy 292.258202 -381.57814)
			(xy 292.276915 -381.585854) (xy 292.29127 -381.600122) (xy 292.299098 -381.618787) (xy 292.299644 -381.628904)
			(xy 292.299644 -381.786638) (xy 292.300049 -381.795826) (xy 292.306568 -381.813009) (xy 292.312344 -381.820166)
			(xy 292.334122 -381.845826) (xy 292.372072 -381.901411) (xy 292.403107 -381.961133) (xy 292.426781 -382.024137)
			(xy 292.442755 -382.089518) (xy 292.450801 -382.15634) (xy 292.450801 -382.223645) (xy 292.450794 -382.223705)
			(xy 295.728841 -382.223705) (xy 295.728842 -382.15628) (xy 295.73692 -382.08934) (xy 295.752957 -382.02385)
			(xy 295.776724 -381.960753) (xy 295.807878 -381.900957) (xy 295.84597 -381.845323) (xy 295.867836 -381.819658)
			(xy 295.873637 -381.812516) (xy 295.880148 -381.795323) (xy 295.880536 -381.78613) (xy 295.880536 -381.628904)
			(xy 295.88092 -381.618777) (xy 295.888674 -381.600067) (xy 295.903001 -381.585751) (xy 295.921717 -381.578012)
			(xy 295.931844 -381.577596) (xy 296.648124 -381.577596) (xy 296.658234 -381.578065) (xy 296.676912 -381.58581)
			(xy 296.691206 -381.600112) (xy 296.69894 -381.618794) (xy 296.699432 -381.628904) (xy 296.699432 -381.78613)
			(xy 296.699843 -381.795317) (xy 296.706358 -381.8125) (xy 296.712132 -381.819658) (xy 296.733985 -381.845332)
			(xy 296.772072 -381.900966) (xy 296.803221 -381.960761) (xy 296.826985 -382.023857) (xy 296.84302 -382.089345)
			(xy 296.851096 -382.156281) (xy 296.851097 -382.223704) (xy 296.851097 -382.223705) (xy 300.128632 -382.223705)
			(xy 300.128633 -382.15628) (xy 300.13671 -382.089341) (xy 300.152748 -382.023851) (xy 300.176514 -381.960753)
			(xy 300.207667 -381.900957) (xy 300.245759 -381.845323) (xy 300.267624 -381.819658) (xy 300.273424 -381.812515)
			(xy 300.279936 -381.795323) (xy 300.280324 -381.78613) (xy 300.280324 -381.628904) (xy 300.28072 -381.618779)
			(xy 300.288471 -381.600071) (xy 300.302794 -381.585755) (xy 300.321507 -381.578014) (xy 300.331632 -381.577596)
			(xy 301.047912 -381.577596) (xy 301.058021 -381.578075) (xy 301.076699 -381.585816) (xy 301.090993 -381.600115)
			(xy 301.098728 -381.618795) (xy 301.09922 -381.628904) (xy 301.09922 -381.78613) (xy 301.099611 -381.795319)
			(xy 301.106138 -381.812504) (xy 301.11192 -381.819658) (xy 301.133773 -381.845332) (xy 301.171861 -381.900965)
			(xy 301.203011 -381.960761) (xy 301.226775 -382.023856) (xy 301.242811 -382.089344) (xy 301.250887 -382.156281)
			(xy 301.250888 -382.223646) (xy 330.929191 -382.223646) (xy 330.929192 -382.156339) (xy 330.937238 -382.089516)
			(xy 330.953213 -382.024133) (xy 330.976888 -381.961128) (xy 331.007923 -381.901404) (xy 331.045875 -381.845818)
			(xy 331.067664 -381.820166) (xy 331.073465 -381.813025) (xy 331.079975 -381.795831) (xy 331.080364 -381.786638)
			(xy 331.080364 -381.628904) (xy 331.080824 -381.618755) (xy 331.088612 -381.600009) (xy 331.102996 -381.585687)
			(xy 331.121775 -381.577981) (xy 331.131926 -381.577596) (xy 331.848206 -381.577596) (xy 331.858328 -381.57812)
			(xy 331.877041 -381.585842) (xy 331.891395 -381.600116) (xy 331.899222 -381.618785) (xy 331.899768 -381.628904)
			(xy 331.899768 -381.786638) (xy 331.900167 -381.795826) (xy 331.906689 -381.81301) (xy 331.912468 -381.820166)
			(xy 331.934246 -381.845826) (xy 331.972195 -381.901412) (xy 332.003228 -381.961134) (xy 332.026901 -382.024138)
			(xy 332.042874 -382.089519) (xy 332.050919 -382.15634) (xy 332.05092 -382.223645) (xy 332.050913 -382.223704)
			(xy 335.328984 -382.223704) (xy 335.328985 -382.156281) (xy 335.337061 -382.089342) (xy 335.353096 -382.023853)
			(xy 335.37686 -381.960756) (xy 335.40801 -381.900959) (xy 335.446097 -381.845324) (xy 335.46796 -381.819658)
			(xy 335.473764 -381.812519) (xy 335.480273 -381.795323) (xy 335.48066 -381.78613) (xy 335.48066 -381.628904)
			(xy 335.481187 -381.6188) (xy 335.488916 -381.60013) (xy 335.5032 -381.585837) (xy 335.521865 -381.578095)
			(xy 335.531968 -381.577596) (xy 336.248248 -381.577596) (xy 336.258359 -381.578046) (xy 336.277038 -381.585799)
			(xy 336.291331 -381.600106) (xy 336.299064 -381.618792) (xy 336.299556 -381.628904) (xy 336.299556 -381.78613)
			(xy 336.299962 -381.795317) (xy 336.30648 -381.812501) (xy 336.312256 -381.819658) (xy 336.334112 -381.845331)
			(xy 336.372204 -381.900963) (xy 336.403357 -381.960758) (xy 336.427124 -382.023854) (xy 336.443161 -382.089342)
			(xy 336.451239 -382.156281) (xy 336.45124 -382.223645) (xy 339.729279 -382.223645) (xy 339.72928 -382.156339)
			(xy 339.737325 -382.089516) (xy 339.753299 -382.024133) (xy 339.776974 -381.961128) (xy 339.808009 -381.901404)
			(xy 339.845959 -381.845818) (xy 339.867748 -381.820166) (xy 339.873547 -381.813023) (xy 339.880059 -381.795831)
			(xy 339.880448 -381.786638) (xy 339.880448 -381.628904) (xy 339.880924 -381.618757) (xy 339.888708 -381.600014)
			(xy 339.903088 -381.585693) (xy 339.921861 -381.577984) (xy 339.93201 -381.577596) (xy 340.64829 -381.577596)
			(xy 340.658411 -381.578133) (xy 340.677123 -381.58585) (xy 340.691478 -381.60012) (xy 340.699306 -381.618786)
			(xy 340.699852 -381.628904) (xy 340.699852 -381.786638) (xy 340.700255 -381.795826) (xy 340.706775 -381.813009)
			(xy 340.712552 -381.820166) (xy 340.73433 -381.845826) (xy 340.77228 -381.901411) (xy 340.803314 -381.961134)
			(xy 340.826988 -382.024137) (xy 340.842962 -382.089518) (xy 340.851007 -382.15634) (xy 340.851007 -382.223645)
			(xy 344.12907 -382.223645) (xy 344.129071 -382.15634) (xy 344.137116 -382.089516) (xy 344.15309 -382.024134)
			(xy 344.176764 -381.961129) (xy 344.207798 -381.901405) (xy 344.245748 -381.845818) (xy 344.267536 -381.820166)
			(xy 344.273334 -381.813022) (xy 344.279847 -381.79583) (xy 344.280236 -381.786638) (xy 344.280236 -381.628904)
			(xy 344.280626 -381.618746) (xy 344.288427 -381.599986) (xy 344.302834 -381.585662) (xy 344.321637 -381.577968)
			(xy 344.331798 -381.577596) (xy 345.048078 -381.577596) (xy 345.058198 -381.578143) (xy 345.07691 -381.585856)
			(xy 345.091266 -381.600123) (xy 345.099094 -381.618787) (xy 345.09964 -381.628904) (xy 345.09964 -381.786638)
			(xy 345.100045 -381.795825) (xy 345.106564 -381.813009) (xy 345.11234 -381.820166) (xy 345.134118 -381.845826)
			(xy 345.172069 -381.901411) (xy 345.203104 -381.961133) (xy 345.226778 -382.024137) (xy 345.242752 -382.089518)
			(xy 345.250798 -382.15634) (xy 345.250798 -382.223645) (xy 345.250798 -382.223646) (xy 374.9291 -382.223646)
			(xy 374.929101 -382.156339) (xy 374.937147 -382.089515) (xy 374.953122 -382.024132) (xy 374.976798 -381.961127)
			(xy 375.007834 -381.901404) (xy 375.045787 -381.845818) (xy 375.067576 -381.820166) (xy 375.073367 -381.813016)
			(xy 375.079886 -381.795829) (xy 375.080276 -381.786638) (xy 375.080276 -381.628904) (xy 375.080724 -381.618753)
			(xy 375.088514 -381.600005) (xy 375.102902 -381.585683) (xy 375.121685 -381.577979) (xy 375.131838 -381.577596)
			(xy 375.848118 -381.577596) (xy 375.85824 -381.57811) (xy 375.876954 -381.585836) (xy 375.891308 -381.600113)
			(xy 375.899134 -381.618784) (xy 375.89968 -381.628904) (xy 375.89968 -381.786638) (xy 375.900076 -381.795827)
			(xy 375.9066 -381.813011) (xy 375.91238 -381.820166) (xy 375.934157 -381.845826) (xy 375.972105 -381.901412)
			(xy 376.003138 -381.961135) (xy 376.02681 -382.024138) (xy 376.042784 -382.089519) (xy 376.050828 -382.156341)
			(xy 376.050829 -382.223644) (xy 376.050822 -382.223704) (xy 379.328893 -382.223704) (xy 379.328894 -382.156281)
			(xy 379.33697 -382.089342) (xy 379.353006 -382.023853) (xy 379.37677 -381.960756) (xy 379.40792 -381.900959)
			(xy 379.446008 -381.845324) (xy 379.467872 -381.819658) (xy 379.473678 -381.81252) (xy 379.480185 -381.795324)
			(xy 379.480572 -381.78613) (xy 379.480572 -381.628904) (xy 379.481088 -381.618799) (xy 379.488819 -381.600126)
			(xy 379.503106 -381.585832) (xy 379.521775 -381.578092) (xy 379.53188 -381.577596) (xy 380.24816 -381.577596)
			(xy 380.258279 -381.578049) (xy 380.276981 -381.585783) (xy 380.291297 -381.600088) (xy 380.299044 -381.618785)
			(xy 380.299468 -381.628904) (xy 380.299468 -381.78613) (xy 380.299871 -381.795318) (xy 380.30639 -381.812502)
			(xy 380.312168 -381.819658) (xy 380.334023 -381.845331) (xy 380.372114 -381.900963) (xy 380.403267 -381.960758)
			(xy 380.427033 -382.023854) (xy 380.443071 -382.089343) (xy 380.451148 -382.156281) (xy 380.451149 -382.223646)
			(xy 383.729188 -382.223646) (xy 383.729189 -382.156339) (xy 383.737235 -382.089516) (xy 383.753209 -382.024133)
			(xy 383.776884 -381.961128) (xy 383.80792 -381.901404) (xy 383.845871 -381.845818) (xy 383.86766 -381.820166)
			(xy 383.873461 -381.813024) (xy 383.879971 -381.795831) (xy 383.88036 -381.786638) (xy 383.88036 -381.628904)
			(xy 383.880824 -381.618755) (xy 383.888611 -381.600011) (xy 383.902994 -381.585689) (xy 383.921771 -381.577981)
			(xy 383.931922 -381.577596) (xy 384.648202 -381.577596) (xy 384.658323 -381.578124) (xy 384.677036 -381.585844)
			(xy 384.691391 -381.600117) (xy 384.699218 -381.618786) (xy 384.699764 -381.628904) (xy 384.699764 -381.786638)
			(xy 384.700164 -381.795826) (xy 384.706686 -381.81301) (xy 384.712464 -381.820166) (xy 384.734242 -381.845826)
			(xy 384.772191 -381.901412) (xy 384.803224 -381.961134) (xy 384.826898 -382.024137) (xy 384.842871 -382.089519)
			(xy 384.850916 -382.15634) (xy 384.850917 -382.223645) (xy 388.128979 -382.223645) (xy 388.12898 -382.156339)
			(xy 388.137025 -382.089516) (xy 388.152999 -382.024133) (xy 388.176674 -381.961128) (xy 388.207709 -381.901404)
			(xy 388.245659 -381.845818) (xy 388.267448 -381.820166) (xy 388.273247 -381.813023) (xy 388.279759 -381.795831)
			(xy 388.280148 -381.786638) (xy 388.280148 -381.628904) (xy 388.280624 -381.618757) (xy 388.288408 -381.600014)
			(xy 388.302788 -381.585693) (xy 388.321561 -381.577984) (xy 388.33171 -381.577596) (xy 389.04799 -381.577596)
			(xy 389.058111 -381.578133) (xy 389.076823 -381.58585) (xy 389.091178 -381.60012) (xy 389.099006 -381.618786)
			(xy 389.099552 -381.628904) (xy 389.099552 -381.786638) (xy 389.099955 -381.795826) (xy 389.106475 -381.813009)
			(xy 389.112252 -381.820166) (xy 389.13403 -381.845826) (xy 389.17198 -381.901411) (xy 389.203014 -381.961134)
			(xy 389.226688 -382.024137) (xy 389.242662 -382.089518) (xy 389.250707 -382.15634) (xy 389.250707 -382.223645)
			(xy 389.250707 -382.223646) (xy 418.92901 -382.223646) (xy 418.92901 -382.156339) (xy 418.937056 -382.089515)
			(xy 418.953032 -382.024132) (xy 418.976708 -381.961127) (xy 419.007745 -381.901403) (xy 419.045698 -381.845818)
			(xy 419.067488 -381.820166) (xy 419.07328 -381.813018) (xy 419.079798 -381.79583) (xy 419.080188 -381.786638)
			(xy 419.080188 -381.628904) (xy 419.080688 -381.618797) (xy 419.088422 -381.600121) (xy 419.102714 -381.585827)
			(xy 419.121389 -381.57809) (xy 419.131496 -381.577596) (xy 419.84803 -381.577596) (xy 419.858153 -381.578101)
			(xy 419.876867 -381.58583) (xy 419.89122 -381.60011) (xy 419.899046 -381.618783) (xy 419.899592 -381.628904)
			(xy 419.899592 -381.786638) (xy 419.899986 -381.795827) (xy 419.906511 -381.813011) (xy 419.912292 -381.820166)
			(xy 419.934069 -381.845827) (xy 419.972016 -381.901413) (xy 420.003048 -381.961135) (xy 420.02672 -382.024139)
			(xy 420.042693 -382.089519) (xy 420.050737 -382.156341) (xy 420.050738 -382.223644) (xy 420.050731 -382.223705)
			(xy 423.328802 -382.223705) (xy 423.328803 -382.15628) (xy 423.33688 -382.089342) (xy 423.352916 -382.023852)
			(xy 423.37668 -381.960755) (xy 423.407831 -381.900959) (xy 423.44592 -381.845324) (xy 423.467784 -381.819658)
			(xy 423.473579 -381.812512) (xy 423.480095 -381.795322) (xy 423.480484 -381.78613) (xy 423.480484 -381.628904)
			(xy 423.480988 -381.618798) (xy 423.488721 -381.600122) (xy 423.503012 -381.585828) (xy 423.521686 -381.57809)
			(xy 423.531792 -381.577596) (xy 424.248072 -381.577596) (xy 424.258192 -381.578039) (xy 424.276895 -381.585777)
			(xy 424.29121 -381.600085) (xy 424.298957 -381.618784) (xy 424.29938 -381.628904) (xy 424.29938 -381.78613)
			(xy 424.29978 -381.795318) (xy 424.306301 -381.812502) (xy 424.31208 -381.819658) (xy 424.333935 -381.845331)
			(xy 424.372025 -381.900964) (xy 424.403177 -381.960759) (xy 424.426943 -382.023855) (xy 424.44298 -382.089343)
			(xy 424.451057 -382.156281) (xy 424.451058 -382.223646) (xy 427.729097 -382.223646) (xy 427.729098 -382.156339)
			(xy 427.737144 -382.089515) (xy 427.753119 -382.024132) (xy 427.776794 -381.961127) (xy 427.807831 -381.901404)
			(xy 427.845783 -381.845818) (xy 427.867572 -381.820166) (xy 427.873374 -381.813025) (xy 427.879883 -381.795831)
			(xy 427.880272 -381.786638) (xy 427.880272 -381.628904) (xy 427.880724 -381.618754) (xy 427.888513 -381.600007)
			(xy 427.9029 -381.585684) (xy 427.921682 -381.577979) (xy 427.931834 -381.577596) (xy 428.648114 -381.577596)
			(xy 428.658236 -381.578114) (xy 428.676949 -381.585838) (xy 428.691303 -381.600114) (xy 428.69913 -381.618785)
			(xy 428.699676 -381.628904) (xy 428.699676 -381.786638) (xy 428.700073 -381.795826) (xy 428.706596 -381.81301)
			(xy 428.712376 -381.820166) (xy 428.734154 -381.845826) (xy 428.772102 -381.901412) (xy 428.803135 -381.961135)
			(xy 428.826807 -382.024138) (xy 428.84278 -382.089519) (xy 428.850825 -382.15634) (xy 428.850826 -382.223644)
			(xy 428.850826 -382.223646) (xy 432.128888 -382.223646) (xy 432.128889 -382.156339) (xy 432.136935 -382.089516)
			(xy 432.152909 -382.024133) (xy 432.176584 -381.961128) (xy 432.20762 -381.901404) (xy 432.245571 -381.845818)
			(xy 432.26736 -381.820166) (xy 432.273161 -381.813024) (xy 432.279671 -381.795831) (xy 432.28006 -381.786638)
			(xy 432.28006 -381.628904) (xy 432.280524 -381.618755) (xy 432.288311 -381.600011) (xy 432.302694 -381.585689)
			(xy 432.321471 -381.577981) (xy 432.331622 -381.577596) (xy 433.047902 -381.577596) (xy 433.058023 -381.578124)
			(xy 433.076736 -381.585844) (xy 433.091091 -381.600117) (xy 433.098918 -381.618786) (xy 433.099464 -381.628904)
			(xy 433.099464 -381.786638) (xy 433.099864 -381.795826) (xy 433.106386 -381.81301) (xy 433.112164 -381.820166)
			(xy 433.133942 -381.845826) (xy 433.171891 -381.901412) (xy 433.202924 -381.961134) (xy 433.226598 -382.024137)
			(xy 433.242571 -382.089519) (xy 433.250616 -382.15634) (xy 433.250617 -382.223645) (xy 433.242574 -382.290466)
			(xy 433.226602 -382.355848) (xy 433.202931 -382.418852) (xy 433.171899 -382.478576) (xy 433.133951 -382.534162)
			(xy 433.112164 -382.559814) (xy 433.106374 -382.566964) (xy 433.099856 -382.584151) (xy 433.099464 -382.593342)
			(xy 433.099464 -383.086864) (xy 433.0999 -383.096048) (xy 433.106397 -383.113232) (xy 433.112164 -383.120392)
			(xy 433.133967 -383.146031) (xy 433.171916 -383.20162) (xy 433.202948 -383.261345) (xy 433.226386 -383.323727)
			(xy 434.32903 -383.323727) (xy 434.329034 -383.256419) (xy 434.337081 -383.189595) (xy 434.353057 -383.124211)
			(xy 434.376732 -383.061205) (xy 434.407768 -383.00148) (xy 434.445719 -382.945893) (xy 434.467508 -382.92024)
			(xy 434.473313 -382.913101) (xy 434.479823 -382.895906) (xy 434.480208 -382.886712) (xy 434.480208 -382.728724)
			(xy 434.480641 -382.71857) (xy 434.48843 -382.699817) (xy 434.502824 -382.685492) (xy 434.521614 -382.677793)
			(xy 434.53177 -382.677416) (xy 435.24805 -382.677416) (xy 435.258171 -382.677967) (xy 435.276886 -382.685674)
			(xy 435.291243 -382.69994) (xy 435.299068 -382.718607) (xy 435.299612 -382.728724) (xy 435.299612 -382.886712)
			(xy 435.300014 -382.8959) (xy 435.306533 -382.913084) (xy 435.312312 -382.92024) (xy 435.334066 -382.945921)
			(xy 435.372019 -383.001502) (xy 435.403056 -383.061221) (xy 435.426733 -383.124222) (xy 435.44271 -383.189601)
			(xy 435.450758 -383.256421) (xy 435.450761 -383.323724) (xy 435.44272 -383.390546) (xy 435.426749 -383.455926)
			(xy 435.403079 -383.518929) (xy 435.372047 -383.578652) (xy 435.334099 -383.634237) (xy 435.312312 -383.659888)
			(xy 435.306497 -383.66702) (xy 435.299993 -383.684221) (xy 435.299612 -383.693416) (xy 435.299612 -384.186684)
			(xy 435.300027 -384.195871) (xy 435.306537 -384.213055) (xy 435.312312 -384.220212) (xy 435.334137 -384.245834)
			(xy 435.372087 -384.301424) (xy 435.403122 -384.361151) (xy 435.426795 -384.42416) (xy 435.442767 -384.489546)
			(xy 435.450809 -384.556373) (xy 435.450805 -384.623681) (xy 435.442757 -384.690507) (xy 435.426779 -384.755892)
			(xy 435.4031 -384.818898) (xy 435.37206 -384.878623) (xy 435.334103 -384.934208) (xy 435.312312 -384.95986)
			(xy 435.306509 -384.967001) (xy 435.299998 -384.984195) (xy 435.299612 -384.993388) (xy 435.299612 -385.151376)
			(xy 435.299159 -385.161527) (xy 435.291374 -385.180277) (xy 435.276987 -385.194601) (xy 435.258203 -385.202303)
			(xy 435.24805 -385.202684) (xy 434.53177 -385.202684) (xy 434.521644 -385.202199) (xy 434.502927 -385.194466)
			(xy 434.488573 -385.180179) (xy 434.48075 -385.161499) (xy 434.480208 -385.151376) (xy 434.480208 -384.993388)
			(xy 434.479802 -384.9842) (xy 434.473285 -384.967016) (xy 434.467508 -384.95986) (xy 434.445757 -384.934178)
			(xy 434.407809 -384.878595) (xy 434.376776 -384.818876) (xy 434.353102 -384.755875) (xy 434.337128 -384.690497)
			(xy 434.329081 -384.623678) (xy 434.329078 -384.556376) (xy 434.337118 -384.489557) (xy 434.353086 -384.424177)
			(xy 434.376753 -384.361174) (xy 434.407781 -384.301451) (xy 434.445723 -384.245864) (xy 434.467508 -384.220212)
			(xy 434.473325 -384.213082) (xy 434.479827 -384.19588) (xy 434.480208 -384.186684) (xy 434.480208 -383.693416)
			(xy 434.479788 -383.68423) (xy 434.473281 -383.667046) (xy 434.467508 -383.659888) (xy 434.445686 -383.634265)
			(xy 434.40774 -383.578673) (xy 434.37671 -383.518945) (xy 434.353041 -383.455937) (xy 434.337071 -383.390552)
			(xy 434.32903 -383.323727) (xy 433.226386 -383.323727) (xy 433.22662 -383.324351) (xy 433.242592 -383.389735)
			(xy 433.250634 -383.456559) (xy 433.250633 -383.523865) (xy 433.242587 -383.590689) (xy 433.226613 -383.656072)
			(xy 433.202938 -383.719077) (xy 433.171903 -383.778801) (xy 433.133953 -383.834388) (xy 433.112164 -383.86004)
			(xy 433.106363 -383.867182) (xy 433.099852 -383.884375) (xy 433.099464 -383.893568) (xy 433.099464 -384.051556)
			(xy 433.099042 -384.061712) (xy 433.091254 -384.08047) (xy 433.076856 -384.094796) (xy 433.05806 -384.102491)
			(xy 433.047902 -384.102864) (xy 432.331622 -384.102864) (xy 432.321497 -384.102356) (xy 432.302777 -384.094636)
			(xy 432.28842 -384.080356) (xy 432.2806 -384.061678) (xy 432.28006 -384.051556) (xy 432.28006 -383.893568)
			(xy 432.279652 -383.884381) (xy 432.273135 -383.867197) (xy 432.26736 -383.86004) (xy 432.245587 -383.834375)
			(xy 432.207637 -383.778791) (xy 432.176602 -383.719069) (xy 432.152927 -383.656066) (xy 432.136952 -383.590686)
			(xy 432.128907 -383.523864) (xy 432.128905 -383.45656) (xy 432.136948 -383.389738) (xy 432.15292 -383.324357)
			(xy 432.176592 -383.261353) (xy 432.207624 -383.20163) (xy 432.245573 -383.146044) (xy 432.26736 -383.120392)
			(xy 432.27315 -383.113242) (xy 432.279667 -383.096055) (xy 432.28006 -383.086864) (xy 432.28006 -382.593342)
			(xy 432.279616 -382.584159) (xy 432.273125 -382.566975) (xy 432.26736 -382.559814) (xy 432.245562 -382.53417)
			(xy 432.207612 -382.478583) (xy 432.176578 -382.418858) (xy 432.152905 -382.355853) (xy 432.136932 -382.290469)
			(xy 432.128888 -382.223646) (xy 428.850826 -382.223646) (xy 428.842783 -382.290466) (xy 428.826812 -382.355848)
			(xy 428.803141 -382.418852) (xy 428.772109 -382.478575) (xy 428.734163 -382.534162) (xy 428.712376 -382.559814)
			(xy 428.706588 -382.566965) (xy 428.700069 -382.584151) (xy 428.699676 -382.593342) (xy 428.699676 -383.086864)
			(xy 428.700109 -383.096049) (xy 428.706607 -383.113233) (xy 428.712376 -383.120392) (xy 428.734179 -383.146031)
			(xy 428.772126 -383.20162) (xy 428.803158 -383.261345) (xy 428.826616 -383.323786) (xy 429.928711 -383.323786)
			(xy 429.928714 -383.25636) (xy 429.936794 -383.189418) (xy 429.952834 -383.123927) (xy 429.976603 -383.060829)
			(xy 430.007759 -383.001032) (xy 430.045853 -382.945397) (xy 430.06772 -382.919732) (xy 430.07353 -382.912597)
			(xy 430.080036 -382.895398) (xy 430.08042 -382.886204) (xy 430.08042 -382.728724) (xy 430.080836 -382.718601)
			(xy 430.08858 -382.699894) (xy 430.102897 -382.685578) (xy 430.121605 -382.677835) (xy 430.131728 -382.677416)
			(xy 430.848008 -382.677416) (xy 430.858133 -382.67781) (xy 430.87684 -382.685564) (xy 430.891154 -382.699887)
			(xy 430.898896 -382.718599) (xy 430.899316 -382.728724) (xy 430.899316 -382.886204) (xy 430.899721 -382.895392)
			(xy 430.906238 -382.912576) (xy 430.912016 -382.919732) (xy 430.933844 -382.945427) (xy 430.971933 -383.001057)
			(xy 431.003084 -383.06085) (xy 431.02685 -383.123943) (xy 431.042887 -383.189428) (xy 431.050966 -383.256363)
			(xy 431.050969 -383.323783) (xy 431.042897 -383.390719) (xy 431.026866 -383.456206) (xy 431.003106 -383.519301)
			(xy 430.971961 -383.579096) (xy 430.933877 -383.634731) (xy 430.912016 -383.660396) (xy 430.90624 -383.667556)
			(xy 430.899713 -383.684735) (xy 430.899316 -383.693924) (xy 430.899316 -384.186176) (xy 430.899734 -384.195362)
			(xy 430.906242 -384.212547) (xy 430.912016 -384.219704) (xy 430.933915 -384.24534) (xy 430.972001 -384.300979)
			(xy 431.00315 -384.36078) (xy 431.026911 -384.42388) (xy 431.042944 -384.489373) (xy 431.051016 -384.556314)
			(xy 431.051013 -384.62374) (xy 431.042934 -384.690681) (xy 431.026895 -384.756171) (xy 431.003128 -384.81927)
			(xy 430.971974 -384.879067) (xy 430.933882 -384.934702) (xy 430.912016 -384.960368) (xy 430.90621 -384.967507)
			(xy 430.8997 -384.984702) (xy 430.899316 -384.993896) (xy 430.899316 -385.151376) (xy 430.898865 -385.161495)
			(xy 430.891128 -385.180195) (xy 430.876822 -385.19451) (xy 430.858127 -385.202259) (xy 430.848008 -385.202684)
			(xy 430.131728 -385.202684) (xy 430.121605 -385.202261) (xy 430.102899 -385.194519) (xy 430.088583 -385.180204)
			(xy 430.08084 -385.161499) (xy 430.08042 -385.151376) (xy 430.08042 -384.993896) (xy 430.080008 -384.984709)
			(xy 430.073495 -384.967525) (xy 430.06772 -384.960368) (xy 430.045891 -384.934674) (xy 430.0078 -384.879044)
			(xy 429.976646 -384.819252) (xy 429.952879 -384.756159) (xy 429.936841 -384.690673) (xy 429.928761 -384.623738)
			(xy 429.928758 -384.556316) (xy 429.936831 -384.48938) (xy 429.952863 -384.423893) (xy 429.976624 -384.360797)
			(xy 430.007772 -384.301002) (xy 430.045857 -384.245369) (xy 430.06772 -384.219704) (xy 430.0735 -384.212547)
			(xy 430.080024 -384.195365) (xy 430.08042 -384.186176) (xy 430.08042 -383.693924) (xy 430.079994 -383.684739)
			(xy 430.073491 -383.667554) (xy 430.06772 -383.660396) (xy 430.04582 -383.63476) (xy 430.007731 -383.579122)
			(xy 429.976581 -383.519322) (xy 429.952818 -383.456221) (xy 429.936784 -383.390728) (xy 429.928711 -383.323786)
			(xy 428.826616 -383.323786) (xy 428.826829 -383.324352) (xy 428.842801 -383.389735) (xy 428.850843 -383.456559)
			(xy 428.850842 -383.523865) (xy 428.842797 -383.590688) (xy 428.826822 -383.656071) (xy 428.803148 -383.719077)
			(xy 428.772114 -383.778801) (xy 428.734164 -383.834388) (xy 428.712376 -383.86004) (xy 428.706577 -383.867183)
			(xy 428.700065 -383.884375) (xy 428.699676 -383.893568) (xy 428.699676 -384.051556) (xy 428.699242 -384.06171)
			(xy 428.691456 -384.080466) (xy 428.677063 -384.094792) (xy 428.65827 -384.102489) (xy 428.648114 -384.102864)
			(xy 427.931834 -384.102864) (xy 427.92171 -384.102345) (xy 427.90299 -384.09463) (xy 427.888633 -384.080353)
			(xy 427.880812 -384.061677) (xy 427.880272 -384.051556) (xy 427.880272 -383.893568) (xy 427.879883 -383.884378)
			(xy 427.873355 -383.867194) (xy 427.867572 -383.86004) (xy 427.845799 -383.834375) (xy 427.807848 -383.778791)
			(xy 427.776812 -383.71907) (xy 427.753137 -383.656067) (xy 427.737162 -383.590686) (xy 427.729116 -383.523864)
			(xy 427.729114 -383.45656) (xy 427.737157 -383.389738) (xy 427.75313 -383.324356) (xy 427.776802 -383.261352)
			(xy 427.807835 -383.201629) (xy 427.845784 -383.146044) (xy 427.867572 -383.120392) (xy 427.873363 -383.113243)
			(xy 427.879879 -383.096055) (xy 427.880272 -383.086864) (xy 427.880272 -382.593342) (xy 427.879848 -382.584156)
			(xy 427.873344 -382.566971) (xy 427.867572 -382.559814) (xy 427.845774 -382.53417) (xy 427.807823 -382.478583)
			(xy 427.776788 -382.418859) (xy 427.753115 -382.355853) (xy 427.737141 -382.29047) (xy 427.729097 -382.223646)
			(xy 424.451058 -382.223646) (xy 424.451058 -382.223704) (xy 424.442983 -382.290642) (xy 424.426948 -382.356131)
			(xy 424.403184 -382.419227) (xy 424.372033 -382.479023) (xy 424.333944 -382.534657) (xy 424.31208 -382.560322)
			(xy 424.306289 -382.567471) (xy 424.299772 -382.584659) (xy 424.29938 -382.59385) (xy 424.29938 -383.086356)
			(xy 424.299816 -383.09554) (xy 424.306312 -383.112725) (xy 424.31208 -383.119884) (xy 424.33396 -383.145536)
			(xy 424.37205 -383.201172) (xy 424.403201 -383.26097) (xy 424.426837 -383.323727) (xy 425.528942 -383.323727)
			(xy 425.528946 -383.256419) (xy 425.536993 -383.189594) (xy 425.55297 -383.12421) (xy 425.576646 -383.061204)
			(xy 425.607682 -383.00148) (xy 425.645635 -382.945892) (xy 425.667424 -382.92024) (xy 425.673231 -382.913103)
			(xy 425.679739 -382.895906) (xy 425.680124 -382.886712) (xy 425.680124 -382.728724) (xy 425.680536 -382.7186)
			(xy 425.688281 -382.699892) (xy 425.702599 -382.685576) (xy 425.721308 -382.677834) (xy 425.731432 -382.677416)
			(xy 426.447966 -382.677416) (xy 426.458088 -382.677954) (xy 426.476803 -382.685666) (xy 426.49116 -382.699937)
			(xy 426.498984 -382.718606) (xy 426.499528 -382.728724) (xy 426.499528 -382.886712) (xy 426.499926 -382.895901)
			(xy 426.506447 -382.913085) (xy 426.512228 -382.92024) (xy 426.533981 -382.945921) (xy 426.571933 -383.001502)
			(xy 426.60297 -383.061222) (xy 426.626646 -383.124223) (xy 426.642623 -383.189602) (xy 426.65067 -383.256422)
			(xy 426.650673 -383.323724) (xy 426.642632 -383.390545) (xy 426.626662 -383.455926) (xy 426.602992 -383.518929)
			(xy 426.571961 -383.578651) (xy 426.534014 -383.634236) (xy 426.512228 -383.659888) (xy 426.506403 -383.667013)
			(xy 426.499907 -383.684219) (xy 426.499528 -383.693416) (xy 426.499528 -384.186684) (xy 426.499939 -384.195871)
			(xy 426.506451 -384.213056) (xy 426.512228 -384.220212) (xy 426.534052 -384.245834) (xy 426.572002 -384.301424)
			(xy 426.603036 -384.361152) (xy 426.626708 -384.42416) (xy 426.64268 -384.489546) (xy 426.650721 -384.556373)
			(xy 426.650718 -384.623681) (xy 426.64267 -384.690507) (xy 426.626692 -384.755892) (xy 426.603014 -384.818898)
			(xy 426.571974 -384.878622) (xy 426.534019 -384.934208) (xy 426.512228 -384.95986) (xy 426.506415 -384.966993)
			(xy 426.499912 -384.984193) (xy 426.499528 -384.993388) (xy 426.499528 -385.151376) (xy 426.499065 -385.161494)
			(xy 426.49133 -385.180191) (xy 426.477028 -385.194505) (xy 426.458337 -385.202257) (xy 426.44822 -385.202684)
			(xy 425.731686 -385.202684) (xy 425.721561 -385.202185) (xy 425.702845 -385.194457) (xy 425.68849 -385.180175)
			(xy 425.680667 -385.161498) (xy 425.680124 -385.151376) (xy 425.680124 -384.993388) (xy 425.679714 -384.984201)
			(xy 425.6732 -384.967017) (xy 425.667424 -384.95986) (xy 425.645672 -384.934178) (xy 425.607723 -384.878596)
			(xy 425.576689 -384.818876) (xy 425.553015 -384.755876) (xy 425.53704 -384.690497) (xy 425.528994 -384.623678)
			(xy 425.52899 -384.556376) (xy 425.537031 -384.489556) (xy 425.552999 -384.424176) (xy 425.576667 -384.361173)
			(xy 425.607696 -384.301451) (xy 425.645639 -384.245865) (xy 425.667424 -384.220212) (xy 425.673243 -384.213083)
			(xy 425.679744 -384.19588) (xy 425.680124 -384.186684) (xy 425.680124 -383.693416) (xy 425.679701 -383.68423)
			(xy 425.673195 -383.667046) (xy 425.667424 -383.659888) (xy 425.645601 -383.634265) (xy 425.607655 -383.578674)
			(xy 425.576624 -383.518946) (xy 425.552954 -383.455938) (xy 425.536984 -383.390552) (xy 425.528942 -383.323727)
			(xy 424.426837 -383.323727) (xy 424.426965 -383.324068) (xy 424.443 -383.389559) (xy 424.451075 -383.456499)
			(xy 424.451074 -383.523925) (xy 424.442996 -383.590864) (xy 424.426958 -383.656355) (xy 424.403191 -383.719452)
			(xy 424.372038 -383.779249) (xy 424.333946 -383.834883) (xy 424.31208 -383.860548) (xy 424.306278 -383.867689)
			(xy 424.299767 -383.884883) (xy 424.29938 -383.894076) (xy 424.29938 -384.051556) (xy 424.298947 -384.061678)
			(xy 424.29121 -384.080385) (xy 424.276898 -384.094701) (xy 424.258194 -384.102444) (xy 424.248072 -384.102864)
			(xy 423.531792 -384.102864) (xy 423.521665 -384.10249) (xy 423.502954 -384.094732) (xy 423.488639 -384.080402)
			(xy 423.4809 -384.061684) (xy 423.480484 -384.051556) (xy 423.480484 -383.894076) (xy 423.480089 -383.884887)
			(xy 423.473565 -383.867703) (xy 423.467784 -383.860548) (xy 423.445936 -383.83487) (xy 423.407848 -383.779237)
			(xy 423.376698 -383.719442) (xy 423.352933 -383.656347) (xy 423.336897 -383.59086) (xy 423.32882 -383.523923)
			(xy 423.328819 -383.456501) (xy 423.336893 -383.389564) (xy 423.352926 -383.324076) (xy 423.376688 -383.26098)
			(xy 423.407836 -383.201184) (xy 423.445922 -383.145549) (xy 423.467784 -383.119884) (xy 423.473568 -383.11273)
			(xy 423.480091 -383.095546) (xy 423.480484 -383.086356) (xy 423.480484 -382.59385) (xy 423.480054 -382.584665)
			(xy 423.473554 -382.56748) (xy 423.467784 -382.560322) (xy 423.445911 -382.534665) (xy 423.407823 -382.479029)
			(xy 423.376674 -382.419231) (xy 423.352911 -382.356133) (xy 423.336877 -382.290643) (xy 423.328802 -382.223705)
			(xy 420.050731 -382.223705) (xy 420.042695 -382.290466) (xy 420.026725 -382.355847) (xy 420.003054 -382.418851)
			(xy 419.972024 -382.478574) (xy 419.934078 -382.534161) (xy 419.912292 -382.559814) (xy 419.906506 -382.566967)
			(xy 419.899985 -382.584151) (xy 419.899592 -382.593342) (xy 419.899592 -383.086864) (xy 419.900021 -383.096049)
			(xy 419.906522 -383.113234) (xy 419.912292 -383.120392) (xy 419.934094 -383.146032) (xy 419.972041 -383.201621)
			(xy 420.003072 -383.261346) (xy 420.02653 -383.323787) (xy 421.128623 -383.323787) (xy 421.128626 -383.256359)
			(xy 421.136706 -383.189418) (xy 421.152747 -383.123926) (xy 421.176516 -383.060828) (xy 421.207673 -383.001031)
			(xy 421.245769 -382.945397) (xy 421.267636 -382.919732) (xy 421.273449 -382.912598) (xy 421.279953 -382.895399)
			(xy 421.280336 -382.886204) (xy 421.280336 -382.728724) (xy 421.280736 -382.718599) (xy 421.288483 -382.699889)
			(xy 421.302805 -382.685572) (xy 421.321518 -382.677832) (xy 421.331644 -382.677416) (xy 422.047924 -382.677416)
			(xy 422.058036 -382.677866) (xy 422.076718 -382.685614) (xy 422.091013 -382.699922) (xy 422.098744 -382.718611)
			(xy 422.099232 -382.728724) (xy 422.099232 -382.886204) (xy 422.099656 -382.895389) (xy 422.106162 -382.912573)
			(xy 422.111932 -382.919732) (xy 422.133759 -382.945427) (xy 422.171847 -383.001058) (xy 422.202998 -383.06085)
			(xy 422.226762 -383.123943) (xy 422.242799 -383.189428) (xy 422.250878 -383.256363) (xy 422.250881 -383.323783)
			(xy 422.242809 -383.390718) (xy 422.226778 -383.456205) (xy 422.20302 -383.5193) (xy 422.171875 -383.579096)
			(xy 422.133793 -383.63473) (xy 422.111932 -383.660396) (xy 422.106146 -383.667549) (xy 422.099627 -383.684734)
			(xy 422.099232 -383.693924) (xy 422.099232 -384.186176) (xy 422.099669 -384.19536) (xy 422.106166 -384.212544)
			(xy 422.111932 -384.219704) (xy 422.13383 -384.245341) (xy 422.171916 -384.30098) (xy 422.203063 -384.36078)
			(xy 422.226824 -384.423881) (xy 422.242856 -384.489373) (xy 422.250928 -384.556314) (xy 422.250925 -384.62374)
			(xy 422.242846 -384.69068) (xy 422.226808 -384.756171) (xy 422.203041 -384.819269) (xy 422.171888 -384.879066)
			(xy 422.133797 -384.934702) (xy 422.111932 -384.960368) (xy 422.106116 -384.967499) (xy 422.099615 -384.984701)
			(xy 422.099232 -384.993896) (xy 422.099232 -385.151376) (xy 422.098696 -385.161479) (xy 422.090972 -385.180151)
			(xy 422.076691 -385.194445) (xy 422.058027 -385.202187) (xy 422.047924 -385.202684) (xy 421.331644 -385.202684)
			(xy 421.321522 -385.202247) (xy 421.302817 -385.194511) (xy 421.2885 -385.1802) (xy 421.280756 -385.161497)
			(xy 421.280336 -385.151376) (xy 421.280336 -384.993896) (xy 421.27992 -384.98471) (xy 421.27341 -384.967526)
			(xy 421.267636 -384.960368) (xy 421.245806 -384.934674) (xy 421.207714 -384.879045) (xy 421.17656 -384.819253)
			(xy 421.152792 -384.756159) (xy 421.136753 -384.690673) (xy 421.128674 -384.623738) (xy 421.12867 -384.556316)
			(xy 421.136743 -384.48938) (xy 421.152776 -384.423892) (xy 421.176538 -384.360797) (xy 421.207686 -384.301002)
			(xy 421.245773 -384.245369) (xy 421.267636 -384.219704) (xy 421.273418 -384.212549) (xy 421.27994 -384.195366)
			(xy 421.280336 -384.186176) (xy 421.280336 -383.693924) (xy 421.279906 -383.684739) (xy 421.273405 -383.667555)
			(xy 421.267636 -383.660396) (xy 421.245735 -383.634761) (xy 421.207645 -383.579123) (xy 421.176494 -383.519323)
			(xy 421.152731 -383.456222) (xy 421.136696 -383.390729) (xy 421.128623 -383.323787) (xy 420.02653 -383.323787)
			(xy 420.026742 -383.324352) (xy 420.042713 -383.389736) (xy 420.050756 -383.456559) (xy 420.050754 -383.523865)
			(xy 420.042709 -383.590688) (xy 420.026735 -383.656071) (xy 420.003062 -383.719076) (xy 419.972028 -383.7788)
			(xy 419.93408 -383.834387) (xy 419.912292 -383.86004) (xy 419.906495 -383.867185) (xy 419.899981 -383.884376)
			(xy 419.899592 -383.893568) (xy 419.899592 -384.051556) (xy 419.899148 -384.061677) (xy 419.891413 -384.080381)
			(xy 419.877104 -384.094697) (xy 419.858404 -384.102442) (xy 419.848284 -384.102864) (xy 419.13175 -384.102864)
			(xy 419.121627 -384.102333) (xy 419.102908 -384.094622) (xy 419.08855 -384.080349) (xy 419.080728 -384.061676)
			(xy 419.080188 -384.051556) (xy 419.080188 -383.893568) (xy 419.079796 -383.884379) (xy 419.07327 -383.867194)
			(xy 419.067488 -383.86004) (xy 419.045715 -383.834376) (xy 419.007762 -383.778792) (xy 418.976725 -383.719071)
			(xy 418.95305 -383.656068) (xy 418.937074 -383.590686) (xy 418.929028 -383.523864) (xy 418.929026 -383.45656)
			(xy 418.93707 -383.389737) (xy 418.953042 -383.324355) (xy 418.976716 -383.261351) (xy 419.00775 -383.201629)
			(xy 419.0457 -383.146043) (xy 419.067488 -383.120392) (xy 419.073269 -383.113236) (xy 419.079793 -383.096054)
			(xy 419.080188 -383.086864) (xy 419.080188 -382.593342) (xy 419.07976 -382.584157) (xy 419.073259 -382.566972)
			(xy 419.067488 -382.559814) (xy 419.045689 -382.534171) (xy 419.007737 -382.478584) (xy 418.976702 -382.41886)
			(xy 418.953027 -382.355854) (xy 418.937054 -382.29047) (xy 418.92901 -382.223646) (xy 389.250707 -382.223646)
			(xy 389.242664 -382.290467) (xy 389.226692 -382.355848) (xy 389.20302 -382.418853) (xy 389.171987 -382.478576)
			(xy 389.134039 -382.534162) (xy 389.112252 -382.559814) (xy 389.106461 -382.566963) (xy 389.099944 -382.584151)
			(xy 389.099552 -382.593342) (xy 389.099552 -383.086864) (xy 389.09999 -383.096048) (xy 389.106485 -383.113232)
			(xy 389.112252 -383.120392) (xy 389.134056 -383.146031) (xy 389.172005 -383.201619) (xy 389.203038 -383.261344)
			(xy 389.226475 -383.323726) (xy 390.329121 -383.323726) (xy 390.329125 -383.256419) (xy 390.337172 -383.189595)
			(xy 390.353147 -383.124211) (xy 390.376822 -383.061206) (xy 390.407857 -383.001481) (xy 390.445807 -382.945893)
			(xy 390.467596 -382.92024) (xy 390.4734 -382.9131) (xy 390.47991 -382.895906) (xy 390.480296 -382.886712)
			(xy 390.480296 -382.728724) (xy 390.480741 -382.718572) (xy 390.488528 -382.699821) (xy 390.502918 -382.685497)
			(xy 390.521704 -382.677795) (xy 390.531858 -382.677416) (xy 391.248138 -382.677416) (xy 391.258264 -382.677895)
			(xy 391.276982 -382.685631) (xy 391.291336 -382.699919) (xy 391.299158 -382.7186) (xy 391.2997 -382.728724)
			(xy 391.2997 -382.886712) (xy 391.300105 -382.8959) (xy 391.306622 -382.913084) (xy 391.3124 -382.92024)
			(xy 391.334151 -382.945922) (xy 391.372099 -383.001505) (xy 391.403131 -383.061225) (xy 391.426804 -383.124225)
			(xy 391.442779 -383.189603) (xy 391.450825 -383.256422) (xy 391.450828 -383.323724) (xy 391.442788 -383.390543)
			(xy 391.42682 -383.455923) (xy 391.403153 -383.518926) (xy 391.372126 -383.578649) (xy 391.334184 -383.634235)
			(xy 391.3124 -383.659888) (xy 391.306584 -383.667019) (xy 391.300081 -383.68422) (xy 391.2997 -383.693416)
			(xy 391.2997 -384.186684) (xy 391.300118 -384.19587) (xy 391.306626 -384.213055) (xy 391.3124 -384.220212)
			(xy 391.334222 -384.245836) (xy 391.372167 -384.301427) (xy 391.403197 -384.361155) (xy 391.426866 -384.424163)
			(xy 391.442835 -384.489548) (xy 391.450876 -384.556374) (xy 391.450872 -384.623681) (xy 391.442825 -384.690505)
			(xy 391.42685 -384.755889) (xy 391.403175 -384.818895) (xy 391.372139 -384.878619) (xy 391.334189 -384.934207)
			(xy 391.3124 -384.95986) (xy 391.306595 -384.967) (xy 391.300086 -384.984194) (xy 391.2997 -384.993388)
			(xy 391.2997 -385.151376) (xy 391.299259 -385.161529) (xy 391.291471 -385.180281) (xy 391.27708 -385.194605)
			(xy 391.258292 -385.202305) (xy 391.248138 -385.202684) (xy 390.531858 -385.202684) (xy 390.521732 -385.202209)
			(xy 390.503014 -385.194471) (xy 390.48866 -385.180182) (xy 390.480838 -385.1615) (xy 390.480296 -385.151376)
			(xy 390.480296 -384.993388) (xy 390.479892 -384.9842) (xy 390.473374 -384.967016) (xy 390.467596 -384.95986)
			(xy 390.445845 -384.934178) (xy 390.407898 -384.878595) (xy 390.376865 -384.818875) (xy 390.353192 -384.755875)
			(xy 390.337218 -384.690496) (xy 390.329172 -384.623678) (xy 390.329169 -384.556376) (xy 390.337209 -384.489557)
			(xy 390.353176 -384.424177) (xy 390.376843 -384.361174) (xy 390.40787 -384.301452) (xy 390.445812 -384.245865)
			(xy 390.467596 -384.220212) (xy 390.473412 -384.21308) (xy 390.479915 -384.19588) (xy 390.480296 -384.186684)
			(xy 390.480296 -383.693416) (xy 390.479879 -383.68423) (xy 390.47337 -383.667045) (xy 390.467596 -383.659888)
			(xy 390.445774 -383.634264) (xy 390.407829 -383.578673) (xy 390.3768 -383.518945) (xy 390.353131 -383.455937)
			(xy 390.337162 -383.390552) (xy 390.329121 -383.323726) (xy 389.226475 -383.323726) (xy 389.22671 -383.324351)
			(xy 389.242682 -383.389735) (xy 389.250725 -383.456559) (xy 389.250724 -383.523865) (xy 389.242678 -383.590689)
			(xy 389.226703 -383.656072) (xy 389.203028 -383.719078) (xy 389.171992 -383.778802) (xy 389.134041 -383.834388)
			(xy 389.112252 -383.86004) (xy 389.10645 -383.867181) (xy 389.09994 -383.884375) (xy 389.099552 -383.893568)
			(xy 389.099552 -384.051556) (xy 389.099043 -384.061701) (xy 389.091272 -384.080442) (xy 389.076902 -384.094765)
			(xy 389.058136 -384.102476) (xy 389.04799 -384.102864) (xy 388.33171 -384.102864) (xy 388.321584 -384.102365)
			(xy 388.302864 -384.094642) (xy 388.288508 -384.080359) (xy 388.280687 -384.061679) (xy 388.280148 -384.051556)
			(xy 388.280148 -383.893568) (xy 388.279742 -383.884381) (xy 388.273224 -383.867197) (xy 388.267448 -383.86004)
			(xy 388.245676 -383.834375) (xy 388.207726 -383.778791) (xy 388.176692 -383.719069) (xy 388.153018 -383.656066)
			(xy 388.137043 -383.590685) (xy 388.128998 -383.523864) (xy 388.128996 -383.45656) (xy 388.137039 -383.389738)
			(xy 388.15301 -383.324357) (xy 388.176682 -383.261353) (xy 388.207714 -383.20163) (xy 388.245661 -383.146044)
			(xy 388.267448 -383.120392) (xy 388.273236 -383.113241) (xy 388.279755 -383.096055) (xy 388.280148 -383.086864)
			(xy 388.280148 -382.593342) (xy 388.279707 -382.584158) (xy 388.273213 -382.566974) (xy 388.267448 -382.559814)
			(xy 388.24565 -382.53417) (xy 388.207701 -382.478583) (xy 388.176668 -382.418858) (xy 388.152995 -382.355852)
			(xy 388.137022 -382.290469) (xy 388.128979 -382.223645) (xy 384.850917 -382.223645) (xy 384.842874 -382.290466)
			(xy 384.826902 -382.355848) (xy 384.803231 -382.418852) (xy 384.772199 -382.478576) (xy 384.734251 -382.534162)
			(xy 384.712464 -382.559814) (xy 384.706674 -382.566964) (xy 384.700156 -382.584151) (xy 384.699764 -382.593342)
			(xy 384.699764 -383.086864) (xy 384.7002 -383.096048) (xy 384.706697 -383.113232) (xy 384.712464 -383.120392)
			(xy 384.734267 -383.146031) (xy 384.772216 -383.20162) (xy 384.803248 -383.261345) (xy 384.826708 -383.323786)
			(xy 385.928802 -383.323786) (xy 385.928805 -383.25636) (xy 385.936885 -383.189419) (xy 385.952924 -383.123928)
			(xy 385.976693 -383.060829) (xy 386.007848 -383.001032) (xy 386.045942 -382.945397) (xy 386.067808 -382.919732)
			(xy 386.073617 -382.912596) (xy 386.080124 -382.895398) (xy 386.080508 -382.886204) (xy 386.080508 -382.728724)
			(xy 386.080936 -382.718602) (xy 386.088677 -382.699897) (xy 386.102991 -382.685582) (xy 386.121694 -382.677837)
			(xy 386.131816 -382.677416) (xy 386.848096 -382.677416) (xy 386.85822 -382.67782) (xy 386.876927 -382.685569)
			(xy 386.891242 -382.69989) (xy 386.898984 -382.7186) (xy 386.899404 -382.728724) (xy 386.899404 -382.886204)
			(xy 386.899811 -382.895391) (xy 386.906327 -382.912576) (xy 386.912104 -382.919732) (xy 386.933932 -382.945426)
			(xy 386.972022 -383.001057) (xy 387.003174 -383.060849) (xy 387.02694 -383.123942) (xy 387.042978 -383.189428)
			(xy 387.051057 -383.256363) (xy 387.05106 -383.323783) (xy 387.042988 -383.390719) (xy 387.026956 -383.456206)
			(xy 387.003196 -383.519301) (xy 386.97205 -383.579097) (xy 386.933966 -383.634731) (xy 386.912104 -383.660396)
			(xy 386.906327 -383.667555) (xy 386.899801 -383.684735) (xy 386.899404 -383.693924) (xy 386.899404 -384.186176)
			(xy 386.899825 -384.195362) (xy 386.906331 -384.212547) (xy 386.912104 -384.219704) (xy 386.934003 -384.24534)
			(xy 386.972091 -384.300979) (xy 387.003239 -384.360779) (xy 387.027001 -384.42388) (xy 387.043034 -384.489372)
			(xy 387.051107 -384.556314) (xy 387.051104 -384.62374) (xy 387.043025 -384.690681) (xy 387.026985 -384.756172)
			(xy 387.003217 -384.81927) (xy 386.972063 -384.879068) (xy 386.93397 -384.934703) (xy 386.912104 -384.960368)
			(xy 386.906297 -384.967506) (xy 386.899788 -384.984702) (xy 386.899404 -384.993896) (xy 386.899404 -385.151376)
			(xy 386.898965 -385.161496) (xy 386.891225 -385.180199) (xy 386.876916 -385.194514) (xy 386.858216 -385.202261)
			(xy 386.848096 -385.202684) (xy 386.131816 -385.202684) (xy 386.121693 -385.202271) (xy 386.102986 -385.194525)
			(xy 386.088671 -385.180207) (xy 386.080928 -385.1615) (xy 386.080508 -385.151376) (xy 386.080508 -384.993896)
			(xy 386.080098 -384.984709) (xy 386.073584 -384.967525) (xy 386.067808 -384.960368) (xy 386.045979 -384.934674)
			(xy 386.007889 -384.879044) (xy 385.976736 -384.819251) (xy 385.95297 -384.756158) (xy 385.936931 -384.690673)
			(xy 385.928852 -384.623738) (xy 385.928849 -384.556317) (xy 385.936922 -384.489381) (xy 385.952954 -384.423893)
			(xy 385.976714 -384.360798) (xy 386.007861 -384.301003) (xy 386.045946 -384.245369) (xy 386.067808 -384.219704)
			(xy 386.073586 -384.212546) (xy 386.080112 -384.195365) (xy 386.080508 -384.186176) (xy 386.080508 -383.693924)
			(xy 386.080084 -383.684738) (xy 386.07358 -383.667554) (xy 386.067808 -383.660396) (xy 386.045908 -383.63476)
			(xy 386.00782 -383.579122) (xy 385.976671 -383.519321) (xy 385.952908 -383.456221) (xy 385.936875 -383.390728)
			(xy 385.928802 -383.323786) (xy 384.826708 -383.323786) (xy 384.82692 -383.324351) (xy 384.842892 -383.389735)
			(xy 384.850934 -383.456559) (xy 384.850933 -383.523865) (xy 384.842887 -383.590689) (xy 384.826913 -383.656072)
			(xy 384.803238 -383.719077) (xy 384.772203 -383.778801) (xy 384.734253 -383.834388) (xy 384.712464 -383.86004)
			(xy 384.706663 -383.867182) (xy 384.700152 -383.884375) (xy 384.699764 -383.893568) (xy 384.699764 -384.051556)
			(xy 384.699342 -384.061712) (xy 384.691554 -384.08047) (xy 384.677156 -384.094796) (xy 384.65836 -384.102491)
			(xy 384.648202 -384.102864) (xy 383.931922 -384.102864) (xy 383.921797 -384.102356) (xy 383.903077 -384.094636)
			(xy 383.88872 -384.080356) (xy 383.8809 -384.061678) (xy 383.88036 -384.051556) (xy 383.88036 -383.893568)
			(xy 383.879952 -383.884381) (xy 383.873435 -383.867197) (xy 383.86766 -383.86004) (xy 383.845887 -383.834375)
			(xy 383.807937 -383.778791) (xy 383.776902 -383.719069) (xy 383.753227 -383.656066) (xy 383.737252 -383.590686)
			(xy 383.729207 -383.523864) (xy 383.729205 -383.45656) (xy 383.737248 -383.389738) (xy 383.75322 -383.324357)
			(xy 383.776892 -383.261353) (xy 383.807924 -383.20163) (xy 383.845873 -383.146044) (xy 383.86766 -383.120392)
			(xy 383.87345 -383.113242) (xy 383.879967 -383.096055) (xy 383.88036 -383.086864) (xy 383.88036 -382.593342)
			(xy 383.879916 -382.584159) (xy 383.873425 -382.566975) (xy 383.86766 -382.559814) (xy 383.845862 -382.53417)
			(xy 383.807912 -382.478583) (xy 383.776878 -382.418858) (xy 383.753205 -382.355853) (xy 383.737232 -382.290469)
			(xy 383.729188 -382.223646) (xy 380.451149 -382.223646) (xy 380.451149 -382.223704) (xy 380.443073 -382.290642)
			(xy 380.427038 -382.356131) (xy 380.403273 -382.419228) (xy 380.372122 -382.479024) (xy 380.334032 -382.534657)
			(xy 380.312168 -382.560322) (xy 380.306375 -382.56747) (xy 380.299859 -382.584658) (xy 380.299468 -382.59385)
			(xy 380.299468 -383.086356) (xy 380.299907 -383.09554) (xy 380.306401 -383.112724) (xy 380.312168 -383.119884)
			(xy 380.334049 -383.145536) (xy 380.372139 -383.201171) (xy 380.403291 -383.260969) (xy 380.426928 -383.323727)
			(xy 381.529033 -383.323727) (xy 381.529037 -383.256419) (xy 381.537084 -383.189595) (xy 381.55306 -383.124211)
			(xy 381.576736 -383.061205) (xy 381.607772 -383.00148) (xy 381.645723 -382.945893) (xy 381.667512 -382.92024)
			(xy 381.673318 -382.913101) (xy 381.679827 -382.895906) (xy 381.680212 -382.886712) (xy 381.680212 -382.728724)
			(xy 381.680641 -382.71857) (xy 381.688431 -382.699816) (xy 381.702826 -382.685491) (xy 381.721618 -382.677793)
			(xy 381.731774 -382.677416) (xy 382.448054 -382.677416) (xy 382.458175 -382.677964) (xy 382.47689 -382.685672)
			(xy 382.491247 -382.699939) (xy 382.499072 -382.718606) (xy 382.499616 -382.728724) (xy 382.499616 -382.886712)
			(xy 382.500017 -382.8959) (xy 382.506537 -382.913085) (xy 382.512316 -382.92024) (xy 382.53407 -382.945921)
			(xy 382.572023 -383.001502) (xy 382.60306 -383.061221) (xy 382.626737 -383.124222) (xy 382.642713 -383.189601)
			(xy 382.650761 -383.256421) (xy 382.650764 -383.323724) (xy 382.642723 -383.390545) (xy 382.626753 -383.455926)
			(xy 382.603082 -383.518929) (xy 382.57205 -383.578652) (xy 382.534103 -383.634236) (xy 382.512316 -383.659888)
			(xy 382.506501 -383.667021) (xy 382.499997 -383.684221) (xy 382.499616 -383.693416) (xy 382.499616 -384.186684)
			(xy 382.50003 -384.195871) (xy 382.506541 -384.213055) (xy 382.512316 -384.220212) (xy 382.53414 -384.245834)
			(xy 382.572091 -384.301424) (xy 382.603125 -384.361151) (xy 382.626798 -384.42416) (xy 382.64277 -384.489546)
			(xy 382.650812 -384.556373) (xy 382.650808 -384.623681) (xy 382.64276 -384.690507) (xy 382.626782 -384.755892)
			(xy 382.603103 -384.818898) (xy 382.572063 -384.878622) (xy 382.534107 -384.934208) (xy 382.512316 -384.95986)
			(xy 382.506513 -384.967001) (xy 382.500002 -384.984195) (xy 382.499616 -384.993388) (xy 382.499616 -385.151376)
			(xy 382.499159 -385.161527) (xy 382.491375 -385.180275) (xy 382.476989 -385.194599) (xy 382.458206 -385.202303)
			(xy 382.448054 -385.202684) (xy 381.731774 -385.202684) (xy 381.721649 -385.202196) (xy 381.702931 -385.194464)
			(xy 381.688577 -385.180179) (xy 381.680754 -385.161499) (xy 381.680212 -385.151376) (xy 381.680212 -384.993388)
			(xy 381.679805 -384.984201) (xy 381.673289 -384.967016) (xy 381.667512 -384.95986) (xy 381.64576 -384.934178)
			(xy 381.607812 -384.878596) (xy 381.576779 -384.818876) (xy 381.553105 -384.755875) (xy 381.537131 -384.690497)
			(xy 381.529084 -384.623678) (xy 381.529081 -384.556376) (xy 381.537121 -384.489557) (xy 381.553089 -384.424177)
			(xy 381.576757 -384.361174) (xy 381.607784 -384.301451) (xy 381.645727 -384.245864) (xy 381.667512 -384.220212)
			(xy 381.67333 -384.213082) (xy 381.679831 -384.19588) (xy 381.680212 -384.186684) (xy 381.680212 -383.693416)
			(xy 381.679791 -383.68423) (xy 381.673285 -383.667046) (xy 381.667512 -383.659888) (xy 381.64569 -383.634265)
			(xy 381.607744 -383.578673) (xy 381.576714 -383.518946) (xy 381.553044 -383.455937) (xy 381.537074 -383.390552)
			(xy 381.529033 -383.323727) (xy 380.426928 -383.323727) (xy 380.427056 -383.324068) (xy 380.443091 -383.389559)
			(xy 380.451166 -383.456499) (xy 380.451165 -383.523925) (xy 380.443087 -383.590865) (xy 380.427049 -383.656355)
			(xy 380.403281 -383.719453) (xy 380.372127 -383.779249) (xy 380.334034 -383.834883) (xy 380.312168 -383.860548)
			(xy 380.306364 -383.867688) (xy 380.299855 -383.884883) (xy 380.299468 -383.894076) (xy 380.299468 -384.051556)
			(xy 380.299047 -384.06168) (xy 380.291308 -384.080388) (xy 380.276992 -384.094705) (xy 380.258284 -384.102446)
			(xy 380.24816 -384.102864) (xy 379.53188 -384.102864) (xy 379.521752 -384.1025) (xy 379.503041 -384.094738)
			(xy 379.488726 -384.080405) (xy 379.480988 -384.061685) (xy 379.480572 -384.051556) (xy 379.480572 -383.894076)
			(xy 379.48018 -383.884887) (xy 379.473654 -383.867702) (xy 379.467872 -383.860548) (xy 379.446025 -383.834869)
			(xy 379.407937 -383.779236) (xy 379.376788 -383.719441) (xy 379.353024 -383.656346) (xy 379.336988 -383.590859)
			(xy 379.328911 -383.523923) (xy 379.32891 -383.456501) (xy 379.336984 -383.389564) (xy 379.353017 -383.324077)
			(xy 379.376778 -383.260981) (xy 379.407925 -383.201185) (xy 379.44601 -383.14555) (xy 379.467872 -383.119884)
			(xy 379.473667 -383.112738) (xy 379.48018 -383.095548) (xy 379.480572 -383.086356) (xy 379.480572 -382.59385)
			(xy 379.480144 -382.584665) (xy 379.473643 -382.56748) (xy 379.467872 -382.560322) (xy 379.445999 -382.534664)
			(xy 379.407913 -382.479028) (xy 379.376764 -382.419231) (xy 379.353002 -382.356133) (xy 379.336968 -382.290643)
			(xy 379.328893 -382.223704) (xy 376.050822 -382.223704) (xy 376.042786 -382.290466) (xy 376.026815 -382.355847)
			(xy 376.003144 -382.418851) (xy 375.972113 -382.478575) (xy 375.934167 -382.534162) (xy 375.91238 -382.559814)
			(xy 375.906593 -382.566966) (xy 375.900073 -382.584151) (xy 375.89968 -382.593342) (xy 375.89968 -383.086864)
			(xy 375.900112 -383.096049) (xy 375.906611 -383.113233) (xy 375.91238 -383.120392) (xy 375.934183 -383.146031)
			(xy 375.97213 -383.20162) (xy 376.003162 -383.261346) (xy 376.02662 -383.323786) (xy 377.128714 -383.323786)
			(xy 377.128717 -383.256359) (xy 377.136797 -383.189418) (xy 377.152837 -383.123927) (xy 377.176606 -383.060828)
			(xy 377.207762 -383.001031) (xy 377.245857 -382.945397) (xy 377.267724 -382.919732) (xy 377.273535 -382.912597)
			(xy 377.28004 -382.895399) (xy 377.280424 -382.886204) (xy 377.280424 -382.728724) (xy 377.280836 -382.7186)
			(xy 377.288581 -382.699892) (xy 377.302899 -382.685576) (xy 377.321608 -382.677834) (xy 377.331732 -382.677416)
			(xy 378.048012 -382.677416) (xy 378.058137 -382.677806) (xy 378.076844 -382.685561) (xy 378.091159 -382.699886)
			(xy 378.098901 -382.718598) (xy 378.09932 -382.728724) (xy 378.09932 -382.886204) (xy 378.099724 -382.895392)
			(xy 378.106241 -382.912576) (xy 378.11202 -382.919732) (xy 378.133848 -382.945427) (xy 378.171936 -383.001058)
			(xy 378.203088 -383.06085) (xy 378.226853 -383.123943) (xy 378.24289 -383.189428) (xy 378.250969 -383.256363)
			(xy 378.250972 -383.323783) (xy 378.2429 -383.390719) (xy 378.226869 -383.456205) (xy 378.20311 -383.519301)
			(xy 378.171964 -383.579096) (xy 378.133881 -383.63473) (xy 378.11202 -383.660396) (xy 378.106245 -383.667557)
			(xy 378.099717 -383.684735) (xy 378.09932 -383.693924) (xy 378.09932 -384.186176) (xy 378.099737 -384.195363)
			(xy 378.106245 -384.212547) (xy 378.11202 -384.219704) (xy 378.133919 -384.24534) (xy 378.172005 -384.30098)
			(xy 378.203153 -384.36078) (xy 378.226914 -384.423881) (xy 378.242947 -384.489373) (xy 378.251019 -384.556314)
			(xy 378.251016 -384.62374) (xy 378.242937 -384.69068) (xy 378.226898 -384.756171) (xy 378.203131 -384.81927)
			(xy 378.171977 -384.879067) (xy 378.133885 -384.934702) (xy 378.11202 -384.960368) (xy 378.106214 -384.967507)
			(xy 378.099704 -384.984702) (xy 378.09932 -384.993896) (xy 378.09932 -385.151376) (xy 378.098865 -385.161494)
			(xy 378.091128 -385.180194) (xy 378.076824 -385.194508) (xy 378.05813 -385.202258) (xy 378.048012 -385.202684)
			(xy 377.331732 -385.202684) (xy 377.32161 -385.202258) (xy 377.302903 -385.194517) (xy 377.288587 -385.180203)
			(xy 377.280844 -385.161498) (xy 377.280424 -385.151376) (xy 377.280424 -384.993896) (xy 377.280011 -384.984709)
			(xy 377.273499 -384.967525) (xy 377.267724 -384.960368) (xy 377.245895 -384.934674) (xy 377.207803 -384.879044)
			(xy 377.17665 -384.819252) (xy 377.152882 -384.756159) (xy 377.136844 -384.690673) (xy 377.128765 -384.623738)
			(xy 377.128761 -384.556316) (xy 377.136834 -384.48938) (xy 377.152866 -384.423893) (xy 377.176627 -384.360797)
			(xy 377.207775 -384.301002) (xy 377.245861 -384.245369) (xy 377.267724 -384.219704) (xy 377.273504 -384.212547)
			(xy 377.280028 -384.195365) (xy 377.280424 -384.186176) (xy 377.280424 -383.693924) (xy 377.279997 -383.684739)
			(xy 377.273494 -383.667555) (xy 377.267724 -383.660396) (xy 377.245824 -383.63476) (xy 377.207735 -383.579122)
			(xy 377.176584 -383.519322) (xy 377.152821 -383.456221) (xy 377.136787 -383.390728) (xy 377.128714 -383.323786)
			(xy 376.02662 -383.323786) (xy 376.026833 -383.324352) (xy 376.042804 -383.389735) (xy 376.050846 -383.456559)
			(xy 376.050845 -383.523865) (xy 376.0428 -383.590688) (xy 376.026826 -383.656071) (xy 376.003152 -383.719076)
			(xy 375.972118 -383.778801) (xy 375.934168 -383.834388) (xy 375.91238 -383.86004) (xy 375.906582 -383.867184)
			(xy 375.900069 -383.884375) (xy 375.89968 -383.893568) (xy 375.89968 -384.051556) (xy 375.899242 -384.06171)
			(xy 375.891457 -384.080465) (xy 375.877065 -384.094791) (xy 375.858274 -384.102488) (xy 375.848118 -384.102864)
			(xy 375.131838 -384.102864) (xy 375.121714 -384.102342) (xy 375.102995 -384.094628) (xy 375.088637 -384.080352)
			(xy 375.080816 -384.061677) (xy 375.080276 -384.051556) (xy 375.080276 -383.893568) (xy 375.079886 -383.884379)
			(xy 375.073359 -383.867194) (xy 375.067576 -383.86004) (xy 375.045803 -383.834375) (xy 375.007851 -383.778792)
			(xy 374.976815 -383.71907) (xy 374.95314 -383.656067) (xy 374.937165 -383.590686) (xy 374.929119 -383.523864)
			(xy 374.929117 -383.45656) (xy 374.93716 -383.389738) (xy 374.953133 -383.324356) (xy 374.976805 -383.261352)
			(xy 375.007839 -383.201629) (xy 375.045788 -383.146044) (xy 375.067576 -383.120392) (xy 375.073356 -383.113235)
			(xy 375.079881 -383.096054) (xy 375.080276 -383.086864) (xy 375.080276 -382.593342) (xy 375.079851 -382.584156)
			(xy 375.073348 -382.566971) (xy 375.067576 -382.559814) (xy 375.045777 -382.53417) (xy 375.007826 -382.478584)
			(xy 374.976792 -382.418859) (xy 374.953118 -382.355853) (xy 374.937144 -382.29047) (xy 374.9291 -382.223646)
			(xy 345.250798 -382.223646) (xy 345.242755 -382.290467) (xy 345.226782 -382.355849) (xy 345.20311 -382.418853)
			(xy 345.172077 -382.478576) (xy 345.134128 -382.534162) (xy 345.11234 -382.559814) (xy 345.106548 -382.566962)
			(xy 345.100032 -382.584151) (xy 345.09964 -382.593342) (xy 345.09964 -383.086864) (xy 345.100081 -383.096048)
			(xy 345.106575 -383.113232) (xy 345.11234 -383.120392) (xy 345.134144 -383.146031) (xy 345.172094 -383.201619)
			(xy 345.203127 -383.261344) (xy 345.226566 -383.323727) (xy 346.329188 -383.323727) (xy 346.329192 -383.256419)
			(xy 346.33724 -383.189593) (xy 346.353218 -383.124208) (xy 346.376897 -383.061202) (xy 346.407937 -383.001478)
			(xy 346.445893 -382.945892) (xy 346.467684 -382.92024) (xy 346.473487 -382.913099) (xy 346.479998 -382.895905)
			(xy 346.480384 -382.886712) (xy 346.480384 -382.728724) (xy 346.480841 -382.718573) (xy 346.488625 -382.699825)
			(xy 346.503011 -382.685501) (xy 346.521794 -382.677797) (xy 346.531946 -382.677416) (xy 347.248226 -382.677416)
			(xy 347.258351 -382.677904) (xy 347.277069 -382.685636) (xy 347.291423 -382.699921) (xy 347.299246 -382.718601)
			(xy 347.299788 -382.728724) (xy 347.299788 -382.886712) (xy 347.300195 -382.895899) (xy 347.306711 -382.913084)
			(xy 347.312488 -382.92024) (xy 347.33424 -382.945922) (xy 347.372188 -383.001504) (xy 347.403221 -383.061224)
			(xy 347.426895 -383.124225) (xy 347.442869 -383.189603) (xy 347.450916 -383.256422) (xy 347.450919 -383.323724)
			(xy 347.442879 -383.390543) (xy 347.426911 -383.455923) (xy 347.403243 -383.518926) (xy 347.372216 -383.578649)
			(xy 347.334273 -383.634236) (xy 347.312488 -383.659888) (xy 347.30667 -383.667018) (xy 347.300169 -383.68422)
			(xy 347.299788 -383.693416) (xy 347.299788 -384.186684) (xy 347.300209 -384.19587) (xy 347.306715 -384.213054)
			(xy 347.312488 -384.220212) (xy 347.33431 -384.245835) (xy 347.372256 -384.301427) (xy 347.403286 -384.361154)
			(xy 347.426956 -384.424163) (xy 347.442926 -384.489548) (xy 347.450967 -384.556373) (xy 347.450963 -384.623681)
			(xy 347.442916 -384.690505) (xy 347.42694 -384.755889) (xy 347.403264 -384.818895) (xy 347.372228 -384.87862)
			(xy 347.334277 -384.934207) (xy 347.312488 -384.95986) (xy 347.306682 -384.966999) (xy 347.300173 -384.984194)
			(xy 347.299788 -384.993388) (xy 347.299788 -385.151376) (xy 347.299359 -385.16153) (xy 347.291569 -385.180284)
			(xy 347.277174 -385.194609) (xy 347.258382 -385.202307) (xy 347.248226 -385.202684) (xy 346.531946 -385.202684)
			(xy 346.521825 -385.202136) (xy 346.50311 -385.194428) (xy 346.488753 -385.180161) (xy 346.480928 -385.161494)
			(xy 346.480384 -385.151376) (xy 346.480384 -384.993388) (xy 346.479983 -384.9842) (xy 346.473463 -384.967015)
			(xy 346.467684 -384.95986) (xy 346.44593 -384.934179) (xy 346.407977 -384.878598) (xy 346.37694 -384.818879)
			(xy 346.353263 -384.755878) (xy 346.337287 -384.690499) (xy 346.329239 -384.623679) (xy 346.329236 -384.556376)
			(xy 346.337277 -384.489555) (xy 346.353247 -384.424174) (xy 346.376918 -384.361171) (xy 346.40795 -384.301448)
			(xy 346.445897 -384.245864) (xy 346.467684 -384.220212) (xy 346.473499 -384.213079) (xy 346.480003 -384.195879)
			(xy 346.480384 -384.186684) (xy 346.480384 -383.693416) (xy 346.47997 -383.684229) (xy 346.473459 -383.667045)
			(xy 346.467684 -383.659888) (xy 346.44586 -383.634266) (xy 346.407909 -383.578676) (xy 346.376875 -383.518949)
			(xy 346.353202 -383.45594) (xy 346.33723 -383.390554) (xy 346.329188 -383.323727) (xy 345.226566 -383.323727)
			(xy 345.2268 -383.32435) (xy 345.242773 -383.389734) (xy 345.250816 -383.456559) (xy 345.250814 -383.523865)
			(xy 345.242768 -383.590689) (xy 345.226793 -383.656073) (xy 345.203118 -383.719078) (xy 345.172081 -383.778802)
			(xy 345.134129 -383.834388) (xy 345.11234 -383.86004) (xy 345.106537 -383.86718) (xy 345.100028 -383.884375)
			(xy 345.09964 -383.893568) (xy 345.09964 -384.051556) (xy 345.099143 -384.061702) (xy 345.09137 -384.080446)
			(xy 345.076996 -384.094769) (xy 345.058226 -384.102478) (xy 345.048078 -384.102864) (xy 344.331798 -384.102864)
			(xy 344.321672 -384.102375) (xy 344.302951 -384.094647) (xy 344.288595 -384.080362) (xy 344.280775 -384.06168)
			(xy 344.280236 -384.051556) (xy 344.280236 -383.893568) (xy 344.279833 -383.88438) (xy 344.273313 -383.867196)
			(xy 344.267536 -383.86004) (xy 344.245764 -383.834375) (xy 344.207815 -383.77879) (xy 344.176781 -383.719068)
			(xy 344.153108 -383.656066) (xy 344.137134 -383.590685) (xy 344.129089 -383.523864) (xy 344.129087 -383.45656)
			(xy 344.13713 -383.389739) (xy 344.153101 -383.324358) (xy 344.176772 -383.261354) (xy 344.207803 -383.201631)
			(xy 344.24575 -383.146044) (xy 344.267536 -383.120392) (xy 344.273323 -383.11324) (xy 344.279843 -383.096055)
			(xy 344.280236 -383.086864) (xy 344.280236 -382.593342) (xy 344.279797 -382.584158) (xy 344.273303 -382.566974)
			(xy 344.267536 -382.559814) (xy 344.245738 -382.53417) (xy 344.20779 -382.478582) (xy 344.176757 -382.418858)
			(xy 344.153085 -382.355852) (xy 344.137113 -382.290469) (xy 344.12907 -382.223645) (xy 340.851007 -382.223645)
			(xy 340.842964 -382.290467) (xy 340.826992 -382.355848) (xy 340.80332 -382.418853) (xy 340.772287 -382.478576)
			(xy 340.734339 -382.534162) (xy 340.712552 -382.559814) (xy 340.706761 -382.566963) (xy 340.700244 -382.584151)
			(xy 340.699852 -382.593342) (xy 340.699852 -383.086864) (xy 340.70029 -383.096048) (xy 340.706785 -383.113232)
			(xy 340.712552 -383.120392) (xy 340.734356 -383.146031) (xy 340.772305 -383.201619) (xy 340.803338 -383.261344)
			(xy 340.826798 -383.323786) (xy 341.928893 -383.323786) (xy 341.928896 -383.25636) (xy 341.936975 -383.189419)
			(xy 341.953015 -383.123928) (xy 341.976783 -383.06083) (xy 342.007937 -383.001032) (xy 342.04603 -382.945397)
			(xy 342.067896 -382.919732) (xy 342.073703 -382.912594) (xy 342.080212 -382.895398) (xy 342.080596 -382.886204)
			(xy 342.080596 -382.728724) (xy 342.081035 -382.718604) (xy 342.088775 -382.699901) (xy 342.103084 -382.685586)
			(xy 342.121784 -382.677839) (xy 342.131904 -382.677416) (xy 342.848184 -382.677416) (xy 342.858307 -382.677829)
			(xy 342.877014 -382.685575) (xy 342.891329 -382.699893) (xy 342.899072 -382.7186) (xy 342.899492 -382.728724)
			(xy 342.899492 -382.886204) (xy 342.899902 -382.895391) (xy 342.906416 -382.912575) (xy 342.912192 -382.919732)
			(xy 342.934021 -382.945426) (xy 342.972111 -383.001056) (xy 343.003264 -383.060849) (xy 343.02703 -383.123942)
			(xy 343.043069 -383.189427) (xy 343.051148 -383.256362) (xy 343.051151 -383.323783) (xy 343.043078 -383.390719)
			(xy 343.027046 -383.456207) (xy 343.003286 -383.519302) (xy 342.972139 -383.579097) (xy 342.934054 -383.634731)
			(xy 342.912192 -383.660396) (xy 342.906414 -383.667554) (xy 342.899888 -383.684735) (xy 342.899492 -383.693924)
			(xy 342.899492 -384.186176) (xy 342.899916 -384.195362) (xy 342.90642 -384.212546) (xy 342.912192 -384.219704)
			(xy 342.934092 -384.24534) (xy 342.97218 -384.300978) (xy 343.003329 -384.360779) (xy 343.027092 -384.423879)
			(xy 343.043125 -384.489372) (xy 343.051198 -384.556314) (xy 343.051195 -384.62374) (xy 343.043115 -384.690681)
			(xy 343.027076 -384.756172) (xy 343.003307 -384.819271) (xy 342.972152 -384.879068) (xy 342.934058 -384.934703)
			(xy 342.912192 -384.960368) (xy 342.906383 -384.967504) (xy 342.899876 -384.984702) (xy 342.899492 -384.993896)
			(xy 342.899492 -385.151376) (xy 342.899064 -385.161498) (xy 342.891323 -385.180203) (xy 342.877009 -385.194518)
			(xy 342.858306 -385.202263) (xy 342.848184 -385.202684) (xy 342.131904 -385.202684) (xy 342.12178 -385.20228)
			(xy 342.103073 -385.194531) (xy 342.088758 -385.18021) (xy 342.081016 -385.1615) (xy 342.080596 -385.151376)
			(xy 342.080596 -384.993896) (xy 342.080189 -384.984709) (xy 342.073673 -384.967524) (xy 342.067896 -384.960368)
			(xy 342.046068 -384.934674) (xy 342.007978 -384.879043) (xy 341.976826 -384.819251) (xy 341.95306 -384.756158)
			(xy 341.937022 -384.690672) (xy 341.928943 -384.623737) (xy 341.92894 -384.556317) (xy 341.937012 -384.489381)
			(xy 341.953044 -384.423894) (xy 341.976804 -384.360799) (xy 342.00795 -384.301003) (xy 342.046034 -384.245369)
			(xy 342.067896 -384.219704) (xy 342.073673 -384.212545) (xy 342.080199 -384.195365) (xy 342.080596 -384.186176)
			(xy 342.080596 -383.693924) (xy 342.080175 -383.684738) (xy 342.073669 -383.667553) (xy 342.067896 -383.660396)
			(xy 342.045997 -383.63476) (xy 342.007909 -383.579121) (xy 341.976761 -383.519321) (xy 341.952999 -383.45622)
			(xy 341.936966 -383.390728) (xy 341.928893 -383.323786) (xy 340.826798 -383.323786) (xy 340.82701 -383.324351)
			(xy 340.842982 -383.389735) (xy 340.851025 -383.456559) (xy 340.851024 -383.523865) (xy 340.842978 -383.590689)
			(xy 340.827003 -383.656072) (xy 340.803328 -383.719078) (xy 340.772292 -383.778802) (xy 340.734341 -383.834388)
			(xy 340.712552 -383.86004) (xy 340.70675 -383.867181) (xy 340.70024 -383.884375) (xy 340.699852 -383.893568)
			(xy 340.699852 -384.051556) (xy 340.699343 -384.061701) (xy 340.691572 -384.080442) (xy 340.677202 -384.094765)
			(xy 340.658436 -384.102476) (xy 340.64829 -384.102864) (xy 339.93201 -384.102864) (xy 339.921884 -384.102365)
			(xy 339.903164 -384.094642) (xy 339.888808 -384.080359) (xy 339.880987 -384.061679) (xy 339.880448 -384.051556)
			(xy 339.880448 -383.893568) (xy 339.880042 -383.884381) (xy 339.873524 -383.867197) (xy 339.867748 -383.86004)
			(xy 339.845976 -383.834375) (xy 339.808026 -383.778791) (xy 339.776992 -383.719069) (xy 339.753318 -383.656066)
			(xy 339.737343 -383.590685) (xy 339.729298 -383.523864) (xy 339.729296 -383.45656) (xy 339.737339 -383.389738)
			(xy 339.75331 -383.324357) (xy 339.776982 -383.261353) (xy 339.808014 -383.20163) (xy 339.845961 -383.146044)
			(xy 339.867748 -383.120392) (xy 339.873536 -383.113241) (xy 339.880055 -383.096055) (xy 339.880448 -383.086864)
			(xy 339.880448 -382.593342) (xy 339.880007 -382.584158) (xy 339.873513 -382.566974) (xy 339.867748 -382.559814)
			(xy 339.84595 -382.53417) (xy 339.808001 -382.478583) (xy 339.776968 -382.418858) (xy 339.753295 -382.355852)
			(xy 339.737322 -382.290469) (xy 339.729279 -382.223645) (xy 336.45124 -382.223645) (xy 336.45124 -382.223704)
			(xy 336.443164 -382.290643) (xy 336.427128 -382.356132) (xy 336.403363 -382.419228) (xy 336.372211 -382.479024)
			(xy 336.334121 -382.534658) (xy 336.312256 -382.560322) (xy 336.306462 -382.567469) (xy 336.299947 -382.584658)
			(xy 336.299556 -382.59385) (xy 336.299556 -383.086356) (xy 336.299997 -383.09554) (xy 336.306491 -383.112724)
			(xy 336.312256 -383.119884) (xy 336.334137 -383.145536) (xy 336.372228 -383.201171) (xy 336.403381 -383.260969)
			(xy 336.427018 -383.323726) (xy 337.529124 -383.323726) (xy 337.529128 -383.256419) (xy 337.537175 -383.189595)
			(xy 337.55315 -383.124211) (xy 337.576825 -383.061205) (xy 337.607861 -383.001481) (xy 337.645811 -382.945893)
			(xy 337.6676 -382.92024) (xy 337.673405 -382.9131) (xy 337.679914 -382.895906) (xy 337.6803 -382.886712)
			(xy 337.6803 -382.728724) (xy 337.680741 -382.718571) (xy 337.688529 -382.699819) (xy 337.70292 -382.685495)
			(xy 337.721708 -382.677795) (xy 337.731862 -382.677416) (xy 338.448142 -382.677416) (xy 338.458268 -382.677891)
			(xy 338.476986 -382.685629) (xy 338.49134 -382.699918) (xy 338.499162 -382.7186) (xy 338.499704 -382.728724)
			(xy 338.499704 -382.886712) (xy 338.500108 -382.8959) (xy 338.506626 -382.913084) (xy 338.512404 -382.92024)
			(xy 338.534155 -382.945922) (xy 338.572102 -383.001505) (xy 338.603135 -383.061225) (xy 338.626808 -383.124225)
			(xy 338.642782 -383.189604) (xy 338.650828 -383.256422) (xy 338.650831 -383.323724) (xy 338.642791 -383.390543)
			(xy 338.626824 -383.455923) (xy 338.603157 -383.518926) (xy 338.57213 -383.578648) (xy 338.534188 -383.634235)
			(xy 338.512404 -383.659888) (xy 338.506588 -383.66702) (xy 338.500085 -383.68422) (xy 338.499704 -383.693416)
			(xy 338.499704 -384.186684) (xy 338.500121 -384.19587) (xy 338.50663 -384.213055) (xy 338.512404 -384.220212)
			(xy 338.534226 -384.245836) (xy 338.572171 -384.301427) (xy 338.6032 -384.361155) (xy 338.626869 -384.424163)
			(xy 338.642838 -384.489548) (xy 338.650879 -384.556374) (xy 338.650875 -384.623681) (xy 338.642828 -384.690505)
			(xy 338.626853 -384.755889) (xy 338.603178 -384.818894) (xy 338.572143 -384.878619) (xy 338.534193 -384.934207)
			(xy 338.512404 -384.95986) (xy 338.5066 -384.967) (xy 338.50009 -384.984194) (xy 338.499704 -384.993388)
			(xy 338.499704 -385.151376) (xy 338.499259 -385.161528) (xy 338.491472 -385.180279) (xy 338.477082 -385.194603)
			(xy 338.458296 -385.202305) (xy 338.448142 -385.202684) (xy 337.731862 -385.202684) (xy 337.721736 -385.202205)
			(xy 337.703018 -385.194469) (xy 337.688664 -385.180181) (xy 337.680842 -385.1615) (xy 337.6803 -385.151376)
			(xy 337.6803 -384.993388) (xy 337.679895 -384.9842) (xy 337.673378 -384.967016) (xy 337.6676 -384.95986)
			(xy 337.645849 -384.934178) (xy 337.607901 -384.878595) (xy 337.576869 -384.818875) (xy 337.553196 -384.755875)
			(xy 337.537221 -384.690497) (xy 337.529175 -384.623678) (xy 337.529172 -384.556376) (xy 337.537212 -384.489557)
			(xy 337.55318 -384.424177) (xy 337.576847 -384.361174) (xy 337.607874 -384.301451) (xy 337.645816 -384.245865)
			(xy 337.6676 -384.220212) (xy 337.673416 -384.213081) (xy 337.679919 -384.19588) (xy 337.6803 -384.186684)
			(xy 337.6803 -383.693416) (xy 337.679882 -383.68423) (xy 337.673374 -383.667045) (xy 337.6676 -383.659888)
			(xy 337.645778 -383.634264) (xy 337.607833 -383.578673) (xy 337.576803 -383.518945) (xy 337.553134 -383.455937)
			(xy 337.537165 -383.390552) (xy 337.529124 -383.323726) (xy 336.427018 -383.323726) (xy 336.427146 -383.324067)
			(xy 336.443182 -383.389559) (xy 336.451257 -383.456499) (xy 336.451256 -383.523925) (xy 336.443177 -383.590865)
			(xy 336.427139 -383.656356) (xy 336.403371 -383.719453) (xy 336.372216 -383.77925) (xy 336.334122 -383.834883)
			(xy 336.312256 -383.860548) (xy 336.306451 -383.867687) (xy 336.299943 -383.884882) (xy 336.299556 -383.894076)
			(xy 336.299556 -384.051556) (xy 336.29898 -384.061655) (xy 336.291267 -384.080321) (xy 336.276999 -384.094616)
			(xy 336.258346 -384.102362) (xy 336.248248 -384.102864) (xy 335.531968 -384.102864) (xy 335.521839 -384.102509)
			(xy 335.503128 -384.094744) (xy 335.488813 -384.080408) (xy 335.481076 -384.061686) (xy 335.48066 -384.051556)
			(xy 335.48066 -383.894076) (xy 335.480248 -383.884889) (xy 335.473734 -383.867706) (xy 335.46796 -383.860548)
			(xy 335.446113 -383.834869) (xy 335.408027 -383.779236) (xy 335.376877 -383.719441) (xy 335.353114 -383.656346)
			(xy 335.337079 -383.590859) (xy 335.329002 -383.523923) (xy 335.329001 -383.456501) (xy 335.337074 -383.389565)
			(xy 335.353107 -383.324077) (xy 335.376868 -383.260981) (xy 335.408014 -383.201185) (xy 335.446098 -383.14555)
			(xy 335.46796 -383.119884) (xy 335.473753 -383.112737) (xy 335.480268 -383.095548) (xy 335.48066 -383.086356)
			(xy 335.48066 -382.59385) (xy 335.480213 -382.584667) (xy 335.473723 -382.567483) (xy 335.46796 -382.560322)
			(xy 335.446088 -382.534664) (xy 335.408002 -382.479028) (xy 335.376854 -382.41923) (xy 335.353092 -382.356132)
			(xy 335.337058 -382.290643) (xy 335.328984 -382.223704) (xy 332.050913 -382.223704) (xy 332.042877 -382.290466)
			(xy 332.026905 -382.355848) (xy 332.003234 -382.418852) (xy 331.972202 -382.478575) (xy 331.934255 -382.534162)
			(xy 331.912468 -382.559814) (xy 331.906679 -382.566964) (xy 331.90016 -382.584151) (xy 331.899768 -382.593342)
			(xy 331.899768 -383.086864) (xy 331.900203 -383.096048) (xy 331.9067 -383.113233) (xy 331.912468 -383.120392)
			(xy 331.934271 -383.146031) (xy 331.972219 -383.20162) (xy 332.003251 -383.261345) (xy 332.026711 -383.323786)
			(xy 333.128805 -383.323786) (xy 333.128808 -383.25636) (xy 333.136888 -383.189419) (xy 333.152927 -383.123927)
			(xy 333.176696 -383.060829) (xy 333.207852 -383.001032) (xy 333.245945 -382.945397) (xy 333.267812 -382.919732)
			(xy 333.273621 -382.912596) (xy 333.280128 -382.895398) (xy 333.280512 -382.886204) (xy 333.280512 -382.728724)
			(xy 333.280936 -382.718602) (xy 333.288678 -382.699896) (xy 333.302993 -382.685581) (xy 333.321698 -382.677837)
			(xy 333.33182 -382.677416) (xy 334.0481 -382.677416) (xy 334.058224 -382.677816) (xy 334.076931 -382.685568)
			(xy 334.091246 -382.699889) (xy 334.098988 -382.718599) (xy 334.099408 -382.728724) (xy 334.099408 -382.886204)
			(xy 334.099815 -382.895392) (xy 334.106331 -382.912576) (xy 334.112108 -382.919732) (xy 334.133936 -382.945427)
			(xy 334.172026 -383.001057) (xy 334.203177 -383.060849) (xy 334.226943 -383.123942) (xy 334.242981 -383.189428)
			(xy 334.25106 -383.256363) (xy 334.251063 -383.323783) (xy 334.242991 -383.390719) (xy 334.226959 -383.456206)
			(xy 334.2032 -383.519301) (xy 334.172053 -383.579096) (xy 334.13397 -383.634731) (xy 334.112108 -383.660396)
			(xy 334.106332 -383.667556) (xy 334.099805 -383.684735) (xy 334.099408 -383.693924) (xy 334.099408 -384.186176)
			(xy 334.099828 -384.195362) (xy 334.106335 -384.212547) (xy 334.112108 -384.219704) (xy 334.134007 -384.24534)
			(xy 334.172094 -384.300979) (xy 334.203243 -384.360779) (xy 334.227005 -384.42388) (xy 334.243037 -384.489373)
			(xy 334.25111 -384.556314) (xy 334.251107 -384.62374) (xy 334.243028 -384.690681) (xy 334.226989 -384.756172)
			(xy 334.203221 -384.81927) (xy 334.172066 -384.879067) (xy 334.133974 -384.934703) (xy 334.112108 -384.960368)
			(xy 334.106301 -384.967506) (xy 334.099792 -384.984702) (xy 334.099408 -384.993896) (xy 334.099408 -385.151376)
			(xy 334.098965 -385.161496) (xy 334.091226 -385.180198) (xy 334.076918 -385.194512) (xy 334.05822 -385.20226)
			(xy 334.0481 -385.202684) (xy 333.33182 -385.202684) (xy 333.321697 -385.202267) (xy 333.302991 -385.194523)
			(xy 333.288675 -385.180206) (xy 333.280932 -385.161499) (xy 333.280512 -385.151376) (xy 333.280512 -384.993896)
			(xy 333.280101 -384.984709) (xy 333.273587 -384.967525) (xy 333.267812 -384.960368) (xy 333.245983 -384.934674)
			(xy 333.207892 -384.879044) (xy 333.176739 -384.819252) (xy 333.152973 -384.756158) (xy 333.136934 -384.690673)
			(xy 333.128855 -384.623738) (xy 333.128852 -384.556316) (xy 333.136925 -384.48938) (xy 333.152957 -384.423893)
			(xy 333.176717 -384.360798) (xy 333.207865 -384.301003) (xy 333.24595 -384.245369) (xy 333.267812 -384.219704)
			(xy 333.273591 -384.212546) (xy 333.280116 -384.195365) (xy 333.280512 -384.186176) (xy 333.280512 -383.693924)
			(xy 333.280088 -383.684738) (xy 333.273583 -383.667554) (xy 333.267812 -383.660396) (xy 333.245912 -383.63476)
			(xy 333.207824 -383.579122) (xy 333.176674 -383.519322) (xy 333.152911 -383.456221) (xy 333.136878 -383.390728)
			(xy 333.128805 -383.323786) (xy 332.026711 -383.323786) (xy 332.026923 -383.324351) (xy 332.042895 -383.389735)
			(xy 332.050937 -383.456559) (xy 332.050936 -383.523865) (xy 332.04289 -383.590689) (xy 332.026916 -383.656072)
			(xy 332.003242 -383.719077) (xy 331.972207 -383.778801) (xy 331.934257 -383.834388) (xy 331.912468 -383.86004)
			(xy 331.906668 -383.867183) (xy 331.900156 -383.884375) (xy 331.899768 -383.893568) (xy 331.899768 -384.051556)
			(xy 331.899342 -384.061711) (xy 331.891555 -384.080469) (xy 331.877159 -384.094795) (xy 331.858363 -384.10249)
			(xy 331.848206 -384.102864) (xy 331.131926 -384.102864) (xy 331.121801 -384.102352) (xy 331.103082 -384.094634)
			(xy 331.088724 -384.080355) (xy 331.080904 -384.061678) (xy 331.080364 -384.051556) (xy 331.080364 -383.893568)
			(xy 331.079955 -383.884381) (xy 331.073439 -383.867198) (xy 331.067664 -383.86004) (xy 331.045891 -383.834375)
			(xy 331.00794 -383.778791) (xy 330.976905 -383.71907) (xy 330.95323 -383.656067) (xy 330.937256 -383.590686)
			(xy 330.92921 -383.523864) (xy 330.929208 -383.45656) (xy 330.937251 -383.389738) (xy 330.953223 -383.324356)
			(xy 330.976895 -383.261352) (xy 331.007928 -383.20163) (xy 331.045877 -383.146044) (xy 331.067664 -383.120392)
			(xy 331.073454 -383.113243) (xy 331.079971 -383.096055) (xy 331.080364 -383.086864) (xy 331.080364 -382.593342)
			(xy 331.079919 -382.584159) (xy 331.073428 -382.566975) (xy 331.067664 -382.559814) (xy 331.045866 -382.53417)
			(xy 331.007916 -382.478583) (xy 330.976881 -382.418859) (xy 330.953208 -382.355853) (xy 330.937235 -382.29047)
			(xy 330.929191 -382.223646) (xy 301.250888 -382.223646) (xy 301.250888 -382.223704) (xy 301.242813 -382.290641)
			(xy 301.226779 -382.356129) (xy 301.203017 -382.419226) (xy 301.171869 -382.479022) (xy 301.133783 -382.534656)
			(xy 301.11192 -382.560322) (xy 301.106134 -382.567475) (xy 301.099612 -382.584659) (xy 301.09922 -382.59385)
			(xy 301.09922 -383.086356) (xy 301.099647 -383.095542) (xy 301.106148 -383.112726) (xy 301.11192 -383.119884)
			(xy 301.133799 -383.145537) (xy 301.171886 -383.201173) (xy 301.203035 -383.260972) (xy 301.22669 -383.323786)
			(xy 302.328775 -383.323786) (xy 302.328778 -383.25636) (xy 302.336857 -383.18942) (xy 302.352895 -383.123929)
			(xy 302.376662 -383.060831) (xy 302.407816 -383.001033) (xy 302.445907 -382.945398) (xy 302.467772 -382.919732)
			(xy 302.473589 -382.912601) (xy 302.480089 -382.895399) (xy 302.480472 -382.886204) (xy 302.480472 -382.728724)
			(xy 302.480935 -382.718606) (xy 302.48867 -382.699909) (xy 302.502972 -382.685595) (xy 302.521663 -382.677843)
			(xy 302.53178 -382.677416) (xy 303.24806 -382.677416) (xy 303.258182 -382.677849) (xy 303.276888 -382.685587)
			(xy 303.291204 -382.699899) (xy 303.298948 -382.718602) (xy 303.299368 -382.728724) (xy 303.299368 -382.886204)
			(xy 303.299783 -382.89539) (xy 303.306294 -382.912575) (xy 303.312068 -382.919732) (xy 303.333898 -382.945426)
			(xy 303.37199 -383.001056) (xy 303.403144 -383.060847) (xy 303.426911 -383.123941) (xy 303.44295 -383.189427)
			(xy 303.451029 -383.256362) (xy 303.451033 -383.323784) (xy 303.44296 -383.39072) (xy 303.426927 -383.456208)
			(xy 303.403166 -383.519303) (xy 303.372017 -383.579098) (xy 303.333931 -383.634731) (xy 303.312068 -383.660396)
			(xy 303.306286 -383.667552) (xy 303.299764 -383.684734) (xy 303.299368 -383.693924) (xy 303.299368 -384.186176)
			(xy 303.299797 -384.195361) (xy 303.306299 -384.212545) (xy 303.312068 -384.219704) (xy 303.333968 -384.24534)
			(xy 303.372058 -384.300978) (xy 303.403209 -384.360778) (xy 303.426973 -384.423878) (xy 303.443007 -384.489371)
			(xy 303.45108 -384.556313) (xy 303.451077 -384.623741) (xy 303.442997 -384.690682) (xy 303.426957 -384.756173)
			(xy 303.403187 -384.819272) (xy 303.37203 -384.879069) (xy 303.333935 -384.934703) (xy 303.312068 -384.960368)
			(xy 303.306256 -384.967502) (xy 303.299751 -384.984701) (xy 303.299368 -384.993896) (xy 303.299368 -385.151376)
			(xy 303.298964 -385.161501) (xy 303.291218 -385.18021) (xy 303.276897 -385.194527) (xy 303.258185 -385.202267)
			(xy 303.24806 -385.202684) (xy 302.53178 -385.202684) (xy 302.521654 -385.2023) (xy 302.502947 -385.194542)
			(xy 302.488633 -385.180216) (xy 302.480891 -385.161502) (xy 302.480472 -385.151376) (xy 302.480472 -384.993896)
			(xy 302.48007 -384.984708) (xy 302.473551 -384.967523) (xy 302.467772 -384.960368) (xy 302.445944 -384.934673)
			(xy 302.407856 -384.879042) (xy 302.376706 -384.81925) (xy 302.352941 -384.756157) (xy 302.336904 -384.690672)
			(xy 302.328825 -384.623737) (xy 302.328822 -384.556317) (xy 302.336894 -384.489382) (xy 302.352925 -384.423895)
			(xy 302.376684 -384.3608) (xy 302.407829 -384.301004) (xy 302.445911 -384.24537) (xy 302.467772 -384.219704)
			(xy 302.473558 -384.212552) (xy 302.480077 -384.195366) (xy 302.480472 -384.186176) (xy 302.480472 -383.693924)
			(xy 302.480057 -383.684737) (xy 302.473547 -383.667552) (xy 302.467772 -383.660396) (xy 302.445874 -383.634759)
			(xy 302.407788 -383.57912) (xy 302.37664 -383.51932) (xy 302.352879 -383.456219) (xy 302.336847 -383.390727)
			(xy 302.328775 -383.323786) (xy 301.22669 -383.323786) (xy 301.226797 -383.32407) (xy 301.242831 -383.38956)
			(xy 301.250905 -383.4565) (xy 301.250904 -383.523924) (xy 301.242827 -383.590863) (xy 301.22679 -383.656353)
			(xy 301.203025 -383.71945) (xy 301.171874 -383.779247) (xy 301.133784 -383.834882) (xy 301.11192 -383.860548)
			(xy 301.106123 -383.867693) (xy 301.099608 -383.884884) (xy 301.09922 -383.894076) (xy 301.09922 -384.051556)
			(xy 301.098748 -384.061673) (xy 301.091018 -384.080372) (xy 301.076719 -384.094687) (xy 301.058029 -384.102437)
			(xy 301.047912 -384.102864) (xy 300.331632 -384.102864) (xy 300.321507 -384.102457) (xy 300.302797 -384.094713)
			(xy 300.28848 -384.080393) (xy 300.28074 -384.061681) (xy 300.280324 -384.051556) (xy 300.280324 -383.894076)
			(xy 300.27992 -383.884888) (xy 300.273402 -383.867704) (xy 300.267624 -383.860548) (xy 300.245775 -383.83487)
			(xy 300.207684 -383.779238) (xy 300.176531 -383.719444) (xy 300.152765 -383.656349) (xy 300.136728 -383.590861)
			(xy 300.12865 -383.523923) (xy 300.128649 -383.456501) (xy 300.136724 -383.389563) (xy 300.152758 -383.324074)
			(xy 300.176522 -383.260978) (xy 300.207672 -383.201183) (xy 300.24576 -383.145549) (xy 300.267624 -383.119884)
			(xy 300.273413 -383.112733) (xy 300.279931 -383.095547) (xy 300.280324 -383.086356) (xy 300.280324 -382.59385)
			(xy 300.279884 -382.584666) (xy 300.273391 -382.567482) (xy 300.267624 -382.560322) (xy 300.245749 -382.534665)
			(xy 300.207659 -382.47903) (xy 300.176508 -382.419233) (xy 300.152743 -382.356135) (xy 300.136708 -382.290645)
			(xy 300.128632 -382.223705) (xy 296.851097 -382.223705) (xy 296.843022 -382.290641) (xy 296.826989 -382.356129)
			(xy 296.803227 -382.419225) (xy 296.77208 -382.479021) (xy 296.733994 -382.534656) (xy 296.712132 -382.560322)
			(xy 296.706335 -382.567467) (xy 296.699823 -382.584658) (xy 296.699432 -382.59385) (xy 296.699432 -383.086356)
			(xy 296.699878 -383.095539) (xy 296.706368 -383.112723) (xy 296.712132 -383.119884) (xy 296.734011 -383.145537)
			(xy 296.772097 -383.201174) (xy 296.803245 -383.260972) (xy 296.826877 -383.323727) (xy 297.928982 -383.323727)
			(xy 297.928985 -383.256419) (xy 297.937033 -383.189593) (xy 297.953011 -383.124208) (xy 297.97669 -383.061202)
			(xy 298.007729 -383.001478) (xy 298.045685 -382.945891) (xy 298.067476 -382.92024) (xy 298.073278 -382.913098)
			(xy 298.07979 -382.895905) (xy 298.080176 -382.886712) (xy 298.080176 -382.728724) (xy 298.080641 -382.718574)
			(xy 298.088424 -382.699827) (xy 298.102807 -382.685504) (xy 298.121587 -382.677799) (xy 298.131738 -382.677416)
			(xy 298.848018 -382.677416) (xy 298.858143 -382.677911) (xy 298.87686 -382.68564) (xy 298.891215 -382.699923)
			(xy 298.899038 -382.718602) (xy 298.89958 -382.728724) (xy 298.89958 -382.886712) (xy 298.899989 -382.895899)
			(xy 298.906504 -382.913083) (xy 298.91228 -382.92024) (xy 298.934031 -382.945922) (xy 298.97198 -383.001504)
			(xy 299.003014 -383.061224) (xy 299.026688 -383.124225) (xy 299.042663 -383.189603) (xy 299.050709 -383.256422)
			(xy 299.050713 -383.323724) (xy 299.042672 -383.390544) (xy 299.026704 -383.455924) (xy 299.003036 -383.518926)
			(xy 298.972008 -383.578649) (xy 298.934065 -383.634235) (xy 298.91228 -383.659888) (xy 298.906461 -383.667017)
			(xy 298.89996 -383.68422) (xy 298.89958 -383.693416) (xy 298.89958 -384.186684) (xy 298.900003 -384.19587)
			(xy 298.906508 -384.213054) (xy 298.91228 -384.220212) (xy 298.934103 -384.245835) (xy 298.972049 -384.301426)
			(xy 299.00308 -384.361154) (xy 299.02675 -384.424162) (xy 299.04272 -384.489548) (xy 299.050761 -384.556373)
			(xy 299.050757 -384.623681) (xy 299.04271 -384.690506) (xy 299.026734 -384.75589) (xy 299.003058 -384.818895)
			(xy 298.972021 -384.87862) (xy 298.934069 -384.934208) (xy 298.91228 -384.95986) (xy 298.906473 -384.966998)
			(xy 298.899965 -384.984194) (xy 298.89958 -384.993388) (xy 298.89958 -385.151376) (xy 298.899159 -385.161531)
			(xy 298.891367 -385.180287) (xy 298.87697 -385.194612) (xy 298.858175 -385.202309) (xy 298.848018 -385.202684)
			(xy 298.131738 -385.202684) (xy 298.121617 -385.202143) (xy 298.102901 -385.194432) (xy 298.088544 -385.180162)
			(xy 298.08072 -385.161494) (xy 298.080176 -385.151376) (xy 298.080176 -384.993388) (xy 298.079777 -384.9842)
			(xy 298.073256 -384.967015) (xy 298.067476 -384.95986) (xy 298.045723 -384.934179) (xy 298.00777 -384.878598)
			(xy 297.976733 -384.818878) (xy 297.953057 -384.755878) (xy 297.93708 -384.690499) (xy 297.929033 -384.623679)
			(xy 297.92903 -384.556376) (xy 297.937071 -384.489555) (xy 297.953041 -384.424174) (xy 297.976711 -384.361171)
			(xy 298.007742 -384.301449) (xy 298.045689 -384.245864) (xy 298.067476 -384.220212) (xy 298.07329 -384.213079)
			(xy 298.079795 -384.195879) (xy 298.080176 -384.186684) (xy 298.080176 -383.693416) (xy 298.079764 -383.684229)
			(xy 298.073252 -383.667044) (xy 298.067476 -383.659888) (xy 298.045651 -383.634266) (xy 298.007701 -383.578676)
			(xy 297.976668 -383.518948) (xy 297.952995 -383.45594) (xy 297.937024 -383.390554) (xy 297.928982 -383.323727)
			(xy 296.826877 -383.323727) (xy 296.827007 -383.324071) (xy 296.84304 -383.389561) (xy 296.851114 -383.4565)
			(xy 296.851113 -383.523924) (xy 296.843036 -383.590863) (xy 296.827 -383.656352) (xy 296.803235 -383.71945)
			(xy 296.772084 -383.779247) (xy 296.733996 -383.834882) (xy 296.712132 -383.860548) (xy 296.706324 -383.867685)
			(xy 296.699818 -383.884882) (xy 296.699432 -383.894076) (xy 296.699432 -384.051556) (xy 296.698949 -384.061672)
			(xy 296.691221 -384.080368) (xy 296.676925 -384.094683) (xy 296.658239 -384.102435) (xy 296.648124 -384.102864)
			(xy 295.931844 -384.102864) (xy 295.92172 -384.102447) (xy 295.90301 -384.094707) (xy 295.888693 -384.08039)
			(xy 295.880953 -384.06168) (xy 295.880536 -384.051556) (xy 295.880536 -383.894076) (xy 295.880129 -383.884889)
			(xy 295.873612 -383.867705) (xy 295.867836 -383.860548) (xy 295.845986 -383.83487) (xy 295.807895 -383.779238)
			(xy 295.776742 -383.719444) (xy 295.752975 -383.656349) (xy 295.736937 -383.590861) (xy 295.728859 -383.523924)
			(xy 295.728858 -383.4565) (xy 295.736933 -383.389563) (xy 295.752968 -383.324074) (xy 295.776732 -383.260978)
			(xy 295.807883 -383.201182) (xy 295.845972 -383.145549) (xy 295.867836 -383.119884) (xy 295.873626 -383.112735)
			(xy 295.880144 -383.095547) (xy 295.880536 -383.086356) (xy 295.880536 -382.59385) (xy 295.880094 -382.584666)
			(xy 295.873601 -382.567482) (xy 295.867836 -382.560322) (xy 295.845961 -382.534665) (xy 295.80787 -382.479031)
			(xy 295.776718 -382.419233) (xy 295.752953 -382.356135) (xy 295.736917 -382.290645) (xy 295.728841 -382.223705)
			(xy 292.450794 -382.223705) (xy 292.442758 -382.290467) (xy 292.426786 -382.355849) (xy 292.403113 -382.418853)
			(xy 292.37208 -382.478576) (xy 292.334131 -382.534162) (xy 292.312344 -382.559814) (xy 292.306552 -382.566962)
			(xy 292.300036 -382.584151) (xy 292.299644 -382.593342) (xy 292.299644 -383.086864) (xy 292.300084 -383.096048)
			(xy 292.306578 -383.113232) (xy 292.312344 -383.120392) (xy 292.334148 -383.146031) (xy 292.372098 -383.201619)
			(xy 292.403131 -383.261344) (xy 292.426592 -383.323786) (xy 293.528687 -383.323786) (xy 293.52869 -383.25636)
			(xy 293.536769 -383.189419) (xy 293.552808 -383.123928) (xy 293.576576 -383.06083) (xy 293.60773 -383.001033)
			(xy 293.645822 -382.945397) (xy 293.667688 -382.919732) (xy 293.673495 -382.912594) (xy 293.680004 -382.895398)
			(xy 293.680388 -382.886204) (xy 293.680388 -382.728724) (xy 293.680835 -382.718605) (xy 293.688573 -382.699904)
			(xy 293.70288 -382.685589) (xy 293.721577 -382.677841) (xy 293.731696 -382.677416) (xy 294.447976 -382.677416)
			(xy 294.458099 -382.677836) (xy 294.476805 -382.685579) (xy 294.491121 -382.699895) (xy 294.498864 -382.718601)
			(xy 294.499284 -382.728724) (xy 294.499284 -382.886204) (xy 294.499696 -382.895391) (xy 294.506209 -382.912575)
			(xy 294.511984 -382.919732) (xy 294.533813 -382.945426) (xy 294.571904 -383.001056) (xy 294.603057 -383.060848)
			(xy 294.626824 -383.123941) (xy 294.642863 -383.189427) (xy 294.650942 -383.256362) (xy 294.650945 -383.323784)
			(xy 294.642872 -383.39072) (xy 294.62684 -383.456207) (xy 294.603079 -383.519302) (xy 294.571932 -383.579097)
			(xy 294.533846 -383.634731) (xy 294.511984 -383.660396) (xy 294.506205 -383.667553) (xy 294.49968 -383.684735)
			(xy 294.499284 -383.693924) (xy 294.499284 -384.186176) (xy 294.499709 -384.195361) (xy 294.506213 -384.212546)
			(xy 294.511984 -384.219704) (xy 294.533884 -384.24534) (xy 294.571973 -384.300978) (xy 294.603123 -384.360778)
			(xy 294.626885 -384.423879) (xy 294.642919 -384.489372) (xy 294.650992 -384.556314) (xy 294.650989 -384.62374)
			(xy 294.642909 -384.690681) (xy 294.626869 -384.756173) (xy 294.603101 -384.819271) (xy 294.571945 -384.879068)
			(xy 294.533851 -384.934703) (xy 294.511984 -384.960368) (xy 294.506174 -384.967504) (xy 294.499668 -384.984702)
			(xy 294.499284 -384.993896) (xy 294.499284 -385.151376) (xy 294.498864 -385.161499) (xy 294.491121 -385.180205)
			(xy 294.476805 -385.194521) (xy 294.458099 -385.202264) (xy 294.447976 -385.202684) (xy 293.731696 -385.202684)
			(xy 293.721571 -385.202287) (xy 293.702865 -385.194534) (xy 293.68855 -385.180212) (xy 293.680808 -385.161501)
			(xy 293.680388 -385.151376) (xy 293.680388 -384.993896) (xy 293.679982 -384.984708) (xy 293.673466 -384.967524)
			(xy 293.667688 -384.960368) (xy 293.64586 -384.934673) (xy 293.607771 -384.879043) (xy 293.576619 -384.819251)
			(xy 293.552854 -384.756158) (xy 293.536816 -384.690672) (xy 293.528737 -384.623737) (xy 293.528734 -384.556317)
			(xy 293.536806 -384.489381) (xy 293.552838 -384.423894) (xy 293.576597 -384.360799) (xy 293.607743 -384.301004)
			(xy 293.645827 -384.245369) (xy 293.667688 -384.219704) (xy 293.673464 -384.212544) (xy 293.679991 -384.195365)
			(xy 293.680388 -384.186176) (xy 293.680388 -383.693924) (xy 293.679969 -383.684738) (xy 293.673462 -383.667553)
			(xy 293.667688 -383.660396) (xy 293.645789 -383.63476) (xy 293.607702 -383.579121) (xy 293.576554 -383.51932)
			(xy 293.552792 -383.45622) (xy 293.53676 -383.390727) (xy 293.528687 -383.323786) (xy 292.426592 -383.323786)
			(xy 292.426804 -383.32435) (xy 292.442776 -383.389734) (xy 292.450819 -383.456559) (xy 292.450818 -383.523865)
			(xy 292.442772 -383.590689) (xy 292.426797 -383.656073) (xy 292.403121 -383.719078) (xy 292.372085 -383.778802)
			(xy 292.334133 -383.834388) (xy 292.312344 -383.86004) (xy 292.306541 -383.86718) (xy 292.300032 -383.884375)
			(xy 292.299644 -383.893568) (xy 292.299644 -384.051556) (xy 292.299149 -384.06167) (xy 292.291423 -384.080364)
			(xy 292.277132 -384.094679) (xy 292.258449 -384.102433) (xy 292.248336 -384.102864) (xy 291.531802 -384.102864)
			(xy 291.521676 -384.102372) (xy 291.502956 -384.094645) (xy 291.488599 -384.080361) (xy 291.480779 -384.06168)
			(xy 291.48024 -384.051556) (xy 291.48024 -383.893568) (xy 291.479836 -383.88438) (xy 291.473317 -383.867197)
			(xy 291.46754 -383.86004) (xy 291.445768 -383.834375) (xy 291.407819 -383.77879) (xy 291.376785 -383.719068)
			(xy 291.353111 -383.656066) (xy 291.337137 -383.590685) (xy 291.329092 -383.523864) (xy 291.32909 -383.45656)
			(xy 291.337133 -383.389739) (xy 291.353104 -383.324357) (xy 291.376775 -383.261354) (xy 291.407806 -383.20163)
			(xy 291.445753 -383.146044) (xy 291.46754 -383.120392) (xy 291.473328 -383.113241) (xy 291.479847 -383.096055)
			(xy 291.48024 -383.086864) (xy 291.48024 -382.593342) (xy 291.4798 -382.584158) (xy 291.473306 -382.566974)
			(xy 291.46754 -382.559814) (xy 291.445742 -382.53417) (xy 291.407794 -382.478582) (xy 291.376761 -382.418858)
			(xy 291.353088 -382.355852) (xy 291.337116 -382.290469) (xy 291.329073 -382.223645) (xy 288.051034 -382.223645)
			(xy 288.051034 -382.223704) (xy 288.042958 -382.290643) (xy 288.026922 -382.356132) (xy 288.003157 -382.419229)
			(xy 287.972004 -382.479024) (xy 287.933913 -382.534658) (xy 287.912048 -382.560322) (xy 287.906253 -382.567468)
			(xy 287.899739 -382.584658) (xy 287.899348 -382.59385) (xy 287.899348 -383.086356) (xy 287.899791 -383.095539)
			(xy 287.906283 -383.112723) (xy 287.912048 -383.119884) (xy 287.93393 -383.145535) (xy 287.972021 -383.201171)
			(xy 288.003174 -383.260968) (xy 288.026812 -383.323727) (xy 289.128894 -383.323727) (xy 289.128898 -383.256418)
			(xy 289.136946 -383.189593) (xy 289.152924 -383.124208) (xy 289.176604 -383.061202) (xy 289.207644 -383.001477)
			(xy 289.245601 -382.945891) (xy 289.267392 -382.92024) (xy 289.273196 -382.9131) (xy 289.279706 -382.895905)
			(xy 289.280092 -382.886712) (xy 289.280092 -382.728724) (xy 289.280535 -382.718604) (xy 289.288274 -382.699902)
			(xy 289.302582 -382.685588) (xy 289.32128 -382.67784) (xy 289.3314 -382.677416) (xy 290.047934 -382.677416)
			(xy 290.05806 -382.677898) (xy 290.076777 -382.685632) (xy 290.091132 -382.69992) (xy 290.098954 -382.7186)
			(xy 290.099496 -382.728724) (xy 290.099496 -382.886712) (xy 290.099901 -382.8959) (xy 290.106419 -382.913084)
			(xy 290.112196 -382.92024) (xy 290.133947 -382.945922) (xy 290.171895 -383.001505) (xy 290.202928 -383.061225)
			(xy 290.226601 -383.124225) (xy 290.242576 -383.189603) (xy 290.250622 -383.256422) (xy 290.250625 -383.323724)
			(xy 290.242585 -383.390543) (xy 290.226617 -383.455923) (xy 290.20295 -383.518926) (xy 290.171923 -383.578649)
			(xy 290.133981 -383.634235) (xy 290.112196 -383.659888) (xy 290.106379 -383.667019) (xy 290.099877 -383.68422)
			(xy 290.099496 -383.693416) (xy 290.099496 -384.186684) (xy 290.099915 -384.19587) (xy 290.106423 -384.213055)
			(xy 290.112196 -384.220212) (xy 290.134018 -384.245836) (xy 290.171963 -384.301427) (xy 290.202993 -384.361155)
			(xy 290.226662 -384.424163) (xy 290.242632 -384.489548) (xy 290.250673 -384.556373) (xy 290.250669 -384.623681)
			(xy 290.242622 -384.690505) (xy 290.226646 -384.755889) (xy 290.202971 -384.818895) (xy 290.171936 -384.87862)
			(xy 290.133985 -384.934207) (xy 290.112196 -384.95986) (xy 290.106391 -384.966999) (xy 290.099881 -384.984194)
			(xy 290.099496 -384.993388) (xy 290.099496 -385.151376) (xy 290.099064 -385.161497) (xy 290.091323 -385.180201)
			(xy 290.077011 -385.194517) (xy 290.058309 -385.202262) (xy 290.048188 -385.202684) (xy 289.331654 -385.202684)
			(xy 289.321527 -385.202212) (xy 289.30281 -385.194473) (xy 289.288456 -385.180183) (xy 289.280634 -385.1615)
			(xy 289.280092 -385.151376) (xy 289.280092 -384.993388) (xy 289.279689 -384.9842) (xy 289.273171 -384.967016)
			(xy 289.267392 -384.95986) (xy 289.245638 -384.934179) (xy 289.207685 -384.878598) (xy 289.176647 -384.818879)
			(xy 289.15297 -384.755878) (xy 289.136993 -384.690499) (xy 289.128945 -384.623679) (xy 289.128942 -384.556375)
			(xy 289.136983 -384.489554) (xy 289.152954 -384.424174) (xy 289.176625 -384.36117) (xy 289.207657 -384.301448)
			(xy 289.245605 -384.245863) (xy 289.267392 -384.220212) (xy 289.273208 -384.21308) (xy 289.279711 -384.195879)
			(xy 289.280092 -384.186684) (xy 289.280092 -383.693416) (xy 289.279676 -383.684229) (xy 289.273167 -383.667045)
			(xy 289.267392 -383.659888) (xy 289.245567 -383.634266) (xy 289.207616 -383.578676) (xy 289.176581 -383.518949)
			(xy 289.152908 -383.45594) (xy 289.136936 -383.390554) (xy 289.128894 -383.323727) (xy 288.026812 -383.323727)
			(xy 288.02694 -383.324067) (xy 288.042976 -383.389558) (xy 288.051051 -383.456499) (xy 288.05105 -383.523925)
			(xy 288.042971 -383.590865) (xy 288.026933 -383.656356) (xy 288.003164 -383.719454) (xy 287.972009 -383.77925)
			(xy 287.933915 -383.834884) (xy 287.912048 -383.860548) (xy 287.906242 -383.867686) (xy 287.899734 -383.884882)
			(xy 287.899348 -383.894076) (xy 287.899348 -384.051556) (xy 287.898849 -384.06167) (xy 287.891124 -384.080363)
			(xy 287.876834 -384.094677) (xy 287.858153 -384.102432) (xy 287.84804 -384.102864) (xy 287.13176 -384.102864)
			(xy 287.12163 -384.102516) (xy 287.102919 -384.094748) (xy 287.088605 -384.08041) (xy 287.080868 -384.061686)
			(xy 287.080452 -384.051556) (xy 287.080452 -383.894076) (xy 287.080042 -383.884889) (xy 287.073527 -383.867705)
			(xy 287.067752 -383.860548) (xy 287.045902 -383.834871) (xy 287.007809 -383.779239) (xy 286.976655 -383.719445)
			(xy 286.952888 -383.65635) (xy 286.936849 -383.590862) (xy 286.928772 -383.523924) (xy 286.92877 -383.4565)
			(xy 286.936845 -383.389562) (xy 286.952881 -383.324073) (xy 286.976645 -383.260977) (xy 287.007797 -383.201182)
			(xy 287.045887 -383.145548) (xy 287.067752 -383.119884) (xy 287.073544 -383.112736) (xy 287.08006 -383.095547)
			(xy 287.080452 -383.086356) (xy 287.080452 -382.59385) (xy 287.080006 -382.584667) (xy 287.073516 -382.567483)
			(xy 287.067752 -382.560322) (xy 287.045876 -382.534666) (xy 287.007785 -382.479031) (xy 286.976631 -382.419234)
			(xy 286.952865 -382.356136) (xy 286.936829 -382.290645) (xy 286.928753 -382.223705) (xy 262.654796 -382.223705)
			(xy 262.654796 -385.608376) (xy 454.303373 -385.608376) (xy 454.303373 -385.479236) (xy 454.311323 -385.350341)
			(xy 454.327193 -385.222181) (xy 454.350922 -385.09524) (xy 454.382421 -384.970001) (xy 454.42157 -384.846938)
			(xy 454.468221 -384.726519) (xy 454.522196 -384.6092) (xy 454.583291 -384.495426) (xy 454.651274 -384.385629)
			(xy 454.725888 -384.280226) (xy 454.806849 -384.179616) (xy 454.893849 -384.084181) (xy 454.98656 -383.994282)
			(xy 455.08463 -383.910261) (xy 455.187685 -383.832437) (xy 455.295336 -383.761105) (xy 455.407175 -383.696535)
			(xy 455.522776 -383.638973) (xy 455.641701 -383.588636) (xy 455.7635 -383.545716) (xy 455.88771 -383.510375)
			(xy 456.013859 -383.482748) (xy 456.141471 -383.462939) (xy 456.27006 -383.451023) (xy 456.399138 -383.447047)
			(xy 456.528216 -383.451023) (xy 456.656805 -383.462939) (xy 456.784417 -383.482748) (xy 456.910566 -383.510375)
			(xy 457.034776 -383.545716) (xy 457.156575 -383.588636) (xy 457.2755 -383.638973) (xy 457.391101 -383.696535)
			(xy 457.50294 -383.761105) (xy 457.610591 -383.832437) (xy 457.713646 -383.910261) (xy 457.811716 -383.994282)
			(xy 457.904427 -384.084181) (xy 457.991427 -384.179616) (xy 458.072388 -384.280226) (xy 458.147002 -384.385629)
			(xy 458.214985 -384.495426) (xy 458.27608 -384.6092) (xy 458.330055 -384.726519) (xy 458.376706 -384.846938)
			(xy 458.415855 -384.970001) (xy 458.447354 -385.09524) (xy 458.471083 -385.222181) (xy 458.486953 -385.350341)
			(xy 458.494903 -385.479236) (xy 458.4954 -385.543806) (xy 458.494903 -385.608376) (xy 458.486953 -385.737271)
			(xy 458.471083 -385.865431) (xy 458.447354 -385.992372) (xy 458.415855 -386.117611) (xy 458.376706 -386.240674)
			(xy 458.330055 -386.361093) (xy 458.27608 -386.478412) (xy 458.214985 -386.592186) (xy 458.147002 -386.701983)
			(xy 458.072388 -386.807386) (xy 457.991427 -386.907996) (xy 457.904427 -387.003431) (xy 457.811716 -387.09333)
			(xy 457.713646 -387.177351) (xy 457.610591 -387.255175) (xy 457.50294 -387.326507) (xy 457.391101 -387.391077)
			(xy 457.2755 -387.448639) (xy 457.156575 -387.498976) (xy 457.034776 -387.541896) (xy 456.910566 -387.577237)
			(xy 456.784417 -387.604864) (xy 456.656805 -387.624673) (xy 456.528216 -387.636589) (xy 456.399138 -387.640566)
			(xy 456.27006 -387.636589) (xy 456.141471 -387.624673) (xy 456.013859 -387.604864) (xy 455.88771 -387.577237)
			(xy 455.7635 -387.541896) (xy 455.641701 -387.498976) (xy 455.522776 -387.448639) (xy 455.407175 -387.391077)
			(xy 455.295336 -387.326507) (xy 455.187685 -387.255175) (xy 455.08463 -387.177351) (xy 454.98656 -387.09333)
			(xy 454.893849 -387.003431) (xy 454.806849 -386.907996) (xy 454.725888 -386.807386) (xy 454.651274 -386.701983)
			(xy 454.583291 -386.592186) (xy 454.522196 -386.478412) (xy 454.468221 -386.361093) (xy 454.42157 -386.240674)
			(xy 454.382421 -386.117611) (xy 454.350922 -385.992372) (xy 454.327193 -385.865431) (xy 454.311323 -385.737271)
			(xy 454.303373 -385.608376) (xy 262.654796 -385.608376) (xy 262.654796 -387.940042) (xy 262.654324 -387.964992)
			(xy 262.646505 -388.014277) (xy 262.631083 -388.061734) (xy 262.608436 -388.1062) (xy 262.57912 -388.146581)
			(xy 262.561832 -388.164578) (xy 259.433314 -391.293096) (xy 259.415316 -391.310383) (xy 259.374941 -391.339708)
			(xy 259.330476 -391.362356) (xy 259.283016 -391.377771) (xy 259.233728 -391.385573) (xy 259.208778 -391.38606)
			(xy 245.30812 -391.38606) (xy 245.29805 -391.38648) (xy 245.279451 -391.394203) (xy 245.272052 -391.401046)
			(xy 244.461792 -392.211306) (xy 244.454956 -392.218709) (xy 244.447234 -392.237306) (xy 244.446806 -392.247374)
			(xy 244.446806 -397.823885) (xy 286.928734 -397.823885) (xy 286.928737 -397.756458) (xy 286.936817 -397.689516)
			(xy 286.952859 -397.624024) (xy 286.976629 -397.560925) (xy 287.007787 -397.501128) (xy 287.045884 -397.445494)
			(xy 287.067752 -397.41983) (xy 287.073567 -397.412698) (xy 287.080069 -397.395497) (xy 287.080452 -397.386302)
			(xy 287.080452 -396.89405) (xy 287.080006 -396.884867) (xy 287.073516 -396.867683) (xy 287.067752 -396.860522)
			(xy 287.045876 -396.834866) (xy 287.007785 -396.779231) (xy 286.976631 -396.719434) (xy 286.952865 -396.656336)
			(xy 286.936829 -396.590845) (xy 286.928753 -396.523905) (xy 286.928754 -396.45648) (xy 286.936832 -396.38954)
			(xy 286.95287 -396.32405) (xy 286.976638 -396.260952) (xy 287.007792 -396.201156) (xy 287.045886 -396.145522)
			(xy 287.067752 -396.119858) (xy 287.073555 -396.112718) (xy 287.080065 -396.095523) (xy 287.080452 -396.08633)
			(xy 287.080452 -395.92885) (xy 287.080968 -395.918725) (xy 287.088682 -395.900003) (xy 287.102959 -395.885644)
			(xy 287.121638 -395.877825) (xy 287.13176 -395.877288) (xy 287.84804 -395.877288) (xy 287.858195 -395.877689)
			(xy 287.876946 -395.885495) (xy 287.891268 -395.899898) (xy 287.898968 -395.918693) (xy 287.899348 -395.92885)
			(xy 287.899348 -396.08633) (xy 287.899755 -396.095517) (xy 287.906272 -396.112701) (xy 287.912048 -396.119858)
			(xy 287.933904 -396.14553) (xy 287.971996 -396.201163) (xy 288.00315 -396.260957) (xy 288.026917 -396.324053)
			(xy 288.042955 -396.389542) (xy 288.051033 -396.456481) (xy 288.051034 -396.523904) (xy 288.042958 -396.590843)
			(xy 288.026922 -396.656332) (xy 288.003157 -396.719429) (xy 287.972004 -396.779224) (xy 287.933913 -396.834858)
			(xy 287.912048 -396.860522) (xy 287.906253 -396.867668) (xy 287.899739 -396.884858) (xy 287.899348 -396.89405)
			(xy 287.899348 -397.386302) (xy 287.899769 -397.395488) (xy 287.906276 -397.412672) (xy 287.912048 -397.41983)
			(xy 287.933876 -397.445525) (xy 287.97197 -397.501154) (xy 288.000733 -397.556355) (xy 289.128926 -397.556355)
			(xy 289.13697 -397.489532) (xy 289.152943 -397.42415) (xy 289.176617 -397.361145) (xy 289.207652 -397.301423)
			(xy 289.245603 -397.245837) (xy 289.267392 -397.220186) (xy 289.273176 -397.213032) (xy 289.279698 -397.195848)
			(xy 289.280092 -397.186658) (xy 289.280092 -397.028924) (xy 289.280541 -397.018772) (xy 289.288327 -397.000022)
			(xy 289.302715 -396.985698) (xy 289.321501 -396.977996) (xy 289.331654 -396.977616) (xy 290.047934 -396.977616)
			(xy 290.05806 -396.978098) (xy 290.076777 -396.985832) (xy 290.091132 -397.00012) (xy 290.098954 -397.0188)
			(xy 290.099496 -397.028924) (xy 290.099496 -397.186658) (xy 290.099927 -397.195843) (xy 290.106426 -397.213027)
			(xy 290.112196 -397.220186) (xy 290.133992 -397.245831) (xy 290.171939 -397.301419) (xy 290.20297 -397.361144)
			(xy 290.22664 -397.424149) (xy 290.242612 -397.489532) (xy 290.250654 -397.556355) (xy 290.250653 -397.62366)
			(xy 290.242609 -397.690483) (xy 290.226636 -397.755865) (xy 290.202963 -397.81887) (xy 290.200388 -397.823825)
			(xy 291.329053 -397.823825) (xy 291.329057 -397.756517) (xy 291.337105 -397.689692) (xy 291.353082 -397.624308)
			(xy 291.376759 -397.561302) (xy 291.407796 -397.501577) (xy 291.44575 -397.44599) (xy 291.46754 -397.420338)
			(xy 291.47335 -397.413203) (xy 291.479856 -397.396004) (xy 291.48024 -397.38681) (xy 291.48024 -396.893542)
			(xy 291.4798 -396.884358) (xy 291.473306 -396.867174) (xy 291.46754 -396.860014) (xy 291.445742 -396.83437)
			(xy 291.407794 -396.778782) (xy 291.376761 -396.719058) (xy 291.353088 -396.656052) (xy 291.337116 -396.590669)
			(xy 291.329073 -396.523845) (xy 291.329074 -396.45654) (xy 291.337119 -396.389716) (xy 291.353093 -396.324333)
			(xy 291.376767 -396.261328) (xy 291.407801 -396.201605) (xy 291.445751 -396.146018) (xy 291.46754 -396.120366)
			(xy 291.473339 -396.113222) (xy 291.479851 -396.096031) (xy 291.48024 -396.086838) (xy 291.48024 -395.92885)
			(xy 291.480705 -395.918681) (xy 291.488474 -395.899887) (xy 291.502847 -395.885501) (xy 291.521634 -395.877714)
			(xy 291.531802 -395.877288) (xy 292.248082 -395.877288) (xy 292.258259 -395.87768) (xy 292.277063 -395.885468)
			(xy 292.29145 -395.899864) (xy 292.299227 -395.918673) (xy 292.299644 -395.92885) (xy 292.299644 -396.086838)
			(xy 292.300049 -396.096026) (xy 292.306568 -396.113209) (xy 292.312344 -396.120366) (xy 292.334122 -396.146026)
			(xy 292.372072 -396.201611) (xy 292.403107 -396.261333) (xy 292.426781 -396.324337) (xy 292.442755 -396.389718)
			(xy 292.450801 -396.45654) (xy 292.450801 -396.523845) (xy 292.442758 -396.590667) (xy 292.426786 -396.656049)
			(xy 292.403113 -396.719053) (xy 292.37208 -396.778776) (xy 292.334131 -396.834362) (xy 292.312344 -396.860014)
			(xy 292.306552 -396.867162) (xy 292.300036 -396.884351) (xy 292.299644 -396.893542) (xy 292.299644 -397.38681)
			(xy 292.300062 -397.395996) (xy 292.306572 -397.41318) (xy 292.312344 -397.420338) (xy 292.334095 -397.446021)
			(xy 292.372046 -397.501602) (xy 292.40047 -397.556296) (xy 293.528718 -397.556296) (xy 293.536793 -397.489359)
			(xy 293.552827 -397.42387) (xy 293.576589 -397.360774) (xy 293.607738 -397.300978) (xy 293.645825 -397.245343)
			(xy 293.667688 -397.219678) (xy 293.673475 -397.212526) (xy 293.679996 -397.195341) (xy 293.680388 -397.18615)
			(xy 293.680388 -397.028924) (xy 293.680835 -397.018805) (xy 293.688573 -397.000104) (xy 293.70288 -396.985789)
			(xy 293.721577 -396.978041) (xy 293.731696 -396.977616) (xy 294.447976 -396.977616) (xy 294.458099 -396.978036)
			(xy 294.476805 -396.985779) (xy 294.491121 -397.000095) (xy 294.498864 -397.018801) (xy 294.499284 -397.028924)
			(xy 294.499284 -397.18615) (xy 294.499722 -397.195334) (xy 294.506217 -397.212519) (xy 294.511984 -397.219678)
			(xy 294.533858 -397.245335) (xy 294.571948 -397.30097) (xy 294.603099 -397.360767) (xy 294.626863 -397.423865)
			(xy 294.642899 -397.489356) (xy 294.650974 -397.556295) (xy 294.650973 -397.62372) (xy 294.642896 -397.690659)
			(xy 294.626859 -397.756149) (xy 294.603093 -397.819246) (xy 294.600676 -397.823885) (xy 295.728821 -397.823885)
			(xy 295.728825 -397.756458) (xy 295.736905 -397.689516) (xy 295.752946 -397.624025) (xy 295.776716 -397.560926)
			(xy 295.807873 -397.501129) (xy 295.845969 -397.445495) (xy 295.867836 -397.41983) (xy 295.873649 -397.412697)
			(xy 295.880153 -397.395497) (xy 295.880536 -397.386302) (xy 295.880536 -396.89405) (xy 295.880094 -396.884866)
			(xy 295.873601 -396.867682) (xy 295.867836 -396.860522) (xy 295.845961 -396.834865) (xy 295.80787 -396.779231)
			(xy 295.776718 -396.719433) (xy 295.752953 -396.656335) (xy 295.736917 -396.590845) (xy 295.728841 -396.523905)
			(xy 295.728842 -396.45648) (xy 295.73692 -396.38954) (xy 295.752957 -396.32405) (xy 295.776724 -396.260953)
			(xy 295.807878 -396.201157) (xy 295.84597 -396.145523) (xy 295.867836 -396.119858) (xy 295.873637 -396.112716)
			(xy 295.880148 -396.095523) (xy 295.880536 -396.08633) (xy 295.880536 -395.92885) (xy 295.881067 -395.918727)
			(xy 295.888778 -395.900008) (xy 295.903051 -395.88565) (xy 295.921724 -395.877828) (xy 295.931844 -395.877288)
			(xy 296.648124 -395.877288) (xy 296.658278 -395.877702) (xy 296.677029 -395.885503) (xy 296.691351 -395.899902)
			(xy 296.699052 -395.918694) (xy 296.699432 -395.92885) (xy 296.699432 -396.08633) (xy 296.699843 -396.095517)
			(xy 296.706358 -396.1127) (xy 296.712132 -396.119858) (xy 296.733985 -396.145532) (xy 296.772072 -396.201166)
			(xy 296.803221 -396.260961) (xy 296.826985 -396.324057) (xy 296.84302 -396.389545) (xy 296.851096 -396.456481)
			(xy 296.851097 -396.523904) (xy 296.843022 -396.590841) (xy 296.826989 -396.656329) (xy 296.803227 -396.719425)
			(xy 296.77208 -396.779221) (xy 296.733994 -396.834856) (xy 296.712132 -396.860522) (xy 296.706335 -396.867667)
			(xy 296.699823 -396.884858) (xy 296.699432 -396.89405) (xy 296.699432 -397.386302) (xy 296.699856 -397.395487)
			(xy 296.706362 -397.412671) (xy 296.712132 -397.41983) (xy 296.733958 -397.445527) (xy 296.772045 -397.501157)
			(xy 296.800802 -397.556355) (xy 297.929014 -397.556355) (xy 297.937057 -397.489532) (xy 297.95303 -397.42415)
			(xy 297.976704 -397.361146) (xy 298.007738 -397.301423) (xy 298.045688 -397.245838) (xy 298.067476 -397.220186)
			(xy 298.073258 -397.21303) (xy 298.079782 -397.195848) (xy 298.080176 -397.186658) (xy 298.080176 -397.028924)
			(xy 298.080641 -397.018774) (xy 298.088424 -397.000027) (xy 298.102807 -396.985704) (xy 298.121587 -396.977999)
			(xy 298.131738 -396.977616) (xy 298.848018 -396.977616) (xy 298.858143 -396.978111) (xy 298.87686 -396.98584)
			(xy 298.891215 -397.000123) (xy 298.899038 -397.018802) (xy 298.89958 -397.028924) (xy 298.89958 -397.186658)
			(xy 298.900015 -397.195842) (xy 298.906512 -397.213027) (xy 298.91228 -397.220186) (xy 298.934077 -397.24583)
			(xy 298.972024 -397.301418) (xy 299.003056 -397.361143) (xy 299.026728 -397.424149) (xy 299.042699 -397.489532)
			(xy 299.050742 -397.556355) (xy 299.050741 -397.62366) (xy 299.042697 -397.690483) (xy 299.026723 -397.755866)
			(xy 299.00305 -397.818871) (xy 299.000445 -397.823885) (xy 300.128612 -397.823885) (xy 300.128616 -397.756458)
			(xy 300.136696 -397.689517) (xy 300.152736 -397.624025) (xy 300.176506 -397.560927) (xy 300.207662 -397.501129)
			(xy 300.245757 -397.445495) (xy 300.267624 -397.41983) (xy 300.273436 -397.412696) (xy 300.27994 -397.395497)
			(xy 300.280324 -397.386302) (xy 300.280324 -396.89405) (xy 300.279884 -396.884866) (xy 300.273391 -396.867682)
			(xy 300.267624 -396.860522) (xy 300.245749 -396.834865) (xy 300.207659 -396.77923) (xy 300.176508 -396.719433)
			(xy 300.152743 -396.656335) (xy 300.136708 -396.590845) (xy 300.128632 -396.523905) (xy 300.128633 -396.45648)
			(xy 300.13671 -396.389541) (xy 300.152748 -396.324051) (xy 300.176514 -396.260953) (xy 300.207667 -396.201157)
			(xy 300.245759 -396.145523) (xy 300.267624 -396.119858) (xy 300.273424 -396.112715) (xy 300.279936 -396.095523)
			(xy 300.280324 -396.08633) (xy 300.280324 -395.92885) (xy 300.280867 -395.918728) (xy 300.288576 -395.900011)
			(xy 300.302845 -395.885654) (xy 300.321514 -395.87783) (xy 300.331632 -395.877288) (xy 301.047912 -395.877288)
			(xy 301.058065 -395.877711) (xy 301.076816 -395.885509) (xy 301.091138 -395.899904) (xy 301.09884 -395.918694)
			(xy 301.09922 -395.92885) (xy 301.09922 -396.08633) (xy 301.099611 -396.095519) (xy 301.106138 -396.112704)
			(xy 301.11192 -396.119858) (xy 301.133773 -396.145532) (xy 301.171861 -396.201165) (xy 301.203011 -396.260961)
			(xy 301.226775 -396.324056) (xy 301.242811 -396.389544) (xy 301.250887 -396.456481) (xy 301.250888 -396.523904)
			(xy 301.242813 -396.590841) (xy 301.226779 -396.656329) (xy 301.203017 -396.719426) (xy 301.171869 -396.779222)
			(xy 301.133783 -396.834856) (xy 301.11192 -396.860522) (xy 301.106134 -396.867675) (xy 301.099612 -396.884859)
			(xy 301.09922 -396.89405) (xy 301.09922 -397.386302) (xy 301.099625 -397.39549) (xy 301.106142 -397.412674)
			(xy 301.11192 -397.41983) (xy 301.133746 -397.445526) (xy 301.171834 -397.501157) (xy 301.200562 -397.556296)
			(xy 302.328806 -397.556296) (xy 302.336881 -397.489359) (xy 302.352914 -397.423871) (xy 302.376676 -397.360775)
			(xy 302.407824 -397.300979) (xy 302.44591 -397.245344) (xy 302.467772 -397.219678) (xy 302.473569 -397.212534)
			(xy 302.480081 -397.195342) (xy 302.480472 -397.18615) (xy 302.480472 -397.028924) (xy 302.480935 -397.018806)
			(xy 302.48867 -397.000109) (xy 302.502972 -396.985795) (xy 302.521663 -396.978043) (xy 302.53178 -396.977616)
			(xy 303.24806 -396.977616) (xy 303.258182 -396.978049) (xy 303.276888 -396.985787) (xy 303.291204 -397.000099)
			(xy 303.298948 -397.018802) (xy 303.299368 -397.028924) (xy 303.299368 -397.18615) (xy 303.299809 -397.195334)
			(xy 303.306302 -397.212518) (xy 303.312068 -397.219678) (xy 303.333943 -397.245335) (xy 303.372033 -397.30097)
			(xy 303.403185 -397.360767) (xy 303.426951 -397.423865) (xy 303.442986 -397.489355) (xy 303.451062 -397.556295)
			(xy 303.451061 -397.62372) (xy 303.442984 -397.69066) (xy 303.426946 -397.75615) (xy 303.403179 -397.819247)
			(xy 303.372026 -397.879043) (xy 303.333934 -397.934677) (xy 303.312068 -397.960342) (xy 303.306267 -397.967484)
			(xy 303.299756 -397.984677) (xy 303.299368 -397.99387) (xy 303.299368 -398.486376) (xy 303.299797 -398.495561)
			(xy 303.306299 -398.512745) (xy 303.312068 -398.519904) (xy 303.333968 -398.54554) (xy 303.372058 -398.601178)
			(xy 303.403209 -398.660978) (xy 303.426973 -398.724078) (xy 303.443007 -398.789571) (xy 303.45108 -398.856513)
			(xy 303.451077 -398.923941) (xy 303.442997 -398.990882) (xy 303.426957 -399.056373) (xy 303.403187 -399.119472)
			(xy 303.37203 -399.179269) (xy 303.333935 -399.234903) (xy 303.312068 -399.260568) (xy 303.306256 -399.267702)
			(xy 303.299751 -399.284901) (xy 303.299368 -399.294096) (xy 303.299368 -399.451576) (xy 303.298964 -399.461701)
			(xy 303.291218 -399.48041) (xy 303.276897 -399.494727) (xy 303.258185 -399.502467) (xy 303.24806 -399.502884)
			(xy 302.53178 -399.502884) (xy 302.521654 -399.5025) (xy 302.502947 -399.494742) (xy 302.488633 -399.480416)
			(xy 302.480891 -399.461702) (xy 302.480472 -399.451576) (xy 302.480472 -399.294096) (xy 302.48007 -399.284908)
			(xy 302.473551 -399.267723) (xy 302.467772 -399.260568) (xy 302.445944 -399.234873) (xy 302.407856 -399.179242)
			(xy 302.376706 -399.11945) (xy 302.352941 -399.056357) (xy 302.336904 -398.990872) (xy 302.328825 -398.923937)
			(xy 302.328822 -398.856517) (xy 302.336894 -398.789582) (xy 302.352925 -398.724095) (xy 302.376684 -398.661)
			(xy 302.407829 -398.601204) (xy 302.445911 -398.54557) (xy 302.467772 -398.519904) (xy 302.473558 -398.512752)
			(xy 302.480077 -398.495566) (xy 302.480472 -398.486376) (xy 302.480472 -397.99387) (xy 302.480082 -397.98468)
			(xy 302.473555 -397.967496) (xy 302.467772 -397.960342) (xy 302.445919 -397.934668) (xy 302.407832 -397.879034)
			(xy 302.376682 -397.819239) (xy 302.352919 -397.756143) (xy 302.336883 -397.690656) (xy 302.328807 -397.623719)
			(xy 302.328806 -397.556296) (xy 301.200562 -397.556296) (xy 301.202986 -397.560949) (xy 301.226751 -397.624042)
			(xy 301.242789 -397.689527) (xy 301.250867 -397.756461) (xy 301.250871 -397.823882) (xy 301.242799 -397.890817)
			(xy 301.226768 -397.956304) (xy 301.203009 -398.019399) (xy 301.171864 -398.079194) (xy 301.133781 -398.134828)
			(xy 301.11192 -398.160494) (xy 301.106146 -398.167655) (xy 301.099617 -398.184833) (xy 301.09922 -398.194022)
			(xy 301.09922 -398.351502) (xy 301.098774 -398.361634) (xy 301.091038 -398.380362) (xy 301.076739 -398.39472)
			(xy 301.058042 -398.402532) (xy 301.047912 -398.403064) (xy 300.331632 -398.403064) (xy 300.321475 -398.402652)
			(xy 300.302717 -398.39486) (xy 300.288391 -398.38046) (xy 300.280696 -398.361661) (xy 300.280324 -398.351502)
			(xy 300.280324 -398.194022) (xy 300.279898 -398.184837) (xy 300.273395 -398.167652) (xy 300.267624 -398.160494)
			(xy 300.245722 -398.13486) (xy 300.207633 -398.079222) (xy 300.176482 -398.019421) (xy 300.152719 -397.95632)
			(xy 300.136686 -397.890827) (xy 300.128612 -397.823885) (xy 299.000445 -397.823885) (xy 298.972017 -397.878595)
			(xy 298.934068 -397.934182) (xy 298.91228 -397.959834) (xy 298.906484 -397.96698) (xy 298.89997 -397.98417)
			(xy 298.89958 -397.993362) (xy 298.89958 -398.486884) (xy 298.900003 -398.49607) (xy 298.906508 -398.513254)
			(xy 298.91228 -398.520412) (xy 298.934103 -398.546035) (xy 298.972049 -398.601626) (xy 299.00308 -398.661354)
			(xy 299.02675 -398.724362) (xy 299.04272 -398.789748) (xy 299.050761 -398.856573) (xy 299.050757 -398.923881)
			(xy 299.04271 -398.990706) (xy 299.026734 -399.05609) (xy 299.003058 -399.119095) (xy 298.972021 -399.17882)
			(xy 298.934069 -399.234408) (xy 298.91228 -399.26006) (xy 298.906473 -399.267198) (xy 298.899965 -399.284394)
			(xy 298.89958 -399.293588) (xy 298.89958 -399.451576) (xy 298.899159 -399.461731) (xy 298.891367 -399.480487)
			(xy 298.87697 -399.494812) (xy 298.858175 -399.502509) (xy 298.848018 -399.502884) (xy 298.131738 -399.502884)
			(xy 298.121617 -399.502343) (xy 298.102901 -399.494632) (xy 298.088544 -399.480362) (xy 298.08072 -399.461694)
			(xy 298.080176 -399.451576) (xy 298.080176 -399.293588) (xy 298.079777 -399.2844) (xy 298.073256 -399.267215)
			(xy 298.067476 -399.26006) (xy 298.045723 -399.234379) (xy 298.00777 -399.178798) (xy 297.976733 -399.119078)
			(xy 297.953057 -399.056078) (xy 297.93708 -398.990699) (xy 297.929033 -398.923879) (xy 297.92903 -398.856576)
			(xy 297.937071 -398.789755) (xy 297.953041 -398.724374) (xy 297.976711 -398.661371) (xy 298.007742 -398.601649)
			(xy 298.045689 -398.546064) (xy 298.067476 -398.520412) (xy 298.07329 -398.513279) (xy 298.079795 -398.496079)
			(xy 298.080176 -398.486884) (xy 298.080176 -397.993362) (xy 298.079789 -397.984172) (xy 298.07326 -397.966988)
			(xy 298.067476 -397.959834) (xy 298.045697 -397.934174) (xy 298.007746 -397.87859) (xy 297.97671 -397.818868)
			(xy 297.953035 -397.755864) (xy 297.93706 -397.690482) (xy 297.929015 -397.62366) (xy 297.929014 -397.556355)
			(xy 296.800802 -397.556355) (xy 296.803196 -397.56095) (xy 296.826961 -397.624042) (xy 296.842998 -397.689527)
			(xy 296.851076 -397.756461) (xy 296.85108 -397.823881) (xy 296.843008 -397.890817) (xy 296.826978 -397.956303)
			(xy 296.803219 -398.019398) (xy 296.772075 -398.079194) (xy 296.733993 -398.134828) (xy 296.712132 -398.160494)
			(xy 296.706347 -398.167647) (xy 296.699827 -398.184832) (xy 296.699432 -398.194022) (xy 296.699432 -398.351502)
			(xy 296.698974 -398.361632) (xy 296.691241 -398.380359) (xy 296.676945 -398.394716) (xy 296.658252 -398.40253)
			(xy 296.648124 -398.403064) (xy 295.931844 -398.403064) (xy 295.921688 -398.402642) (xy 295.90293 -398.394854)
			(xy 295.888604 -398.380456) (xy 295.880909 -398.36166) (xy 295.880536 -398.351502) (xy 295.880536 -398.194022)
			(xy 295.880107 -398.184837) (xy 295.873606 -398.167653) (xy 295.867836 -398.160494) (xy 295.845933 -398.13486)
			(xy 295.807843 -398.079222) (xy 295.776692 -398.019422) (xy 295.752929 -397.956321) (xy 295.736895 -397.890827)
			(xy 295.728821 -397.823885) (xy 294.600676 -397.823885) (xy 294.57194 -397.879043) (xy 294.533849 -397.934677)
			(xy 294.511984 -397.960342) (xy 294.506185 -397.967486) (xy 294.499672 -397.984677) (xy 294.499284 -397.99387)
			(xy 294.499284 -398.486376) (xy 294.499709 -398.495561) (xy 294.506213 -398.512746) (xy 294.511984 -398.519904)
			(xy 294.533884 -398.54554) (xy 294.571973 -398.601178) (xy 294.603123 -398.660978) (xy 294.626885 -398.724079)
			(xy 294.642919 -398.789572) (xy 294.650992 -398.856514) (xy 294.650989 -398.92394) (xy 294.642909 -398.990881)
			(xy 294.626869 -399.056373) (xy 294.603101 -399.119471) (xy 294.571945 -399.179268) (xy 294.533851 -399.234903)
			(xy 294.511984 -399.260568) (xy 294.506174 -399.267704) (xy 294.499668 -399.284902) (xy 294.499284 -399.294096)
			(xy 294.499284 -399.451576) (xy 294.498864 -399.461699) (xy 294.491121 -399.480405) (xy 294.476805 -399.494721)
			(xy 294.458099 -399.502464) (xy 294.447976 -399.502884) (xy 293.731696 -399.502884) (xy 293.721571 -399.502487)
			(xy 293.702865 -399.494734) (xy 293.68855 -399.480412) (xy 293.680808 -399.461701) (xy 293.680388 -399.451576)
			(xy 293.680388 -399.294096) (xy 293.679982 -399.284908) (xy 293.673466 -399.267724) (xy 293.667688 -399.260568)
			(xy 293.64586 -399.234873) (xy 293.607771 -399.179243) (xy 293.576619 -399.119451) (xy 293.552854 -399.056358)
			(xy 293.536816 -398.990872) (xy 293.528737 -398.923937) (xy 293.528734 -398.856517) (xy 293.536806 -398.789581)
			(xy 293.552838 -398.724094) (xy 293.576597 -398.660999) (xy 293.607743 -398.601204) (xy 293.645827 -398.545569)
			(xy 293.667688 -398.519904) (xy 293.673464 -398.512744) (xy 293.679991 -398.495565) (xy 293.680388 -398.486376)
			(xy 293.680388 -397.99387) (xy 293.679995 -397.984681) (xy 293.673469 -397.967497) (xy 293.667688 -397.960342)
			(xy 293.645834 -397.934668) (xy 293.607746 -397.879035) (xy 293.576596 -397.81924) (xy 293.552831 -397.756144)
			(xy 293.536796 -397.690656) (xy 293.528719 -397.623719) (xy 293.528718 -397.556296) (xy 292.40047 -397.556296)
			(xy 292.403082 -397.561322) (xy 292.426757 -397.624322) (xy 292.442733 -397.689701) (xy 292.450781 -397.75652)
			(xy 292.450784 -397.823823) (xy 292.442744 -397.890643) (xy 292.426774 -397.956023) (xy 292.403105 -398.019026)
			(xy 292.372075 -398.078748) (xy 292.33413 -398.134334) (xy 292.312344 -398.159986) (xy 292.306522 -398.167113)
			(xy 292.300024 -398.184318) (xy 292.299644 -398.193514) (xy 292.299644 -398.351502) (xy 292.299237 -398.361676)
			(xy 292.291448 -398.380474) (xy 292.277057 -398.39486) (xy 292.258256 -398.402641) (xy 292.248082 -398.403064)
			(xy 291.531802 -398.403064) (xy 291.521645 -398.402565) (xy 291.502876 -398.394792) (xy 291.488511 -398.380427)
			(xy 291.480736 -398.361659) (xy 291.48024 -398.351502) (xy 291.48024 -398.193514) (xy 291.479814 -398.184329)
			(xy 291.473311 -398.167145) (xy 291.46754 -398.159986) (xy 291.445715 -398.134365) (xy 291.407767 -398.078774)
			(xy 291.376735 -398.019046) (xy 291.353065 -397.956037) (xy 291.337094 -397.890651) (xy 291.329053 -397.823825)
			(xy 290.200388 -397.823825) (xy 290.171931 -397.878594) (xy 290.133983 -397.934181) (xy 290.112196 -397.959834)
			(xy 290.106402 -397.966981) (xy 290.099886 -397.98417) (xy 290.099496 -397.993362) (xy 290.099496 -398.486884)
			(xy 290.099915 -398.49607) (xy 290.106423 -398.513255) (xy 290.112196 -398.520412) (xy 290.134018 -398.546036)
			(xy 290.171963 -398.601627) (xy 290.202993 -398.661355) (xy 290.226662 -398.724363) (xy 290.242632 -398.789748)
			(xy 290.250673 -398.856573) (xy 290.250669 -398.923881) (xy 290.242622 -398.990705) (xy 290.226646 -399.056089)
			(xy 290.202971 -399.119095) (xy 290.171936 -399.17882) (xy 290.133985 -399.234407) (xy 290.112196 -399.26006)
			(xy 290.106391 -399.267199) (xy 290.099881 -399.284394) (xy 290.099496 -399.293588) (xy 290.099496 -399.451576)
			(xy 290.099059 -399.461729) (xy 290.09127 -399.480482) (xy 290.076878 -399.494806) (xy 290.058089 -399.502506)
			(xy 290.047934 -399.502884) (xy 289.331654 -399.502884) (xy 289.321527 -399.502412) (xy 289.30281 -399.494673)
			(xy 289.288456 -399.480383) (xy 289.280634 -399.4617) (xy 289.280092 -399.451576) (xy 289.280092 -399.293588)
			(xy 289.279689 -399.2844) (xy 289.273171 -399.267216) (xy 289.267392 -399.26006) (xy 289.245638 -399.234379)
			(xy 289.207685 -399.178798) (xy 289.176647 -399.119079) (xy 289.15297 -399.056078) (xy 289.136993 -398.990699)
			(xy 289.128945 -398.923879) (xy 289.128942 -398.856575) (xy 289.136983 -398.789754) (xy 289.152954 -398.724374)
			(xy 289.176625 -398.66137) (xy 289.207657 -398.601648) (xy 289.245605 -398.546063) (xy 289.267392 -398.520412)
			(xy 289.273208 -398.51328) (xy 289.279711 -398.496079) (xy 289.280092 -398.486884) (xy 289.280092 -397.993362)
			(xy 289.279702 -397.984173) (xy 289.273175 -397.966988) (xy 289.267392 -397.959834) (xy 289.245612 -397.934174)
			(xy 289.20766 -397.87859) (xy 289.176623 -397.818868) (xy 289.152948 -397.755865) (xy 289.136972 -397.690483)
			(xy 289.128927 -397.62366) (xy 289.128926 -397.556355) (xy 288.000733 -397.556355) (xy 288.003125 -397.560946)
			(xy 288.026894 -397.624039) (xy 288.042933 -397.689525) (xy 288.051013 -397.756461) (xy 288.051016 -397.823882)
			(xy 288.042944 -397.890819) (xy 288.026911 -397.956307) (xy 288.003148 -398.019402) (xy 287.971999 -398.079197)
			(xy 287.933912 -398.13483) (xy 287.912048 -398.160494) (xy 287.906265 -398.167649) (xy 287.899744 -398.184832)
			(xy 287.899348 -398.194022) (xy 287.899348 -398.351502) (xy 287.898875 -398.36163) (xy 287.891144 -398.380354)
			(xy 287.876853 -398.39471) (xy 287.858166 -398.402527) (xy 287.84804 -398.403064) (xy 287.13176 -398.403064)
			(xy 287.121599 -398.40271) (xy 287.102839 -398.394895) (xy 287.088515 -398.380477) (xy 287.080824 -398.361666)
			(xy 287.080452 -398.351502) (xy 287.080452 -398.194022) (xy 287.08002 -398.184837) (xy 287.07352 -398.167653)
			(xy 287.067752 -398.160494) (xy 287.045849 -398.13486) (xy 287.007758 -398.079223) (xy 286.976606 -398.019423)
			(xy 286.952842 -397.956321) (xy 286.936807 -397.890828) (xy 286.928734 -397.823885) (xy 244.446806 -397.823885)
			(xy 244.446806 -399.877788) (xy 244.446297 -399.902737) (xy 244.438487 -399.952019) (xy 244.423074 -399.999476)
			(xy 244.400434 -400.043943) (xy 244.371126 -400.084326) (xy 244.353842 -400.102324) (xy 243.288058 -401.168108)
			(xy 243.270087 -401.185424) (xy 243.229704 -401.214744) (xy 243.185232 -401.237387) (xy 243.137766 -401.252795)
			(xy 243.088474 -401.260589) (xy 243.063522 -401.261072) (xy 239.143794 -401.261072) (xy 239.133722 -401.261475)
			(xy 239.115123 -401.269209) (xy 239.107726 -401.276058) (xy 238.659987 -401.723797) (xy 286.928745 -401.723797)
			(xy 286.928747 -401.65637) (xy 286.936826 -401.58943) (xy 286.952865 -401.523939) (xy 286.976634 -401.460841)
			(xy 287.00779 -401.401044) (xy 287.045885 -401.34541) (xy 287.067752 -401.319746) (xy 287.07356 -401.312609)
			(xy 287.080067 -401.295412) (xy 287.080452 -401.286218) (xy 287.080452 -400.793966) (xy 287.080046 -400.784779)
			(xy 287.073528 -400.767595) (xy 287.067752 -400.760438) (xy 287.045892 -400.734769) (xy 287.0078 -400.679136)
			(xy 286.976646 -400.619341) (xy 286.952879 -400.556244) (xy 286.936842 -400.490755) (xy 286.928764 -400.423817)
			(xy 286.928764 -400.356392) (xy 286.93684 -400.289454) (xy 286.952876 -400.223964) (xy 286.976642 -400.160867)
			(xy 287.007795 -400.101072) (xy 287.045887 -400.045438) (xy 287.067752 -400.019774) (xy 287.073549 -400.012629)
			(xy 287.080062 -399.995438) (xy 287.080452 -399.986246) (xy 287.080452 -399.828766) (xy 287.080899 -399.818636)
			(xy 287.08864 -399.799911) (xy 287.102939 -399.785556) (xy 287.121632 -399.77774) (xy 287.13176 -399.777204)
			(xy 287.84804 -399.777204) (xy 287.858197 -399.777589) (xy 287.876951 -399.785399) (xy 287.891273 -399.799806)
			(xy 287.898971 -399.818606) (xy 287.899348 -399.828766) (xy 287.899348 -399.986246) (xy 287.899796 -399.995429)
			(xy 287.906285 -400.012613) (xy 287.912048 -400.019774) (xy 287.93392 -400.045433) (xy 287.972012 -400.101068)
			(xy 288.003165 -400.160864) (xy 288.026931 -400.223962) (xy 288.042968 -400.289452) (xy 288.051044 -400.356392)
			(xy 288.051043 -400.423817) (xy 288.042966 -400.490757) (xy 288.026928 -400.556247) (xy 288.003161 -400.619344)
			(xy 287.972007 -400.67914) (xy 287.933914 -400.734774) (xy 287.912048 -400.760438) (xy 287.906246 -400.767579)
			(xy 287.899736 -400.784773) (xy 287.899348 -400.793966) (xy 287.899348 -401.286218) (xy 287.899761 -401.295405)
			(xy 287.906274 -401.312588) (xy 287.912048 -401.319746) (xy 287.933892 -401.345428) (xy 287.971985 -401.401059)
			(xy 288.00314 -401.460852) (xy 288.026907 -401.523947) (xy 288.042946 -401.589435) (xy 288.051024 -401.656372)
			(xy 288.051026 -401.723795) (xy 288.042952 -401.790733) (xy 288.026917 -401.856221) (xy 288.003153 -401.919317)
			(xy 287.972002 -401.979113) (xy 287.933912 -402.034746) (xy 287.912048 -402.06041) (xy 287.906258 -402.06756)
			(xy 287.899741 -402.084747) (xy 287.899348 -402.093938) (xy 287.899348 -402.251418) (xy 287.898888 -402.261547)
			(xy 287.891152 -402.280271) (xy 287.876858 -402.294627) (xy 287.858167 -402.302444) (xy 287.84804 -402.30298)
			(xy 287.13176 -402.30298) (xy 287.121601 -402.302611) (xy 287.102844 -402.294798) (xy 287.088521 -402.280385)
			(xy 287.080826 -402.26158) (xy 287.080452 -402.251418) (xy 287.080452 -402.093938) (xy 287.080012 -402.084754)
			(xy 287.073518 -402.06757) (xy 287.067752 -402.06041) (xy 287.045865 -402.034763) (xy 287.007773 -401.979127)
			(xy 286.97662 -401.919329) (xy 286.952855 -401.85623) (xy 286.93682 -401.790738) (xy 286.928745 -401.723797)
			(xy 238.659987 -401.723797) (xy 237.559965 -402.823819) (xy 289.128886 -402.823819) (xy 289.12889 -402.756509)
			(xy 289.13694 -402.689682) (xy 289.15292 -402.624297) (xy 289.1766 -402.56129) (xy 289.207642 -402.501565)
			(xy 289.2456 -402.445979) (xy 289.267392 -402.420328) (xy 289.273201 -402.413191) (xy 289.279708 -402.395994)
			(xy 289.280092 -402.3868) (xy 289.280092 -401.893532) (xy 289.279668 -401.884346) (xy 289.273164 -401.867162)
			(xy 289.267392 -401.860004) (xy 289.245583 -401.834369) (xy 289.207631 -401.778781) (xy 289.176596 -401.719056)
			(xy 289.152922 -401.656049) (xy 289.136949 -401.590664) (xy 289.128906 -401.523839) (xy 289.128907 -401.456531)
			(xy 289.136954 -401.389706) (xy 289.152931 -401.324322) (xy 289.176608 -401.261317) (xy 289.207647 -401.201593)
			(xy 289.245601 -401.146007) (xy 289.267392 -401.120356) (xy 289.273189 -401.113211) (xy 289.279704 -401.09602)
			(xy 289.280092 -401.086828) (xy 289.280092 -400.92884) (xy 289.280554 -400.918689) (xy 289.288335 -400.89994)
			(xy 289.30272 -400.885615) (xy 289.321502 -400.877913) (xy 289.331654 -400.877532) (xy 290.047934 -400.877532)
			(xy 290.058062 -400.877998) (xy 290.076782 -400.885736) (xy 290.091137 -400.900028) (xy 290.098957 -400.918714)
			(xy 290.099496 -400.92884) (xy 290.099496 -401.086828) (xy 290.099893 -401.096017) (xy 290.106416 -401.113201)
			(xy 290.112196 -401.120356) (xy 290.133963 -401.146025) (xy 290.17191 -401.20161) (xy 290.202942 -401.261331)
			(xy 290.226615 -401.324334) (xy 290.242588 -401.389713) (xy 290.250633 -401.456534) (xy 290.250635 -401.523836)
			(xy 290.242593 -401.590657) (xy 290.226624 -401.656038) (xy 290.202955 -401.719041) (xy 290.200515 -401.723737)
			(xy 291.329064 -401.723737) (xy 291.329066 -401.65643) (xy 291.337113 -401.589606) (xy 291.353088 -401.524222)
			(xy 291.376763 -401.461217) (xy 291.407799 -401.401493) (xy 291.445751 -401.345906) (xy 291.46754 -401.320254)
			(xy 291.473344 -401.313114) (xy 291.479853 -401.295919) (xy 291.48024 -401.286726) (xy 291.48024 -400.793458)
			(xy 291.479841 -400.78427) (xy 291.473319 -400.767086) (xy 291.46754 -400.75993) (xy 291.445758 -400.734273)
			(xy 291.407809 -400.678687) (xy 291.376776 -400.618964) (xy 291.353103 -400.55596) (xy 291.337129 -400.490579)
			(xy 291.329085 -400.423757) (xy 291.329084 -400.356452) (xy 291.337128 -400.28963) (xy 291.3531 -400.224248)
			(xy 291.376772 -400.161244) (xy 291.407805 -400.101521) (xy 291.445753 -400.045934) (xy 291.46754 -400.020282)
			(xy 291.473332 -400.013134) (xy 291.479848 -399.995945) (xy 291.48024 -399.986754) (xy 291.48024 -399.828766)
			(xy 291.480706 -399.818606) (xy 291.488492 -399.799835) (xy 291.502866 -399.785471) (xy 291.521641 -399.777698)
			(xy 291.531802 -399.777204) (xy 292.248082 -399.777204) (xy 292.258234 -399.777747) (xy 292.276997 -399.785509)
			(xy 292.291361 -399.79986) (xy 292.299143 -399.818614) (xy 292.299644 -399.828766) (xy 292.299644 -399.986754)
			(xy 292.300089 -399.995937) (xy 292.30658 -400.013121) (xy 292.312344 -400.020282) (xy 292.334138 -400.045929)
			(xy 292.372088 -400.101516) (xy 292.403122 -400.16124) (xy 292.426795 -400.224245) (xy 292.442768 -400.289628)
			(xy 292.450812 -400.356452) (xy 292.450811 -400.423757) (xy 292.442766 -400.490581) (xy 292.426792 -400.555963)
			(xy 292.403118 -400.618968) (xy 292.372083 -400.678692) (xy 292.334132 -400.734278) (xy 292.312344 -400.75993)
			(xy 292.306545 -400.767073) (xy 292.300033 -400.784266) (xy 292.299644 -400.793458) (xy 292.299644 -401.286726)
			(xy 292.300054 -401.295913) (xy 292.306569 -401.313097) (xy 292.312344 -401.320254) (xy 292.33411 -401.345924)
			(xy 292.372061 -401.401507) (xy 292.403096 -401.461228) (xy 292.426771 -401.524231) (xy 292.442746 -401.589611)
			(xy 292.450792 -401.656432) (xy 292.450794 -401.723735) (xy 292.442752 -401.790557) (xy 292.426781 -401.855938)
			(xy 292.40311 -401.918941) (xy 292.372078 -401.978664) (xy 292.334131 -402.03425) (xy 292.312344 -402.059902)
			(xy 292.306557 -402.067054) (xy 292.300038 -402.084239) (xy 292.299644 -402.09343) (xy 292.299644 -402.251418)
			(xy 292.299181 -402.261579) (xy 292.291397 -402.280352) (xy 292.277022 -402.294718) (xy 292.258244 -402.302488)
			(xy 292.248082 -402.30298) (xy 291.531802 -402.30298) (xy 291.521647 -402.302465) (xy 291.502881 -402.294695)
			(xy 291.488516 -402.280336) (xy 291.480739 -402.261573) (xy 291.48024 -402.251418) (xy 291.48024 -402.09343)
			(xy 291.479806 -402.084246) (xy 291.473308 -402.067061) (xy 291.46754 -402.059902) (xy 291.44573 -402.034268)
			(xy 291.407782 -401.978679) (xy 291.37675 -401.918953) (xy 291.353078 -401.855946) (xy 291.337107 -401.790561)
			(xy 291.329064 -401.723737) (xy 290.200515 -401.723737) (xy 290.171926 -401.778764) (xy 290.133981 -401.834351)
			(xy 290.112196 -401.860004) (xy 290.106415 -401.86716) (xy 290.099891 -401.884342) (xy 290.099496 -401.893532)
			(xy 290.099496 -402.3868) (xy 290.099907 -402.395987) (xy 290.10642 -402.413171) (xy 290.112196 -402.420328)
			(xy 290.133935 -402.44602) (xy 290.171883 -402.501601) (xy 290.202916 -402.56132) (xy 290.22659 -402.624319)
			(xy 290.242566 -402.689696) (xy 290.250613 -402.756514) (xy 290.250617 -402.823814) (xy 290.250609 -402.823878)
			(xy 293.528678 -402.823878) (xy 293.528683 -402.75645) (xy 293.536763 -402.689509) (xy 293.552803 -402.624017)
			(xy 293.576572 -402.560919) (xy 293.607728 -402.501121) (xy 293.645822 -402.445485) (xy 293.667688 -402.41982)
			(xy 293.6735 -402.412685) (xy 293.680006 -402.395487) (xy 293.680388 -402.386292) (xy 293.680388 -401.89404)
			(xy 293.679961 -401.884854) (xy 293.67346 -401.86767) (xy 293.667688 -401.860512) (xy 293.645805 -401.834863)
			(xy 293.607717 -401.779226) (xy 293.576568 -401.719427) (xy 293.552806 -401.656328) (xy 293.536772 -401.590837)
			(xy 293.528698 -401.523897) (xy 293.5287 -401.456472) (xy 293.536777 -401.389533) (xy 293.552815 -401.324043)
			(xy 293.576581 -401.260945) (xy 293.607733 -401.201149) (xy 293.645823 -401.145513) (xy 293.667688 -401.119848)
			(xy 293.673488 -401.112705) (xy 293.680001 -401.095513) (xy 293.680388 -401.08632) (xy 293.680388 -400.92884)
			(xy 293.680849 -400.918722) (xy 293.688581 -400.900021) (xy 293.702884 -400.885706) (xy 293.721578 -400.877957)
			(xy 293.731696 -400.877532) (xy 294.447976 -400.877532) (xy 294.458101 -400.877936) (xy 294.47681 -400.885682)
			(xy 294.491127 -400.900003) (xy 294.498867 -400.918715) (xy 294.499284 -400.92884) (xy 294.499284 -401.08632)
			(xy 294.499688 -401.095508) (xy 294.506206 -401.112692) (xy 294.511984 -401.119848) (xy 294.533829 -401.145529)
			(xy 294.571919 -401.201161) (xy 294.603072 -401.260955) (xy 294.626838 -401.32405) (xy 294.642875 -401.389537)
			(xy 294.650953 -401.456474) (xy 294.650955 -401.523896) (xy 294.64288 -401.590833) (xy 294.626847 -401.656322)
			(xy 294.603084 -401.719418) (xy 294.600803 -401.723797) (xy 295.728833 -401.723797) (xy 295.728835 -401.65637)
			(xy 295.736913 -401.58943) (xy 295.752952 -401.523939) (xy 295.77672 -401.460841) (xy 295.807876 -401.401045)
			(xy 295.845969 -401.345411) (xy 295.867836 -401.319746) (xy 295.873643 -401.312608) (xy 295.88015 -401.295412)
			(xy 295.880536 -401.286218) (xy 295.880536 -400.793966) (xy 295.880134 -400.784778) (xy 295.873614 -400.767594)
			(xy 295.867836 -400.760438) (xy 295.845977 -400.734769) (xy 295.807885 -400.679135) (xy 295.776732 -400.61934)
			(xy 295.752966 -400.556244) (xy 295.736929 -400.490755) (xy 295.728852 -400.423816) (xy 295.728852 -400.356393)
			(xy 295.736928 -400.289454) (xy 295.752964 -400.223965) (xy 295.776729 -400.160868) (xy 295.807881 -400.101072)
			(xy 295.845971 -400.045439) (xy 295.867836 -400.019774) (xy 295.873631 -400.012628) (xy 295.880146 -399.995438)
			(xy 295.880536 -399.986246) (xy 295.880536 -399.828766) (xy 295.880999 -399.818638) (xy 295.888737 -399.799916)
			(xy 295.90303 -399.785561) (xy 295.921718 -399.777743) (xy 295.931844 -399.777204) (xy 296.648124 -399.777204)
			(xy 296.65828 -399.777602) (xy 296.677034 -399.785406) (xy 296.691357 -399.79981) (xy 296.699055 -399.818608)
			(xy 296.699432 -399.828766) (xy 296.699432 -399.986246) (xy 296.699883 -399.995429) (xy 296.70637 -400.012613)
			(xy 296.712132 -400.019774) (xy 296.734001 -400.045435) (xy 296.772087 -400.101071) (xy 296.803236 -400.160868)
			(xy 296.826998 -400.223965) (xy 296.843032 -400.289455) (xy 296.851107 -400.356393) (xy 296.851107 -400.423816)
			(xy 296.843031 -400.490754) (xy 296.826996 -400.556243) (xy 296.803232 -400.61934) (xy 296.772083 -400.679137)
			(xy 296.733995 -400.734772) (xy 296.712132 -400.760438) (xy 296.706329 -400.767578) (xy 296.69982 -400.784773)
			(xy 296.699432 -400.793966) (xy 296.699432 -401.286218) (xy 296.699849 -401.295404) (xy 296.70636 -401.312588)
			(xy 296.712132 -401.319746) (xy 296.733973 -401.34543) (xy 296.77206 -401.401062) (xy 296.80321 -401.460856)
			(xy 296.826974 -401.523951) (xy 296.84301 -401.589437) (xy 296.851088 -401.656373) (xy 296.85109 -401.723794)
			(xy 296.843016 -401.79073) (xy 296.826984 -401.856218) (xy 296.803224 -401.919314) (xy 296.772078 -401.979109)
			(xy 296.733994 -402.034744) (xy 296.712132 -402.06041) (xy 296.70634 -402.067558) (xy 296.699825 -402.084747)
			(xy 296.699432 -402.093938) (xy 296.699432 -402.251418) (xy 296.698988 -402.261549) (xy 296.691249 -402.280276)
			(xy 296.676949 -402.294633) (xy 296.658253 -402.302447) (xy 296.648124 -402.30298) (xy 295.931844 -402.30298)
			(xy 295.92169 -402.302542) (xy 295.902935 -402.294757) (xy 295.888609 -402.280365) (xy 295.880912 -402.261574)
			(xy 295.880536 -402.251418) (xy 295.880536 -402.093938) (xy 295.880099 -402.084754) (xy 295.873603 -402.06757)
			(xy 295.867836 -402.06041) (xy 295.845949 -402.034763) (xy 295.807859 -401.979127) (xy 295.776707 -401.919328)
			(xy 295.752942 -401.856229) (xy 295.736907 -401.790737) (xy 295.728833 -401.723797) (xy 294.600803 -401.723797)
			(xy 294.571935 -401.779213) (xy 294.533847 -401.834847) (xy 294.511984 -401.860512) (xy 294.506198 -401.867665)
			(xy 294.499678 -401.88485) (xy 294.499284 -401.89404) (xy 294.499284 -402.386292) (xy 294.499702 -402.395478)
			(xy 294.506211 -402.412662) (xy 294.511984 -402.41982) (xy 294.533801 -402.445524) (xy 294.571893 -402.501152)
			(xy 294.603046 -402.560943) (xy 294.626814 -402.624035) (xy 294.642853 -402.68952) (xy 294.650933 -402.756454)
			(xy 294.650937 -402.823819) (xy 297.928973 -402.823819) (xy 297.928978 -402.756509) (xy 297.937027 -402.689683)
			(xy 297.953006 -402.624297) (xy 297.976686 -402.561291) (xy 298.007727 -402.501566) (xy 298.045684 -402.445979)
			(xy 298.067476 -402.420328) (xy 298.073283 -402.41319) (xy 298.079792 -402.395994) (xy 298.080176 -402.3868)
			(xy 298.080176 -401.893532) (xy 298.079756 -401.884346) (xy 298.07325 -401.867161) (xy 298.067476 -401.860004)
			(xy 298.045668 -401.834368) (xy 298.007717 -401.77878) (xy 297.976683 -401.719055) (xy 297.953009 -401.656048)
			(xy 297.937037 -401.590664) (xy 297.928993 -401.523839) (xy 297.928995 -401.456531) (xy 297.937042 -401.389707)
			(xy 297.953018 -401.324323) (xy 297.976695 -401.261318) (xy 298.007732 -401.201594) (xy 298.045686 -401.146008)
			(xy 298.067476 -401.120356) (xy 298.073271 -401.113209) (xy 298.079787 -401.09602) (xy 298.080176 -401.086828)
			(xy 298.080176 -400.92884) (xy 298.080654 -400.918691) (xy 298.088432 -400.899945) (xy 298.102811 -400.885621)
			(xy 298.121588 -400.877915) (xy 298.131738 -400.877532) (xy 298.848018 -400.877532) (xy 298.858145 -400.878011)
			(xy 298.876865 -400.885744) (xy 298.89122 -400.900032) (xy 298.89904 -400.918716) (xy 298.89958 -400.92884)
			(xy 298.89958 -401.086828) (xy 298.899981 -401.096016) (xy 298.906502 -401.1132) (xy 298.91228 -401.120356)
			(xy 298.934048 -401.146024) (xy 298.971996 -401.201609) (xy 299.003029 -401.261331) (xy 299.026702 -401.324333)
			(xy 299.042676 -401.389713) (xy 299.050721 -401.456533) (xy 299.050723 -401.523837) (xy 299.042681 -401.590657)
			(xy 299.026711 -401.656038) (xy 299.003041 -401.719042) (xy 299.000571 -401.723796) (xy 300.128624 -401.723796)
			(xy 300.128626 -401.656371) (xy 300.136704 -401.58943) (xy 300.152743 -401.52394) (xy 300.17651 -401.460842)
			(xy 300.207665 -401.401045) (xy 300.245758 -401.345411) (xy 300.267624 -401.319746) (xy 300.273429 -401.312607)
			(xy 300.279938 -401.295412) (xy 300.280324 -401.286218) (xy 300.280324 -400.793966) (xy 300.279925 -400.784778)
			(xy 300.273403 -400.767594) (xy 300.267624 -400.760438) (xy 300.245765 -400.734768) (xy 300.207675 -400.679135)
			(xy 300.176522 -400.61934) (xy 300.152757 -400.556243) (xy 300.13672 -400.490755) (xy 300.128643 -400.423816)
			(xy 300.128643 -400.356393) (xy 300.136719 -400.289454) (xy 300.152754 -400.223965) (xy 300.176519 -400.160869)
			(xy 300.20767 -400.101073) (xy 300.24576 -400.045439) (xy 300.267624 -400.019774) (xy 300.273417 -400.012626)
			(xy 300.279933 -399.995438) (xy 300.280324 -399.986246) (xy 300.280324 -399.828766) (xy 300.280798 -399.818639)
			(xy 300.288534 -399.79992) (xy 300.302824 -399.785566) (xy 300.321507 -399.777745) (xy 300.331632 -399.777204)
			(xy 301.047912 -399.777204) (xy 301.058067 -399.777612) (xy 301.076821 -399.785412) (xy 301.091144 -399.799813)
			(xy 301.098843 -399.818608) (xy 301.09922 -399.828766) (xy 301.09922 -399.986246) (xy 301.099652 -399.995431)
			(xy 301.10615 -400.012616) (xy 301.11192 -400.019774) (xy 301.133789 -400.045435) (xy 301.171876 -400.10107)
			(xy 301.203026 -400.160867) (xy 301.226789 -400.223965) (xy 301.242823 -400.289454) (xy 301.250898 -400.356393)
			(xy 301.250898 -400.423816) (xy 301.242821 -400.490755) (xy 301.226786 -400.556244) (xy 301.203022 -400.619341)
			(xy 301.171872 -400.679137) (xy 301.133784 -400.734772) (xy 301.11192 -400.760438) (xy 301.106127 -400.767586)
			(xy 301.09961 -400.784774) (xy 301.09922 -400.793966) (xy 301.09922 -401.286218) (xy 301.099617 -401.295407)
			(xy 301.106139 -401.312591) (xy 301.11192 -401.319746) (xy 301.133762 -401.345429) (xy 301.17185 -401.401062)
			(xy 301.203 -401.460856) (xy 301.226765 -401.52395) (xy 301.242801 -401.589437) (xy 301.250878 -401.656373)
			(xy 301.25088 -401.723794) (xy 301.242807 -401.790731) (xy 301.226775 -401.856218) (xy 301.203014 -401.919314)
			(xy 301.171867 -401.97911) (xy 301.133782 -402.034744) (xy 301.11192 -402.06041) (xy 301.106139 -402.067566)
			(xy 301.099614 -402.084748) (xy 301.09922 -402.093938) (xy 301.09922 -402.251418) (xy 301.098787 -402.261551)
			(xy 301.091046 -402.28028) (xy 301.076743 -402.294637) (xy 301.058043 -402.302449) (xy 301.047912 -402.30298)
			(xy 300.331632 -402.30298) (xy 300.321477 -402.302552) (xy 300.302722 -402.294763) (xy 300.288396 -402.280368)
			(xy 300.280699 -402.261575) (xy 300.280324 -402.251418) (xy 300.280324 -402.093938) (xy 300.27989 -402.084753)
			(xy 300.273392 -402.067569) (xy 300.267624 -402.06041) (xy 300.245738 -402.034763) (xy 300.207648 -401.979126)
			(xy 300.176497 -401.919328) (xy 300.152733 -401.856229) (xy 300.136698 -401.790737) (xy 300.128624 -401.723796)
			(xy 299.000571 -401.723796) (xy 298.972011 -401.778765) (xy 298.934066 -401.834352) (xy 298.91228 -401.860004)
			(xy 298.906497 -401.867159) (xy 298.899975 -401.884342) (xy 298.89958 -401.893532) (xy 298.89958 -402.3868)
			(xy 298.899994 -402.395987) (xy 298.906505 -402.413171) (xy 298.91228 -402.420328) (xy 298.93402 -402.446019)
			(xy 298.971969 -402.501601) (xy 299.003003 -402.561319) (xy 299.026678 -402.624318) (xy 299.042653 -402.689696)
			(xy 299.050701 -402.756513) (xy 299.050705 -402.823814) (xy 299.050697 -402.823877) (xy 302.328766 -402.823877)
			(xy 302.328771 -402.75645) (xy 302.336851 -402.689509) (xy 302.35289 -402.624018) (xy 302.376659 -402.560919)
			(xy 302.407814 -402.501122) (xy 302.445906 -402.445486) (xy 302.467772 -402.41982) (xy 302.473594 -402.412693)
			(xy 302.480091 -402.395488) (xy 302.480472 -402.386292) (xy 302.480472 -401.89404) (xy 302.480049 -401.884854)
			(xy 302.473545 -401.867669) (xy 302.467772 -401.860512) (xy 302.445889 -401.834863) (xy 302.407803 -401.779225)
			(xy 302.376655 -401.719426) (xy 302.352893 -401.656328) (xy 302.33686 -401.590837) (xy 302.328786 -401.523897)
			(xy 302.328788 -401.456473) (xy 302.336865 -401.389534) (xy 302.352902 -401.324044) (xy 302.376667 -401.260946)
			(xy 302.407819 -401.201149) (xy 302.445908 -401.145514) (xy 302.467772 -401.119848) (xy 302.473582 -401.112713)
			(xy 302.480087 -401.095514) (xy 302.480472 -401.08632) (xy 302.480472 -400.92884) (xy 302.480948 -400.918724)
			(xy 302.488678 -400.900026) (xy 302.502976 -400.885712) (xy 302.521664 -400.87796) (xy 302.53178 -400.877532)
			(xy 303.24806 -400.877532) (xy 303.258184 -400.87795) (xy 303.276893 -400.885691) (xy 303.291209 -400.900007)
			(xy 303.29895 -400.918716) (xy 303.299368 -400.92884) (xy 303.299368 -401.08632) (xy 303.299776 -401.095507)
			(xy 303.306292 -401.112691) (xy 303.312068 -401.119848) (xy 303.333913 -401.145529) (xy 303.372005 -401.20116)
			(xy 303.403158 -401.260954) (xy 303.426925 -401.324049) (xy 303.442963 -401.389537) (xy 303.451041 -401.456474)
			(xy 303.451043 -401.523896) (xy 303.442968 -401.590834) (xy 303.426934 -401.656322) (xy 303.40317 -401.719418)
			(xy 303.37202 -401.779214) (xy 303.333932 -401.834847) (xy 303.312068 -401.860512) (xy 303.30628 -401.867663)
			(xy 303.299761 -401.884849) (xy 303.299368 -401.89404) (xy 303.299368 -402.386292) (xy 303.299789 -402.395478)
			(xy 303.306296 -402.412662) (xy 303.312068 -402.41982) (xy 303.333886 -402.445524) (xy 303.371978 -402.501152)
			(xy 303.403133 -402.560942) (xy 303.426901 -402.624034) (xy 303.442941 -402.689519) (xy 303.451021 -402.756454)
			(xy 303.451025 -402.823874) (xy 303.442954 -402.89081) (xy 303.426922 -402.956297) (xy 303.403162 -403.019392)
			(xy 303.372015 -403.079186) (xy 303.33393 -403.134819) (xy 303.312068 -403.160484) (xy 303.306249 -403.167613)
			(xy 303.299749 -403.184816) (xy 303.299368 -403.194012) (xy 303.299368 -403.351492) (xy 303.298977 -403.361618)
			(xy 303.291225 -403.380328) (xy 303.276901 -403.394643) (xy 303.258186 -403.402383) (xy 303.24806 -403.4028)
			(xy 302.53178 -403.4028) (xy 302.52167 -403.402331) (xy 302.502991 -403.394587) (xy 302.488697 -403.380285)
			(xy 302.480963 -403.361602) (xy 302.480472 -403.351492) (xy 302.480472 -403.194012) (xy 302.480062 -403.184825)
			(xy 302.473549 -403.16764) (xy 302.467772 -403.160484) (xy 302.445862 -403.134857) (xy 302.407776 -403.079216)
			(xy 302.376629 -403.019415) (xy 302.352869 -402.956313) (xy 302.336838 -402.890819) (xy 302.328766 -402.823877)
			(xy 299.050697 -402.823877) (xy 299.042666 -402.890633) (xy 299.026699 -402.956013) (xy 299.003032 -403.019015)
			(xy 298.972006 -403.078737) (xy 298.934064 -403.134323) (xy 298.91228 -403.159976) (xy 298.906466 -403.167109)
			(xy 298.899963 -403.184309) (xy 298.89958 -403.193504) (xy 298.89958 -403.351492) (xy 298.899171 -403.361648)
			(xy 298.891375 -403.380404) (xy 298.876974 -403.394729) (xy 298.858176 -403.402425) (xy 298.848018 -403.4028)
			(xy 298.131738 -403.4028) (xy 298.121619 -403.402243) (xy 298.102906 -403.394535) (xy 298.08855 -403.380271)
			(xy 298.080722 -403.361608) (xy 298.080176 -403.351492) (xy 298.080176 -403.193504) (xy 298.079769 -403.184316)
			(xy 298.073254 -403.167132) (xy 298.067476 -403.159976) (xy 298.04564 -403.134363) (xy 298.00769 -403.078772)
			(xy 297.976657 -403.019043) (xy 297.952985 -402.956034) (xy 297.937014 -402.890646) (xy 297.928973 -402.823819)
			(xy 294.650937 -402.823819) (xy 294.650937 -402.823874) (xy 294.642866 -402.890809) (xy 294.626835 -402.956296)
			(xy 294.603076 -403.019391) (xy 294.57193 -403.079186) (xy 294.533846 -403.134819) (xy 294.511984 -403.160484)
			(xy 294.506167 -403.167615) (xy 294.499665 -403.184816) (xy 294.499284 -403.194012) (xy 294.499284 -403.351492)
			(xy 294.498877 -403.361616) (xy 294.491129 -403.380322) (xy 294.476809 -403.394638) (xy 294.4581 -403.40238)
			(xy 294.447976 -403.4028) (xy 293.731696 -403.4028) (xy 293.721573 -403.402387) (xy 293.70287 -403.394638)
			(xy 293.688556 -403.38032) (xy 293.68081 -403.361615) (xy 293.680388 -403.351492) (xy 293.680388 -403.194012)
			(xy 293.679975 -403.184825) (xy 293.673464 -403.167641) (xy 293.667688 -403.160484) (xy 293.645777 -403.134857)
			(xy 293.607691 -403.079217) (xy 293.576543 -403.019415) (xy 293.552782 -402.956314) (xy 293.53675 -402.89082)
			(xy 293.528678 -402.823878) (xy 290.250609 -402.823878) (xy 290.242579 -402.890633) (xy 290.226612 -402.956012)
			(xy 290.202946 -403.019014) (xy 290.17192 -403.078737) (xy 290.133979 -403.134323) (xy 290.112196 -403.159976)
			(xy 290.106384 -403.16711) (xy 290.099879 -403.184309) (xy 290.099496 -403.193504) (xy 290.099496 -403.351492)
			(xy 290.099072 -403.361646) (xy 290.091278 -403.380399) (xy 290.076882 -403.394723) (xy 290.05809 -403.402422)
			(xy 290.047934 -403.4028) (xy 289.331654 -403.4028) (xy 289.321529 -403.402312) (xy 289.302815 -403.394577)
			(xy 289.288461 -403.380292) (xy 289.280637 -403.361614) (xy 289.280092 -403.351492) (xy 289.280092 -403.193504)
			(xy 289.279682 -403.184317) (xy 289.273168 -403.167132) (xy 289.267392 -403.159976) (xy 289.245556 -403.134363)
			(xy 289.207605 -403.078772) (xy 289.176571 -403.019044) (xy 289.152898 -402.956034) (xy 289.136927 -402.890647)
			(xy 289.128886 -402.823819) (xy 237.559965 -402.823819) (xy 237.421928 -402.961856) (xy 237.415119 -402.969281)
			(xy 237.40738 -402.987861) (xy 237.406942 -402.997924) (xy 237.406942 -405.623708) (xy 286.928756 -405.623708)
			(xy 286.928757 -405.556283) (xy 286.936834 -405.489343) (xy 286.952872 -405.423853) (xy 286.976639 -405.360756)
			(xy 287.007793 -405.30096) (xy 287.045886 -405.245326) (xy 287.067752 -405.219662) (xy 287.073554 -405.212521)
			(xy 287.080064 -405.195327) (xy 287.080452 -405.186134) (xy 287.080452 -404.693882) (xy 287.080039 -404.684695)
			(xy 287.073526 -404.667512) (xy 287.067752 -404.660354) (xy 287.045908 -404.634672) (xy 287.007815 -404.579041)
			(xy 286.97666 -404.519248) (xy 286.952893 -404.456153) (xy 286.936854 -404.390665) (xy 286.928776 -404.323728)
			(xy 286.928774 -404.256305) (xy 286.936848 -404.189367) (xy 286.952883 -404.123879) (xy 286.976647 -404.060783)
			(xy 287.007798 -404.000987) (xy 287.045888 -403.945354) (xy 287.067752 -403.91969) (xy 287.073542 -403.91254)
			(xy 287.080059 -403.895353) (xy 287.080452 -403.886162) (xy 287.080452 -403.728682) (xy 287.080912 -403.718553)
			(xy 287.088648 -403.699829) (xy 287.102942 -403.685473) (xy 287.121633 -403.677656) (xy 287.13176 -403.67712)
			(xy 287.84804 -403.67712) (xy 287.858199 -403.677489) (xy 287.876956 -403.685302) (xy 287.891279 -403.699715)
			(xy 287.898974 -403.71852) (xy 287.899348 -403.728682) (xy 287.899348 -403.886162) (xy 287.899788 -403.895346)
			(xy 287.906282 -403.91253) (xy 287.912048 -403.91969) (xy 287.933935 -403.945337) (xy 287.972027 -404.000973)
			(xy 288.00318 -404.060771) (xy 288.026945 -404.12387) (xy 288.04298 -404.189362) (xy 288.051055 -404.256303)
			(xy 288.051053 -404.32373) (xy 288.042974 -404.39067) (xy 288.026935 -404.456161) (xy 288.003166 -404.519259)
			(xy 287.97201 -404.579056) (xy 287.933915 -404.63469) (xy 287.912048 -404.660354) (xy 287.90624 -404.667491)
			(xy 287.899733 -404.684688) (xy 287.899348 -404.693882) (xy 287.899348 -405.186134) (xy 287.899754 -405.195321)
			(xy 287.906272 -405.212505) (xy 287.912048 -405.219662) (xy 287.933908 -405.245331) (xy 287.972 -405.300964)
			(xy 288.003154 -405.360759) (xy 288.026921 -405.423856) (xy 288.042958 -405.489345) (xy 288.051036 -405.556283)
			(xy 288.051036 -405.623708) (xy 288.04296 -405.690646) (xy 288.026924 -405.756136) (xy 288.003158 -405.819233)
			(xy 287.972005 -405.879028) (xy 287.933913 -405.934662) (xy 287.912048 -405.960326) (xy 287.906251 -405.967471)
			(xy 287.899738 -405.984662) (xy 287.899348 -405.993854) (xy 287.899348 -406.151334) (xy 287.898901 -406.161464)
			(xy 287.89116 -406.180189) (xy 287.876861 -406.194544) (xy 287.858168 -406.20236) (xy 287.84804 -406.202896)
			(xy 287.13176 -406.202896) (xy 287.121603 -406.202511) (xy 287.102849 -406.194701) (xy 287.088527 -406.180294)
			(xy 287.080829 -406.161494) (xy 287.080452 -406.151334) (xy 287.080452 -405.993854) (xy 287.080004 -405.984671)
			(xy 287.073515 -405.967487) (xy 287.067752 -405.960326) (xy 287.04588 -405.934667) (xy 287.007788 -405.879032)
			(xy 286.976635 -405.819236) (xy 286.952869 -405.756138) (xy 286.936832 -405.690648) (xy 286.928756 -405.623708)
			(xy 237.406942 -405.623708) (xy 237.406942 -406.72373) (xy 289.128897 -406.72373) (xy 289.1289 -406.656422)
			(xy 289.136948 -406.589596) (xy 289.152926 -406.524211) (xy 289.176605 -406.461205) (xy 289.207645 -406.401481)
			(xy 289.245601 -406.345895) (xy 289.267392 -406.320244) (xy 289.273194 -406.313103) (xy 289.279706 -406.295909)
			(xy 289.280092 -406.286716) (xy 289.280092 -405.793448) (xy 289.279661 -405.784263) (xy 289.273162 -405.767078)
			(xy 289.267392 -405.75992) (xy 289.245599 -405.734272) (xy 289.207647 -405.678686) (xy 289.176611 -405.618962)
			(xy 289.152936 -405.555957) (xy 289.136961 -405.490574) (xy 289.128917 -405.42375) (xy 289.128917 -405.356444)
			(xy 289.136962 -405.28962) (xy 289.152937 -405.224237) (xy 289.176613 -405.161232) (xy 289.20765 -405.101509)
			(xy 289.245602 -405.045923) (xy 289.267392 -405.020272) (xy 289.273182 -405.013122) (xy 289.279701 -404.995935)
			(xy 289.280092 -404.986744) (xy 289.280092 -404.828756) (xy 289.280486 -404.8186) (xy 289.288294 -404.799848)
			(xy 289.302699 -404.785527) (xy 289.321496 -404.777827) (xy 289.331654 -404.777448) (xy 290.047934 -404.777448)
			(xy 290.058064 -404.777899) (xy 290.076787 -404.785639) (xy 290.091143 -404.799936) (xy 290.098959 -404.818628)
			(xy 290.099496 -404.828756) (xy 290.099496 -404.986744) (xy 290.099886 -404.995933) (xy 290.106414 -405.013117)
			(xy 290.112196 -405.020272) (xy 290.133979 -405.045928) (xy 290.171925 -405.101515) (xy 290.202957 -405.161238)
			(xy 290.226628 -405.224242) (xy 290.242601 -405.289623) (xy 290.250644 -405.356445) (xy 290.250645 -405.423749)
			(xy 290.242602 -405.490571) (xy 290.22663 -405.555952) (xy 290.202959 -405.618957) (xy 290.200522 -405.623648)
			(xy 291.329076 -405.623648) (xy 291.329076 -405.556343) (xy 291.337121 -405.48952) (xy 291.353095 -405.424137)
			(xy 291.376768 -405.361132) (xy 291.407802 -405.301409) (xy 291.445752 -405.245822) (xy 291.46754 -405.22017)
			(xy 291.473337 -405.213025) (xy 291.47985 -405.195834) (xy 291.48024 -405.186642) (xy 291.48024 -404.693374)
			(xy 291.479833 -404.684187) (xy 291.473316 -404.667003) (xy 291.46754 -404.659846) (xy 291.445774 -404.634176)
			(xy 291.407825 -404.578592) (xy 291.37679 -404.518871) (xy 291.353116 -404.455869) (xy 291.337142 -404.390489)
			(xy 291.329096 -404.323668) (xy 291.329094 -404.256365) (xy 291.337136 -404.189544) (xy 291.353106 -404.124163)
			(xy 291.376777 -404.061159) (xy 291.407808 -404.001436) (xy 291.445754 -403.94585) (xy 291.46754 -403.920198)
			(xy 291.473325 -403.913045) (xy 291.479846 -403.89586) (xy 291.48024 -403.88667) (xy 291.48024 -403.728682)
			(xy 291.480718 -403.718523) (xy 291.488499 -403.699753) (xy 291.50287 -403.685388) (xy 291.521643 -403.677615)
			(xy 291.531802 -403.67712) (xy 292.248082 -403.67712) (xy 292.258236 -403.677648) (xy 292.277002 -403.685413)
			(xy 292.291367 -403.699768) (xy 292.299145 -403.718528) (xy 292.299644 -403.728682) (xy 292.299644 -403.88667)
			(xy 292.300081 -403.895854) (xy 292.306577 -403.913038) (xy 292.312344 -403.920198) (xy 292.334154 -403.945832)
			(xy 292.372103 -404.001421) (xy 292.403137 -404.061147) (xy 292.426809 -404.124153) (xy 292.442781 -404.189538)
			(xy 292.450824 -404.256363) (xy 292.450822 -404.32367) (xy 292.442775 -404.390495) (xy 292.426799 -404.455878)
			(xy 292.403123 -404.518884) (xy 292.372086 -404.578608) (xy 292.334134 -404.634194) (xy 292.312344 -404.659846)
			(xy 292.306539 -404.666985) (xy 292.300031 -404.68418) (xy 292.299644 -404.693374) (xy 292.299644 -405.186642)
			(xy 292.300047 -405.19583) (xy 292.306567 -405.213013) (xy 292.312344 -405.22017) (xy 292.334126 -405.245827)
			(xy 292.372076 -405.301412) (xy 292.403111 -405.361135) (xy 292.426785 -405.424139) (xy 292.442758 -405.489521)
			(xy 292.450803 -405.556343) (xy 292.450804 -405.623648) (xy 292.44276 -405.69047) (xy 292.426787 -405.755852)
			(xy 292.403114 -405.818857) (xy 292.372081 -405.87858) (xy 292.334132 -405.934166) (xy 292.312344 -405.959818)
			(xy 292.30655 -405.966965) (xy 292.300035 -405.984154) (xy 292.299644 -405.993346) (xy 292.299644 -406.151334)
			(xy 292.299194 -406.161496) (xy 292.291405 -406.18027) (xy 292.277026 -406.194634) (xy 292.258245 -406.202404)
			(xy 292.248082 -406.202896) (xy 291.531802 -406.202896) (xy 291.521649 -406.202366) (xy 291.502886 -406.194598)
			(xy 291.488522 -406.180244) (xy 291.480741 -406.161487) (xy 291.48024 -406.151334) (xy 291.48024 -405.993346)
			(xy 291.479799 -405.984162) (xy 291.473306 -405.966978) (xy 291.46754 -405.959818) (xy 291.445746 -405.934171)
			(xy 291.407797 -405.878584) (xy 291.376764 -405.818859) (xy 291.353092 -405.755854) (xy 291.337119 -405.690471)
			(xy 291.329076 -405.623648) (xy 290.200522 -405.623648) (xy 290.171928 -405.67868) (xy 290.133982 -405.734267)
			(xy 290.112196 -405.75992) (xy 290.106408 -405.767071) (xy 290.099888 -405.784257) (xy 290.099496 -405.793448)
			(xy 290.099496 -406.286716) (xy 290.099899 -406.295904) (xy 290.106418 -406.313088) (xy 290.112196 -406.320244)
			(xy 290.133951 -406.345922) (xy 290.171899 -406.401506) (xy 290.202931 -406.461226) (xy 290.226605 -406.524227)
			(xy 290.242579 -406.589606) (xy 290.250625 -406.656425) (xy 290.250628 -406.723727) (xy 290.250621 -406.723789)
			(xy 293.52869 -406.723789) (xy 293.528692 -406.656363) (xy 293.536771 -406.589423) (xy 293.55281 -406.523932)
			(xy 293.576577 -406.460834) (xy 293.607731 -406.401037) (xy 293.645823 -406.345401) (xy 293.667688 -406.319736)
			(xy 293.673493 -406.312597) (xy 293.680003 -406.295402) (xy 293.680388 -406.286208) (xy 293.680388 -405.793956)
			(xy 293.680002 -405.784766) (xy 293.673472 -405.767582) (xy 293.667688 -405.760428) (xy 293.645821 -405.734766)
			(xy 293.607733 -405.679131) (xy 293.576583 -405.619334) (xy 293.552819 -405.556237) (xy 293.536785 -405.490747)
			(xy 293.528709 -405.423809) (xy 293.52871 -405.356385) (xy 293.536786 -405.289447) (xy 293.552821 -405.223958)
			(xy 293.576585 -405.160861) (xy 293.607736 -405.101064) (xy 293.645824 -405.045429) (xy 293.667688 -405.019764)
			(xy 293.673481 -405.012616) (xy 293.679998 -404.995428) (xy 293.680388 -404.986236) (xy 293.680388 -404.828756)
			(xy 293.680849 -404.818646) (xy 293.688599 -404.799969) (xy 293.702903 -404.785676) (xy 293.721586 -404.777941)
			(xy 293.731696 -404.777448) (xy 294.447976 -404.777448) (xy 294.458077 -404.778003) (xy 294.476745 -404.785723)
			(xy 294.491038 -404.799998) (xy 294.498783 -404.818656) (xy 294.499284 -404.828756) (xy 294.499284 -404.986236)
			(xy 294.49968 -404.995425) (xy 294.506204 -405.012609) (xy 294.511984 -405.019764) (xy 294.533845 -405.045432)
			(xy 294.571934 -405.101066) (xy 294.603086 -405.160862) (xy 294.626851 -405.223958) (xy 294.642888 -405.289447)
			(xy 294.650964 -405.356385) (xy 294.650964 -405.423809) (xy 294.642889 -405.490747) (xy 294.626853 -405.556236)
			(xy 294.603089 -405.619333) (xy 294.60081 -405.623708) (xy 295.728844 -405.623708) (xy 295.728845 -405.556283)
			(xy 295.736922 -405.489344) (xy 295.752959 -405.423854) (xy 295.776725 -405.360757) (xy 295.807879 -405.30096)
			(xy 295.84597 -405.245327) (xy 295.867836 -405.219662) (xy 295.873636 -405.212519) (xy 295.880148 -405.195327)
			(xy 295.880536 -405.186134) (xy 295.880536 -404.693882) (xy 295.880126 -404.684695) (xy 295.873611 -404.667511)
			(xy 295.867836 -404.660354) (xy 295.845992 -404.634672) (xy 295.807901 -404.57904) (xy 295.776747 -404.519247)
			(xy 295.75298 -404.456152) (xy 295.736942 -404.390665) (xy 295.728864 -404.323728) (xy 295.728862 -404.256305)
			(xy 295.736936 -404.189368) (xy 295.75297 -404.123879) (xy 295.776733 -404.060783) (xy 295.807884 -404.000988)
			(xy 295.845972 -403.945355) (xy 295.867836 -403.91969) (xy 295.873624 -403.912539) (xy 295.880143 -403.895353)
			(xy 295.880536 -403.886162) (xy 295.880536 -403.728682) (xy 295.881011 -403.718555) (xy 295.888744 -403.699834)
			(xy 295.903034 -403.685478) (xy 295.921719 -403.677659) (xy 295.931844 -403.67712) (xy 296.648124 -403.67712)
			(xy 296.658282 -403.677502) (xy 296.677039 -403.685309) (xy 296.691362 -403.699718) (xy 296.699058 -403.718521)
			(xy 296.699432 -403.728682) (xy 296.699432 -403.886162) (xy 296.699876 -403.895345) (xy 296.706368 -403.912529)
			(xy 296.712132 -403.91969) (xy 296.734016 -403.945338) (xy 296.772102 -404.000976) (xy 296.80325 -404.060775)
			(xy 296.827012 -404.123874) (xy 296.843045 -404.189364) (xy 296.851118 -404.256304) (xy 296.851117 -404.323729)
			(xy 296.843039 -404.390668) (xy 296.827002 -404.456158) (xy 296.803237 -404.519256) (xy 296.772085 -404.579053)
			(xy 296.733996 -404.634688) (xy 296.712132 -404.660354) (xy 296.706322 -404.667489) (xy 296.699817 -404.684688)
			(xy 296.699432 -404.693882) (xy 296.699432 -405.186134) (xy 296.699841 -405.195321) (xy 296.706357 -405.212505)
			(xy 296.712132 -405.219662) (xy 296.733989 -405.245333) (xy 296.772076 -405.300967) (xy 296.803225 -405.360763)
			(xy 296.826988 -405.423859) (xy 296.843023 -405.489347) (xy 296.851099 -405.556284) (xy 296.851099 -405.623707)
			(xy 296.843025 -405.690644) (xy 296.826991 -405.756132) (xy 296.803229 -405.819229) (xy 296.77208 -405.879025)
			(xy 296.733994 -405.93466) (xy 296.712132 -405.960326) (xy 296.706334 -405.96747) (xy 296.699822 -405.984662)
			(xy 296.699432 -405.993854) (xy 296.699432 -406.151334) (xy 296.699001 -406.161466) (xy 296.691256 -406.180194)
			(xy 296.676953 -406.19455) (xy 296.658254 -406.202363) (xy 296.648124 -406.202896) (xy 295.931844 -406.202896)
			(xy 295.921692 -406.202442) (xy 295.90294 -406.19466) (xy 295.888615 -406.180273) (xy 295.880915 -406.161487)
			(xy 295.880536 -406.151334) (xy 295.880536 -405.993854) (xy 295.880092 -405.984671) (xy 295.873601 -405.967486)
			(xy 295.867836 -405.960326) (xy 295.845965 -405.934666) (xy 295.807874 -405.879032) (xy 295.776722 -405.819235)
			(xy 295.752956 -405.756137) (xy 295.73692 -405.690647) (xy 295.728844 -405.623708) (xy 294.60081 -405.623708)
			(xy 294.571938 -405.679129) (xy 294.533848 -405.734763) (xy 294.511984 -405.760428) (xy 294.506191 -405.767576)
			(xy 294.499675 -405.784764) (xy 294.499284 -405.793956) (xy 294.499284 -406.286208) (xy 294.499694 -406.295395)
			(xy 294.506208 -406.312579) (xy 294.511984 -406.319736) (xy 294.533817 -406.345427) (xy 294.571908 -406.401057)
			(xy 294.603061 -406.46085) (xy 294.626827 -406.523943) (xy 294.642866 -406.58943) (xy 294.650944 -406.656365)
			(xy 294.650947 -406.72373) (xy 297.928985 -406.72373) (xy 297.928988 -406.656422) (xy 297.937036 -406.589596)
			(xy 297.953013 -406.524212) (xy 297.976691 -406.461206) (xy 298.00773 -406.401482) (xy 298.045685 -406.345896)
			(xy 298.067476 -406.320244) (xy 298.073276 -406.313101) (xy 298.079789 -406.295909) (xy 298.080176 -406.286716)
			(xy 298.080176 -405.793448) (xy 298.079748 -405.784263) (xy 298.073247 -405.767078) (xy 298.067476 -405.75992)
			(xy 298.045683 -405.734272) (xy 298.007732 -405.678685) (xy 297.976697 -405.618962) (xy 297.953023 -405.555957)
			(xy 297.937049 -405.490574) (xy 297.929005 -405.42375) (xy 297.929005 -405.356444) (xy 297.93705 -405.28962)
			(xy 297.953025 -405.224238) (xy 297.9767 -405.161233) (xy 298.007735 -405.101509) (xy 298.045687 -405.045924)
			(xy 298.067476 -405.020272) (xy 298.073264 -405.013121) (xy 298.079785 -404.995935) (xy 298.080176 -404.986744)
			(xy 298.080176 -404.828756) (xy 298.080585 -404.818602) (xy 298.088391 -404.799853) (xy 298.102791 -404.785532)
			(xy 298.121582 -404.77783) (xy 298.131738 -404.777448) (xy 298.848018 -404.777448) (xy 298.858147 -404.777912)
			(xy 298.87687 -404.785647) (xy 298.891226 -404.79994) (xy 298.899043 -404.818629) (xy 298.89958 -404.828756)
			(xy 298.89958 -404.986744) (xy 298.899973 -404.995933) (xy 298.906499 -405.013117) (xy 298.91228 -405.020272)
			(xy 298.934063 -405.045928) (xy 298.972011 -405.101514) (xy 299.003043 -405.161237) (xy 299.026716 -405.224241)
			(xy 299.042688 -405.289623) (xy 299.050732 -405.356445) (xy 299.050733 -405.423749) (xy 299.042689 -405.490571)
			(xy 299.026717 -405.555953) (xy 299.003046 -405.618957) (xy 299.000577 -405.623708) (xy 300.128635 -405.623708)
			(xy 300.128635 -405.556283) (xy 300.136712 -405.489344) (xy 300.152749 -405.423854) (xy 300.176515 -405.360757)
			(xy 300.207668 -405.300961) (xy 300.245759 -405.245327) (xy 300.267624 -405.219662) (xy 300.273422 -405.212518)
			(xy 300.279935 -405.195326) (xy 300.280324 -405.186134) (xy 300.280324 -404.693882) (xy 300.279917 -404.684695)
			(xy 300.273401 -404.66751) (xy 300.267624 -404.660354) (xy 300.245781 -404.634671) (xy 300.20769 -404.57904)
			(xy 300.176537 -404.519246) (xy 300.15277 -404.456152) (xy 300.136733 -404.390664) (xy 300.128655 -404.323728)
			(xy 300.128653 -404.256305) (xy 300.136727 -404.189368) (xy 300.152761 -404.12388) (xy 300.176523 -404.060784)
			(xy 300.207673 -404.000989) (xy 300.245761 -403.945355) (xy 300.267624 -403.91969) (xy 300.27341 -403.912538)
			(xy 300.27993 -403.895352) (xy 300.280324 -403.886162) (xy 300.280324 -403.728682) (xy 300.280811 -403.718556)
			(xy 300.288542 -403.699837) (xy 300.302828 -403.685482) (xy 300.321509 -403.677661) (xy 300.331632 -403.67712)
			(xy 301.047912 -403.67712) (xy 301.058069 -403.677512) (xy 301.076826 -403.685315) (xy 301.09115 -403.699721)
			(xy 301.098846 -403.718522) (xy 301.09922 -403.728682) (xy 301.09922 -403.886162) (xy 301.099644 -403.895348)
			(xy 301.106147 -403.912533) (xy 301.11192 -403.91969) (xy 301.133805 -403.945338) (xy 301.171892 -404.000975)
			(xy 301.20304 -404.060774) (xy 301.226802 -404.123873) (xy 301.242836 -404.189364) (xy 301.250909 -404.256304)
			(xy 301.250907 -404.323729) (xy 301.24283 -404.390668) (xy 301.226793 -404.456158) (xy 301.203027 -404.519256)
			(xy 301.171875 -404.579053) (xy 301.133785 -404.634688) (xy 301.11192 -404.660354) (xy 301.10612 -404.667497)
			(xy 301.099607 -404.684689) (xy 301.09922 -404.693882) (xy 301.09922 -405.186134) (xy 301.099609 -405.195323)
			(xy 301.106137 -405.212508) (xy 301.11192 -405.219662) (xy 301.133777 -405.245332) (xy 301.171865 -405.300967)
			(xy 301.203015 -405.360762) (xy 301.226778 -405.423859) (xy 301.242814 -405.489347) (xy 301.25089 -405.556284)
			(xy 301.25089 -405.623707) (xy 301.242815 -405.690644) (xy 301.226781 -405.756133) (xy 301.203018 -405.819229)
			(xy 301.17187 -405.879026) (xy 301.133783 -405.93466) (xy 301.11192 -405.960326) (xy 301.106132 -405.967478)
			(xy 301.099612 -405.984663) (xy 301.09922 -405.993854) (xy 301.09922 -406.151334) (xy 301.0988 -406.161468)
			(xy 301.091054 -406.180197) (xy 301.076747 -406.194554) (xy 301.058044 -406.202365) (xy 301.047912 -406.202896)
			(xy 300.331632 -406.202896) (xy 300.321479 -406.202452) (xy 300.302727 -406.194667) (xy 300.288402 -406.180276)
			(xy 300.280702 -406.161488) (xy 300.280324 -406.151334) (xy 300.280324 -405.993854) (xy 300.279882 -405.98467)
			(xy 300.27339 -405.967486) (xy 300.267624 -405.960326) (xy 300.245753 -405.934666) (xy 300.207663 -405.879031)
			(xy 300.176511 -405.819235) (xy 300.152747 -405.756137) (xy 300.136711 -405.690647) (xy 300.128635 -405.623708)
			(xy 299.000577 -405.623708) (xy 298.972014 -405.678681) (xy 298.934067 -405.734268) (xy 298.91228 -405.75992)
			(xy 298.90649 -405.76707) (xy 298.899972 -405.784257) (xy 298.89958 -405.793448) (xy 298.89958 -406.286716)
			(xy 298.899987 -406.295903) (xy 298.906503 -406.313088) (xy 298.91228 -406.320244) (xy 298.934035 -406.345922)
			(xy 298.971984 -406.401506) (xy 299.003018 -406.461226) (xy 299.026691 -406.524227) (xy 299.042666 -406.589606)
			(xy 299.050712 -406.656425) (xy 299.050715 -406.723727) (xy 299.050708 -406.723789) (xy 302.328777 -406.723789)
			(xy 302.32878 -406.656363) (xy 302.336859 -406.589423) (xy 302.352897 -406.523933) (xy 302.376664 -406.460835)
			(xy 302.407816 -406.401037) (xy 302.445907 -406.345402) (xy 302.467772 -406.319736) (xy 302.473587 -406.312604)
			(xy 302.480089 -406.295403) (xy 302.480472 -406.286208) (xy 302.480472 -405.793956) (xy 302.480089 -405.784766)
			(xy 302.473557 -405.767581) (xy 302.467772 -405.760428) (xy 302.445905 -405.734766) (xy 302.407818 -405.67913)
			(xy 302.376669 -405.619333) (xy 302.352907 -405.556236) (xy 302.336872 -405.490747) (xy 302.328797 -405.423809)
			(xy 302.328798 -405.356385) (xy 302.336873 -405.289447) (xy 302.352908 -405.223958) (xy 302.376672 -405.160861)
			(xy 302.407821 -405.101065) (xy 302.445909 -405.04543) (xy 302.467772 -405.019764) (xy 302.473575 -405.012624)
			(xy 302.480084 -404.995429) (xy 302.480472 -404.986236) (xy 302.480472 -404.828756) (xy 302.480948 -404.818648)
			(xy 302.488695 -404.799974) (xy 302.502994 -404.785682) (xy 302.521672 -404.777944) (xy 302.53178 -404.777448)
			(xy 303.24806 -404.777448) (xy 303.25816 -404.778017) (xy 303.276827 -404.785732) (xy 303.291121 -404.800002)
			(xy 303.298867 -404.818657) (xy 303.299368 -404.828756) (xy 303.299368 -404.986236) (xy 303.299768 -404.995424)
			(xy 303.30629 -405.012608) (xy 303.312068 -405.019764) (xy 303.333929 -405.045432) (xy 303.37202 -405.101065)
			(xy 303.403173 -405.160861) (xy 303.426939 -405.223957) (xy 303.442975 -405.289447) (xy 303.451052 -405.356385)
			(xy 303.451052 -405.423809) (xy 303.442976 -405.490748) (xy 303.42694 -405.556237) (xy 303.403175 -405.619334)
			(xy 303.372023 -405.67913) (xy 303.333933 -405.734763) (xy 303.312068 -405.760428) (xy 303.306273 -405.767574)
			(xy 303.299758 -405.784764) (xy 303.299368 -405.793956) (xy 303.299368 -406.286208) (xy 303.299781 -406.295395)
			(xy 303.306294 -406.312579) (xy 303.312068 -406.319736) (xy 303.333902 -406.345427) (xy 303.371993 -406.401057)
			(xy 303.403147 -406.460849) (xy 303.426915 -406.523943) (xy 303.442953 -406.589429) (xy 303.451032 -406.656365)
			(xy 303.451035 -406.723787) (xy 303.442962 -406.790724) (xy 303.426929 -406.856211) (xy 303.403167 -406.919307)
			(xy 303.372018 -406.979102) (xy 303.333931 -407.034735) (xy 303.312068 -407.0604) (xy 303.306285 -407.067555)
			(xy 303.299763 -407.084738) (xy 303.299368 -407.093928) (xy 303.299368 -407.251408) (xy 303.29899 -407.261535)
			(xy 303.291233 -407.280245) (xy 303.276904 -407.29456) (xy 303.258187 -407.302299) (xy 303.24806 -407.302716)
			(xy 302.53178 -407.302716) (xy 302.521672 -407.302232) (xy 302.502996 -407.294491) (xy 302.488703 -407.280194)
			(xy 302.480966 -407.261516) (xy 302.480472 -407.251408) (xy 302.480472 -407.093928) (xy 302.480055 -407.084741)
			(xy 302.473547 -407.067557) (xy 302.467772 -407.0604) (xy 302.445878 -407.03476) (xy 302.407792 -406.979121)
			(xy 302.376644 -406.919321) (xy 302.352883 -406.856221) (xy 302.33685 -406.790729) (xy 302.328777 -406.723789)
			(xy 299.050708 -406.723789) (xy 299.042674 -406.790547) (xy 299.026705 -406.855927) (xy 299.003037 -406.91893)
			(xy 298.972009 -406.978653) (xy 298.934065 -407.034239) (xy 298.91228 -407.059892) (xy 298.906502 -407.06705)
			(xy 298.899977 -407.084231) (xy 298.89958 -407.09342) (xy 298.89958 -407.251408) (xy 298.899184 -407.261565)
			(xy 298.891382 -407.280321) (xy 298.876978 -407.294645) (xy 298.858177 -407.302341) (xy 298.848018 -407.302716)
			(xy 298.131738 -407.302716) (xy 298.121608 -407.302241) (xy 298.10288 -407.294517) (xy 298.088521 -407.280227)
			(xy 298.080708 -407.261535) (xy 298.080176 -407.251408) (xy 298.080176 -407.09342) (xy 298.079762 -407.084233)
			(xy 298.073252 -407.067048) (xy 298.067476 -407.059892) (xy 298.045656 -407.034266) (xy 298.007706 -406.978677)
			(xy 297.976672 -406.91895) (xy 297.952999 -406.855942) (xy 297.937027 -406.790556) (xy 297.928985 -406.72373)
			(xy 294.650947 -406.72373) (xy 294.650947 -406.723787) (xy 294.642874 -406.790723) (xy 294.626842 -406.856211)
			(xy 294.60308 -406.919306) (xy 294.571933 -406.979101) (xy 294.533847 -407.034735) (xy 294.511984 -407.0604)
			(xy 294.506203 -407.067556) (xy 294.49968 -407.084738) (xy 294.499284 -407.093928) (xy 294.499284 -407.251408)
			(xy 294.49889 -407.261533) (xy 294.491136 -407.28024) (xy 294.476813 -407.294554) (xy 294.458101 -407.302296)
			(xy 294.447976 -407.302716) (xy 293.731696 -407.302716) (xy 293.721589 -407.302218) (xy 293.702914 -407.294482)
			(xy 293.68862 -407.28019) (xy 293.680882 -407.261515) (xy 293.680388 -407.251408) (xy 293.680388 -407.093928)
			(xy 293.679967 -407.084742) (xy 293.673461 -407.067557) (xy 293.667688 -407.0604) (xy 293.645793 -407.03476)
			(xy 293.607706 -406.979122) (xy 293.576557 -406.919322) (xy 293.552796 -406.856222) (xy 293.536763 -406.79073)
			(xy 293.52869 -406.723789) (xy 290.250621 -406.723789) (xy 290.242587 -406.790547) (xy 290.226619 -406.855927)
			(xy 290.202951 -406.91893) (xy 290.171924 -406.978653) (xy 290.133981 -407.034239) (xy 290.112196 -407.059892)
			(xy 290.10642 -407.067052) (xy 290.099893 -407.084231) (xy 290.099496 -407.09342) (xy 290.099496 -407.251408)
			(xy 290.099085 -407.261563) (xy 290.091286 -407.280316) (xy 290.076886 -407.29464) (xy 290.058091 -407.302338)
			(xy 290.047934 -407.302716) (xy 289.331654 -407.302716) (xy 289.321519 -407.30231) (xy 289.302788 -407.294559)
			(xy 289.288432 -407.280248) (xy 289.280622 -407.261541) (xy 289.280092 -407.251408) (xy 289.280092 -407.09342)
			(xy 289.279674 -407.084234) (xy 289.273166 -407.067049) (xy 289.267392 -407.059892) (xy 289.245571 -407.034266)
			(xy 289.20762 -406.978677) (xy 289.176585 -406.918951) (xy 289.152912 -406.855943) (xy 289.136939 -406.790557)
			(xy 289.128897 -406.72373) (xy 237.406942 -406.72373) (xy 237.406942 -409.523887) (xy 286.928735 -409.523887)
			(xy 286.928738 -409.456459) (xy 286.936818 -409.389518) (xy 286.952859 -409.324026) (xy 286.97663 -409.260927)
			(xy 287.007788 -409.20113) (xy 287.045884 -409.145496) (xy 287.067752 -409.119832) (xy 287.073566 -409.1127)
			(xy 287.080069 -409.095499) (xy 287.080452 -409.086304) (xy 287.080452 -408.594052) (xy 287.080005 -408.584869)
			(xy 287.073516 -408.567685) (xy 287.067752 -408.560524) (xy 287.045878 -408.534866) (xy 287.007786 -408.479232)
			(xy 286.976633 -408.419435) (xy 286.952867 -408.356337) (xy 286.936831 -408.290847) (xy 286.928755 -408.223907)
			(xy 286.928755 -408.156481) (xy 286.936833 -408.089542) (xy 286.952871 -408.024051) (xy 286.976638 -407.960954)
			(xy 287.007793 -407.901158) (xy 287.045886 -407.845524) (xy 287.067752 -407.81986) (xy 287.073554 -407.812719)
			(xy 287.080064 -407.795525) (xy 287.080452 -407.786332) (xy 287.080452 -407.628852) (xy 287.080945 -407.618746)
			(xy 287.088689 -407.600076) (xy 287.102983 -407.585785) (xy 287.121654 -407.578043) (xy 287.13176 -407.577544)
			(xy 287.84804 -407.577544) (xy 287.858144 -407.578051) (xy 287.876813 -407.585791) (xy 287.891104 -407.600081)
			(xy 287.898847 -407.618748) (xy 287.899348 -407.628852) (xy 287.899348 -407.786332) (xy 287.899755 -407.795519)
			(xy 287.906272 -407.812703) (xy 287.912048 -407.81986) (xy 287.933906 -407.845531) (xy 287.971998 -407.901163)
			(xy 288.003152 -407.960958) (xy 288.026919 -408.024055) (xy 288.042957 -408.089543) (xy 288.051034 -408.156482)
			(xy 288.051035 -408.223906) (xy 288.042959 -408.290845) (xy 288.026923 -408.356334) (xy 288.003157 -408.419431)
			(xy 287.972004 -408.479226) (xy 287.933913 -408.53486) (xy 287.912048 -408.560524) (xy 287.906252 -408.56767)
			(xy 287.899739 -408.58486) (xy 287.899348 -408.594052) (xy 287.899348 -409.086304) (xy 287.899768 -409.09549)
			(xy 287.906276 -409.112674) (xy 287.912048 -409.119832) (xy 287.933878 -409.145526) (xy 287.971972 -409.201155)
			(xy 288.003127 -409.260947) (xy 288.026895 -409.32404) (xy 288.042935 -409.389526) (xy 288.051014 -409.456462)
			(xy 288.051018 -409.523884) (xy 288.042945 -409.590821) (xy 288.026911 -409.656308) (xy 288.003149 -409.719404)
			(xy 287.971999 -409.779199) (xy 287.933912 -409.834832) (xy 287.912048 -409.860496) (xy 287.906264 -409.86765)
			(xy 287.899743 -409.884834) (xy 287.899348 -409.894024) (xy 287.899348 -410.051504) (xy 287.898819 -410.061607)
			(xy 287.891089 -410.080276) (xy 287.876806 -410.094569) (xy 287.858143 -410.102312) (xy 287.84804 -410.102812)
			(xy 287.13176 -410.102812) (xy 287.12165 -410.102348) (xy 287.102973 -410.094599) (xy 287.08868 -410.080296)
			(xy 287.080945 -410.061614) (xy 287.080452 -410.051504) (xy 287.080452 -409.894024) (xy 287.080019 -409.884839)
			(xy 287.07352 -409.867655) (xy 287.067752 -409.860496) (xy 287.045851 -409.834861) (xy 287.00776 -409.779223)
			(xy 286.976608 -409.719423) (xy 286.952843 -409.656322) (xy 286.936809 -409.590829) (xy 286.928735 -409.523887)
			(xy 237.406942 -409.523887) (xy 237.406942 -410.623642) (xy 289.128908 -410.623642) (xy 289.12891 -410.556334)
			(xy 289.136956 -410.48951) (xy 289.152933 -410.424126) (xy 289.176609 -410.361121) (xy 289.207648 -410.301397)
			(xy 289.245602 -410.245811) (xy 289.267392 -410.22016) (xy 289.273187 -410.213014) (xy 289.279703 -410.195824)
			(xy 289.280092 -410.186632) (xy 289.280092 -409.693364) (xy 289.279701 -409.684175) (xy 289.273174 -409.66699)
			(xy 289.267392 -409.659836) (xy 289.245614 -409.634175) (xy 289.207662 -409.578591) (xy 289.176625 -409.518869)
			(xy 289.152949 -409.455866) (xy 289.136974 -409.390484) (xy 289.128928 -409.323662) (xy 289.128927 -409.256356)
			(xy 289.136971 -409.189534) (xy 289.152944 -409.124152) (xy 289.176618 -409.061147) (xy 289.207653 -409.001425)
			(xy 289.245603 -408.945839) (xy 289.267392 -408.920188) (xy 289.273175 -408.913033) (xy 289.279698 -408.89585)
			(xy 289.280092 -408.88666) (xy 289.280092 -408.728672) (xy 289.280498 -408.718517) (xy 289.288302 -408.699766)
			(xy 289.302703 -408.685443) (xy 289.321497 -408.677743) (xy 289.331654 -408.677364) (xy 290.047934 -408.677364)
			(xy 290.058066 -408.677799) (xy 290.076792 -408.685543) (xy 290.091148 -408.699845) (xy 290.098962 -408.718542)
			(xy 290.099496 -408.728672) (xy 290.099496 -408.88666) (xy 290.099926 -408.895845) (xy 290.106426 -408.91303)
			(xy 290.112196 -408.920188) (xy 290.133994 -408.945831) (xy 290.171941 -409.00142) (xy 290.202971 -409.061145)
			(xy 290.226642 -409.12415) (xy 290.242613 -409.189533) (xy 290.250656 -409.256356) (xy 290.250655 -409.323662)
			(xy 290.24261 -409.390484) (xy 290.226637 -409.455867) (xy 290.202964 -409.518872) (xy 290.200389 -409.523827)
			(xy 291.329055 -409.523827) (xy 291.329058 -409.456519) (xy 291.337106 -409.389694) (xy 291.353082 -409.32431)
			(xy 291.376759 -409.261304) (xy 291.407797 -409.201579) (xy 291.44575 -409.145992) (xy 291.46754 -409.12034)
			(xy 291.47335 -409.113204) (xy 291.479855 -409.096006) (xy 291.48024 -409.086812) (xy 291.48024 -408.593544)
			(xy 291.4798 -408.58436) (xy 291.473306 -408.567176) (xy 291.46754 -408.560016) (xy 291.445744 -408.53437)
			(xy 291.407796 -408.478783) (xy 291.376763 -408.419059) (xy 291.35309 -408.356053) (xy 291.337118 -408.29067)
			(xy 291.329074 -408.223847) (xy 291.329075 -408.156541) (xy 291.33712 -408.089718) (xy 291.353094 -408.024335)
			(xy 291.376767 -407.96133) (xy 291.407802 -407.901607) (xy 291.445752 -407.84602) (xy 291.46754 -407.820368)
			(xy 291.473338 -407.813224) (xy 291.479851 -407.796032) (xy 291.48024 -407.78684) (xy 291.48024 -407.628852)
			(xy 291.480583 -407.61869) (xy 291.488402 -407.599929) (xy 291.502823 -407.585606) (xy 291.521637 -407.577915)
			(xy 291.531802 -407.577544) (xy 292.248082 -407.577544) (xy 292.258208 -407.578041) (xy 292.27693 -407.585764)
			(xy 292.291287 -407.600047) (xy 292.299106 -407.618729) (xy 292.299644 -407.628852) (xy 292.299644 -407.78684)
			(xy 292.300048 -407.796028) (xy 292.306567 -407.813211) (xy 292.312344 -407.820368) (xy 292.334124 -407.846026)
			(xy 292.372074 -407.901612) (xy 292.403109 -407.961334) (xy 292.426783 -408.024338) (xy 292.442757 -408.089719)
			(xy 292.450802 -408.156542) (xy 292.450803 -408.223846) (xy 292.442759 -408.290669) (xy 292.426786 -408.356051)
			(xy 292.403114 -408.419055) (xy 292.372081 -408.478778) (xy 292.334132 -408.534364) (xy 292.312344 -408.560016)
			(xy 292.306551 -408.567164) (xy 292.300036 -408.584353) (xy 292.299644 -408.593544) (xy 292.299644 -409.086812)
			(xy 292.300061 -409.095998) (xy 292.306571 -409.113182) (xy 292.312344 -409.12034) (xy 292.334097 -409.146021)
			(xy 292.372048 -409.201603) (xy 292.403083 -409.261322) (xy 292.426759 -409.324323) (xy 292.442735 -409.389702)
			(xy 292.450782 -409.456522) (xy 292.450786 -409.523824) (xy 292.442745 -409.590645) (xy 292.426775 -409.656025)
			(xy 292.403106 -409.719028) (xy 292.372076 -409.77875) (xy 292.33413 -409.834336) (xy 292.312344 -409.859988)
			(xy 292.306521 -409.867114) (xy 292.300024 -409.884319) (xy 292.299644 -409.893516) (xy 292.299644 -410.051504)
			(xy 292.299182 -410.061653) (xy 292.291394 -410.080397) (xy 292.27701 -410.094718) (xy 292.258233 -410.102426)
			(xy 292.248082 -410.102812) (xy 291.531802 -410.102812) (xy 291.521682 -410.102273) (xy 291.502971 -410.094556)
			(xy 291.488616 -410.080286) (xy 291.480788 -410.061621) (xy 291.48024 -410.051504) (xy 291.48024 -409.893516)
			(xy 291.479813 -409.884331) (xy 291.47331 -409.867147) (xy 291.46754 -409.859988) (xy 291.445717 -409.834365)
			(xy 291.407769 -409.778774) (xy 291.376737 -409.719047) (xy 291.353066 -409.656039) (xy 291.337096 -409.590653)
			(xy 291.329055 -409.523827) (xy 290.200389 -409.523827) (xy 290.171931 -409.578596) (xy 290.133983 -409.634183)
			(xy 290.112196 -409.659836) (xy 290.106401 -409.666982) (xy 290.099886 -409.684172) (xy 290.099496 -409.693364)
			(xy 290.099496 -410.186632) (xy 290.099891 -410.195821) (xy 290.106415 -410.213005) (xy 290.112196 -410.22016)
			(xy 290.133967 -410.245826) (xy 290.171914 -410.301411) (xy 290.202946 -410.361133) (xy 290.226618 -410.424136)
			(xy 290.242591 -410.489516) (xy 290.250636 -410.556336) (xy 290.250638 -410.62364) (xy 290.250631 -410.6237)
			(xy 293.528701 -410.6237) (xy 293.528702 -410.556276) (xy 293.53678 -410.489336) (xy 293.552816 -410.423847)
			(xy 293.576582 -410.360749) (xy 293.607734 -410.300952) (xy 293.645824 -410.245317) (xy 293.667688 -410.219652)
			(xy 293.673486 -410.212508) (xy 293.68 -410.195317) (xy 293.680388 -410.186124) (xy 293.680388 -409.693872)
			(xy 293.679994 -409.684683) (xy 293.673469 -409.667499) (xy 293.667688 -409.660344) (xy 293.645836 -409.634669)
			(xy 293.607748 -409.579035) (xy 293.576597 -409.519241) (xy 293.552833 -409.456145) (xy 293.536797 -409.390657)
			(xy 293.52872 -409.32372) (xy 293.528719 -409.256298) (xy 293.536794 -409.189361) (xy 293.552828 -409.123872)
			(xy 293.57659 -409.060776) (xy 293.607739 -409.00098) (xy 293.645825 -408.945345) (xy 293.667688 -408.91968)
			(xy 293.673474 -408.912527) (xy 293.679995 -408.895343) (xy 293.680388 -408.886152) (xy 293.680388 -408.728672)
			(xy 293.680862 -408.718563) (xy 293.688606 -408.699886) (xy 293.702907 -408.685593) (xy 293.721587 -408.677857)
			(xy 293.731696 -408.677364) (xy 294.447976 -408.677364) (xy 294.458079 -408.677904) (xy 294.47675 -408.685627)
			(xy 294.491044 -408.699907) (xy 294.498786 -408.71857) (xy 294.499284 -408.728672) (xy 294.499284 -408.886152)
			(xy 294.499721 -408.895336) (xy 294.506216 -408.912521) (xy 294.511984 -408.91968) (xy 294.53386 -408.945335)
			(xy 294.57195 -409.000971) (xy 294.603101 -409.060768) (xy 294.626865 -409.123866) (xy 294.6429 -409.189357)
			(xy 294.650975 -409.256297) (xy 294.650974 -409.323721) (xy 294.642897 -409.390661) (xy 294.62686 -409.456151)
			(xy 294.603093 -409.519248) (xy 294.600676 -409.523887) (xy 295.728823 -409.523887) (xy 295.728826 -409.456459)
			(xy 295.736906 -409.389518) (xy 295.752947 -409.324026) (xy 295.776716 -409.260928) (xy 295.807873 -409.201131)
			(xy 295.845969 -409.145497) (xy 295.867836 -409.119832) (xy 295.873649 -409.112698) (xy 295.880153 -409.095499)
			(xy 295.880536 -409.086304) (xy 295.880536 -408.594052) (xy 295.880093 -408.584869) (xy 295.873601 -408.567684)
			(xy 295.867836 -408.560524) (xy 295.845963 -408.534866) (xy 295.807872 -408.479231) (xy 295.77672 -408.419434)
			(xy 295.752954 -408.356336) (xy 295.736918 -408.290846) (xy 295.728843 -408.223907) (xy 295.728843 -408.156481)
			(xy 295.736921 -408.089542) (xy 295.752958 -408.024052) (xy 295.776725 -407.960955) (xy 295.807878 -407.901159)
			(xy 295.84597 -407.845525) (xy 295.867836 -407.81986) (xy 295.873637 -407.812718) (xy 295.880148 -407.795525)
			(xy 295.880536 -407.786332) (xy 295.880536 -407.628852) (xy 295.880947 -407.618736) (xy 295.888707 -407.60005)
			(xy 295.903027 -407.585755) (xy 295.921727 -407.578029) (xy 295.931844 -407.577544) (xy 296.648124 -407.577544)
			(xy 296.658227 -407.578064) (xy 296.676895 -407.585799) (xy 296.691187 -407.600084) (xy 296.698931 -407.618749)
			(xy 296.699432 -407.628852) (xy 296.699432 -407.786332) (xy 296.699842 -407.795519) (xy 296.706357 -407.812703)
			(xy 296.712132 -407.81986) (xy 296.733987 -407.845532) (xy 296.772074 -407.901167) (xy 296.803223 -407.960962)
			(xy 296.826986 -408.024058) (xy 296.843021 -408.089546) (xy 296.851097 -408.156483) (xy 296.851098 -408.223905)
			(xy 296.843024 -408.290842) (xy 296.82699 -408.356331) (xy 296.803228 -408.419427) (xy 296.77208 -408.479223)
			(xy 296.733994 -408.534858) (xy 296.712132 -408.560524) (xy 296.706334 -408.567668) (xy 296.699822 -408.58486)
			(xy 296.699432 -408.594052) (xy 296.699432 -409.086304) (xy 296.699856 -409.095489) (xy 296.706362 -409.112673)
			(xy 296.712132 -409.119832) (xy 296.733959 -409.145527) (xy 296.772047 -409.201158) (xy 296.803198 -409.26095)
			(xy 296.826962 -409.324043) (xy 296.842999 -409.389528) (xy 296.851078 -409.456463) (xy 296.851081 -409.523883)
			(xy 296.843009 -409.590818) (xy 296.826978 -409.656305) (xy 296.80322 -409.7194) (xy 296.772075 -409.779196)
			(xy 296.733993 -409.83483) (xy 296.712132 -409.860496) (xy 296.706346 -409.867649) (xy 296.699827 -409.884834)
			(xy 296.699432 -409.894024) (xy 296.699432 -410.051504) (xy 296.698919 -410.061609) (xy 296.691186 -410.080281)
			(xy 296.676898 -410.094575) (xy 296.658229 -410.102315) (xy 296.648124 -410.102812) (xy 295.931844 -410.102812)
			(xy 295.921726 -410.102348) (xy 295.903026 -410.094617) (xy 295.88871 -410.080315) (xy 295.880961 -410.061622)
			(xy 295.880536 -410.051504) (xy 295.880536 -409.894024) (xy 295.880106 -409.884839) (xy 295.873605 -409.867655)
			(xy 295.867836 -409.860496) (xy 295.845935 -409.834861) (xy 295.807845 -409.779223) (xy 295.776694 -409.719423)
			(xy 295.752931 -409.656322) (xy 295.736896 -409.590829) (xy 295.728823 -409.523887) (xy 294.600676 -409.523887)
			(xy 294.57194 -409.579045) (xy 294.533849 -409.634679) (xy 294.511984 -409.660344) (xy 294.506184 -409.667487)
			(xy 294.499672 -409.684679) (xy 294.499284 -409.693872) (xy 294.499284 -410.186124) (xy 294.499686 -410.195312)
			(xy 294.506206 -410.212496) (xy 294.511984 -410.219652) (xy 294.533833 -410.24533) (xy 294.571923 -410.300962)
			(xy 294.603075 -410.360757) (xy 294.626841 -410.423852) (xy 294.642878 -410.489339) (xy 294.650956 -410.556277)
			(xy 294.650957 -410.623641) (xy 297.928996 -410.623641) (xy 297.928998 -410.556334) (xy 297.937044 -410.48951)
			(xy 297.95302 -410.424127) (xy 297.976696 -410.361121) (xy 298.007733 -410.301398) (xy 298.045686 -410.245812)
			(xy 298.067476 -410.22016) (xy 298.073269 -410.213012) (xy 298.079787 -410.195824) (xy 298.080176 -410.186632)
			(xy 298.080176 -409.693364) (xy 298.079788 -409.684174) (xy 298.07326 -409.66699) (xy 298.067476 -409.659836)
			(xy 298.045699 -409.634175) (xy 298.007747 -409.57859) (xy 297.976712 -409.518868) (xy 297.953037 -409.455865)
			(xy 297.937062 -409.390484) (xy 297.929016 -409.323661) (xy 297.929015 -409.256357) (xy 297.937058 -409.189534)
			(xy 297.953031 -409.124152) (xy 297.976704 -409.061148) (xy 298.007738 -409.001425) (xy 298.045688 -408.94584)
			(xy 298.067476 -408.920188) (xy 298.073257 -408.913032) (xy 298.079782 -408.89585) (xy 298.080176 -408.88666)
			(xy 298.080176 -408.728672) (xy 298.080598 -408.718519) (xy 298.088398 -408.699771) (xy 298.102794 -408.685449)
			(xy 298.121583 -408.677746) (xy 298.131738 -408.677364) (xy 298.848018 -408.677364) (xy 298.858149 -408.677812)
			(xy 298.876875 -408.68555) (xy 298.891232 -408.699849) (xy 298.899046 -408.718543) (xy 298.89958 -408.728672)
			(xy 298.89958 -408.88666) (xy 298.900014 -408.895845) (xy 298.906512 -408.913029) (xy 298.91228 -408.920188)
			(xy 298.934079 -408.945831) (xy 298.972026 -409.001419) (xy 299.003058 -409.061144) (xy 299.026729 -409.12415)
			(xy 299.042701 -409.189533) (xy 299.050744 -409.256356) (xy 299.050743 -409.323662) (xy 299.042698 -409.390485)
			(xy 299.026724 -409.455868) (xy 299.003051 -409.518873) (xy 299.000446 -409.523886) (xy 300.128614 -409.523886)
			(xy 300.128617 -409.456459) (xy 300.136697 -409.389518) (xy 300.152737 -409.324027) (xy 300.176506 -409.260928)
			(xy 300.207662 -409.201131) (xy 300.245757 -409.145497) (xy 300.267624 -409.119832) (xy 300.273435 -409.112697)
			(xy 300.27994 -409.095499) (xy 300.280324 -409.086304) (xy 300.280324 -408.594052) (xy 300.279883 -408.584868)
			(xy 300.27339 -408.567684) (xy 300.267624 -408.560524) (xy 300.245751 -408.534866) (xy 300.207661 -408.479231)
			(xy 300.17651 -408.419434) (xy 300.152745 -408.356336) (xy 300.136709 -408.290846) (xy 300.128634 -408.223906)
			(xy 300.128634 -408.156482) (xy 300.136711 -408.089542) (xy 300.152748 -408.024053) (xy 300.176514 -407.960955)
			(xy 300.207667 -407.901159) (xy 300.245759 -407.845525) (xy 300.267624 -407.81986) (xy 300.273423 -407.812717)
			(xy 300.279935 -407.795525) (xy 300.280324 -407.786332) (xy 300.280324 -407.628852) (xy 300.280747 -407.618737)
			(xy 300.288504 -407.600053) (xy 300.302821 -407.585759) (xy 300.321516 -407.578031) (xy 300.331632 -407.577544)
			(xy 301.047912 -407.577544) (xy 301.058015 -407.578074) (xy 301.076682 -407.585805) (xy 301.090975 -407.600088)
			(xy 301.098719 -407.61875) (xy 301.09922 -407.628852) (xy 301.09922 -407.786332) (xy 301.09961 -407.795521)
			(xy 301.106137 -407.812706) (xy 301.11192 -407.81986) (xy 301.133775 -407.845532) (xy 301.171863 -407.901166)
			(xy 301.203013 -407.960962) (xy 301.226777 -408.024057) (xy 301.242812 -408.089545) (xy 301.250888 -408.156483)
			(xy 301.250889 -408.223905) (xy 301.242814 -408.290843) (xy 301.22678 -408.356331) (xy 301.203018 -408.419427)
			(xy 301.171869 -408.479224) (xy 301.133783 -408.534858) (xy 301.11192 -408.560524) (xy 301.106133 -408.567676)
			(xy 301.099612 -408.584861) (xy 301.09922 -408.594052) (xy 301.09922 -409.086304) (xy 301.099624 -409.095492)
			(xy 301.106141 -409.112676) (xy 301.11192 -409.119832) (xy 301.133748 -409.145527) (xy 301.171836 -409.201158)
			(xy 301.202988 -409.26095) (xy 301.226753 -409.324043) (xy 301.24279 -409.389528) (xy 301.250869 -409.456463)
			(xy 301.250872 -409.523883) (xy 301.2428 -409.590819) (xy 301.226769 -409.656305) (xy 301.20301 -409.719401)
			(xy 301.171864 -409.779196) (xy 301.133781 -409.83483) (xy 301.11192 -409.860496) (xy 301.106145 -409.867657)
			(xy 301.099617 -409.884835) (xy 301.09922 -409.894024) (xy 301.09922 -410.051504) (xy 301.098719 -410.06161)
			(xy 301.090983 -410.080285) (xy 301.076692 -410.094579) (xy 301.058018 -410.102317) (xy 301.047912 -410.102812)
			(xy 300.331632 -410.102812) (xy 300.321513 -410.102358) (xy 300.302812 -410.094623) (xy 300.288497 -410.080318)
			(xy 300.280749 -410.061623) (xy 300.280324 -410.051504) (xy 300.280324 -409.894024) (xy 300.279897 -409.884839)
			(xy 300.273394 -409.867655) (xy 300.267624 -409.860496) (xy 300.245724 -409.83486) (xy 300.207635 -409.779222)
			(xy 300.176484 -409.719422) (xy 300.152721 -409.656321) (xy 300.136687 -409.590828) (xy 300.128614 -409.523886)
			(xy 299.000446 -409.523886) (xy 298.972017 -409.578597) (xy 298.934068 -409.634184) (xy 298.91228 -409.659836)
			(xy 298.906483 -409.666981) (xy 298.899969 -409.684172) (xy 298.89958 -409.693364) (xy 298.89958 -410.186632)
			(xy 298.899979 -410.19582) (xy 298.906501 -410.213004) (xy 298.91228 -410.22016) (xy 298.934052 -410.245825)
			(xy 298.972 -410.30141) (xy 299.003032 -410.361132) (xy 299.026705 -410.424135) (xy 299.042679 -410.489515)
			(xy 299.050724 -410.556336) (xy 299.050725 -410.62364) (xy 299.050718 -410.6237) (xy 302.328789 -410.6237)
			(xy 302.32879 -410.556276) (xy 302.336867 -410.489337) (xy 302.352904 -410.423847) (xy 302.376668 -410.36075)
			(xy 302.407819 -410.300953) (xy 302.445908 -410.245318) (xy 302.467772 -410.219652) (xy 302.47358 -410.212515)
			(xy 302.480086 -410.195318) (xy 302.480472 -410.186124) (xy 302.480472 -409.693872) (xy 302.480082 -409.684683)
			(xy 302.473555 -409.667498) (xy 302.467772 -409.660344) (xy 302.445921 -409.634669) (xy 302.407834 -409.579035)
			(xy 302.376684 -409.51924) (xy 302.35292 -409.456144) (xy 302.336885 -409.390657) (xy 302.328808 -409.32372)
			(xy 302.328807 -409.256298) (xy 302.336882 -409.189361) (xy 302.352915 -409.123873) (xy 302.376677 -409.060777)
			(xy 302.407824 -409.000981) (xy 302.44591 -408.945346) (xy 302.467772 -408.91968) (xy 302.473568 -408.912535)
			(xy 302.480081 -408.895344) (xy 302.480472 -408.886152) (xy 302.480472 -408.728672) (xy 302.480961 -408.718565)
			(xy 302.488703 -408.699891) (xy 302.502998 -408.685599) (xy 302.521673 -408.67786) (xy 302.53178 -408.677364)
			(xy 303.24806 -408.677364) (xy 303.258175 -408.677848) (xy 303.276871 -408.685576) (xy 303.291186 -408.699872)
			(xy 303.298939 -408.718557) (xy 303.299368 -408.728672) (xy 303.299368 -408.886152) (xy 303.299809 -408.895336)
			(xy 303.306302 -408.91252) (xy 303.312068 -408.91968) (xy 303.333945 -408.945335) (xy 303.372035 -409.00097)
			(xy 303.403187 -409.060768) (xy 303.426952 -409.123866) (xy 303.442988 -409.189356) (xy 303.451063 -409.256296)
			(xy 303.451062 -409.323722) (xy 303.442985 -409.390661) (xy 303.426947 -409.456151) (xy 303.40318 -409.519249)
			(xy 303.372026 -409.579045) (xy 303.333934 -409.634679) (xy 303.312068 -409.660344) (xy 303.306266 -409.667485)
			(xy 303.299755 -409.684679) (xy 303.299368 -409.693872) (xy 303.299368 -410.186124) (xy 303.299774 -410.195312)
			(xy 303.306291 -410.212495) (xy 303.312068 -410.219652) (xy 303.333917 -410.24533) (xy 303.372009 -410.300962)
			(xy 303.403162 -410.360756) (xy 303.426928 -410.423851) (xy 303.442966 -410.489339) (xy 303.451044 -410.556276)
			(xy 303.451045 -410.6237) (xy 303.44297 -410.690637) (xy 303.426935 -410.756126) (xy 303.403172 -410.819222)
			(xy 303.372021 -410.879018) (xy 303.333932 -410.934651) (xy 303.312068 -410.960316) (xy 303.306278 -410.967466)
			(xy 303.29976 -410.984653) (xy 303.299368 -410.993844) (xy 303.299368 -411.151324) (xy 303.299003 -411.161452)
			(xy 303.291241 -411.180162) (xy 303.276909 -411.194477) (xy 303.258189 -411.202216) (xy 303.24806 -411.202632)
			(xy 302.53178 -411.202632) (xy 302.521674 -411.202132) (xy 302.503001 -411.194394) (xy 302.488708 -411.180102)
			(xy 302.480969 -411.16143) (xy 302.480472 -411.151324) (xy 302.480472 -410.993844) (xy 302.480047 -410.984658)
			(xy 302.473544 -410.967474) (xy 302.467772 -410.960316) (xy 302.445893 -410.934663) (xy 302.407807 -410.879026)
			(xy 302.376658 -410.819228) (xy 302.352896 -410.75613) (xy 302.336863 -410.690639) (xy 302.328789 -410.6237)
			(xy 299.050718 -410.6237) (xy 299.042683 -410.690461) (xy 299.026712 -410.755842) (xy 299.003042 -410.818846)
			(xy 298.972012 -410.878569) (xy 298.934066 -410.934156) (xy 298.91228 -410.959808) (xy 298.906495 -410.966961)
			(xy 298.899974 -410.984146) (xy 298.89958 -410.993336) (xy 298.89958 -411.151324) (xy 298.899198 -411.161482)
			(xy 298.891391 -411.180239) (xy 298.876982 -411.194562) (xy 298.858179 -411.202258) (xy 298.848018 -411.202632)
			(xy 298.131738 -411.202632) (xy 298.12161 -411.202141) (xy 298.102885 -411.194421) (xy 298.088526 -411.180135)
			(xy 298.080711 -411.161449) (xy 298.080176 -411.151324) (xy 298.080176 -410.993336) (xy 298.079754 -410.98415)
			(xy 298.073249 -410.966965) (xy 298.067476 -410.959808) (xy 298.045672 -410.934169) (xy 298.007721 -410.878582)
			(xy 297.976686 -410.818857) (xy 297.953013 -410.75585) (xy 297.93704 -410.690466) (xy 297.928996 -410.623641)
			(xy 294.650957 -410.623641) (xy 294.650957 -410.623699) (xy 294.642883 -410.690637) (xy 294.626848 -410.756125)
			(xy 294.603085 -410.819221) (xy 294.571935 -410.879017) (xy 294.533848 -410.934651) (xy 294.511984 -410.960316)
			(xy 294.506196 -410.967467) (xy 294.499677 -410.984653) (xy 294.499284 -410.993844) (xy 294.499284 -411.151324)
			(xy 294.498834 -411.161436) (xy 294.491086 -411.180118) (xy 294.476778 -411.194413) (xy 294.458089 -411.202144)
			(xy 294.447976 -411.202632) (xy 293.731696 -411.202632) (xy 293.721591 -411.202119) (xy 293.702919 -411.194386)
			(xy 293.688625 -411.180098) (xy 293.680885 -411.161429) (xy 293.680388 -411.151324) (xy 293.680388 -410.993844)
			(xy 293.679959 -410.984659) (xy 293.673459 -410.967474) (xy 293.667688 -410.960316) (xy 293.645809 -410.934664)
			(xy 293.607721 -410.879027) (xy 293.576572 -410.819229) (xy 293.552809 -410.75613) (xy 293.536775 -410.69064)
			(xy 293.528701 -410.6237) (xy 290.250631 -410.6237) (xy 290.242595 -410.69046) (xy 290.226625 -410.755841)
			(xy 290.202956 -410.818845) (xy 290.171926 -410.878568) (xy 290.133982 -410.934155) (xy 290.112196 -410.959808)
			(xy 290.106413 -410.966963) (xy 290.09989 -410.984146) (xy 290.099496 -410.993336) (xy 290.099496 -411.151324)
			(xy 290.099098 -411.16148) (xy 290.091294 -411.180234) (xy 290.07689 -411.194557) (xy 290.058092 -411.202255)
			(xy 290.047934 -411.202632) (xy 289.331654 -411.202632) (xy 289.321521 -411.20221) (xy 289.302793 -411.194462)
			(xy 289.288438 -411.180156) (xy 289.280625 -411.161455) (xy 289.280092 -411.151324) (xy 289.280092 -410.993336)
			(xy 289.279666 -410.98415) (xy 289.273164 -410.966966) (xy 289.267392 -410.959808) (xy 289.245587 -410.934169)
			(xy 289.207635 -410.878582) (xy 289.1766 -410.818857) (xy 289.152925 -410.755851) (xy 289.136952 -410.690467)
			(xy 289.128908 -410.623642) (xy 237.406942 -410.623642) (xy 237.406942 -412.06928) (xy 237.406417 -412.094228)
			(xy 237.39861 -412.143509) (xy 237.383199 -412.190966) (xy 237.360564 -412.235432) (xy 237.33126 -412.275817)
			(xy 237.313978 -412.293816) (xy 235.9787 -413.629094) (xy 235.960708 -413.646388) (xy 235.920331 -413.675711)
			(xy 235.875865 -413.698359) (xy 235.828403 -413.713772) (xy 235.779115 -413.721572) (xy 235.754164 -413.722058)
			(xy 208.805526 -413.722058) (xy 208.780578 -413.721525) (xy 208.731298 -413.713719) (xy 208.683841 -413.69831)
			(xy 208.639375 -413.675677) (xy 208.59899 -413.646375) (xy 208.58099 -413.629094) (xy 207.025748 -412.073852)
			(xy 207.008419 -412.055891) (xy 206.979094 -412.015508) (xy 206.956447 -411.971034) (xy 206.941036 -411.923565)
			(xy 206.933241 -411.87427) (xy 206.932784 -411.849316) (xy 206.932784 -389.931402) (xy 206.932362 -389.921332)
			(xy 206.924639 -389.902734) (xy 206.917798 -389.895334) (xy 204.423264 -387.4008) (xy 204.405961 -387.382815)
			(xy 204.376631 -387.342439) (xy 204.353979 -387.297971) (xy 204.338563 -387.250507) (xy 204.330761 -387.201216)
			(xy 204.3303 -387.176264) (xy 204.3303 -378.650754) (xy 204.31379 -378.625608) (xy 204.299566 -378.619512)
			(xy 204.274196 -378.60805) (xy 204.226725 -378.578976) (xy 204.183985 -378.543309) (xy 204.146885 -378.501809)
			(xy 204.116211 -378.455355) (xy 204.092616 -378.404937) (xy 204.076601 -378.351623) (xy 204.068507 -378.296548)
			(xy 204.068504 -378.240882) (xy 197.862607 -378.240882) (xy 197.885782 -378.367343) (xy 197.901882 -378.499931)
			(xy 197.909946 -378.633249) (xy 197.91045 -378.70003) (xy 197.909946 -378.766811) (xy 197.901882 -378.900129)
			(xy 197.885782 -379.032717) (xy 197.861707 -379.164091) (xy 197.829744 -379.293772) (xy 197.790009 -379.421286)
			(xy 197.742647 -379.546169) (xy 197.687832 -379.667964) (xy 197.625762 -379.786227) (xy 197.556666 -379.900526)
			(xy 197.480794 -380.010446) (xy 197.398424 -380.115583) (xy 197.309856 -380.215556) (xy 197.215414 -380.309998)
			(xy 197.115441 -380.398566) (xy 197.010304 -380.480936) (xy 196.900384 -380.556808) (xy 196.786085 -380.625904)
			(xy 196.667822 -380.687974) (xy 196.546027 -380.742789) (xy 196.421144 -380.790151) (xy 196.29363 -380.829886)
			(xy 196.163949 -380.861849) (xy 196.032575 -380.885924) (xy 195.899987 -380.902024) (xy 195.766669 -380.910088)
			(xy 195.633107 -380.910088) (xy 195.499789 -380.902024) (xy 195.367201 -380.885924) (xy 195.235827 -380.861849)
			(xy 195.106146 -380.829886) (xy 194.978632 -380.790151) (xy 194.853749 -380.742789) (xy 194.731954 -380.687974)
			(xy 194.613691 -380.625904) (xy 194.499392 -380.556808) (xy 194.389472 -380.480936) (xy 194.284335 -380.398566)
			(xy 194.184362 -380.309998) (xy 194.08992 -380.215556) (xy 194.001352 -380.115583) (xy 193.918982 -380.010446)
			(xy 193.84311 -379.900526) (xy 193.774014 -379.786227) (xy 193.711944 -379.667964) (xy 193.657129 -379.546169)
			(xy 193.609767 -379.421286) (xy 193.570032 -379.293772) (xy 193.538069 -379.164091) (xy 193.513994 -379.032717)
			(xy 193.497894 -378.900129) (xy 193.48983 -378.766811) (xy 173.519592 -378.766811) (xy 173.519592 -379.186694)
			(xy 173.520007 -379.195881) (xy 173.526518 -379.213065) (xy 173.532292 -379.220222) (xy 173.554124 -379.245837)
			(xy 173.592069 -379.30143) (xy 173.623099 -379.361159) (xy 173.646768 -379.424168) (xy 173.662737 -379.489554)
			(xy 173.670777 -379.556381) (xy 173.670772 -379.623689) (xy 173.662724 -379.690514) (xy 173.646747 -379.755898)
			(xy 173.623071 -379.818905) (xy 173.592034 -379.87863) (xy 173.554082 -379.934217) (xy 173.532292 -379.95987)
			(xy 173.526482 -379.967006) (xy 173.519976 -379.984204) (xy 173.519592 -379.993398) (xy 173.519592 -380.151386)
			(xy 173.519056 -380.161539) (xy 173.511292 -380.180302) (xy 173.496939 -380.194667) (xy 173.478183 -380.202447)
			(xy 173.46803 -380.202948) (xy 172.75175 -380.202948) (xy 172.74158 -380.202495) (xy 172.722784 -380.194724)
			(xy 172.708396 -380.180347) (xy 172.700612 -380.161556) (xy 172.700188 -380.151386) (xy 172.700188 -379.993398)
			(xy 172.699781 -379.98421) (xy 172.693266 -379.967026) (xy 172.687488 -379.95987) (xy 172.665744 -379.934181)
			(xy 172.627791 -379.878601) (xy 172.596753 -379.818883) (xy 172.573075 -379.755883) (xy 172.557097 -379.690505)
			(xy 172.549049 -379.623686) (xy 172.549045 -379.556383) (xy 172.557085 -379.489563) (xy 172.573055 -379.424183)
			(xy 172.596724 -379.36118) (xy 172.627755 -379.301458) (xy 172.665702 -379.245873) (xy 172.687488 -379.220222)
			(xy 172.693299 -379.213087) (xy 172.699805 -379.195889) (xy 172.700188 -379.186694) (xy 172.700188 -378.693426)
			(xy 172.699768 -378.68424) (xy 172.693262 -378.667055) (xy 172.687488 -378.659898) (xy 172.665673 -378.634268)
			(xy 172.627722 -378.578679) (xy 172.596687 -378.518953) (xy 172.573014 -378.455946) (xy 172.557041 -378.39056)
			(xy 172.548998 -378.323734) (xy 169.270937 -378.323734) (xy 169.262897 -378.390552) (xy 169.246928 -378.455932)
			(xy 169.22326 -378.518935) (xy 169.192232 -378.578658) (xy 169.154289 -378.634245) (xy 169.132504 -378.659898)
			(xy 169.126726 -378.667057) (xy 169.1202 -378.684237) (xy 169.119804 -378.693426) (xy 169.119804 -379.186694)
			(xy 169.120216 -379.195881) (xy 169.126728 -379.213065) (xy 169.132504 -379.220222) (xy 169.154336 -379.245838)
			(xy 169.19228 -379.30143) (xy 169.223309 -379.361159) (xy 169.246977 -379.424169) (xy 169.262946 -379.489555)
			(xy 169.270986 -379.556381) (xy 169.270982 -379.623689) (xy 169.262933 -379.690513) (xy 169.246957 -379.755898)
			(xy 169.223281 -379.818904) (xy 169.192245 -379.878629) (xy 169.154293 -379.934217) (xy 169.132504 -379.95987)
			(xy 169.126696 -379.967007) (xy 169.120188 -379.984204) (xy 169.119804 -379.993398) (xy 169.119804 -380.151386)
			(xy 169.119256 -380.161538) (xy 169.111494 -380.180299) (xy 169.097146 -380.194663) (xy 169.078393 -380.202445)
			(xy 169.068242 -380.202948) (xy 168.351962 -380.202948) (xy 168.3418 -380.202497) (xy 168.323027 -380.194708)
			(xy 168.308663 -380.180329) (xy 168.300892 -380.161548) (xy 168.3004 -380.151386) (xy 168.3004 -379.993398)
			(xy 168.299991 -379.984211) (xy 168.293476 -379.967026) (xy 168.2877 -379.95987) (xy 168.265959 -379.93418)
			(xy 168.228011 -379.878598) (xy 168.196978 -379.818879) (xy 168.173304 -379.75588) (xy 168.157329 -379.690503)
			(xy 168.149282 -379.623685) (xy 168.149278 -379.556384) (xy 168.157317 -379.489565) (xy 168.173284 -379.424186)
			(xy 168.19695 -379.361184) (xy 168.227975 -379.301461) (xy 168.265916 -379.245875) (xy 168.2877 -379.220222)
			(xy 168.293512 -379.213088) (xy 168.300018 -379.195889) (xy 168.3004 -379.186694) (xy 168.3004 -378.693426)
			(xy 168.299977 -378.68424) (xy 168.293472 -378.667056) (xy 168.2877 -378.659898) (xy 168.265888 -378.634266)
			(xy 168.227942 -378.578676) (xy 168.196912 -378.518949) (xy 168.173243 -378.455942) (xy 168.157273 -378.390558)
			(xy 168.149231 -378.323734) (xy 164.871169 -378.323734) (xy 164.871169 -378.323791) (xy 164.863096 -378.390728)
			(xy 164.847063 -378.456215) (xy 164.823302 -378.519311) (xy 164.792155 -378.579106) (xy 164.75407 -378.634741)
			(xy 164.732208 -378.660406) (xy 164.726427 -378.667563) (xy 164.719903 -378.684744) (xy 164.719508 -378.693934)
			(xy 164.719508 -379.186186) (xy 164.719923 -379.195373) (xy 164.726433 -379.212557) (xy 164.732208 -379.219714)
			(xy 164.754117 -379.245342) (xy 164.792204 -379.300982) (xy 164.823352 -379.360784) (xy 164.847113 -379.423885)
			(xy 164.863145 -379.489379) (xy 164.871217 -379.556321) (xy 164.871213 -379.623748) (xy 164.863133 -379.690689)
			(xy 164.847093 -379.756181) (xy 164.823324 -379.81928) (xy 164.792168 -379.879077) (xy 164.754074 -379.934713)
			(xy 164.732208 -379.960378) (xy 164.726397 -379.967513) (xy 164.719891 -379.984711) (xy 164.719508 -379.993906)
			(xy 164.719508 -380.151386) (xy 164.718963 -380.161506) (xy 164.711249 -380.180218) (xy 164.696981 -380.194573)
			(xy 164.678317 -380.202401) (xy 164.6682 -380.202948) (xy 163.95192 -380.202948) (xy 163.941773 -380.202463)
			(xy 163.92303 -380.194683) (xy 163.908708 -380.180306) (xy 163.900999 -380.161534) (xy 163.900612 -380.151386)
			(xy 163.900612 -379.993906) (xy 163.900196 -379.98472) (xy 163.893686 -379.967535) (xy 163.887912 -379.960378)
			(xy 163.866093 -379.934676) (xy 163.828002 -379.879047) (xy 163.796849 -379.819256) (xy 163.773081 -379.756164)
			(xy 163.757042 -379.690679) (xy 163.748963 -379.623745) (xy 163.748958 -379.556324) (xy 163.75703 -379.489389)
			(xy 163.773061 -379.423902) (xy 163.79682 -379.360807) (xy 163.827966 -379.301013) (xy 163.86605 -379.245379)
			(xy 163.887912 -379.219714) (xy 163.893729 -379.212583) (xy 163.900231 -379.195382) (xy 163.900612 -379.186186)
			(xy 163.900612 -378.693934) (xy 163.900183 -378.684749) (xy 163.893682 -378.667565) (xy 163.887912 -378.660406)
			(xy 163.866022 -378.634762) (xy 163.827933 -378.579125) (xy 163.796783 -378.519326) (xy 163.77302 -378.456226)
			(xy 163.756986 -378.390734) (xy 163.748912 -378.323793) (xy 160.470867 -378.323793) (xy 160.462831 -378.390554)
			(xy 160.44686 -378.455935) (xy 160.423188 -378.518939) (xy 160.392156 -378.578661) (xy 160.354207 -378.634246)
			(xy 160.33242 -378.659898) (xy 160.326644 -378.667058) (xy 160.320116 -378.684237) (xy 160.31972 -378.693426)
			(xy 160.31972 -379.186694) (xy 160.320129 -379.195881) (xy 160.326643 -379.213066) (xy 160.33242 -379.220222)
			(xy 160.354254 -379.245836) (xy 160.392205 -379.301427) (xy 160.423238 -379.361156) (xy 160.44691 -379.424165)
			(xy 160.462881 -379.489552) (xy 160.470922 -379.55638) (xy 160.470918 -379.623689) (xy 160.462869 -379.690516)
			(xy 160.44689 -379.755901) (xy 160.42321 -379.818908) (xy 160.392169 -379.878632) (xy 160.354212 -379.934219)
			(xy 160.33242 -379.95987) (xy 160.326614 -379.967008) (xy 160.320104 -379.984204) (xy 160.31972 -379.993398)
			(xy 160.31972 -380.151386) (xy 160.319324 -380.161562) (xy 160.311536 -380.180364) (xy 160.297141 -380.194751)
			(xy 160.278334 -380.202529) (xy 160.268158 -380.202948) (xy 159.551878 -380.202948) (xy 159.541717 -380.202484)
			(xy 159.522945 -380.1947) (xy 159.50858 -380.180325) (xy 159.500808 -380.161547) (xy 159.500316 -380.151386)
			(xy 159.500316 -379.993398) (xy 159.499903 -379.984211) (xy 159.493391 -379.967027) (xy 159.487616 -379.95987)
			(xy 159.465874 -379.93418) (xy 159.427926 -379.878599) (xy 159.396892 -379.81888) (xy 159.373217 -379.75588)
			(xy 159.357242 -379.690503) (xy 159.349195 -379.623685) (xy 159.34919 -379.556384) (xy 159.35723 -379.489565)
			(xy 159.373197 -379.424186) (xy 159.396864 -379.361183) (xy 159.42789 -379.301461) (xy 159.465832 -379.245875)
			(xy 159.487616 -379.220222) (xy 159.49343 -379.213089) (xy 159.499934 -379.195889) (xy 159.500316 -379.186694)
			(xy 159.500316 -378.693426) (xy 159.49989 -378.684241) (xy 159.493387 -378.667056) (xy 159.487616 -378.659898)
			(xy 159.465803 -378.634267) (xy 159.427857 -378.578677) (xy 159.396826 -378.51895) (xy 159.373156 -378.455943)
			(xy 159.357185 -378.390558) (xy 159.349143 -378.323734) (xy 129.670819 -378.323734) (xy 129.662778 -378.390552)
			(xy 129.646808 -378.455933) (xy 129.623139 -378.518936) (xy 129.59211 -378.578659) (xy 129.554166 -378.634246)
			(xy 129.53238 -378.659898) (xy 129.526599 -378.667054) (xy 129.520076 -378.684236) (xy 129.51968 -378.693426)
			(xy 129.51968 -379.186694) (xy 129.520098 -379.19588) (xy 129.526607 -379.213064) (xy 129.53238 -379.220222)
			(xy 129.554212 -379.245837) (xy 129.592159 -379.301429) (xy 129.623189 -379.361158) (xy 129.646858 -379.424168)
			(xy 129.662827 -379.489554) (xy 129.670868 -379.55638) (xy 129.670863 -379.623689) (xy 129.662815 -379.690514)
			(xy 129.646838 -379.755899) (xy 129.623161 -379.818905) (xy 129.592123 -379.87863) (xy 129.55417 -379.934218)
			(xy 129.53238 -379.95987) (xy 129.526569 -379.967005) (xy 129.520064 -379.984203) (xy 129.51968 -379.993398)
			(xy 129.51968 -380.151386) (xy 129.519156 -380.161541) (xy 129.511389 -380.180306) (xy 129.497033 -380.194671)
			(xy 129.478272 -380.202449) (xy 129.468118 -380.202948) (xy 128.751838 -380.202948) (xy 128.741667 -380.202505)
			(xy 128.722871 -380.19473) (xy 128.708484 -380.18035) (xy 128.7007 -380.161557) (xy 128.700276 -380.151386)
			(xy 128.700276 -379.993398) (xy 128.699872 -379.98421) (xy 128.693355 -379.967025) (xy 128.687576 -379.95987)
			(xy 128.665832 -379.934181) (xy 128.62788 -379.878601) (xy 128.596842 -379.818883) (xy 128.573165 -379.755883)
			(xy 128.557188 -379.690505) (xy 128.54914 -379.623686) (xy 128.549136 -379.556384) (xy 128.557176 -379.489563)
			(xy 128.573145 -379.424183) (xy 128.596814 -379.361181) (xy 128.627844 -379.301459) (xy 128.66579 -379.245874)
			(xy 128.687576 -379.220222) (xy 128.693385 -379.213086) (xy 128.699893 -379.195889) (xy 128.700276 -379.186694)
			(xy 128.700276 -378.693426) (xy 128.699859 -378.684239) (xy 128.693351 -378.667055) (xy 128.687576 -378.659898)
			(xy 128.665762 -378.634267) (xy 128.627811 -378.578679) (xy 128.596777 -378.518952) (xy 128.573104 -378.455945)
			(xy 128.557132 -378.39056) (xy 128.549089 -378.323734) (xy 125.271028 -378.323734) (xy 125.262987 -378.390552)
			(xy 125.247018 -378.455932) (xy 125.223349 -378.518936) (xy 125.192321 -378.578659) (xy 125.154377 -378.634245)
			(xy 125.132592 -378.659898) (xy 125.126813 -378.667056) (xy 125.120288 -378.684237) (xy 125.119892 -378.693426)
			(xy 125.119892 -379.186694) (xy 125.120307 -379.195881) (xy 125.126818 -379.213065) (xy 125.132592 -379.220222)
			(xy 125.154424 -379.245837) (xy 125.192369 -379.30143) (xy 125.223399 -379.361159) (xy 125.247068 -379.424168)
			(xy 125.263037 -379.489554) (xy 125.271077 -379.556381) (xy 125.271072 -379.623689) (xy 125.263024 -379.690514)
			(xy 125.247047 -379.755898) (xy 125.223371 -379.818905) (xy 125.192334 -379.87863) (xy 125.154382 -379.934217)
			(xy 125.132592 -379.95987) (xy 125.126782 -379.967006) (xy 125.120276 -379.984204) (xy 125.119892 -379.993398)
			(xy 125.119892 -380.151386) (xy 125.119356 -380.161539) (xy 125.111592 -380.180302) (xy 125.097239 -380.194667)
			(xy 125.078483 -380.202447) (xy 125.06833 -380.202948) (xy 124.35205 -380.202948) (xy 124.34188 -380.202495)
			(xy 124.323084 -380.194724) (xy 124.308696 -380.180347) (xy 124.300912 -380.161556) (xy 124.300488 -380.151386)
			(xy 124.300488 -379.993398) (xy 124.300081 -379.98421) (xy 124.293566 -379.967026) (xy 124.287788 -379.95987)
			(xy 124.266044 -379.934181) (xy 124.228091 -379.878601) (xy 124.197053 -379.818883) (xy 124.173375 -379.755883)
			(xy 124.157397 -379.690505) (xy 124.149349 -379.623686) (xy 124.149345 -379.556383) (xy 124.157385 -379.489563)
			(xy 124.173355 -379.424183) (xy 124.197024 -379.36118) (xy 124.228055 -379.301458) (xy 124.266002 -379.245873)
			(xy 124.287788 -379.220222) (xy 124.293599 -379.213087) (xy 124.300105 -379.195889) (xy 124.300488 -379.186694)
			(xy 124.300488 -378.693426) (xy 124.300068 -378.68424) (xy 124.293562 -378.667055) (xy 124.287788 -378.659898)
			(xy 124.265973 -378.634268) (xy 124.228022 -378.578679) (xy 124.196987 -378.518953) (xy 124.173314 -378.455946)
			(xy 124.157341 -378.39056) (xy 124.149298 -378.323734) (xy 120.87126 -378.323734) (xy 120.87126 -378.323791)
			(xy 120.863187 -378.390728) (xy 120.847154 -378.456216) (xy 120.823392 -378.519311) (xy 120.792244 -378.579107)
			(xy 120.754159 -378.634741) (xy 120.732296 -378.660406) (xy 120.726514 -378.667561) (xy 120.719991 -378.684744)
			(xy 120.719596 -378.693934) (xy 120.719596 -379.186186) (xy 120.720014 -379.195372) (xy 120.726522 -379.212557)
			(xy 120.732296 -379.219714) (xy 120.754205 -379.245342) (xy 120.792293 -379.300982) (xy 120.823442 -379.360783)
			(xy 120.847204 -379.423885) (xy 120.863236 -379.489378) (xy 120.871308 -379.556321) (xy 120.871304 -379.623748)
			(xy 120.863224 -379.69069) (xy 120.847183 -379.756181) (xy 120.823414 -379.81928) (xy 120.792257 -379.879078)
			(xy 120.754163 -379.934713) (xy 120.732296 -379.960378) (xy 120.726483 -379.967512) (xy 120.719978 -379.984711)
			(xy 120.719596 -379.993906) (xy 120.719596 -380.151386) (xy 120.719063 -380.161507) (xy 120.711347 -380.180221)
			(xy 120.697075 -380.194577) (xy 120.678406 -380.202403) (xy 120.668288 -380.202948) (xy 119.952008 -380.202948)
			(xy 119.94186 -380.202473) (xy 119.923117 -380.194689) (xy 119.908795 -380.180309) (xy 119.901087 -380.161535)
			(xy 119.9007 -380.151386) (xy 119.9007 -379.993906) (xy 119.900287 -379.984719) (xy 119.893775 -379.967535)
			(xy 119.888 -379.960378) (xy 119.866181 -379.934675) (xy 119.828091 -379.879046) (xy 119.796938 -379.819255)
			(xy 119.773172 -379.756163) (xy 119.757133 -379.690679) (xy 119.749053 -379.623745) (xy 119.749049 -379.556325)
			(xy 119.757121 -379.489389) (xy 119.773151 -379.423903) (xy 119.79691 -379.360808) (xy 119.828056 -379.301013)
			(xy 119.866139 -379.245379) (xy 119.888 -379.219714) (xy 119.893816 -379.212582) (xy 119.900319 -379.195381)
			(xy 119.9007 -379.186186) (xy 119.9007 -378.693934) (xy 119.900273 -378.684749) (xy 119.893771 -378.667564)
			(xy 119.888 -378.660406) (xy 119.86611 -378.634762) (xy 119.828023 -378.579124) (xy 119.796873 -378.519325)
			(xy 119.77311 -378.456226) (xy 119.757077 -378.390734) (xy 119.749003 -378.323793) (xy 116.470957 -378.323793)
			(xy 116.462922 -378.390554) (xy 116.44695 -378.455936) (xy 116.423278 -378.518939) (xy 116.392245 -378.578662)
			(xy 116.354296 -378.634247) (xy 116.332508 -378.659898) (xy 116.326731 -378.667057) (xy 116.320204 -378.684237)
			(xy 116.319808 -378.693426) (xy 116.319808 -379.186694) (xy 116.320219 -379.195881) (xy 116.326732 -379.213066)
			(xy 116.332508 -379.220222) (xy 116.354343 -379.245836) (xy 116.392293 -379.301427) (xy 116.423328 -379.361155)
			(xy 116.447 -379.424165) (xy 116.462971 -379.489552) (xy 116.471013 -379.55638) (xy 116.471009 -379.623689)
			(xy 116.462959 -379.690516) (xy 116.44698 -379.755901) (xy 116.423299 -379.818908) (xy 116.392258 -379.878633)
			(xy 116.3543 -379.934219) (xy 116.332508 -379.95987) (xy 116.3267 -379.967007) (xy 116.320192 -379.984204)
			(xy 116.319808 -379.993398) (xy 116.319808 -380.151386) (xy 116.319256 -380.161537) (xy 116.311495 -380.180297)
			(xy 116.297148 -380.194661) (xy 116.278397 -380.202445) (xy 116.268246 -380.202948) (xy 115.551966 -380.202948)
			(xy 115.541804 -380.202494) (xy 115.523032 -380.194706) (xy 115.508667 -380.180328) (xy 115.500896 -380.161548)
			(xy 115.500404 -380.151386) (xy 115.500404 -379.993398) (xy 115.499994 -379.984211) (xy 115.49348 -379.967027)
			(xy 115.487704 -379.95987) (xy 115.465963 -379.93418) (xy 115.428015 -379.878598) (xy 115.396981 -379.81888)
			(xy 115.373307 -379.75588) (xy 115.357332 -379.690503) (xy 115.349285 -379.623685) (xy 115.349281 -379.556384)
			(xy 115.35732 -379.489565) (xy 115.373287 -379.424186) (xy 115.396953 -379.361184) (xy 115.427979 -379.301461)
			(xy 115.46592 -379.245875) (xy 115.487704 -379.220222) (xy 115.493517 -379.213088) (xy 115.500022 -379.195889)
			(xy 115.500404 -379.186694) (xy 115.500404 -378.693426) (xy 115.49998 -378.68424) (xy 115.493476 -378.667056)
			(xy 115.487704 -378.659898) (xy 115.465892 -378.634266) (xy 115.427946 -378.578676) (xy 115.396916 -378.518949)
			(xy 115.373246 -378.455942) (xy 115.357276 -378.390558) (xy 115.349234 -378.323734) (xy 85.670933 -378.323734)
			(xy 85.670933 -378.323792) (xy 85.662859 -378.390729) (xy 85.646825 -378.456217) (xy 85.623062 -378.519313)
			(xy 85.591912 -378.579108) (xy 85.553824 -378.634741) (xy 85.53196 -378.660406) (xy 85.526173 -378.667558)
			(xy 85.519654 -378.684743) (xy 85.51926 -378.693934) (xy 85.51926 -379.186186) (xy 85.519686 -379.195371)
			(xy 85.526189 -379.212555) (xy 85.53196 -379.219714) (xy 85.553871 -379.245341) (xy 85.591961 -379.30098)
			(xy 85.623111 -379.360781) (xy 85.646875 -379.423883) (xy 85.662908 -379.489377) (xy 85.670981 -379.55632)
			(xy 85.670977 -379.623749) (xy 85.662896 -379.690691) (xy 85.646854 -379.756183) (xy 85.623083 -379.819282)
			(xy 85.591925 -379.879079) (xy 85.553828 -379.934713) (xy 85.53196 -379.960378) (xy 85.526143 -379.967508)
			(xy 85.519641 -379.98471) (xy 85.51926 -379.993906) (xy 85.51926 -380.151386) (xy 85.518762 -380.161512)
			(xy 85.511039 -380.180233) (xy 85.496756 -380.194589) (xy 85.478075 -380.202409) (xy 85.467952 -380.202948)
			(xy 84.751672 -380.202948) (xy 84.741567 -380.202439) (xy 84.722898 -380.194701) (xy 84.708606 -380.180412)
			(xy 84.700863 -380.161744) (xy 84.700364 -380.15164) (xy 84.700364 -379.993906) (xy 84.699937 -379.984721)
			(xy 84.693433 -379.967537) (xy 84.687664 -379.960378) (xy 84.665846 -379.934675) (xy 84.627759 -379.879045)
			(xy 84.596608 -379.819254) (xy 84.572843 -379.756162) (xy 84.556805 -379.690678) (xy 84.548726 -379.623744)
			(xy 84.548722 -379.556325) (xy 84.556793 -379.48939) (xy 84.572822 -379.423904) (xy 84.59658 -379.36081)
			(xy 84.627723 -379.301014) (xy 84.665804 -379.24538) (xy 84.687664 -379.219714) (xy 84.693487 -379.212588)
			(xy 84.699984 -379.195383) (xy 84.700364 -379.186186) (xy 84.700364 -378.693934) (xy 84.699923 -378.68475)
			(xy 84.693429 -378.667566) (xy 84.687664 -378.660406) (xy 84.665776 -378.634761) (xy 84.62769 -378.579123)
			(xy 84.596543 -378.519324) (xy 84.572781 -378.456224) (xy 84.556749 -378.390733) (xy 84.548676 -378.323793)
			(xy 81.271142 -378.323793) (xy 81.263068 -378.390729) (xy 81.247035 -378.456217) (xy 81.223272 -378.519312)
			(xy 81.192123 -378.579108) (xy 81.154035 -378.634741) (xy 81.132172 -378.660406) (xy 81.126387 -378.667559)
			(xy 81.119866 -378.684744) (xy 81.119472 -378.693934) (xy 81.119472 -379.186186) (xy 81.119895 -379.195372)
			(xy 81.126401 -379.212556) (xy 81.132172 -379.219714) (xy 81.154082 -379.245341) (xy 81.192171 -379.300981)
			(xy 81.223322 -379.360782) (xy 81.247084 -379.423884) (xy 81.263118 -379.489378) (xy 81.27119 -379.556321)
			(xy 81.271186 -379.623748) (xy 81.263105 -379.69069) (xy 81.247064 -379.756182) (xy 81.223293 -379.819281)
			(xy 81.192136 -379.879079) (xy 81.15404 -379.934713) (xy 81.132172 -379.960378) (xy 81.126356 -379.967509)
			(xy 81.119854 -379.984711) (xy 81.119472 -379.993906) (xy 81.119472 -380.151386) (xy 81.118962 -380.16151)
			(xy 81.111241 -380.180229) (xy 81.096962 -380.194585) (xy 81.078286 -380.202407) (xy 81.068164 -380.202948)
			(xy 80.351884 -380.202948) (xy 80.34178 -380.202429) (xy 80.323111 -380.194695) (xy 80.308818 -380.180409)
			(xy 80.301076 -380.161744) (xy 80.300576 -380.15164) (xy 80.300576 -379.993906) (xy 80.300168 -379.984718)
			(xy 80.293654 -379.967534) (xy 80.287876 -379.960378) (xy 80.266058 -379.934675) (xy 80.22797 -379.879045)
			(xy 80.196818 -379.819254) (xy 80.173052 -379.756162) (xy 80.157015 -379.690678) (xy 80.148935 -379.623744)
			(xy 80.148931 -379.556325) (xy 80.157002 -379.48939) (xy 80.173032 -379.423904) (xy 80.19679 -379.360809)
			(xy 80.227934 -379.301014) (xy 80.266016 -379.24538) (xy 80.287876 -379.219714) (xy 80.293689 -379.21258)
			(xy 80.300195 -379.195381) (xy 80.300576 -379.186186) (xy 80.300576 -378.693934) (xy 80.300155 -378.684748)
			(xy 80.29365 -378.667563) (xy 80.287876 -378.660406) (xy 80.265987 -378.634761) (xy 80.227901 -378.579123)
			(xy 80.196753 -378.519324) (xy 80.172991 -378.456225) (xy 80.156958 -378.390733) (xy 80.148885 -378.323793)
			(xy 76.870815 -378.323793) (xy 76.862781 -378.390552) (xy 76.846812 -378.455933) (xy 76.823143 -378.518936)
			(xy 76.792114 -378.578659) (xy 76.75417 -378.634246) (xy 76.732384 -378.659898) (xy 76.726604 -378.667055)
			(xy 76.72008 -378.684236) (xy 76.719684 -378.693426) (xy 76.719684 -379.186694) (xy 76.720101 -379.19588)
			(xy 76.72661 -379.213065) (xy 76.732384 -379.220222) (xy 76.754216 -379.245837) (xy 76.792162 -379.30143)
			(xy 76.823192 -379.361158) (xy 76.846861 -379.424168) (xy 76.86283 -379.489554) (xy 76.870871 -379.55638)
			(xy 76.870866 -379.623689) (xy 76.862818 -379.690514) (xy 76.846841 -379.755899) (xy 76.823164 -379.818905)
			(xy 76.792127 -379.87863) (xy 76.754174 -379.934218) (xy 76.732384 -379.95987) (xy 76.726573 -379.967005)
			(xy 76.720068 -379.984203) (xy 76.719684 -379.993398) (xy 76.719684 -380.151386) (xy 76.719156 -380.16154)
			(xy 76.71139 -380.180305) (xy 76.697035 -380.19467) (xy 76.678276 -380.202449) (xy 76.668122 -380.202948)
			(xy 75.951842 -380.202948) (xy 75.941671 -380.202501) (xy 75.922875 -380.194728) (xy 75.908488 -380.180349)
			(xy 75.900704 -380.161556) (xy 75.90028 -380.151386) (xy 75.90028 -379.993398) (xy 75.899875 -379.98421)
			(xy 75.893358 -379.967026) (xy 75.88758 -379.95987) (xy 75.865836 -379.934181) (xy 75.827883 -379.878601)
			(xy 75.796846 -379.818883) (xy 75.773169 -379.755883) (xy 75.757191 -379.690505) (xy 75.749143 -379.623686)
			(xy 75.749139 -379.556383) (xy 75.757179 -379.489563) (xy 75.773148 -379.424183) (xy 75.796818 -379.36118)
			(xy 75.827848 -379.301458) (xy 75.865794 -379.245874) (xy 75.88758 -379.220222) (xy 75.89339 -379.213086)
			(xy 75.899897 -379.195889) (xy 75.90028 -379.186694) (xy 75.90028 -378.693426) (xy 75.899862 -378.68424)
			(xy 75.893354 -378.667055) (xy 75.88758 -378.659898) (xy 75.865766 -378.634267) (xy 75.827815 -378.578679)
			(xy 75.79678 -378.518953) (xy 75.773107 -378.455945) (xy 75.757135 -378.39056) (xy 75.749092 -378.323734)
			(xy 72.471054 -378.323734) (xy 72.471054 -378.323791) (xy 72.46298 -378.390728) (xy 72.446947 -378.456216)
			(xy 72.423186 -378.519312) (xy 72.392037 -378.579107) (xy 72.353951 -378.634741) (xy 72.332088 -378.660406)
			(xy 72.326305 -378.667561) (xy 72.319783 -378.684744) (xy 72.319388 -378.693934) (xy 72.319388 -379.186186)
			(xy 72.319808 -379.195372) (xy 72.326315 -379.212556) (xy 72.332088 -379.219714) (xy 72.353998 -379.245342)
			(xy 72.392086 -379.300981) (xy 72.423235 -379.360783) (xy 72.446997 -379.423884) (xy 72.46303 -379.489378)
			(xy 72.471102 -379.556321) (xy 72.471098 -379.623748) (xy 72.463017 -379.69069) (xy 72.446977 -379.756182)
			(xy 72.423207 -379.819281) (xy 72.39205 -379.879078) (xy 72.353955 -379.934713) (xy 72.332088 -379.960378)
			(xy 72.326274 -379.967511) (xy 72.31977 -379.984711) (xy 72.319388 -379.993906) (xy 72.319388 -380.151386)
			(xy 72.318863 -380.161508) (xy 72.311145 -380.180224) (xy 72.296871 -380.19458) (xy 72.278199 -380.202404)
			(xy 72.26808 -380.202948) (xy 71.5518 -380.202948) (xy 71.541652 -380.202479) (xy 71.522909 -380.194693)
			(xy 71.508587 -380.180311) (xy 71.500879 -380.161536) (xy 71.500492 -380.151386) (xy 71.500492 -379.993906)
			(xy 71.500081 -379.984719) (xy 71.493568 -379.967534) (xy 71.487792 -379.960378) (xy 71.465974 -379.934675)
			(xy 71.427884 -379.879046) (xy 71.396732 -379.819255) (xy 71.372965 -379.756163) (xy 71.356927 -379.690678)
			(xy 71.348847 -379.623744) (xy 71.348843 -379.556325) (xy 71.356914 -379.48939) (xy 71.372945 -379.423903)
			(xy 71.396703 -379.360808) (xy 71.427848 -379.301013) (xy 71.465931 -379.245379) (xy 71.487792 -379.219714)
			(xy 71.493607 -379.212582) (xy 71.500111 -379.195381) (xy 71.500492 -379.186186) (xy 71.500492 -378.693934)
			(xy 71.500067 -378.684748) (xy 71.493564 -378.667564) (xy 71.487792 -378.660406) (xy 71.465903 -378.634762)
			(xy 71.427815 -378.579124) (xy 71.396666 -378.519325) (xy 71.372904 -378.456225) (xy 71.35687 -378.390734)
			(xy 71.348797 -378.323793) (xy 41.671024 -378.323793) (xy 41.66295 -378.390729) (xy 41.646915 -378.456218)
			(xy 41.623152 -378.519314) (xy 41.592001 -378.579109) (xy 41.553912 -378.634742) (xy 41.532048 -378.660406)
			(xy 41.52626 -378.667557) (xy 41.519742 -378.684743) (xy 41.519348 -378.693934) (xy 41.519348 -379.186186)
			(xy 41.519776 -379.195371) (xy 41.526279 -379.212555) (xy 41.532048 -379.219714) (xy 41.553959 -379.245341)
			(xy 41.59205 -379.30098) (xy 41.623201 -379.360781) (xy 41.646965 -379.423883) (xy 41.662999 -379.489377)
			(xy 41.671072 -379.55632) (xy 41.671068 -379.623749) (xy 41.662987 -379.690691) (xy 41.646945 -379.756183)
			(xy 41.623173 -379.819282) (xy 41.592014 -379.879079) (xy 41.553917 -379.934714) (xy 41.532048 -379.960378)
			(xy 41.526229 -379.967507) (xy 41.519729 -379.98471) (xy 41.519348 -379.993906) (xy 41.519348 -380.151386)
			(xy 41.518862 -380.161513) (xy 41.511136 -380.180236) (xy 41.49685 -380.194594) (xy 41.478165 -380.202411)
			(xy 41.46804 -380.202948) (xy 40.75176 -380.202948) (xy 40.741609 -380.202512) (xy 40.722865 -380.194712)
			(xy 40.708545 -380.180321) (xy 40.700838 -380.161539) (xy 40.700452 -380.151386) (xy 40.700452 -379.993906)
			(xy 40.700027 -379.984721) (xy 40.693523 -379.967537) (xy 40.687752 -379.960378) (xy 40.665931 -379.934676)
			(xy 40.627838 -379.879048) (xy 40.596682 -379.819258) (xy 40.572913 -379.756165) (xy 40.556873 -379.69068)
			(xy 40.548793 -379.623745) (xy 40.548788 -379.556324) (xy 40.556861 -379.489388) (xy 40.572893 -379.423901)
			(xy 40.596654 -379.360806) (xy 40.627802 -379.301011) (xy 40.665889 -379.245378) (xy 40.687752 -379.219714)
			(xy 40.693574 -379.212587) (xy 40.700072 -379.195382) (xy 40.700452 -379.186186) (xy 40.700452 -378.693934)
			(xy 40.700014 -378.68475) (xy 40.693519 -378.667566) (xy 40.687752 -378.660406) (xy 40.665861 -378.634763)
			(xy 40.627769 -378.579126) (xy 40.596617 -378.519328) (xy 40.572852 -378.456228) (xy 40.556817 -378.390735)
			(xy 40.548742 -378.323794) (xy 37.271233 -378.323794) (xy 37.263159 -378.390729) (xy 37.247125 -378.456217)
			(xy 37.223362 -378.519313) (xy 37.192212 -378.579108) (xy 37.154124 -378.634741) (xy 37.13226 -378.660406)
			(xy 37.126473 -378.667558) (xy 37.119954 -378.684743) (xy 37.11956 -378.693934) (xy 37.11956 -379.186186)
			(xy 37.119986 -379.195371) (xy 37.126489 -379.212555) (xy 37.13226 -379.219714) (xy 37.154171 -379.245341)
			(xy 37.192261 -379.30098) (xy 37.223411 -379.360781) (xy 37.247175 -379.423883) (xy 37.263208 -379.489377)
			(xy 37.271281 -379.55632) (xy 37.271277 -379.623749) (xy 37.263196 -379.690691) (xy 37.247154 -379.756183)
			(xy 37.223383 -379.819282) (xy 37.192225 -379.879079) (xy 37.154128 -379.934713) (xy 37.13226 -379.960378)
			(xy 37.126443 -379.967508) (xy 37.119941 -379.98471) (xy 37.11956 -379.993906) (xy 37.11956 -380.151386)
			(xy 37.119062 -380.161512) (xy 37.111339 -380.180233) (xy 37.097056 -380.194589) (xy 37.078375 -380.202409)
			(xy 37.068252 -380.202948) (xy 36.351972 -380.202948) (xy 36.341822 -380.202502) (xy 36.323078 -380.194707)
			(xy 36.308758 -380.180318) (xy 36.30105 -380.161538) (xy 36.300664 -380.151386) (xy 36.300664 -379.993906)
			(xy 36.300237 -379.984721) (xy 36.293733 -379.967537) (xy 36.287964 -379.960378) (xy 36.266146 -379.934675)
			(xy 36.228059 -379.879045) (xy 36.196908 -379.819254) (xy 36.173143 -379.756162) (xy 36.157105 -379.690678)
			(xy 36.149026 -379.623744) (xy 36.149022 -379.556325) (xy 36.157093 -379.48939) (xy 36.173122 -379.423904)
			(xy 36.19688 -379.36081) (xy 36.228023 -379.301014) (xy 36.266104 -379.24538) (xy 36.287964 -379.219714)
			(xy 36.293787 -379.212588) (xy 36.300284 -379.195383) (xy 36.300664 -379.186186) (xy 36.300664 -378.693934)
			(xy 36.300223 -378.68475) (xy 36.293729 -378.667566) (xy 36.287964 -378.660406) (xy 36.266076 -378.634761)
			(xy 36.22799 -378.579123) (xy 36.196843 -378.519324) (xy 36.173081 -378.456224) (xy 36.157049 -378.390733)
			(xy 36.148976 -378.323793) (xy 32.870906 -378.323793) (xy 32.862871 -378.390552) (xy 32.846902 -378.455933)
			(xy 32.823232 -378.518936) (xy 32.792203 -378.578659) (xy 32.754258 -378.634246) (xy 32.732472 -378.659898)
			(xy 32.72669 -378.667053) (xy 32.720167 -378.684236) (xy 32.719772 -378.693426) (xy 32.719772 -379.186694)
			(xy 32.720191 -379.19588) (xy 32.726699 -379.213064) (xy 32.732472 -379.220222) (xy 32.754305 -379.245837)
			(xy 32.792251 -379.301429) (xy 32.823282 -379.361158) (xy 32.846952 -379.424167) (xy 32.862921 -379.489554)
			(xy 32.870962 -379.55638) (xy 32.870957 -379.623689) (xy 32.862909 -379.690514) (xy 32.846931 -379.755899)
			(xy 32.823254 -379.818905) (xy 32.792216 -379.87863) (xy 32.754262 -379.934218) (xy 32.732472 -379.95987)
			(xy 32.72666 -379.967004) (xy 32.720155 -379.984203) (xy 32.719772 -379.993398) (xy 32.719772 -380.151386)
			(xy 32.719325 -380.161556) (xy 32.711547 -380.180348) (xy 32.697168 -380.194733) (xy 32.678379 -380.20252)
			(xy 32.66821 -380.202948) (xy 31.95193 -380.202948) (xy 31.941759 -380.202511) (xy 31.922962 -380.194733)
			(xy 31.908576 -380.180351) (xy 31.900792 -380.161557) (xy 31.900368 -380.151386) (xy 31.900368 -379.993398)
			(xy 31.899944 -379.984213) (xy 31.893438 -379.967029) (xy 31.887668 -379.95987) (xy 31.865925 -379.934181)
			(xy 31.827973 -379.878601) (xy 31.796936 -379.818882) (xy 31.773259 -379.755883) (xy 31.757282 -379.690505)
			(xy 31.749234 -379.623686) (xy 31.74923 -379.556384) (xy 31.75727 -379.489564) (xy 31.773239 -379.424184)
			(xy 31.796908 -379.361181) (xy 31.827937 -379.301459) (xy 31.865882 -379.245874) (xy 31.887668 -379.220222)
			(xy 31.893488 -379.213094) (xy 31.899987 -379.19589) (xy 31.900368 -379.186694) (xy 31.900368 -378.693426)
			(xy 31.89993 -378.684242) (xy 31.893434 -378.667058) (xy 31.887668 -378.659898) (xy 31.865854 -378.634267)
			(xy 31.827904 -378.578678) (xy 31.79687 -378.518952) (xy 31.773198 -378.455945) (xy 31.757226 -378.39056)
			(xy 31.749183 -378.323734) (xy 28.471145 -378.323734) (xy 28.471145 -378.323792) (xy 28.463071 -378.390728)
			(xy 28.447038 -378.456216) (xy 28.423275 -378.519312) (xy 28.392126 -378.579108) (xy 28.354039 -378.634741)
			(xy 28.332176 -378.660406) (xy 28.326392 -378.66756) (xy 28.31987 -378.684744) (xy 28.319476 -378.693934)
			(xy 28.319476 -379.186186) (xy 28.319898 -379.195372) (xy 28.326404 -379.212556) (xy 28.332176 -379.219714)
			(xy 28.354036 -379.245382) (xy 28.392125 -379.301016) (xy 28.423276 -379.360812) (xy 28.447 -379.423801)
			(xy 29.549058 -379.423801) (xy 29.549059 -379.356496) (xy 29.557103 -379.289673) (xy 29.573076 -379.224291)
			(xy 29.596749 -379.161286) (xy 29.627783 -379.101562) (xy 29.665732 -379.045976) (xy 29.68752 -379.020324)
			(xy 29.693334 -379.013191) (xy 29.699837 -378.995991) (xy 29.70022 -378.986796) (xy 29.70022 -378.828554)
			(xy 29.700695 -378.818396) (xy 29.708482 -378.799629) (xy 29.722852 -378.785266) (xy 29.741623 -378.77749)
			(xy 29.751782 -378.776992) (xy 30.468062 -378.776992) (xy 30.478212 -378.777564) (xy 30.496971 -378.785317)
			(xy 30.511336 -378.799658) (xy 30.51912 -378.818405) (xy 30.519624 -378.828554) (xy 30.519624 -378.986796)
			(xy 30.520031 -378.995984) (xy 30.526546 -379.013168) (xy 30.532324 -379.020324) (xy 30.55411 -379.045978)
			(xy 30.592059 -379.101564) (xy 30.623093 -379.161287) (xy 30.646766 -379.224291) (xy 30.662739 -379.289673)
			(xy 30.670784 -379.356496) (xy 30.670784 -379.423801) (xy 30.66274 -379.490624) (xy 30.646767 -379.556006)
			(xy 30.623094 -379.61901) (xy 30.592061 -379.678734) (xy 30.554112 -379.73432) (xy 30.532324 -379.759972)
			(xy 30.526517 -379.76711) (xy 30.520008 -379.784306) (xy 30.519624 -379.7935) (xy 30.519624 -380.286768)
			(xy 30.520044 -380.295954) (xy 30.52655 -380.313139) (xy 30.532324 -380.320296) (xy 30.554132 -380.345932)
			(xy 30.592083 -380.40152) (xy 30.623117 -380.461245) (xy 30.646791 -380.524252) (xy 30.662763 -380.589636)
			(xy 30.6708 -380.656404) (xy 33.948845 -380.656404) (xy 33.95692 -380.589467) (xy 33.972953 -380.523978)
			(xy 33.996716 -380.460882) (xy 34.027865 -380.401087) (xy 34.065953 -380.345453) (xy 34.087816 -380.319788)
			(xy 34.093602 -380.312635) (xy 34.100122 -380.29545) (xy 34.100516 -380.28626) (xy 34.100516 -379.794008)
			(xy 34.100098 -379.784822) (xy 34.093589 -379.767638) (xy 34.087816 -379.76048) (xy 34.065999 -379.734776)
			(xy 34.027907 -379.679148) (xy 33.996754 -379.619357) (xy 33.972986 -379.556265) (xy 33.956947 -379.49078)
			(xy 33.948867 -379.423846) (xy 33.948863 -379.356426) (xy 33.956934 -379.289491) (xy 33.972965 -379.224004)
			(xy 33.996724 -379.160909) (xy 34.02787 -379.101114) (xy 34.065954 -379.045481) (xy 34.087816 -379.019816)
			(xy 34.093633 -379.012685) (xy 34.100135 -378.995484) (xy 34.100516 -378.986288) (xy 34.100516 -378.828554)
			(xy 34.100988 -378.818427) (xy 34.108727 -378.79971) (xy 34.123017 -378.785356) (xy 34.1417 -378.777534)
			(xy 34.151824 -378.776992) (xy 34.868104 -378.776992) (xy 34.878257 -378.777418) (xy 34.897008 -378.785214)
			(xy 34.911331 -378.799609) (xy 34.919032 -378.818399) (xy 34.919412 -378.828554) (xy 34.919412 -378.986288)
			(xy 34.919825 -378.995475) (xy 34.926336 -379.012659) (xy 34.932112 -379.019816) (xy 34.954023 -379.045443)
			(xy 34.992109 -379.101083) (xy 35.023257 -379.160885) (xy 35.047018 -379.223986) (xy 35.06305 -379.28948)
			(xy 35.071122 -379.356422) (xy 35.071117 -379.42385) (xy 35.063037 -379.490791) (xy 35.046997 -379.556283)
			(xy 35.023228 -379.619381) (xy 34.992072 -379.679179) (xy 34.953978 -379.734815) (xy 34.932112 -379.76048)
			(xy 34.9263 -379.767615) (xy 34.919794 -379.784813) (xy 34.919412 -379.794008) (xy 34.919412 -380.28626)
			(xy 34.919839 -380.295446) (xy 34.92634 -380.31263) (xy 34.932112 -380.319788) (xy 34.953995 -380.345437)
			(xy 34.992083 -380.401074) (xy 35.023232 -380.460873) (xy 35.046994 -380.523972) (xy 35.063028 -380.589463)
			(xy 35.071102 -380.656403) (xy 35.071102 -380.656464) (xy 38.349165 -380.656464) (xy 38.357207 -380.589643)
			(xy 38.373176 -380.524262) (xy 38.396845 -380.461259) (xy 38.427874 -380.401536) (xy 38.465819 -380.345949)
			(xy 38.487604 -380.320296) (xy 38.493385 -380.31314) (xy 38.499909 -380.295958) (xy 38.500304 -380.286768)
			(xy 38.500304 -379.7935) (xy 38.499893 -379.784313) (xy 38.49338 -379.767129) (xy 38.487604 -379.759972)
			(xy 38.465865 -379.73428) (xy 38.427917 -379.678699) (xy 38.396884 -379.61898) (xy 38.37321 -379.555981)
			(xy 38.357234 -379.490604) (xy 38.349187 -379.423786) (xy 38.349183 -379.356486) (xy 38.357221 -379.289667)
			(xy 38.373188 -379.224288) (xy 38.396854 -379.161286) (xy 38.42788 -379.101563) (xy 38.465821 -379.045977)
			(xy 38.487604 -379.020324) (xy 38.493416 -379.01319) (xy 38.499921 -378.995991) (xy 38.500304 -378.986796)
			(xy 38.500304 -378.828554) (xy 38.500795 -378.818397) (xy 38.508578 -378.799634) (xy 38.522944 -378.785271)
			(xy 38.541709 -378.777493) (xy 38.551866 -378.776992) (xy 39.268146 -378.776992) (xy 39.278301 -378.777495)
			(xy 39.297062 -378.785276) (xy 39.311424 -378.799638) (xy 39.319205 -378.818399) (xy 39.319708 -378.828554)
			(xy 39.319708 -378.986796) (xy 39.320118 -378.995983) (xy 39.326632 -379.013168) (xy 39.332408 -379.020324)
			(xy 39.354244 -379.045937) (xy 39.392195 -379.101528) (xy 39.423229 -379.161256) (xy 39.446902 -379.224266)
			(xy 39.462873 -379.289653) (xy 39.470914 -379.356481) (xy 39.47091 -379.423791) (xy 39.46286 -379.490618)
			(xy 39.44688 -379.556003) (xy 39.4232 -379.61901) (xy 39.392158 -379.678735) (xy 39.3542 -379.734321)
			(xy 39.332408 -379.759972) (xy 39.326599 -379.767109) (xy 39.320092 -379.784306) (xy 39.319708 -379.7935)
			(xy 39.319708 -380.286768) (xy 39.320132 -380.295954) (xy 39.326636 -380.313138) (xy 39.332408 -380.320296)
			(xy 39.354217 -380.345931) (xy 39.392169 -380.401519) (xy 39.423204 -380.461244) (xy 39.446878 -380.524251)
			(xy 39.462851 -380.589636) (xy 39.470887 -380.656404) (xy 42.748933 -380.656404) (xy 42.757007 -380.589467)
			(xy 42.773041 -380.523979) (xy 42.796803 -380.460883) (xy 42.827951 -380.401087) (xy 42.866037 -380.345453)
			(xy 42.8879 -380.319788) (xy 42.893684 -380.312634) (xy 42.900206 -380.29545) (xy 42.9006 -380.28626)
			(xy 42.9006 -379.794008) (xy 42.900186 -379.784821) (xy 42.893675 -379.767637) (xy 42.8879 -379.76048)
			(xy 42.866083 -379.734776) (xy 42.827993 -379.679147) (xy 42.79684 -379.619356) (xy 42.773073 -379.556264)
			(xy 42.757035 -379.49078) (xy 42.748955 -379.423846) (xy 42.748951 -379.356426) (xy 42.757022 -379.289491)
			(xy 42.773052 -379.224005) (xy 42.796811 -379.16091) (xy 42.827956 -379.101115) (xy 42.866039 -379.045481)
			(xy 42.8879 -379.019816) (xy 42.893715 -379.012684) (xy 42.900219 -378.995483) (xy 42.9006 -378.986288)
			(xy 42.9006 -378.828554) (xy 42.901088 -378.818429) (xy 42.908823 -378.799715) (xy 42.923108 -378.785361)
			(xy 42.941786 -378.777537) (xy 42.951908 -378.776992) (xy 43.668188 -378.776992) (xy 43.67834 -378.777431)
			(xy 43.697091 -378.785221) (xy 43.711414 -378.799613) (xy 43.719116 -378.8184) (xy 43.719496 -378.828554)
			(xy 43.719496 -378.986288) (xy 43.719913 -378.995474) (xy 43.726422 -379.012659) (xy 43.732196 -379.019816)
			(xy 43.754107 -379.045442) (xy 43.792195 -379.101082) (xy 43.823344 -379.160884) (xy 43.847105 -379.223986)
			(xy 43.863138 -379.28948) (xy 43.87121 -379.356422) (xy 43.871205 -379.42385) (xy 43.863125 -379.490791)
			(xy 43.847084 -379.556283) (xy 43.823314 -379.619382) (xy 43.792158 -379.67918) (xy 43.754063 -379.734815)
			(xy 43.732196 -379.76048) (xy 43.726382 -379.767613) (xy 43.719878 -379.784813) (xy 43.719496 -379.794008)
			(xy 43.719496 -380.28626) (xy 43.719926 -380.295445) (xy 43.726426 -380.31263) (xy 43.732196 -380.319788)
			(xy 43.75408 -380.345437) (xy 43.792168 -380.401074) (xy 43.823318 -380.460872) (xy 43.847081 -380.523971)
			(xy 43.863116 -380.589462) (xy 43.87119 -380.656402) (xy 43.87119 -380.656463) (xy 73.548987 -380.656463)
			(xy 73.557029 -380.589642) (xy 73.572999 -380.524261) (xy 73.596669 -380.461258) (xy 73.6277 -380.401535)
			(xy 73.665646 -380.345948) (xy 73.687432 -380.320296) (xy 73.693217 -380.313143) (xy 73.699738 -380.295958)
			(xy 73.700132 -380.286768) (xy 73.700132 -379.7935) (xy 73.699715 -379.784314) (xy 73.693205 -379.76713)
			(xy 73.687432 -379.759972) (xy 73.665692 -379.734281) (xy 73.627742 -379.6787) (xy 73.596707 -379.618982)
			(xy 73.573032 -379.555982) (xy 73.557056 -379.490605) (xy 73.549008 -379.423787) (xy 73.549004 -379.356486)
			(xy 73.557043 -379.289666) (xy 73.573011 -379.224287) (xy 73.596678 -379.161285) (xy 73.627705 -379.101562)
			(xy 73.665648 -379.045976) (xy 73.687432 -379.020324) (xy 73.693247 -379.013192) (xy 73.69975 -378.995991)
			(xy 73.700132 -378.986796) (xy 73.700132 -378.828554) (xy 73.700596 -378.818394) (xy 73.708384 -378.799625)
			(xy 73.722759 -378.785262) (xy 73.741534 -378.777488) (xy 73.751694 -378.776992) (xy 74.467974 -378.776992)
			(xy 74.478125 -378.777553) (xy 74.496884 -378.785311) (xy 74.511249 -378.799655) (xy 74.519032 -378.818404)
			(xy 74.519536 -378.828554) (xy 74.519536 -378.986796) (xy 74.519962 -378.995981) (xy 74.526466 -379.013165)
			(xy 74.532236 -379.020324) (xy 74.554072 -379.045937) (xy 74.592021 -379.101528) (xy 74.623053 -379.161257)
			(xy 74.646725 -379.224267) (xy 74.662695 -379.289654) (xy 74.670736 -379.356481) (xy 74.670731 -379.423791)
			(xy 74.662682 -379.490617) (xy 74.646703 -379.556002) (xy 74.623024 -379.619009) (xy 74.591984 -379.678734)
			(xy 74.554028 -379.73432) (xy 74.532236 -379.759972) (xy 74.526419 -379.767102) (xy 74.519918 -379.784304)
			(xy 74.519536 -379.7935) (xy 74.519536 -380.286768) (xy 74.519976 -380.295952) (xy 74.52647 -380.313136)
			(xy 74.532236 -380.320296) (xy 74.554044 -380.345932) (xy 74.591994 -380.40152) (xy 74.623028 -380.461246)
			(xy 74.6467 -380.524252) (xy 74.662673 -380.589637) (xy 74.670709 -380.656404) (xy 77.948754 -380.656404)
			(xy 77.956829 -380.589466) (xy 77.972863 -380.523978) (xy 77.996626 -380.460882) (xy 78.027776 -380.401086)
			(xy 78.065864 -380.345453) (xy 78.087728 -380.319788) (xy 78.093516 -380.312637) (xy 78.100035 -380.295451)
			(xy 78.100428 -380.28626) (xy 78.100428 -379.794008) (xy 78.100008 -379.784822) (xy 78.093501 -379.767638)
			(xy 78.087728 -379.76048) (xy 78.06591 -379.734776) (xy 78.027818 -379.679148) (xy 77.996664 -379.619357)
			(xy 77.972896 -379.556265) (xy 77.956856 -379.490781) (xy 77.948776 -379.423846) (xy 77.948772 -379.356426)
			(xy 77.956843 -379.28949) (xy 77.972874 -379.224004) (xy 77.996634 -379.160909) (xy 78.027781 -379.101114)
			(xy 78.065866 -379.045481) (xy 78.087728 -379.019816) (xy 78.093546 -379.012686) (xy 78.100047 -378.995484)
			(xy 78.100428 -378.986288) (xy 78.100428 -378.828554) (xy 78.100889 -378.818426) (xy 78.108629 -378.799706)
			(xy 78.122923 -378.785352) (xy 78.14161 -378.777532) (xy 78.151736 -378.776992) (xy 78.868016 -378.776992)
			(xy 78.878125 -378.777472) (xy 78.896802 -378.785213) (xy 78.911096 -378.799512) (xy 78.918831 -378.818191)
			(xy 78.919324 -378.8283) (xy 78.919324 -378.986288) (xy 78.919734 -378.995475) (xy 78.926247 -379.01266)
			(xy 78.932024 -379.019816) (xy 78.953934 -379.045443) (xy 78.99202 -379.101083) (xy 79.023167 -379.160885)
			(xy 79.046928 -379.223987) (xy 79.062959 -379.28948) (xy 79.071031 -379.356423) (xy 79.071026 -379.42385)
			(xy 79.062946 -379.490791) (xy 79.046906 -379.556282) (xy 79.023138 -379.619381) (xy 78.991983 -379.679179)
			(xy 78.95389 -379.734814) (xy 78.932024 -379.76048) (xy 78.926214 -379.767616) (xy 78.919706 -379.784813)
			(xy 78.919324 -379.794008) (xy 78.919324 -380.28626) (xy 78.919748 -380.295446) (xy 78.926251 -380.312631)
			(xy 78.932024 -380.319788) (xy 78.953907 -380.345437) (xy 78.991993 -380.401075) (xy 79.023142 -380.460873)
			(xy 79.046904 -380.523972) (xy 79.062937 -380.589463) (xy 79.071011 -380.656403) (xy 79.071011 -380.656464)
			(xy 82.349074 -380.656464) (xy 82.357116 -380.589643) (xy 82.373086 -380.524262) (xy 82.396755 -380.461258)
			(xy 82.427785 -380.401535) (xy 82.46573 -380.345948) (xy 82.487516 -380.320296) (xy 82.493299 -380.313141)
			(xy 82.499821 -380.295958) (xy 82.500216 -380.286768) (xy 82.500216 -379.7935) (xy 82.499803 -379.784313)
			(xy 82.493291 -379.767129) (xy 82.487516 -379.759972) (xy 82.465776 -379.734281) (xy 82.427828 -379.678699)
			(xy 82.396794 -379.618981) (xy 82.373119 -379.555982) (xy 82.357144 -379.490604) (xy 82.349096 -379.423786)
			(xy 82.349092 -379.356486) (xy 82.357131 -379.289667) (xy 82.373098 -379.224288) (xy 82.396764 -379.161285)
			(xy 82.427791 -379.101563) (xy 82.465732 -379.045977) (xy 82.487516 -379.020324) (xy 82.493329 -379.013191)
			(xy 82.499833 -378.995991) (xy 82.500216 -378.986796) (xy 82.500216 -378.828554) (xy 82.500695 -378.818396)
			(xy 82.508481 -378.79963) (xy 82.52285 -378.785267) (xy 82.54162 -378.777491) (xy 82.551778 -378.776992)
			(xy 83.268058 -378.776992) (xy 83.278207 -378.777567) (xy 83.296967 -378.785319) (xy 83.311332 -378.799659)
			(xy 83.319116 -378.818405) (xy 83.31962 -378.828554) (xy 83.31962 -378.986796) (xy 83.320028 -378.995984)
			(xy 83.326543 -379.013168) (xy 83.33232 -379.020324) (xy 83.354156 -379.045937) (xy 83.392107 -379.101528)
			(xy 83.42314 -379.161256) (xy 83.446812 -379.224266) (xy 83.462783 -379.289654) (xy 83.470824 -379.356481)
			(xy 83.470819 -379.423791) (xy 83.46277 -379.490618) (xy 83.446791 -379.556003) (xy 83.423111 -379.61901)
			(xy 83.392069 -379.678734) (xy 83.354112 -379.734321) (xy 83.33232 -379.759972) (xy 83.326513 -379.76711)
			(xy 83.320004 -379.784306) (xy 83.31962 -379.7935) (xy 83.31962 -380.286768) (xy 83.320041 -380.295954)
			(xy 83.326547 -380.313139) (xy 83.33232 -380.320296) (xy 83.354129 -380.345931) (xy 83.392079 -380.401519)
			(xy 83.423114 -380.461245) (xy 83.446788 -380.524252) (xy 83.46276 -380.589636) (xy 83.470797 -380.656404)
			(xy 86.748842 -380.656404) (xy 86.756916 -380.589467) (xy 86.77295 -380.523979) (xy 86.796713 -380.460883)
			(xy 86.827862 -380.401087) (xy 86.865949 -380.345453) (xy 86.887812 -380.319788) (xy 86.893598 -380.312635)
			(xy 86.900118 -380.29545) (xy 86.900512 -380.28626) (xy 86.900512 -379.794008) (xy 86.900095 -379.784822)
			(xy 86.893586 -379.767637) (xy 86.887812 -379.76048) (xy 86.865995 -379.734776) (xy 86.827904 -379.679147)
			(xy 86.79675 -379.619357) (xy 86.772983 -379.556265) (xy 86.756944 -379.49078) (xy 86.748864 -379.423846)
			(xy 86.74886 -379.356426) (xy 86.756931 -379.289491) (xy 86.772962 -379.224004) (xy 86.796721 -379.160909)
			(xy 86.827867 -379.101115) (xy 86.86595 -379.045481) (xy 86.887812 -379.019816) (xy 86.893628 -379.012685)
			(xy 86.900131 -378.995483) (xy 86.900512 -378.986288) (xy 86.900512 -378.828554) (xy 86.900988 -378.818428)
			(xy 86.908726 -378.799711) (xy 86.923015 -378.785357) (xy 86.941696 -378.777535) (xy 86.95182 -378.776992)
			(xy 87.6681 -378.776992) (xy 87.678208 -378.777485) (xy 87.696884 -378.785221) (xy 87.711179 -378.799516)
			(xy 87.718915 -378.818192) (xy 87.719408 -378.8283) (xy 87.719408 -378.986288) (xy 87.719822 -378.995475)
			(xy 87.726333 -379.012659) (xy 87.732108 -379.019816) (xy 87.754019 -379.045442) (xy 87.792106 -379.101083)
			(xy 87.823254 -379.160884) (xy 87.847015 -379.223986) (xy 87.863047 -379.28948) (xy 87.871119 -379.356422)
			(xy 87.871114 -379.42385) (xy 87.863034 -379.490791) (xy 87.846994 -379.556283) (xy 87.823224 -379.619382)
			(xy 87.792068 -379.679179) (xy 87.753975 -379.734815) (xy 87.732108 -379.76048) (xy 87.726296 -379.767614)
			(xy 87.71979 -379.784813) (xy 87.719408 -379.794008) (xy 87.719408 -379.824742) (xy 104.262936 -379.824742)
			(xy 104.262936 -379.623574) (xy 104.263462 -379.606825) (xy 104.272137 -379.574469) (xy 104.28889 -379.54546)
			(xy 104.31258 -379.521776) (xy 104.341591 -379.505028) (xy 104.373949 -379.496358) (xy 104.390698 -379.495812)
			(xy 104.644698 -379.495812) (xy 104.661444 -379.496386) (xy 104.693795 -379.505053) (xy 104.722801 -379.521797)
			(xy 104.746486 -379.545476) (xy 104.763236 -379.574479) (xy 104.77191 -379.606828) (xy 104.77246 -379.623574)
			(xy 104.77246 -379.824742) (xy 104.771952 -379.841492) (xy 104.763273 -379.873849) (xy 104.746516 -379.902858)
			(xy 104.722823 -379.926543) (xy 104.693808 -379.94329) (xy 104.661448 -379.951958) (xy 104.644698 -379.952504)
			(xy 104.390698 -379.952504) (xy 104.373953 -379.951917) (xy 104.341604 -379.943251) (xy 104.3126 -379.926509)
			(xy 104.288915 -379.902832) (xy 104.272164 -379.873833) (xy 104.263488 -379.841487) (xy 104.262936 -379.824742)
			(xy 87.719408 -379.824742) (xy 87.719408 -380.28626) (xy 87.719836 -380.295445) (xy 87.726337 -380.31263)
			(xy 87.732108 -380.319788) (xy 87.753991 -380.345437) (xy 87.792079 -380.401074) (xy 87.823228 -380.460873)
			(xy 87.846991 -380.523972) (xy 87.863025 -380.589463) (xy 87.867292 -380.624842) (xy 104.262936 -380.624842)
			(xy 104.262936 -380.423674) (xy 104.263462 -380.406925) (xy 104.272137 -380.374569) (xy 104.28889 -380.34556)
			(xy 104.31258 -380.321876) (xy 104.341591 -380.305128) (xy 104.373949 -380.296458) (xy 104.390698 -380.295912)
			(xy 104.644698 -380.295912) (xy 104.661444 -380.296486) (xy 104.693795 -380.305153) (xy 104.722801 -380.321897)
			(xy 104.746486 -380.345576) (xy 104.763236 -380.374579) (xy 104.77191 -380.406928) (xy 104.77246 -380.423674)
			(xy 104.77246 -380.624842) (xy 104.771952 -380.641592) (xy 104.763273 -380.673949) (xy 104.746516 -380.702958)
			(xy 104.722823 -380.726643) (xy 104.693808 -380.74339) (xy 104.661448 -380.752058) (xy 104.644698 -380.752604)
			(xy 104.390698 -380.752604) (xy 104.373953 -380.752017) (xy 104.341604 -380.743351) (xy 104.3126 -380.726609)
			(xy 104.288915 -380.702932) (xy 104.272164 -380.673933) (xy 104.263488 -380.641587) (xy 104.262936 -380.624842)
			(xy 87.867292 -380.624842) (xy 87.871099 -380.656402) (xy 87.871097 -380.723828) (xy 87.863019 -380.790767)
			(xy 87.846982 -380.856257) (xy 87.838954 -380.877572) (xy 105.0036 -380.877572) (xy 105.0036 -380.013972)
			(xy 105.00409 -379.983988) (xy 105.011918 -379.924532) (xy 105.027439 -379.866607) (xy 105.050388 -379.811203)
			(xy 105.080372 -379.759269) (xy 105.116878 -379.711693) (xy 105.159283 -379.669288) (xy 105.206859 -379.632782)
			(xy 105.258793 -379.602798) (xy 105.314197 -379.579849) (xy 105.372122 -379.564328) (xy 105.431578 -379.5565)
			(xy 105.491546 -379.5565) (xy 105.551002 -379.564328) (xy 105.608927 -379.579849) (xy 105.664331 -379.602798)
			(xy 105.716265 -379.632782) (xy 105.763841 -379.669288) (xy 105.806246 -379.711693) (xy 105.842752 -379.759269)
			(xy 105.866328 -379.800104) (xy 106.130344 -379.800104) (xy 106.130344 -379.598936) (xy 106.130965 -379.582248)
			(xy 106.139583 -379.550003) (xy 106.156243 -379.521082) (xy 106.179813 -379.49745) (xy 106.20869 -379.480713)
			(xy 106.240911 -379.47201) (xy 106.257598 -379.471428) (xy 106.512106 -379.471428) (xy 106.528833 -379.471976)
			(xy 106.561149 -379.480624) (xy 106.590131 -379.497332) (xy 106.61381 -379.520963) (xy 106.630576 -379.549912)
			(xy 106.63929 -379.58221) (xy 106.639868 -379.598936) (xy 106.639868 -379.800104) (xy 106.639368 -379.816801)
			(xy 106.630733 -379.84906) (xy 106.614052 -379.87799) (xy 106.590457 -379.901623) (xy 106.561555 -379.918353)
			(xy 106.52931 -379.927041) (xy 106.512614 -379.927612) (xy 106.258106 -379.927612) (xy 106.241375 -379.927112)
			(xy 106.20905 -379.918462) (xy 106.180062 -379.901747) (xy 106.156381 -379.878105) (xy 106.139619 -379.849144)
			(xy 106.130915 -379.816834) (xy 106.130344 -379.800104) (xy 105.866328 -379.800104) (xy 105.872736 -379.811203)
			(xy 105.895685 -379.866607) (xy 105.911206 -379.924532) (xy 105.919034 -379.983988) (xy 105.919524 -380.013972)
			(xy 105.919524 -380.600204) (xy 106.130344 -380.600204) (xy 106.130344 -380.399036) (xy 106.130965 -380.382348)
			(xy 106.139583 -380.350103) (xy 106.156243 -380.321182) (xy 106.179813 -380.29755) (xy 106.20869 -380.280813)
			(xy 106.240911 -380.27211) (xy 106.257598 -380.271528) (xy 106.512106 -380.271528) (xy 106.528833 -380.272076)
			(xy 106.561149 -380.280724) (xy 106.590131 -380.297432) (xy 106.61381 -380.321063) (xy 106.630576 -380.350012)
			(xy 106.63929 -380.38231) (xy 106.639868 -380.399036) (xy 106.639868 -380.600204) (xy 106.639368 -380.616901)
			(xy 106.630733 -380.64916) (xy 106.626557 -380.656403) (xy 117.548873 -380.656403) (xy 117.556947 -380.589466)
			(xy 117.572982 -380.523977) (xy 117.596746 -380.460881) (xy 117.627898 -380.401085) (xy 117.665987 -380.345452)
			(xy 117.687852 -380.319788) (xy 117.693643 -380.312639) (xy 117.700159 -380.295451) (xy 117.700552 -380.28626)
			(xy 117.700552 -379.794008) (xy 117.700126 -379.784823) (xy 117.693622 -379.767639) (xy 117.687852 -379.76048)
			(xy 117.666033 -379.734777) (xy 117.62794 -379.679149) (xy 117.596784 -379.619358) (xy 117.573015 -379.556266)
			(xy 117.556975 -379.490781) (xy 117.548894 -379.423846) (xy 117.54889 -379.356426) (xy 117.556962 -379.28949)
			(xy 117.572994 -379.224003) (xy 117.596755 -379.160908) (xy 117.627903 -379.101113) (xy 117.665989 -379.04548)
			(xy 117.687852 -379.019816) (xy 117.693673 -379.012688) (xy 117.700172 -378.995484) (xy 117.700552 -378.986288)
			(xy 117.700552 -378.828554) (xy 117.700989 -378.818423) (xy 117.708734 -378.799698) (xy 117.723036 -378.785343)
			(xy 117.741731 -378.777528) (xy 117.75186 -378.776992) (xy 118.46814 -378.776992) (xy 118.478296 -378.777389)
			(xy 118.497047 -378.785196) (xy 118.511369 -378.7996) (xy 118.519069 -378.818396) (xy 118.519448 -378.828554)
			(xy 118.519448 -378.986288) (xy 118.519875 -378.995473) (xy 118.526378 -379.012657) (xy 118.532148 -379.019816)
			(xy 118.554061 -379.045441) (xy 118.592152 -379.10108) (xy 118.623303 -379.160882) (xy 118.647067 -379.223984)
			(xy 118.663101 -379.289478) (xy 118.671174 -379.356422) (xy 118.671169 -379.42385) (xy 118.663088 -379.490793)
			(xy 118.647046 -379.556285) (xy 118.623274 -379.619384) (xy 118.592115 -379.679181) (xy 118.554017 -379.734816)
			(xy 118.532148 -379.76048) (xy 118.526329 -379.767609) (xy 118.519829 -379.784812) (xy 118.519448 -379.794008)
			(xy 118.519448 -380.28626) (xy 118.519889 -380.295444) (xy 118.526382 -380.312628) (xy 118.532148 -380.319788)
			(xy 118.554033 -380.345436) (xy 118.592125 -380.401072) (xy 118.623278 -380.46087) (xy 118.647043 -380.523969)
			(xy 118.663079 -380.589461) (xy 118.671154 -380.656402) (xy 118.671154 -380.656463) (xy 121.949193 -380.656463)
			(xy 121.957235 -380.589642) (xy 121.973206 -380.524261) (xy 121.996876 -380.461257) (xy 122.027907 -380.401534)
			(xy 122.065854 -380.345948) (xy 122.08764 -380.320296) (xy 122.093426 -380.313143) (xy 122.099946 -380.295958)
			(xy 122.10034 -380.286768) (xy 122.10034 -379.7935) (xy 122.099921 -379.784314) (xy 122.093413 -379.76713)
			(xy 122.08764 -379.759972) (xy 122.0659 -379.734281) (xy 122.027949 -379.6787) (xy 121.996914 -379.618982)
			(xy 121.973238 -379.555982) (xy 121.957262 -379.490605) (xy 121.949214 -379.423787) (xy 121.94921 -379.356485)
			(xy 121.957249 -379.289666) (xy 121.973217 -379.224287) (xy 121.996884 -379.161284) (xy 122.027912 -379.101562)
			(xy 122.065855 -379.045976) (xy 122.08764 -379.020324) (xy 122.093456 -379.013193) (xy 122.099958 -378.995991)
			(xy 122.10034 -378.986796) (xy 122.10034 -378.828554) (xy 122.100796 -378.818393) (xy 122.108586 -378.799623)
			(xy 122.122963 -378.785259) (xy 122.141741 -378.777486) (xy 122.151902 -378.776992) (xy 122.868182 -378.776992)
			(xy 122.878333 -378.777547) (xy 122.897093 -378.785307) (xy 122.911457 -378.799653) (xy 122.919241 -378.818404)
			(xy 122.919744 -378.828554) (xy 122.919744 -378.986796) (xy 122.920169 -378.995981) (xy 122.926674 -379.013165)
			(xy 122.932444 -379.020324) (xy 122.95428 -379.045937) (xy 122.992228 -379.101529) (xy 123.02326 -379.161257)
			(xy 123.046931 -379.224267) (xy 123.062901 -379.289654) (xy 123.070942 -379.356482) (xy 123.070937 -379.423791)
			(xy 123.062888 -379.490617) (xy 123.04691 -379.556002) (xy 123.023231 -379.619009) (xy 122.992191 -379.678733)
			(xy 122.954235 -379.73432) (xy 122.932444 -379.759972) (xy 122.926627 -379.767103) (xy 122.920126 -379.784305)
			(xy 122.919744 -379.7935) (xy 122.919744 -380.286768) (xy 122.920182 -380.295952) (xy 122.926678 -380.313136)
			(xy 122.932444 -380.320296) (xy 122.954252 -380.345932) (xy 122.992201 -380.40152) (xy 123.023235 -380.461246)
			(xy 123.046907 -380.524252) (xy 123.062879 -380.589637) (xy 123.070915 -380.656404) (xy 126.34896 -380.656404)
			(xy 126.357035 -380.589466) (xy 126.373069 -380.523978) (xy 126.396833 -380.460881) (xy 126.427983 -380.401086)
			(xy 126.466072 -380.345453) (xy 126.487936 -380.319788) (xy 126.493725 -380.312637) (xy 126.500243 -380.295451)
			(xy 126.500636 -380.28626) (xy 126.500636 -379.794008) (xy 126.500214 -379.784822) (xy 126.493708 -379.767638)
			(xy 126.487936 -379.76048) (xy 126.466118 -379.734776) (xy 126.428025 -379.679148) (xy 126.396871 -379.619358)
			(xy 126.373102 -379.556266) (xy 126.357062 -379.490781) (xy 126.348982 -379.423846) (xy 126.348978 -379.356426)
			(xy 126.357049 -379.28949) (xy 126.373081 -379.224003) (xy 126.396841 -379.160908) (xy 126.427988 -379.101114)
			(xy 126.466074 -379.045481) (xy 126.487936 -379.019816) (xy 126.493755 -379.012687) (xy 126.500256 -378.995484)
			(xy 126.500636 -378.986288) (xy 126.500636 -378.828554) (xy 126.501089 -378.818425) (xy 126.508831 -378.799703)
			(xy 126.523127 -378.785349) (xy 126.541817 -378.777531) (xy 126.551944 -378.776992) (xy 127.268224 -378.776992)
			(xy 127.278379 -378.777402) (xy 127.29713 -378.785204) (xy 127.311452 -378.799604) (xy 127.319153 -378.818397)
			(xy 127.319532 -378.828554) (xy 127.319532 -378.986288) (xy 127.319963 -378.995473) (xy 127.326464 -379.012656)
			(xy 127.332232 -379.019816) (xy 127.354142 -379.045443) (xy 127.392227 -379.101084) (xy 127.423374 -379.160885)
			(xy 127.447134 -379.223987) (xy 127.463165 -379.289481) (xy 127.471237 -379.356423) (xy 127.471232 -379.423849)
			(xy 127.463152 -379.49079) (xy 127.447113 -379.556282) (xy 127.423345 -379.61938) (xy 127.39219 -379.679178)
			(xy 127.354098 -379.734814) (xy 127.332232 -379.76048) (xy 127.326411 -379.767607) (xy 127.319913 -379.784812)
			(xy 127.319532 -379.794008) (xy 127.319532 -380.28626) (xy 127.319977 -380.295443) (xy 127.326468 -380.312627)
			(xy 127.332232 -380.319788) (xy 127.354114 -380.345438) (xy 127.392201 -380.401075) (xy 127.423349 -380.460874)
			(xy 127.44711 -380.523973) (xy 127.463143 -380.589463) (xy 127.471217 -380.656403) (xy 127.471217 -380.656463)
			(xy 130.74928 -380.656463) (xy 130.757322 -380.589642) (xy 130.773292 -380.524262) (xy 130.796962 -380.461258)
			(xy 130.827992 -380.401535) (xy 130.865938 -380.345948) (xy 130.887724 -380.320296) (xy 130.893508 -380.313142)
			(xy 130.900029 -380.295958) (xy 130.900424 -380.286768) (xy 130.900424 -379.7935) (xy 130.900009 -379.784313)
			(xy 130.893498 -379.767129) (xy 130.887724 -379.759972) (xy 130.865984 -379.734281) (xy 130.828035 -379.678699)
			(xy 130.797 -379.618981) (xy 130.773326 -379.555982) (xy 130.75735 -379.490605) (xy 130.749302 -379.423787)
			(xy 130.749298 -379.356486) (xy 130.757337 -379.289667) (xy 130.773304 -379.224287) (xy 130.796971 -379.161285)
			(xy 130.827998 -379.101563) (xy 130.86594 -379.045977) (xy 130.887724 -379.020324) (xy 130.893538 -379.013191)
			(xy 130.900042 -378.995991) (xy 130.900424 -378.986796) (xy 130.900424 -378.828554) (xy 130.900895 -378.818395)
			(xy 130.908682 -378.799628) (xy 130.923054 -378.785264) (xy 130.941827 -378.777489) (xy 130.951986 -378.776992)
			(xy 131.668266 -378.776992) (xy 131.678416 -378.77756) (xy 131.697175 -378.785315) (xy 131.71154 -378.799657)
			(xy 131.719324 -378.818405) (xy 131.719828 -378.828554) (xy 131.719828 -378.986796) (xy 131.720234 -378.995984)
			(xy 131.72675 -379.013168) (xy 131.732528 -379.020324) (xy 131.754364 -379.045937) (xy 131.792314 -379.101528)
			(xy 131.823347 -379.161257) (xy 131.847018 -379.224267) (xy 131.862989 -379.289654) (xy 131.87103 -379.356481)
			(xy 131.871025 -379.423791) (xy 131.862976 -379.490617) (xy 131.846997 -379.556003) (xy 131.823317 -379.619009)
			(xy 131.792277 -379.678734) (xy 131.75432 -379.73432) (xy 131.732528 -379.759972) (xy 131.72671 -379.767101)
			(xy 131.72021 -379.784304) (xy 131.719828 -379.7935) (xy 131.719828 -380.286768) (xy 131.720247 -380.295954)
			(xy 131.726754 -380.313139) (xy 131.732528 -380.320296) (xy 131.754336 -380.345932) (xy 131.792287 -380.40152)
			(xy 131.823321 -380.461245) (xy 131.846994 -380.524252) (xy 131.862967 -380.589636) (xy 131.871003 -380.656404)
			(xy 161.548806 -380.656404) (xy 161.55688 -380.589468) (xy 161.572912 -380.523981) (xy 161.596672 -380.460885)
			(xy 161.627819 -380.401089) (xy 161.665902 -380.345454) (xy 161.687764 -380.319788) (xy 161.693556 -380.31264)
			(xy 161.700072 -380.295451) (xy 161.700464 -380.28626) (xy 161.700464 -379.794008) (xy 161.700036 -379.784823)
			(xy 161.693533 -379.767639) (xy 161.687764 -379.76048) (xy 161.665948 -379.734775) (xy 161.627861 -379.679146)
			(xy 161.59671 -379.619354) (xy 161.572945 -379.556263) (xy 161.556907 -379.490779) (xy 161.548828 -379.423846)
			(xy 161.548823 -379.356426) (xy 161.556894 -379.289492) (xy 161.572923 -379.224006) (xy 161.59668 -379.160911)
			(xy 161.627824 -379.101116) (xy 161.665904 -379.045482) (xy 161.687764 -379.019816) (xy 161.693587 -379.01269)
			(xy 161.700084 -378.995484) (xy 161.700464 -378.986288) (xy 161.700464 -378.828554) (xy 161.70089 -378.818421)
			(xy 161.708637 -378.799695) (xy 161.722942 -378.785339) (xy 161.741641 -378.777526) (xy 161.751772 -378.776992)
			(xy 162.468052 -378.776992) (xy 162.47817 -378.777455) (xy 162.496871 -378.785186) (xy 162.511187 -378.799488)
			(xy 162.518935 -378.818182) (xy 162.51936 -378.8283) (xy 162.51936 -378.986288) (xy 162.519785 -378.995473)
			(xy 162.526289 -379.012658) (xy 162.53206 -379.019816) (xy 162.553973 -379.045442) (xy 162.592062 -379.101081)
			(xy 162.623213 -379.160882) (xy 162.646977 -379.223984) (xy 162.66301 -379.289479) (xy 162.671083 -379.356422)
			(xy 162.671078 -379.42385) (xy 162.662997 -379.490792) (xy 162.646955 -379.556285) (xy 162.623184 -379.619384)
			(xy 162.592025 -379.679181) (xy 162.553928 -379.734815) (xy 162.53206 -379.76048) (xy 162.526242 -379.76761)
			(xy 162.519741 -379.784812) (xy 162.51936 -379.794008) (xy 162.51936 -380.28626) (xy 162.519799 -380.295444)
			(xy 162.526294 -380.312628) (xy 162.53206 -380.319788) (xy 162.553945 -380.345436) (xy 162.592036 -380.401072)
			(xy 162.623188 -380.460871) (xy 162.646953 -380.52397) (xy 162.662988 -380.589461) (xy 162.671063 -380.656402)
			(xy 162.671063 -380.656463) (xy 165.949102 -380.656463) (xy 165.957144 -380.589642) (xy 165.973115 -380.524261)
			(xy 165.996786 -380.461257) (xy 166.027818 -380.401534) (xy 166.065765 -380.345948) (xy 166.087552 -380.320296)
			(xy 166.093339 -380.313144) (xy 166.099858 -380.295959) (xy 166.100252 -380.286768) (xy 166.100252 -379.7935)
			(xy 166.09983 -379.784314) (xy 166.093323 -379.76713) (xy 166.087552 -379.759972) (xy 166.065811 -379.734281)
			(xy 166.02786 -379.678701) (xy 165.996824 -379.618982) (xy 165.973148 -379.555983) (xy 165.957171 -379.490605)
			(xy 165.949123 -379.423787) (xy 165.949119 -379.356485) (xy 165.957158 -379.289666) (xy 165.973127 -379.224286)
			(xy 165.996795 -379.161284) (xy 166.027823 -379.101562) (xy 166.065767 -379.045976) (xy 166.087552 -379.020324)
			(xy 166.09337 -379.013194) (xy 166.09987 -378.995992) (xy 166.100252 -378.986796) (xy 166.100252 -378.828554)
			(xy 166.100696 -378.818392) (xy 166.108488 -378.799619) (xy 166.122869 -378.785255) (xy 166.141651 -378.777484)
			(xy 166.151814 -378.776992) (xy 166.868094 -378.776992) (xy 166.878246 -378.777537) (xy 166.897006 -378.785301)
			(xy 166.91137 -378.79965) (xy 166.919153 -378.818403) (xy 166.919656 -378.828554) (xy 166.919656 -378.986796)
			(xy 166.920078 -378.995982) (xy 166.926584 -379.013166) (xy 166.932356 -379.020324) (xy 166.954191 -379.045937)
			(xy 166.992139 -379.101529) (xy 167.02317 -379.161258) (xy 167.046841 -379.224268) (xy 167.06281 -379.289655)
			(xy 167.070851 -379.356482) (xy 167.070847 -379.423791) (xy 167.062798 -379.490617) (xy 167.046819 -379.556001)
			(xy 167.023141 -379.619008) (xy 166.992102 -379.678733) (xy 166.954147 -379.73432) (xy 166.932356 -379.759972)
			(xy 166.926541 -379.767104) (xy 166.920038 -379.784305) (xy 166.919656 -379.7935) (xy 166.919656 -380.286768)
			(xy 166.920091 -380.295952) (xy 166.926588 -380.313137) (xy 166.932356 -380.320296) (xy 166.954164 -380.345932)
			(xy 166.992112 -380.40152) (xy 167.023145 -380.461246) (xy 167.046817 -380.524253) (xy 167.062789 -380.589637)
			(xy 167.070824 -380.656403) (xy 170.34887 -380.656403) (xy 170.356944 -380.589466) (xy 170.372979 -380.523977)
			(xy 170.396743 -380.460881) (xy 170.427894 -380.401086) (xy 170.465984 -380.345452) (xy 170.487848 -380.319788)
			(xy 170.493638 -380.312638) (xy 170.500155 -380.295451) (xy 170.500548 -380.28626) (xy 170.500548 -379.794008)
			(xy 170.500123 -379.784823) (xy 170.493619 -379.767639) (xy 170.487848 -379.76048) (xy 170.46603 -379.734777)
			(xy 170.427936 -379.679149) (xy 170.396781 -379.619358) (xy 170.373012 -379.556266) (xy 170.356971 -379.490781)
			(xy 170.348891 -379.423846) (xy 170.348887 -379.356426) (xy 170.356959 -379.28949) (xy 170.37299 -379.224003)
			(xy 170.396751 -379.160908) (xy 170.427899 -379.101113) (xy 170.465985 -379.04548) (xy 170.487848 -379.019816)
			(xy 170.493669 -379.012688) (xy 170.500168 -378.995484) (xy 170.500548 -378.986288) (xy 170.500548 -378.828554)
			(xy 170.500989 -378.818423) (xy 170.508734 -378.7997) (xy 170.523034 -378.785345) (xy 170.541727 -378.777529)
			(xy 170.551856 -378.776992) (xy 171.268136 -378.776992) (xy 171.278291 -378.777392) (xy 171.297043 -378.785198)
			(xy 171.311365 -378.799601) (xy 171.319065 -378.818396) (xy 171.319444 -378.828554) (xy 171.319444 -378.986288)
			(xy 171.319872 -378.995473) (xy 171.326375 -379.012657) (xy 171.332144 -379.019816) (xy 171.354057 -379.045441)
			(xy 171.392148 -379.10108) (xy 171.4233 -379.160881) (xy 171.447064 -379.223984) (xy 171.463098 -379.289478)
			(xy 171.47117 -379.356422) (xy 171.471166 -379.42385) (xy 171.463085 -379.490793) (xy 171.447042 -379.556285)
			(xy 171.42327 -379.619384) (xy 171.392111 -379.679182) (xy 171.354013 -379.734816) (xy 171.332144 -379.76048)
			(xy 171.326324 -379.767608) (xy 171.319825 -379.784812) (xy 171.319444 -379.794008) (xy 171.319444 -380.28626)
			(xy 171.319886 -380.295444) (xy 171.326379 -380.312628) (xy 171.332144 -380.319788) (xy 171.35403 -380.345436)
			(xy 171.392121 -380.401072) (xy 171.423274 -380.46087) (xy 171.44704 -380.523969) (xy 171.463076 -380.589461)
			(xy 171.471151 -380.656402) (xy 171.471151 -380.656463) (xy 174.74919 -380.656463) (xy 174.757232 -380.589642)
			(xy 174.773202 -380.524261) (xy 174.796873 -380.461258) (xy 174.827904 -380.401535) (xy 174.86585 -380.345948)
			(xy 174.887636 -380.320296) (xy 174.893421 -380.313143) (xy 174.899942 -380.295958) (xy 174.900336 -380.286768)
			(xy 174.900336 -379.7935) (xy 174.899918 -379.784314) (xy 174.893409 -379.76713) (xy 174.887636 -379.759972)
			(xy 174.865896 -379.734281) (xy 174.827946 -379.6787) (xy 174.796911 -379.618982) (xy 174.773235 -379.555982)
			(xy 174.757259 -379.490605) (xy 174.749211 -379.423787) (xy 174.749207 -379.356486) (xy 174.757246 -379.289666)
			(xy 174.773214 -379.224287) (xy 174.796881 -379.161284) (xy 174.827909 -379.101562) (xy 174.865851 -379.045976)
			(xy 174.887636 -379.020324) (xy 174.893452 -379.013193) (xy 174.899954 -378.995991) (xy 174.900336 -378.986796)
			(xy 174.900336 -378.828554) (xy 174.900796 -378.818394) (xy 174.908585 -378.799624) (xy 174.922961 -378.78526)
			(xy 174.941737 -378.777487) (xy 174.951898 -378.776992) (xy 175.668178 -378.776992) (xy 175.678329 -378.77755)
			(xy 175.697089 -378.785309) (xy 175.711453 -378.799654) (xy 175.719237 -378.818404) (xy 175.71974 -378.828554)
			(xy 175.71974 -378.986796) (xy 175.720166 -378.995981) (xy 175.72667 -379.013165) (xy 175.73244 -379.020324)
			(xy 175.754276 -379.045937) (xy 175.792225 -379.101529) (xy 175.823257 -379.161257) (xy 175.846928 -379.224267)
			(xy 175.862898 -379.289654) (xy 175.870939 -379.356481) (xy 175.870934 -379.423791) (xy 175.862885 -379.490617)
			(xy 175.846907 -379.556002) (xy 175.823227 -379.619009) (xy 175.792187 -379.678734) (xy 175.754231 -379.73432)
			(xy 175.73244 -379.759972) (xy 175.726623 -379.767102) (xy 175.720122 -379.784305) (xy 175.71974 -379.7935)
			(xy 175.71974 -380.286768) (xy 175.720179 -380.295952) (xy 175.726674 -380.313136) (xy 175.73244 -380.320296)
			(xy 175.754248 -380.345932) (xy 175.792198 -380.40152) (xy 175.823231 -380.461246) (xy 175.846904 -380.524252)
			(xy 175.862876 -380.589637) (xy 175.870919 -380.656462) (xy 175.870917 -380.723769) (xy 175.862871 -380.790593)
			(xy 175.846895 -380.855977) (xy 175.823219 -380.918982) (xy 175.792182 -380.978706) (xy 175.75423 -381.034292)
			(xy 175.73244 -381.059944) (xy 175.726635 -381.067083) (xy 175.720127 -381.084278) (xy 175.71974 -381.093472)
			(xy 175.71974 -381.251206) (xy 175.71934 -381.261381) (xy 175.711549 -381.28018) (xy 175.697156 -381.294565)
			(xy 175.678353 -381.302346) (xy 175.668178 -381.302768) (xy 174.951898 -381.302768) (xy 174.941741 -381.302268)
			(xy 174.922973 -381.294494) (xy 174.908608 -381.280131) (xy 174.900832 -381.261363) (xy 174.900336 -381.251206)
			(xy 174.900336 -381.093472) (xy 174.899931 -381.084284) (xy 174.893413 -381.067101) (xy 174.887636 -381.059944)
			(xy 174.865868 -381.034275) (xy 174.827919 -380.978691) (xy 174.796885 -380.91897) (xy 174.773211 -380.855968)
			(xy 174.757237 -380.790587) (xy 174.749191 -380.723767) (xy 174.74919 -380.656463) (xy 171.471151 -380.656463)
			(xy 171.471149 -380.723828) (xy 171.46307 -380.790769) (xy 171.447031 -380.85626) (xy 171.423262 -380.919358)
			(xy 171.392106 -380.979154) (xy 171.354011 -381.034788) (xy 171.332144 -381.060452) (xy 171.326336 -381.067589)
			(xy 171.31983 -381.084786) (xy 171.319444 -381.09398) (xy 171.319444 -381.251206) (xy 171.318978 -381.261335)
			(xy 171.311245 -381.280059) (xy 171.296952 -381.294416) (xy 171.278263 -381.302232) (xy 171.268136 -381.302768)
			(xy 170.551856 -381.302768) (xy 170.541695 -381.302414) (xy 170.522936 -381.294598) (xy 170.508613 -381.28018)
			(xy 170.50092 -381.26137) (xy 170.500548 -381.251206) (xy 170.500548 -381.09398) (xy 170.500137 -381.084793)
			(xy 170.493623 -381.067609) (xy 170.487848 -381.060452) (xy 170.466002 -381.034771) (xy 170.42791 -380.97914)
			(xy 170.396755 -380.919347) (xy 170.372988 -380.856252) (xy 170.35695 -380.790764) (xy 170.348871 -380.723827)
			(xy 170.34887 -380.656403) (xy 167.070824 -380.656403) (xy 167.070831 -380.656462) (xy 167.070829 -380.723768)
			(xy 167.062783 -380.790592) (xy 167.046808 -380.855976) (xy 167.023133 -380.918981) (xy 166.992097 -380.978705)
			(xy 166.954145 -381.034292) (xy 166.932356 -381.059944) (xy 166.926553 -381.067084) (xy 166.920043 -381.084279)
			(xy 166.919656 -381.093472) (xy 166.919656 -381.251206) (xy 166.919171 -381.261365) (xy 166.911394 -381.280135)
			(xy 166.897025 -381.2945) (xy 166.878253 -381.302274) (xy 166.868094 -381.302768) (xy 166.151814 -381.302768)
			(xy 166.141644 -381.302325) (xy 166.122851 -381.294546) (xy 166.108466 -381.280166) (xy 166.100679 -381.261376)
			(xy 166.100252 -381.251206) (xy 166.100252 -381.093472) (xy 166.099844 -381.084285) (xy 166.093327 -381.067101)
			(xy 166.087552 -381.059944) (xy 166.065784 -381.034276) (xy 166.027833 -380.978692) (xy 165.996799 -380.918971)
			(xy 165.973124 -380.855968) (xy 165.957149 -380.790588) (xy 165.949103 -380.723767) (xy 165.949102 -380.656463)
			(xy 162.671063 -380.656463) (xy 162.671061 -380.723828) (xy 162.662983 -380.790768) (xy 162.646944 -380.856259)
			(xy 162.623176 -380.919357) (xy 162.59202 -380.979153) (xy 162.553927 -381.034787) (xy 162.53206 -381.060452)
			(xy 162.526254 -381.06759) (xy 162.519746 -381.084786) (xy 162.51936 -381.09398) (xy 162.51936 -381.251206)
			(xy 162.518878 -381.261333) (xy 162.511148 -381.280054) (xy 162.496861 -381.29441) (xy 162.478177 -381.302229)
			(xy 162.468052 -381.302768) (xy 161.751772 -381.302768) (xy 161.741644 -381.302406) (xy 161.722933 -381.294643)
			(xy 161.708619 -381.28031) (xy 161.70088 -381.261589) (xy 161.700464 -381.25146) (xy 161.700464 -381.09398)
			(xy 161.700049 -381.084794) (xy 161.693537 -381.06761) (xy 161.687764 -381.060452) (xy 161.665921 -381.03477)
			(xy 161.627834 -380.979137) (xy 161.596684 -380.919343) (xy 161.572921 -380.856248) (xy 161.556885 -380.790762)
			(xy 161.548808 -380.723826) (xy 161.548806 -380.656404) (xy 131.871003 -380.656404) (xy 131.87101 -380.656461)
			(xy 131.871008 -380.723769) (xy 131.862961 -380.790593) (xy 131.846985 -380.855977) (xy 131.823309 -380.918982)
			(xy 131.792271 -380.978706) (xy 131.754318 -381.034292) (xy 131.732528 -381.059944) (xy 131.726722 -381.067082)
			(xy 131.720215 -381.084278) (xy 131.719828 -381.093472) (xy 131.719828 -381.251206) (xy 131.71944 -381.261382)
			(xy 131.711647 -381.280184) (xy 131.69725 -381.294569) (xy 131.678443 -381.302348) (xy 131.668266 -381.302768)
			(xy 130.951986 -381.302768) (xy 130.941828 -381.302278) (xy 130.92306 -381.2945) (xy 130.908695 -381.280133)
			(xy 130.90092 -381.261364) (xy 130.900424 -381.251206) (xy 130.900424 -381.093472) (xy 130.900022 -381.084284)
			(xy 130.893502 -381.0671) (xy 130.887724 -381.059944) (xy 130.865956 -381.034276) (xy 130.828008 -380.978691)
			(xy 130.796975 -380.91897) (xy 130.773301 -380.855967) (xy 130.757327 -380.790587) (xy 130.749282 -380.723767)
			(xy 130.74928 -380.656463) (xy 127.471217 -380.656463) (xy 127.471215 -380.723827) (xy 127.463138 -380.790766)
			(xy 127.447101 -380.856256) (xy 127.423336 -380.919354) (xy 127.392185 -380.979151) (xy 127.354096 -381.034786)
			(xy 127.332232 -381.060452) (xy 127.326423 -381.067588) (xy 127.319918 -381.084786) (xy 127.319532 -381.09398)
			(xy 127.319532 -381.251206) (xy 127.319077 -381.261337) (xy 127.311342 -381.280063) (xy 127.297046 -381.29442)
			(xy 127.278352 -381.302234) (xy 127.268224 -381.302768) (xy 126.551944 -381.302768) (xy 126.541789 -381.302342)
			(xy 126.523031 -381.294555) (xy 126.508705 -381.280159) (xy 126.50101 -381.261363) (xy 126.500636 -381.251206)
			(xy 126.500636 -381.09398) (xy 126.500227 -381.084793) (xy 126.493712 -381.067609) (xy 126.487936 -381.060452)
			(xy 126.46609 -381.034771) (xy 126.427999 -380.97914) (xy 126.396845 -380.919346) (xy 126.373078 -380.856251)
			(xy 126.35704 -380.790764) (xy 126.348962 -380.723826) (xy 126.34896 -380.656404) (xy 123.070915 -380.656404)
			(xy 123.070922 -380.656462) (xy 123.07092 -380.723769) (xy 123.062874 -380.790593) (xy 123.046898 -380.855976)
			(xy 123.023223 -380.918982) (xy 122.992186 -380.978706) (xy 122.954234 -381.034292) (xy 122.932444 -381.059944)
			(xy 122.926639 -381.067083) (xy 122.920131 -381.084279) (xy 122.919744 -381.093472) (xy 122.919744 -381.251206)
			(xy 122.919341 -381.26138) (xy 122.91155 -381.280178) (xy 122.897158 -381.294564) (xy 122.878356 -381.302345)
			(xy 122.868182 -381.302768) (xy 122.151902 -381.302768) (xy 122.141745 -381.302265) (xy 122.122977 -381.294492)
			(xy 122.108612 -381.28013) (xy 122.100836 -381.261363) (xy 122.10034 -381.251206) (xy 122.10034 -381.093472)
			(xy 122.099934 -381.084285) (xy 122.093417 -381.067101) (xy 122.08764 -381.059944) (xy 122.065872 -381.034276)
			(xy 122.027923 -380.978691) (xy 121.996888 -380.91897) (xy 121.973215 -380.855968) (xy 121.95724 -380.790588)
			(xy 121.949194 -380.723767) (xy 121.949193 -380.656463) (xy 118.671154 -380.656463) (xy 118.671152 -380.723828)
			(xy 118.663073 -380.790769) (xy 118.647034 -380.85626) (xy 118.623265 -380.919357) (xy 118.592109 -380.979154)
			(xy 118.554015 -381.034788) (xy 118.532148 -381.060452) (xy 118.52634 -381.067589) (xy 118.519834 -381.084786)
			(xy 118.519448 -381.09398) (xy 118.519448 -381.251206) (xy 118.518978 -381.261335) (xy 118.511246 -381.280058)
			(xy 118.496954 -381.294415) (xy 118.478266 -381.302231) (xy 118.46814 -381.302768) (xy 117.75186 -381.302768)
			(xy 117.741699 -381.30241) (xy 117.72294 -381.294596) (xy 117.708617 -381.280179) (xy 117.700924 -381.261369)
			(xy 117.700552 -381.251206) (xy 117.700552 -381.09398) (xy 117.70014 -381.084793) (xy 117.693626 -381.06761)
			(xy 117.687852 -381.060452) (xy 117.666006 -381.034771) (xy 117.627913 -380.97914) (xy 117.596759 -380.919347)
			(xy 117.572991 -380.856252) (xy 117.556953 -380.790764) (xy 117.548874 -380.723827) (xy 117.548873 -380.656403)
			(xy 106.626557 -380.656403) (xy 106.614052 -380.67809) (xy 106.590457 -380.701723) (xy 106.561555 -380.718453)
			(xy 106.52931 -380.727141) (xy 106.512614 -380.727712) (xy 106.258106 -380.727712) (xy 106.241375 -380.727212)
			(xy 106.20905 -380.718562) (xy 106.180062 -380.701847) (xy 106.156381 -380.678205) (xy 106.139619 -380.649244)
			(xy 106.130915 -380.616934) (xy 106.130344 -380.600204) (xy 105.919524 -380.600204) (xy 105.919524 -380.877572)
			(xy 105.919034 -380.907556) (xy 105.911206 -380.967012) (xy 105.895685 -381.024937) (xy 105.872736 -381.080341)
			(xy 105.842752 -381.132275) (xy 105.806246 -381.179851) (xy 105.763841 -381.222256) (xy 105.716265 -381.258762)
			(xy 105.664331 -381.288746) (xy 105.608927 -381.311695) (xy 105.551002 -381.327216) (xy 105.491546 -381.335044)
			(xy 105.431578 -381.335044) (xy 105.372122 -381.327216) (xy 105.314197 -381.311695) (xy 105.258793 -381.288746)
			(xy 105.206859 -381.258762) (xy 105.159283 -381.222256) (xy 105.116878 -381.179851) (xy 105.080372 -381.132275)
			(xy 105.050388 -381.080341) (xy 105.027439 -381.024937) (xy 105.011918 -380.967012) (xy 105.00409 -380.907556)
			(xy 105.0036 -380.877572) (xy 87.838954 -380.877572) (xy 87.823216 -380.919355) (xy 87.792063 -380.979152)
			(xy 87.753973 -381.034787) (xy 87.732108 -381.060452) (xy 87.726308 -381.067595) (xy 87.719795 -381.084787)
			(xy 87.719408 -381.09398) (xy 87.719408 -381.251206) (xy 87.71888 -381.261327) (xy 87.711159 -381.280039)
			(xy 87.696886 -381.294394) (xy 87.678218 -381.302221) (xy 87.6681 -381.302768) (xy 86.95182 -381.302768)
			(xy 86.941695 -381.302367) (xy 86.922985 -381.294619) (xy 86.908669 -381.280298) (xy 86.900929 -381.261585)
			(xy 86.900512 -381.25146) (xy 86.900512 -381.09398) (xy 86.900109 -381.084792) (xy 86.89359 -381.067608)
			(xy 86.887812 -381.060452) (xy 86.865967 -381.034771) (xy 86.827877 -380.979139) (xy 86.796725 -380.919345)
			(xy 86.772959 -380.85625) (xy 86.756922 -380.790763) (xy 86.748844 -380.723826) (xy 86.748842 -380.656404)
			(xy 83.470797 -380.656404) (xy 83.470804 -380.656461) (xy 83.470802 -380.723769) (xy 83.462755 -380.790593)
			(xy 83.446779 -380.855977) (xy 83.423102 -380.918983) (xy 83.392064 -380.978706) (xy 83.35411 -381.034292)
			(xy 83.33232 -381.059944) (xy 83.326525 -381.06709) (xy 83.320009 -381.08428) (xy 83.31962 -381.093472)
			(xy 83.31962 -381.251206) (xy 83.31924 -381.261383) (xy 83.311445 -381.280186) (xy 83.297046 -381.294572)
			(xy 83.278236 -381.302349) (xy 83.268058 -381.302768) (xy 82.551778 -381.302768) (xy 82.54162 -381.302285)
			(xy 82.522851 -381.294504) (xy 82.508487 -381.280136) (xy 82.500712 -381.261365) (xy 82.500216 -381.251206)
			(xy 82.500216 -381.093472) (xy 82.499816 -381.084284) (xy 82.493295 -381.0671) (xy 82.487516 -381.059944)
			(xy 82.465749 -381.034275) (xy 82.427801 -380.978691) (xy 82.396768 -380.918969) (xy 82.373095 -380.855967)
			(xy 82.357121 -380.790587) (xy 82.349076 -380.723767) (xy 82.349074 -380.656464) (xy 79.071011 -380.656464)
			(xy 79.071009 -380.723827) (xy 79.062932 -380.790767) (xy 79.046895 -380.856256) (xy 79.02313 -380.919354)
			(xy 78.991978 -380.979151) (xy 78.953888 -381.034786) (xy 78.932024 -381.060452) (xy 78.926226 -381.067596)
			(xy 78.919711 -381.084787) (xy 78.919324 -381.09398) (xy 78.919324 -381.251206) (xy 78.918877 -381.261337)
			(xy 78.911141 -381.280066) (xy 78.896842 -381.294423) (xy 78.878145 -381.302235) (xy 78.868016 -381.302768)
			(xy 78.151736 -381.302768) (xy 78.141612 -381.302354) (xy 78.122903 -381.294611) (xy 78.108586 -381.280294)
			(xy 78.100846 -381.261584) (xy 78.100428 -381.25146) (xy 78.100428 -381.09398) (xy 78.100021 -381.084793)
			(xy 78.093505 -381.067609) (xy 78.087728 -381.060452) (xy 78.065883 -381.034771) (xy 78.027792 -380.979139)
			(xy 77.996638 -380.919346) (xy 77.972872 -380.856251) (xy 77.956834 -380.790763) (xy 77.948756 -380.723826)
			(xy 77.948754 -380.656404) (xy 74.670709 -380.656404) (xy 74.670716 -380.656462) (xy 74.670714 -380.723769)
			(xy 74.662667 -380.790593) (xy 74.646691 -380.855977) (xy 74.623015 -380.918982) (xy 74.591978 -380.978706)
			(xy 74.554026 -381.034292) (xy 74.532236 -381.059944) (xy 74.52643 -381.067082) (xy 74.519923 -381.084278)
			(xy 74.519536 -381.093472) (xy 74.519536 -381.251206) (xy 74.51914 -381.261381) (xy 74.511349 -381.280181)
			(xy 74.496954 -381.294567) (xy 74.478149 -381.302347) (xy 74.467974 -381.302768) (xy 73.751694 -381.302768)
			(xy 73.741537 -381.302272) (xy 73.722769 -381.294496) (xy 73.708404 -381.280131) (xy 73.700628 -381.261363)
			(xy 73.700132 -381.251206) (xy 73.700132 -381.093472) (xy 73.699728 -381.084284) (xy 73.693209 -381.0671)
			(xy 73.687432 -381.059944) (xy 73.665664 -381.034275) (xy 73.627715 -380.978691) (xy 73.596682 -380.91897)
			(xy 73.573008 -380.855967) (xy 73.557034 -380.790587) (xy 73.548988 -380.723767) (xy 73.548987 -380.656463)
			(xy 43.87119 -380.656463) (xy 43.871188 -380.723828) (xy 43.86311 -380.790767) (xy 43.847073 -380.856258)
			(xy 43.823306 -380.919355) (xy 43.792153 -380.979152) (xy 43.754061 -381.034787) (xy 43.732196 -381.060452)
			(xy 43.726394 -381.067594) (xy 43.719883 -381.084787) (xy 43.719496 -381.09398) (xy 43.719496 -381.251206)
			(xy 43.718979 -381.261329) (xy 43.711256 -381.280043) (xy 43.69698 -381.294398) (xy 43.678308 -381.302223)
			(xy 43.668188 -381.302768) (xy 42.951908 -381.302768) (xy 42.94175 -381.302371) (xy 42.922992 -381.294572)
			(xy 42.908667 -381.280167) (xy 42.900973 -381.261366) (xy 42.9006 -381.251206) (xy 42.9006 -381.09398)
			(xy 42.9002 -381.084792) (xy 42.893679 -381.067607) (xy 42.8879 -381.060452) (xy 42.866056 -381.034771)
			(xy 42.827966 -380.979138) (xy 42.796815 -380.919344) (xy 42.773049 -380.85625) (xy 42.757013 -380.790763)
			(xy 42.748935 -380.723826) (xy 42.748933 -380.656404) (xy 39.470887 -380.656404) (xy 39.470894 -380.656461)
			(xy 39.470893 -380.723769) (xy 39.462846 -380.790594) (xy 39.446869 -380.855978) (xy 39.423192 -380.918983)
			(xy 39.392153 -380.978707) (xy 39.354199 -381.034293) (xy 39.332408 -381.059944) (xy 39.326611 -381.067089)
			(xy 39.320096 -381.08428) (xy 39.319708 -381.093472) (xy 39.319708 -381.251206) (xy 39.319173 -381.261358)
			(xy 39.311405 -381.280119) (xy 39.297052 -381.294482) (xy 39.278298 -381.302265) (xy 39.268146 -381.302768)
			(xy 38.551866 -381.302768) (xy 38.541707 -381.302295) (xy 38.522938 -381.29451) (xy 38.508574 -381.280138)
			(xy 38.5008 -381.261365) (xy 38.500304 -381.251206) (xy 38.500304 -381.093472) (xy 38.499907 -381.084283)
			(xy 38.493384 -381.067099) (xy 38.487604 -381.059944) (xy 38.465837 -381.034275) (xy 38.42789 -380.97869)
			(xy 38.396858 -380.918969) (xy 38.373185 -380.855966) (xy 38.357212 -380.790587) (xy 38.349167 -380.723766)
			(xy 38.349165 -380.656464) (xy 35.071102 -380.656464) (xy 35.0711 -380.723828) (xy 35.063023 -380.790767)
			(xy 35.046985 -380.856257) (xy 35.023219 -380.919355) (xy 34.992067 -380.979151) (xy 34.953977 -381.034787)
			(xy 34.932112 -381.060452) (xy 34.926312 -381.067595) (xy 34.919799 -381.084787) (xy 34.919412 -381.09398)
			(xy 34.919412 -381.251206) (xy 34.91888 -381.261327) (xy 34.91116 -381.280038) (xy 34.896888 -381.294392)
			(xy 34.878222 -381.30222) (xy 34.868104 -381.302768) (xy 34.151824 -381.302768) (xy 34.141667 -381.302358)
			(xy 34.122909 -381.294565) (xy 34.108584 -381.280164) (xy 34.100889 -381.261365) (xy 34.100516 -381.251206)
			(xy 34.100516 -381.09398) (xy 34.100112 -381.084792) (xy 34.093594 -381.067608) (xy 34.087816 -381.060452)
			(xy 34.065971 -381.034771) (xy 34.027881 -380.979139) (xy 33.996728 -380.919345) (xy 33.972962 -380.85625)
			(xy 33.956925 -380.790763) (xy 33.948847 -380.723826) (xy 33.948845 -380.656404) (xy 30.6708 -380.656404)
			(xy 30.670807 -380.656461) (xy 30.670805 -380.723769) (xy 30.662758 -380.790593) (xy 30.646782 -380.855977)
			(xy 30.623105 -380.918982) (xy 30.592068 -380.978706) (xy 30.554114 -381.034292) (xy 30.532324 -381.059944)
			(xy 30.526529 -381.067091) (xy 30.520013 -381.08428) (xy 30.519624 -381.093472) (xy 30.519624 -381.251206)
			(xy 30.51924 -381.261383) (xy 30.511446 -381.280185) (xy 30.497048 -381.294571) (xy 30.478239 -381.302349)
			(xy 30.468062 -381.302768) (xy 29.751782 -381.302768) (xy 29.741624 -381.302282) (xy 29.722855 -381.294502)
			(xy 29.708491 -381.280135) (xy 29.700716 -381.261364) (xy 29.70022 -381.251206) (xy 29.70022 -381.093472)
			(xy 29.699819 -381.084284) (xy 29.693298 -381.0671) (xy 29.68752 -381.059944) (xy 29.665752 -381.034276)
			(xy 29.627804 -380.978691) (xy 29.596771 -380.918969) (xy 29.573098 -380.855967) (xy 29.557124 -380.790587)
			(xy 29.549079 -380.723767) (xy 29.549077 -380.656463) (xy 29.557119 -380.589643) (xy 29.573089 -380.524262)
			(xy 29.596759 -380.461258) (xy 29.627789 -380.401535) (xy 29.665734 -380.345948) (xy 29.68752 -380.320296)
			(xy 29.693303 -380.313141) (xy 29.699825 -380.295958) (xy 29.70022 -380.286768) (xy 29.70022 -379.7935)
			(xy 29.699806 -379.784313) (xy 29.693295 -379.767129) (xy 29.68752 -379.759972) (xy 29.66573 -379.734322)
			(xy 29.627781 -379.678735) (xy 29.596748 -379.619011) (xy 29.573075 -379.556006) (xy 29.557102 -379.490624)
			(xy 29.549058 -379.423801) (xy 28.447 -379.423801) (xy 28.447041 -379.423909) (xy 28.463077 -379.489397)
			(xy 28.471153 -379.556335) (xy 28.471153 -379.623759) (xy 28.463078 -379.690697) (xy 28.447043 -379.756186)
			(xy 28.423279 -379.819282) (xy 28.392128 -379.879078) (xy 28.35404 -379.934713) (xy 28.332176 -379.960378)
			(xy 28.326361 -379.96751) (xy 28.319858 -379.984711) (xy 28.319476 -379.993906) (xy 28.319476 -380.151386)
			(xy 28.318962 -380.16151) (xy 28.311242 -380.180228) (xy 28.296964 -380.194584) (xy 28.278289 -380.202406)
			(xy 28.268168 -380.202948) (xy 27.551888 -380.202948) (xy 27.541784 -380.202426) (xy 27.523115 -380.194693)
			(xy 27.508823 -380.180408) (xy 27.50108 -380.161743) (xy 27.50058 -380.15164) (xy 27.50058 -379.993906)
			(xy 27.500171 -379.984719) (xy 27.493657 -379.967534) (xy 27.48788 -379.960378) (xy 27.466012 -379.934716)
			(xy 27.427923 -379.879081) (xy 27.396771 -379.819285) (xy 27.373007 -379.756187) (xy 27.356972 -379.690698)
			(xy 27.348896 -379.623759) (xy 27.348896 -379.556335) (xy 27.356973 -379.489396) (xy 27.373009 -379.423907)
			(xy 27.396774 -379.36081) (xy 27.427926 -379.301013) (xy 27.466015 -379.245379) (xy 27.48788 -379.219714)
			(xy 27.493693 -379.21258) (xy 27.500199 -379.195381) (xy 27.50058 -379.186186) (xy 27.50058 -378.693934)
			(xy 27.500158 -378.684748) (xy 27.493653 -378.667563) (xy 27.48788 -378.660406) (xy 27.465991 -378.634761)
			(xy 27.427905 -378.579124) (xy 27.396756 -378.519324) (xy 27.372994 -378.456225) (xy 27.356961 -378.390733)
			(xy 27.348888 -378.323793) (xy 0.509016 -378.323793) (xy 0.509016 -381.424942) (xy 104.262936 -381.424942)
			(xy 104.262936 -381.223774) (xy 104.263462 -381.207025) (xy 104.272137 -381.174669) (xy 104.28889 -381.14566)
			(xy 104.31258 -381.121976) (xy 104.341591 -381.105228) (xy 104.373949 -381.096558) (xy 104.390698 -381.096012)
			(xy 104.644698 -381.096012) (xy 104.661444 -381.096586) (xy 104.693795 -381.105253) (xy 104.722801 -381.121997)
			(xy 104.746486 -381.145676) (xy 104.763236 -381.174679) (xy 104.77191 -381.207028) (xy 104.77246 -381.223774)
			(xy 104.77246 -381.400304) (xy 106.130344 -381.400304) (xy 106.130344 -381.199136) (xy 106.130965 -381.182448)
			(xy 106.139583 -381.150203) (xy 106.156243 -381.121282) (xy 106.179813 -381.09765) (xy 106.20869 -381.080913)
			(xy 106.240911 -381.07221) (xy 106.257598 -381.071628) (xy 106.512106 -381.071628) (xy 106.528833 -381.072176)
			(xy 106.561149 -381.080824) (xy 106.590131 -381.097532) (xy 106.61381 -381.121163) (xy 106.630576 -381.150112)
			(xy 106.63929 -381.18241) (xy 106.639868 -381.199136) (xy 106.639868 -381.400304) (xy 106.639368 -381.417001)
			(xy 106.630733 -381.44926) (xy 106.614052 -381.47819) (xy 106.590457 -381.501823) (xy 106.561555 -381.518553)
			(xy 106.52931 -381.527241) (xy 106.512614 -381.527812) (xy 106.258106 -381.527812) (xy 106.241375 -381.527312)
			(xy 106.20905 -381.518662) (xy 106.180062 -381.501947) (xy 106.156381 -381.478305) (xy 106.139619 -381.449344)
			(xy 106.130915 -381.417034) (xy 106.130344 -381.400304) (xy 104.77246 -381.400304) (xy 104.77246 -381.424942)
			(xy 104.771952 -381.441692) (xy 104.763273 -381.474049) (xy 104.746516 -381.503058) (xy 104.722823 -381.526743)
			(xy 104.693808 -381.54349) (xy 104.661448 -381.552158) (xy 104.644698 -381.552704) (xy 104.390698 -381.552704)
			(xy 104.373953 -381.552117) (xy 104.341604 -381.543451) (xy 104.3126 -381.526709) (xy 104.288915 -381.503032)
			(xy 104.272164 -381.474033) (xy 104.263488 -381.441687) (xy 104.262936 -381.424942) (xy 0.509016 -381.424942)
			(xy 0.509016 -382.269746) (xy 10.309352 -382.269746) (xy 10.309352 -381.923798) (xy 10.309834 -381.907042)
			(xy 10.318509 -381.874672) (xy 10.335266 -381.845651) (xy 10.358964 -381.821956) (xy 10.387987 -381.805202)
			(xy 10.420358 -381.796532) (xy 10.437114 -381.796036) (xy 10.923016 -381.796036) (xy 10.939763 -381.796477)
			(xy 10.972111 -381.805162) (xy 11.001103 -381.821934) (xy 11.024758 -381.845647) (xy 11.041458 -381.87468)
			(xy 11.050063 -381.90705) (xy 11.050524 -381.923798) (xy 11.050524 -382.223705) (xy 27.348899 -382.223705)
			(xy 27.3489 -382.15628) (xy 27.356976 -382.089342) (xy 27.373012 -382.023853) (xy 27.396777 -381.960755)
			(xy 27.427928 -381.900959) (xy 27.466016 -381.845324) (xy 27.48788 -381.819658) (xy 27.493675 -381.812511)
			(xy 27.500191 -381.795322) (xy 27.50058 -381.78613) (xy 27.50058 -381.628904) (xy 27.501088 -381.618798)
			(xy 27.508821 -381.600124) (xy 27.52311 -381.58583) (xy 27.541782 -381.578091) (xy 27.551888 -381.577596)
			(xy 28.268168 -381.577596) (xy 28.278288 -381.578042) (xy 28.29699 -381.585779) (xy 28.311306 -381.600086)
			(xy 28.319053 -381.618784) (xy 28.319476 -381.628904) (xy 28.319476 -381.78613) (xy 28.319877 -381.795318)
			(xy 28.326398 -381.812502) (xy 28.332176 -381.819658) (xy 28.354031 -381.845331) (xy 28.392122 -381.900964)
			(xy 28.423274 -381.960759) (xy 28.44704 -382.023855) (xy 28.463077 -382.089343) (xy 28.471154 -382.156281)
			(xy 28.471155 -382.223646) (xy 31.749194 -382.223646) (xy 31.749195 -382.156339) (xy 31.757241 -382.089516)
			(xy 31.773216 -382.024132) (xy 31.796891 -381.961127) (xy 31.827927 -381.901404) (xy 31.865879 -381.845818)
			(xy 31.887668 -381.820166) (xy 31.89347 -381.813025) (xy 31.899979 -381.795831) (xy 31.900368 -381.786638)
			(xy 31.900368 -381.628904) (xy 31.900824 -381.618754) (xy 31.908613 -381.600008) (xy 31.922998 -381.585686)
			(xy 31.941778 -381.57798) (xy 31.95193 -381.577596) (xy 32.66821 -381.577596) (xy 32.678332 -381.578117)
			(xy 32.697045 -381.58584) (xy 32.711399 -381.600115) (xy 32.719226 -381.618785) (xy 32.719772 -381.628904)
			(xy 32.719772 -381.786638) (xy 32.72017 -381.795826) (xy 32.726693 -381.81301) (xy 32.732472 -381.820166)
			(xy 32.75425 -381.845826) (xy 32.792198 -381.901412) (xy 32.823231 -381.961134) (xy 32.846904 -382.024138)
			(xy 32.862877 -382.089519) (xy 32.870922 -382.15634) (xy 32.870923 -382.223645) (xy 32.870916 -382.223704)
			(xy 36.148987 -382.223704) (xy 36.148988 -382.156281) (xy 36.157064 -382.089342) (xy 36.1731 -382.023853)
			(xy 36.196863 -381.960756) (xy 36.228013 -381.900959) (xy 36.266101 -381.845324) (xy 36.287964 -381.819658)
			(xy 36.293769 -381.812519) (xy 36.300277 -381.795323) (xy 36.300664 -381.78613) (xy 36.300664 -381.628904)
			(xy 36.301188 -381.6188) (xy 36.308917 -381.600129) (xy 36.323202 -381.585835) (xy 36.341868 -381.578094)
			(xy 36.351972 -381.577596) (xy 37.068252 -381.577596) (xy 37.078371 -381.578055) (xy 37.097073 -381.585787)
			(xy 37.111388 -381.60009) (xy 37.119136 -381.618786) (xy 37.11956 -381.628904) (xy 37.11956 -381.78613)
			(xy 37.119965 -381.795318) (xy 37.126483 -381.812501) (xy 37.13226 -381.819658) (xy 37.154116 -381.845331)
			(xy 37.192207 -381.900963) (xy 37.223361 -381.960758) (xy 37.247127 -382.023854) (xy 37.263164 -382.089343)
			(xy 37.271242 -382.156281) (xy 37.271243 -382.223704) (xy 37.271243 -382.223705) (xy 40.548753 -382.223705)
			(xy 40.548754 -382.15628) (xy 40.556832 -382.08934) (xy 40.57287 -382.02385) (xy 40.596638 -381.960752)
			(xy 40.627792 -381.900956) (xy 40.665886 -381.845322) (xy 40.687752 -381.819658) (xy 40.693555 -381.812518)
			(xy 40.700065 -381.795323) (xy 40.700452 -381.78613) (xy 40.700452 -381.628904) (xy 40.700987 -381.618801)
			(xy 40.708715 -381.600133) (xy 40.722996 -381.585839) (xy 40.741658 -381.578096) (xy 40.75176 -381.577596)
			(xy 41.46804 -381.577596) (xy 41.478151 -381.578052) (xy 41.496829 -381.585802) (xy 41.511122 -381.600108)
			(xy 41.518856 -381.618793) (xy 41.519348 -381.628904) (xy 41.519348 -381.78613) (xy 41.519755 -381.795317)
			(xy 41.526272 -381.812501) (xy 41.532048 -381.819658) (xy 41.553904 -381.84533) (xy 41.591996 -381.900963)
			(xy 41.62315 -381.960757) (xy 41.646917 -382.023853) (xy 41.662955 -382.089342) (xy 41.671033 -382.156281)
			(xy 41.671034 -382.223645) (xy 44.949073 -382.223645) (xy 44.949074 -382.15634) (xy 44.957119 -382.089516)
			(xy 44.973093 -382.024133) (xy 44.996767 -381.961128) (xy 45.027801 -381.901405) (xy 45.065751 -381.845818)
			(xy 45.08754 -381.820166) (xy 45.093339 -381.813022) (xy 45.099851 -381.795831) (xy 45.10024 -381.786638)
			(xy 45.10024 -381.628904) (xy 45.100626 -381.618745) (xy 45.108427 -381.599985) (xy 45.122836 -381.58566)
			(xy 45.141641 -381.577968) (xy 45.151802 -381.577596) (xy 45.868082 -381.577596) (xy 45.878202 -381.57814)
			(xy 45.896915 -381.585854) (xy 45.91127 -381.600122) (xy 45.919098 -381.618787) (xy 45.919644 -381.628904)
			(xy 45.919644 -381.786638) (xy 45.920049 -381.795826) (xy 45.926568 -381.813009) (xy 45.932344 -381.820166)
			(xy 45.954122 -381.845826) (xy 45.992072 -381.901411) (xy 46.023107 -381.961133) (xy 46.046781 -382.024137)
			(xy 46.062755 -382.089518) (xy 46.070801 -382.15634) (xy 46.070801 -382.223645) (xy 46.070794 -382.223705)
			(xy 71.348808 -382.223705) (xy 71.348809 -382.15628) (xy 71.356886 -382.089342) (xy 71.372922 -382.023852)
			(xy 71.396687 -381.960755) (xy 71.427838 -381.900958) (xy 71.465928 -381.845323) (xy 71.487792 -381.819658)
			(xy 71.493588 -381.812512) (xy 71.500103 -381.795322) (xy 71.500492 -381.78613) (xy 71.500492 -381.628904)
			(xy 71.500919 -381.618783) (xy 71.508664 -381.600081) (xy 71.522977 -381.585767) (xy 71.541679 -381.57802)
			(xy 71.5518 -381.577596) (xy 72.26808 -381.577596) (xy 72.278201 -381.578032) (xy 72.296903 -381.585773)
			(xy 72.311218 -381.600083) (xy 72.318965 -381.618783) (xy 72.319388 -381.628904) (xy 72.319388 -381.78613)
			(xy 72.319786 -381.795318) (xy 72.326308 -381.812503) (xy 72.332088 -381.819658) (xy 72.353943 -381.845331)
			(xy 72.392032 -381.900964) (xy 72.423184 -381.960759) (xy 72.446949 -382.023855) (xy 72.462986 -382.089343)
			(xy 72.471063 -382.156281) (xy 72.471064 -382.223646) (xy 75.749104 -382.223646) (xy 75.749104 -382.156339)
			(xy 75.75715 -382.089515) (xy 75.773125 -382.024132) (xy 75.796801 -381.961127) (xy 75.827838 -381.901403)
			(xy 75.86579 -381.845818) (xy 75.88758 -381.820166) (xy 75.893371 -381.813017) (xy 75.89989 -381.795829)
			(xy 75.90028 -381.786638) (xy 75.90028 -381.628904) (xy 75.900725 -381.618753) (xy 75.908515 -381.600004)
			(xy 75.922904 -381.585681) (xy 75.941689 -381.577978) (xy 75.951842 -381.577596) (xy 76.668122 -381.577596)
			(xy 76.678245 -381.578107) (xy 76.696958 -381.585834) (xy 76.711312 -381.600112) (xy 76.719138 -381.618784)
			(xy 76.719684 -381.628904) (xy 76.719684 -381.786638) (xy 76.720079 -381.795827) (xy 76.726604 -381.813011)
			(xy 76.732384 -381.820166) (xy 76.754161 -381.845826) (xy 76.792109 -381.901412) (xy 76.823141 -381.961135)
			(xy 76.846814 -382.024138) (xy 76.862787 -382.089519) (xy 76.870831 -382.156341) (xy 76.870832 -382.223644)
			(xy 76.870825 -382.223704) (xy 80.148896 -382.223704) (xy 80.148897 -382.15628) (xy 80.156973 -382.089342)
			(xy 80.173009 -382.023853) (xy 80.196773 -381.960755) (xy 80.227924 -381.900959) (xy 80.266012 -381.845324)
			(xy 80.287876 -381.819658) (xy 80.29367 -381.812511) (xy 80.300187 -381.795322) (xy 80.300576 -381.78613)
			(xy 80.300576 -381.628904) (xy 80.301088 -381.618798) (xy 80.30882 -381.600125) (xy 80.323108 -381.585831)
			(xy 80.341779 -381.578092) (xy 80.351884 -381.577596) (xy 81.068164 -381.577596) (xy 81.078284 -381.578046)
			(xy 81.096986 -381.585781) (xy 81.111301 -381.600087) (xy 81.119048 -381.618785) (xy 81.119472 -381.628904)
			(xy 81.119472 -381.78613) (xy 81.119874 -381.795318) (xy 81.126394 -381.812502) (xy 81.132172 -381.819658)
			(xy 81.154027 -381.845331) (xy 81.192118 -381.900964) (xy 81.223271 -381.960759) (xy 81.247037 -382.023854)
			(xy 81.263074 -382.089343) (xy 81.271151 -382.156281) (xy 81.271152 -382.223704) (xy 84.548687 -382.223704)
			(xy 84.548688 -382.156281) (xy 84.556764 -382.089342) (xy 84.5728 -382.023853) (xy 84.596563 -381.960756)
			(xy 84.627713 -381.900959) (xy 84.665801 -381.845324) (xy 84.687664 -381.819658) (xy 84.693469 -381.812519)
			(xy 84.699977 -381.795323) (xy 84.700364 -381.78613) (xy 84.700364 -381.628904) (xy 84.700888 -381.6188)
			(xy 84.708617 -381.600129) (xy 84.722902 -381.585835) (xy 84.741568 -381.578094) (xy 84.751672 -381.577596)
			(xy 85.467952 -381.577596) (xy 85.478071 -381.578055) (xy 85.496773 -381.585787) (xy 85.511088 -381.60009)
			(xy 85.518836 -381.618786) (xy 85.51926 -381.628904) (xy 85.51926 -381.78613) (xy 85.519665 -381.795318)
			(xy 85.526183 -381.812501) (xy 85.53196 -381.819658) (xy 85.553816 -381.845331) (xy 85.591907 -381.900963)
			(xy 85.623061 -381.960758) (xy 85.646827 -382.023854) (xy 85.662864 -382.089343) (xy 85.670942 -382.156281)
			(xy 85.670943 -382.223646) (xy 88.948982 -382.223646) (xy 88.948983 -382.156339) (xy 88.957028 -382.089516)
			(xy 88.973003 -382.024133) (xy 88.996677 -381.961128) (xy 89.027712 -381.901404) (xy 89.065663 -381.845818)
			(xy 89.087452 -381.820166) (xy 89.093252 -381.813023) (xy 89.099763 -381.795831) (xy 89.100152 -381.786638)
			(xy 89.100152 -381.628904) (xy 89.100624 -381.618756) (xy 89.108409 -381.600013) (xy 89.12279 -381.585691)
			(xy 89.141564 -381.577983) (xy 89.151714 -381.577596) (xy 89.867994 -381.577596) (xy 89.878115 -381.57813)
			(xy 89.896828 -381.585848) (xy 89.911183 -381.600119) (xy 89.91901 -381.618786) (xy 89.919556 -381.628904)
			(xy 89.919556 -381.786638) (xy 89.919958 -381.795826) (xy 89.926478 -381.81301) (xy 89.932256 -381.820166)
			(xy 89.954034 -381.845826) (xy 89.991983 -381.901411) (xy 90.023017 -381.961134) (xy 90.046691 -382.024137)
			(xy 90.062665 -382.089519) (xy 90.07071 -382.15634) (xy 90.070711 -382.223645) (xy 115.349246 -382.223645)
			(xy 115.349247 -382.15634) (xy 115.357291 -382.089517) (xy 115.373264 -382.024135) (xy 115.396937 -381.96113)
			(xy 115.427969 -381.901406) (xy 115.465917 -381.845819) (xy 115.487704 -381.820166) (xy 115.493498 -381.813019)
			(xy 115.500014 -381.79583) (xy 115.500404 -381.786638) (xy 115.500404 -381.628904) (xy 115.500825 -381.61875)
			(xy 115.50862 -381.599997) (xy 115.523017 -381.585673) (xy 115.54181 -381.577974) (xy 115.551966 -381.577596)
			(xy 116.268246 -381.577596) (xy 116.27837 -381.578088) (xy 116.297084 -381.585822) (xy 116.311437 -381.600106)
			(xy 116.319262 -381.618782) (xy 116.319808 -381.628904) (xy 116.319808 -381.786638) (xy 116.320198 -381.795827)
			(xy 116.326725 -381.813012) (xy 116.332508 -381.820166) (xy 116.354288 -381.845826) (xy 116.39224 -381.90141)
			(xy 116.423277 -381.961132) (xy 116.446952 -382.024135) (xy 116.462928 -382.089517) (xy 116.470973 -382.15634)
			(xy 116.470974 -382.223645) (xy 116.470967 -382.223705) (xy 119.749014 -382.223705) (xy 119.749015 -382.15628)
			(xy 119.757092 -382.089341) (xy 119.773128 -382.023852) (xy 119.796894 -381.960754) (xy 119.828046 -381.900958)
			(xy 119.866135 -381.845323) (xy 119.888 -381.819658) (xy 119.893797 -381.812513) (xy 119.900311 -381.795322)
			(xy 119.9007 -381.78613) (xy 119.9007 -381.628904) (xy 119.901119 -381.618782) (xy 119.908866 -381.600078)
			(xy 119.923182 -381.585764) (xy 119.941886 -381.578019) (xy 119.952008 -381.577596) (xy 120.668288 -381.577596)
			(xy 120.678409 -381.578026) (xy 120.697112 -381.585769) (xy 120.711426 -381.600081) (xy 120.719173 -381.618783)
			(xy 120.719596 -381.628904) (xy 120.719596 -381.78613) (xy 120.719992 -381.795319) (xy 120.726516 -381.812503)
			(xy 120.732296 -381.819658) (xy 120.75415 -381.845331) (xy 120.79224 -381.900965) (xy 120.823391 -381.96076)
			(xy 120.847156 -382.023855) (xy 120.863192 -382.089344) (xy 120.871269 -382.156281) (xy 120.87127 -382.223646)
			(xy 124.14931 -382.223646) (xy 124.14931 -382.156339) (xy 124.157356 -382.089515) (xy 124.173332 -382.024132)
			(xy 124.197008 -381.961127) (xy 124.228045 -381.901403) (xy 124.265998 -381.845818) (xy 124.287788 -381.820166)
			(xy 124.29358 -381.813018) (xy 124.300098 -381.79583) (xy 124.300488 -381.786638) (xy 124.300488 -381.628904)
			(xy 124.300925 -381.618752) (xy 124.308717 -381.600002) (xy 124.323109 -381.585679) (xy 124.341896 -381.577977)
			(xy 124.35205 -381.577596) (xy 125.06833 -381.577596) (xy 125.078453 -381.578101) (xy 125.097167 -381.58583)
			(xy 125.11152 -381.60011) (xy 125.119346 -381.618783) (xy 125.119892 -381.628904) (xy 125.119892 -381.786638)
			(xy 125.120286 -381.795827) (xy 125.126811 -381.813011) (xy 125.132592 -381.820166) (xy 125.154369 -381.845827)
			(xy 125.192316 -381.901413) (xy 125.223348 -381.961135) (xy 125.24702 -382.024139) (xy 125.262993 -382.089519)
			(xy 125.271037 -382.156341) (xy 125.271038 -382.223644) (xy 125.271038 -382.223646) (xy 128.5491 -382.223646)
			(xy 128.549101 -382.156339) (xy 128.557147 -382.089515) (xy 128.573122 -382.024132) (xy 128.596798 -381.961127)
			(xy 128.627834 -381.901404) (xy 128.665787 -381.845818) (xy 128.687576 -381.820166) (xy 128.693367 -381.813016)
			(xy 128.699886 -381.795829) (xy 128.700276 -381.786638) (xy 128.700276 -381.628904) (xy 128.700724 -381.618753)
			(xy 128.708514 -381.600005) (xy 128.722902 -381.585683) (xy 128.741685 -381.577979) (xy 128.751838 -381.577596)
			(xy 129.468118 -381.577596) (xy 129.47824 -381.57811) (xy 129.496954 -381.585836) (xy 129.511308 -381.600113)
			(xy 129.519134 -381.618784) (xy 129.51968 -381.628904) (xy 129.51968 -381.786638) (xy 129.520076 -381.795827)
			(xy 129.5266 -381.813011) (xy 129.53238 -381.820166) (xy 129.554157 -381.845826) (xy 129.592105 -381.901412)
			(xy 129.623138 -381.961135) (xy 129.64681 -382.024138) (xy 129.662784 -382.089519) (xy 129.670828 -382.156341)
			(xy 129.670829 -382.223644) (xy 129.670829 -382.223645) (xy 159.349155 -382.223645) (xy 159.349156 -382.15634)
			(xy 159.3572 -382.089517) (xy 159.373174 -382.024134) (xy 159.396847 -381.96113) (xy 159.42788 -381.901406)
			(xy 159.465828 -381.845818) (xy 159.487616 -381.820166) (xy 159.493411 -381.81302) (xy 159.499926 -381.79583)
			(xy 159.500316 -381.786638) (xy 159.500316 -381.628904) (xy 159.50072 -381.61878) (xy 159.508469 -381.600073)
			(xy 159.52279 -381.585758) (xy 159.5415 -381.578016) (xy 159.551624 -381.577596) (xy 160.268158 -381.577596)
			(xy 160.278277 -381.57816) (xy 160.296988 -381.585866) (xy 160.311345 -381.600128) (xy 160.319173 -381.618789)
			(xy 160.31972 -381.628904) (xy 160.31972 -381.786638) (xy 160.320108 -381.795828) (xy 160.326637 -381.813012)
			(xy 160.33242 -381.820166) (xy 160.354199 -381.845826) (xy 160.392151 -381.90141) (xy 160.423187 -381.961132)
			(xy 160.446862 -382.024136) (xy 160.462837 -382.089518) (xy 160.470882 -382.15634) (xy 160.470883 -382.223645)
			(xy 160.470876 -382.223705) (xy 163.748923 -382.223705) (xy 163.748924 -382.15628) (xy 163.757001 -382.089341)
			(xy 163.773038 -382.023851) (xy 163.796804 -381.960754) (xy 163.827956 -381.900957) (xy 163.866047 -381.845323)
			(xy 163.887912 -381.819658) (xy 163.89371 -381.812514) (xy 163.900224 -381.795323) (xy 163.900612 -381.78613)
			(xy 163.900612 -381.628904) (xy 163.90102 -381.61878) (xy 163.908769 -381.600074) (xy 163.923088 -381.58576)
			(xy 163.941796 -381.578016) (xy 163.95192 -381.577596) (xy 164.6682 -381.577596) (xy 164.678322 -381.578016)
			(xy 164.697025 -381.585763) (xy 164.711339 -381.600079) (xy 164.719085 -381.618782) (xy 164.719508 -381.628904)
			(xy 164.719508 -381.78613) (xy 164.719902 -381.795319) (xy 164.726426 -381.812503) (xy 164.732208 -381.819658)
			(xy 164.754062 -381.845331) (xy 164.79215 -381.900965) (xy 164.823301 -381.96076) (xy 164.847065 -382.023856)
			(xy 164.863101 -382.089344) (xy 164.871178 -382.156281) (xy 164.871179 -382.223645) (xy 168.149243 -382.223645)
			(xy 168.149244 -382.15634) (xy 168.157288 -382.089517) (xy 168.173261 -382.024135) (xy 168.196933 -381.96113)
			(xy 168.227965 -381.901406) (xy 168.265913 -381.845819) (xy 168.2877 -381.820166) (xy 168.293494 -381.813019)
			(xy 168.30001 -381.79583) (xy 168.3004 -381.786638) (xy 168.3004 -381.628904) (xy 168.300825 -381.61875)
			(xy 168.308619 -381.599998) (xy 168.323015 -381.585674) (xy 168.341806 -381.577975) (xy 168.351962 -381.577596)
			(xy 169.068242 -381.577596) (xy 169.078366 -381.578091) (xy 169.09708 -381.585824) (xy 169.111433 -381.600107)
			(xy 169.119258 -381.618783) (xy 169.119804 -381.628904) (xy 169.119804 -381.786638) (xy 169.120195 -381.795827)
			(xy 169.126722 -381.813012) (xy 169.132504 -381.820166) (xy 169.154281 -381.845827) (xy 169.192227 -381.901413)
			(xy 169.223258 -381.961136) (xy 169.24693 -382.024139) (xy 169.262902 -382.08952) (xy 169.270946 -382.156341)
			(xy 169.270947 -382.223644) (xy 169.270947 -382.223646) (xy 172.54901 -382.223646) (xy 172.54901 -382.156339)
			(xy 172.557056 -382.089515) (xy 172.573032 -382.024132) (xy 172.596708 -381.961127) (xy 172.627745 -381.901403)
			(xy 172.665698 -381.845818) (xy 172.687488 -381.820166) (xy 172.69328 -381.813018) (xy 172.699798 -381.79583)
			(xy 172.700188 -381.786638) (xy 172.700188 -381.628904) (xy 172.700625 -381.618752) (xy 172.708417 -381.600002)
			(xy 172.722809 -381.585679) (xy 172.741596 -381.577977) (xy 172.75175 -381.577596) (xy 173.46803 -381.577596)
			(xy 173.478153 -381.578101) (xy 173.496867 -381.58583) (xy 173.51122 -381.60011) (xy 173.519046 -381.618783)
			(xy 173.519592 -381.628904) (xy 173.519592 -381.786638) (xy 173.519986 -381.795827) (xy 173.526511 -381.813011)
			(xy 173.532292 -381.820166) (xy 173.554069 -381.845827) (xy 173.592016 -381.901413) (xy 173.623048 -381.961135)
			(xy 173.64672 -382.024139) (xy 173.662693 -382.089519) (xy 173.670737 -382.156341) (xy 173.670738 -382.223644)
			(xy 173.662695 -382.290466) (xy 173.646725 -382.355847) (xy 173.623054 -382.418851) (xy 173.592024 -382.478574)
			(xy 173.554078 -382.534161) (xy 173.532292 -382.559814) (xy 173.526506 -382.566967) (xy 173.519985 -382.584151)
			(xy 173.519592 -382.593342) (xy 173.519592 -383.086864) (xy 173.520021 -383.096049) (xy 173.526522 -383.113234)
			(xy 173.532292 -383.120392) (xy 173.554094 -383.146032) (xy 173.592041 -383.201621) (xy 173.623072 -383.261346)
			(xy 173.646507 -383.323727) (xy 174.749152 -383.323727) (xy 174.749155 -383.256419) (xy 174.757202 -383.189594)
			(xy 174.773179 -383.12421) (xy 174.796856 -383.061204) (xy 174.827893 -383.001479) (xy 174.865846 -382.945892)
			(xy 174.887636 -382.92024) (xy 174.893445 -382.913104) (xy 174.899951 -382.895906) (xy 174.900336 -382.886712)
			(xy 174.900336 -382.728724) (xy 174.900742 -382.718567) (xy 174.908536 -382.699808) (xy 174.922939 -382.685482)
			(xy 174.941739 -382.677788) (xy 174.951898 -382.677416) (xy 175.668178 -382.677416) (xy 175.6783 -382.677944)
			(xy 175.697017 -382.68566) (xy 175.711373 -382.699933) (xy 175.719197 -382.718605) (xy 175.71974 -382.728724)
			(xy 175.71974 -382.886712) (xy 175.720158 -382.895898) (xy 175.726668 -382.913082) (xy 175.73244 -382.92024)
			(xy 175.754193 -382.945921) (xy 175.792144 -383.001503) (xy 175.82318 -383.061222) (xy 175.846856 -383.124223)
			(xy 175.862832 -383.189602) (xy 175.870879 -383.256422) (xy 175.870883 -383.323724) (xy 175.862842 -383.390545)
			(xy 175.846872 -383.455925) (xy 175.823202 -383.518928) (xy 175.792172 -383.578651) (xy 175.754226 -383.634236)
			(xy 175.73244 -383.659888) (xy 175.726616 -383.667014) (xy 175.720119 -383.684219) (xy 175.71974 -383.693416)
			(xy 175.71974 -384.186684) (xy 175.720171 -384.195869) (xy 175.726672 -384.213053) (xy 175.73244 -384.220212)
			(xy 175.754264 -384.245835) (xy 175.792213 -384.301425) (xy 175.823246 -384.361152) (xy 175.846918 -384.424161)
			(xy 175.862889 -384.489547) (xy 175.87093 -384.556373) (xy 175.870927 -384.623681) (xy 175.862879 -384.690507)
			(xy 175.846902 -384.755891) (xy 175.823224 -384.818897) (xy 175.792185 -384.878622) (xy 175.754231 -384.934208)
			(xy 175.73244 -384.95986) (xy 175.726628 -384.966994) (xy 175.720124 -384.984193) (xy 175.71974 -384.993388)
			(xy 175.71974 -385.151376) (xy 175.71926 -385.161524) (xy 175.71148 -385.180268) (xy 175.697101 -385.194591)
			(xy 175.678327 -385.202298) (xy 175.668178 -385.202684) (xy 174.951898 -385.202684) (xy 174.941774 -385.202176)
			(xy 174.923058 -385.194452) (xy 174.908702 -385.180172) (xy 174.900879 -385.161497) (xy 174.900336 -385.151376)
			(xy 174.900336 -384.993388) (xy 174.899924 -384.984201) (xy 174.893411 -384.967017) (xy 174.887636 -384.95986)
			(xy 174.865884 -384.934179) (xy 174.827934 -384.878596) (xy 174.7969 -384.818877) (xy 174.773225 -384.755876)
			(xy 174.75725 -384.690497) (xy 174.749203 -384.623678) (xy 174.749199 -384.556376) (xy 174.75724 -384.489556)
			(xy 174.773209 -384.424176) (xy 174.796878 -384.361173) (xy 174.827906 -384.30145) (xy 174.865851 -384.245864)
			(xy 174.887636 -384.220212) (xy 174.893457 -384.213084) (xy 174.899956 -384.19588) (xy 174.900336 -384.186684)
			(xy 174.900336 -383.693416) (xy 174.89991 -383.684231) (xy 174.893407 -383.667046) (xy 174.887636 -383.659888)
			(xy 174.865813 -383.634265) (xy 174.827865 -383.578674) (xy 174.796834 -383.518947) (xy 174.773163 -383.455938)
			(xy 174.757193 -383.390553) (xy 174.749152 -383.323727) (xy 173.646507 -383.323727) (xy 173.646742 -383.324352)
			(xy 173.662713 -383.389736) (xy 173.670756 -383.456559) (xy 173.670754 -383.523865) (xy 173.662709 -383.590688)
			(xy 173.646735 -383.656071) (xy 173.623062 -383.719076) (xy 173.592028 -383.7788) (xy 173.55408 -383.834387)
			(xy 173.532292 -383.86004) (xy 173.526495 -383.867185) (xy 173.519981 -383.884376) (xy 173.519592 -383.893568)
			(xy 173.519592 -384.051556) (xy 173.519142 -384.061708) (xy 173.51136 -384.080461) (xy 173.496971 -384.094786)
			(xy 173.478184 -384.102486) (xy 173.46803 -384.102864) (xy 172.75175 -384.102864) (xy 172.741627 -384.102333)
			(xy 172.722908 -384.094622) (xy 172.70855 -384.080349) (xy 172.700728 -384.061676) (xy 172.700188 -384.051556)
			(xy 172.700188 -383.893568) (xy 172.699796 -383.884379) (xy 172.69327 -383.867194) (xy 172.687488 -383.86004)
			(xy 172.665715 -383.834376) (xy 172.627762 -383.778792) (xy 172.596725 -383.719071) (xy 172.57305 -383.656068)
			(xy 172.557074 -383.590686) (xy 172.549028 -383.523864) (xy 172.549026 -383.45656) (xy 172.55707 -383.389737)
			(xy 172.573042 -383.324355) (xy 172.596716 -383.261351) (xy 172.62775 -383.201629) (xy 172.6657 -383.146043)
			(xy 172.687488 -383.120392) (xy 172.693269 -383.113236) (xy 172.699793 -383.096054) (xy 172.700188 -383.086864)
			(xy 172.700188 -382.593342) (xy 172.69976 -382.584157) (xy 172.693259 -382.566972) (xy 172.687488 -382.559814)
			(xy 172.665689 -382.534171) (xy 172.627737 -382.478584) (xy 172.596702 -382.41886) (xy 172.573027 -382.355854)
			(xy 172.557054 -382.29047) (xy 172.54901 -382.223646) (xy 169.270947 -382.223646) (xy 169.262905 -382.290465)
			(xy 169.246934 -382.355847) (xy 169.223264 -382.41885) (xy 169.192235 -382.478574) (xy 169.15429 -382.534161)
			(xy 169.132504 -382.559814) (xy 169.126719 -382.566968) (xy 169.120197 -382.584152) (xy 169.119804 -382.593342)
			(xy 169.119804 -383.086864) (xy 169.120231 -383.096049) (xy 169.126733 -383.113234) (xy 169.132504 -383.120392)
			(xy 169.154306 -383.146032) (xy 169.192252 -383.201621) (xy 169.223282 -383.261347) (xy 169.246739 -383.323787)
			(xy 170.348832 -383.323787) (xy 170.348835 -383.256359) (xy 170.356915 -383.189418) (xy 170.372956 -383.123926)
			(xy 170.396726 -383.060827) (xy 170.427884 -383.001031) (xy 170.46598 -382.945396) (xy 170.487848 -382.919732)
			(xy 170.493662 -382.912599) (xy 170.500165 -382.895399) (xy 170.500548 -382.886204) (xy 170.500548 -382.728724)
			(xy 170.501103 -382.718623) (xy 170.508823 -382.699955) (xy 170.523098 -382.685662) (xy 170.541756 -382.677917)
			(xy 170.551856 -382.677416) (xy 171.268136 -382.677416) (xy 171.278249 -382.677856) (xy 171.296931 -382.685608)
			(xy 171.311225 -382.699919) (xy 171.318956 -382.71861) (xy 171.319444 -382.728724) (xy 171.319444 -382.886204)
			(xy 171.319865 -382.89539) (xy 171.326372 -382.912574) (xy 171.332144 -382.919732) (xy 171.353975 -382.945425)
			(xy 171.392068 -383.001055) (xy 171.423223 -383.060846) (xy 171.446992 -383.12394) (xy 171.463032 -383.189426)
			(xy 171.471111 -383.256362) (xy 171.471115 -383.323784) (xy 171.463041 -383.390721) (xy 171.447008 -383.456209)
			(xy 171.423246 -383.519304) (xy 171.392096 -383.579099) (xy 171.354008 -383.634732) (xy 171.332144 -383.660396)
			(xy 171.32636 -383.66755) (xy 171.319839 -383.684734) (xy 171.319444 -383.693924) (xy 171.319444 -384.186176)
			(xy 171.319878 -384.19536) (xy 171.326376 -384.212544) (xy 171.332144 -384.219704) (xy 171.354045 -384.245339)
			(xy 171.392137 -384.300977) (xy 171.423289 -384.360776) (xy 171.447054 -384.423877) (xy 171.463088 -384.489371)
			(xy 171.471162 -384.556313) (xy 171.471159 -384.623741) (xy 171.463078 -384.690683) (xy 171.447037 -384.756174)
			(xy 171.423267 -384.819273) (xy 171.392109 -384.87907) (xy 171.354012 -384.934704) (xy 171.332144 -384.960368)
			(xy 171.326329 -384.9675) (xy 171.319827 -384.984701) (xy 171.319444 -384.993896) (xy 171.319444 -385.151376)
			(xy 171.318896 -385.161478) (xy 171.311175 -385.180147) (xy 171.296897 -385.194441) (xy 171.278237 -385.202185)
			(xy 171.268136 -385.202684) (xy 170.551856 -385.202684) (xy 170.541742 -385.20225) (xy 170.52306 -385.194495)
			(xy 170.508766 -385.180183) (xy 170.501036 -385.16149) (xy 170.500548 -385.151376) (xy 170.500548 -384.993896)
			(xy 170.500129 -384.98471) (xy 170.49362 -384.967526) (xy 170.487848 -384.960368) (xy 170.466018 -384.934674)
			(xy 170.427925 -384.879045) (xy 170.39677 -384.819253) (xy 170.373001 -384.75616) (xy 170.356962 -384.690674)
			(xy 170.348883 -384.623738) (xy 170.348879 -384.556316) (xy 170.356952 -384.489379) (xy 170.372985 -384.423892)
			(xy 170.396748 -384.360796) (xy 170.427897 -384.301001) (xy 170.465984 -384.245368) (xy 170.487848 -384.219704)
			(xy 170.493631 -384.21255) (xy 170.500153 -384.195366) (xy 170.500548 -384.186176) (xy 170.500548 -383.693924)
			(xy 170.500116 -383.684739) (xy 170.493616 -383.667555) (xy 170.487848 -383.660396) (xy 170.465947 -383.634761)
			(xy 170.427856 -383.579123) (xy 170.396704 -383.519323) (xy 170.37294 -383.456222) (xy 170.356906 -383.390729)
			(xy 170.348832 -383.323787) (xy 169.246739 -383.323787) (xy 169.246952 -383.324353) (xy 169.262922 -383.389736)
			(xy 169.270965 -383.456559) (xy 169.270963 -383.523865) (xy 169.262918 -383.590688) (xy 169.246945 -383.65607)
			(xy 169.223272 -383.719075) (xy 169.192239 -383.7788) (xy 169.154291 -383.834387) (xy 169.132504 -383.86004)
			(xy 169.126708 -383.867186) (xy 169.120193 -383.884376) (xy 169.119804 -383.893568) (xy 169.119804 -384.051556)
			(xy 169.119342 -384.061707) (xy 169.111562 -384.080457) (xy 169.097177 -384.094782) (xy 169.078394 -384.102484)
			(xy 169.068242 -384.102864) (xy 168.351962 -384.102864) (xy 168.341833 -384.102405) (xy 168.323112 -384.094665)
			(xy 168.308757 -384.080371) (xy 168.300939 -384.061682) (xy 168.3004 -384.051556) (xy 168.3004 -383.893568)
			(xy 168.300005 -383.884379) (xy 168.293481 -383.867195) (xy 168.2877 -383.86004) (xy 168.265929 -383.834374)
			(xy 168.227982 -383.778789) (xy 168.196951 -383.719067) (xy 168.173279 -383.656064) (xy 168.157306 -383.590684)
			(xy 168.149261 -383.523864) (xy 168.149259 -383.456561) (xy 168.157301 -383.38974) (xy 168.173272 -383.324359)
			(xy 168.196941 -383.261355) (xy 168.22797 -383.201632) (xy 168.265914 -383.146045) (xy 168.2877 -383.120392)
			(xy 168.293482 -383.113237) (xy 168.300006 -383.096054) (xy 168.3004 -383.086864) (xy 168.3004 -382.593342)
			(xy 168.29997 -382.584157) (xy 168.29347 -382.566972) (xy 168.2877 -382.559814) (xy 168.265904 -382.534169)
			(xy 168.227958 -382.478581) (xy 168.196927 -382.418856) (xy 168.173256 -382.355851) (xy 168.157285 -382.290468)
			(xy 168.149243 -382.223645) (xy 164.871179 -382.223645) (xy 164.871179 -382.223704) (xy 164.863104 -382.290641)
			(xy 164.84707 -382.35613) (xy 164.823307 -382.419226) (xy 164.792158 -382.479022) (xy 164.754071 -382.534657)
			(xy 164.732208 -382.560322) (xy 164.726421 -382.567474) (xy 164.7199 -382.584659) (xy 164.719508 -382.59385)
			(xy 164.719508 -383.086356) (xy 164.719937 -383.095541) (xy 164.726437 -383.112726) (xy 164.732208 -383.119884)
			(xy 164.754087 -383.145536) (xy 164.792175 -383.201173) (xy 164.823325 -383.260971) (xy 164.846959 -383.323727)
			(xy 165.949064 -383.323727) (xy 165.949067 -383.256419) (xy 165.957115 -383.189594) (xy 165.973092 -383.124209)
			(xy 165.996769 -383.061203) (xy 166.027808 -383.001479) (xy 166.065762 -382.945892) (xy 166.087552 -382.92024)
			(xy 166.093363 -382.913105) (xy 166.099868 -382.895907) (xy 166.100252 -382.886712) (xy 166.100252 -382.728724)
			(xy 166.10074 -382.718577) (xy 166.108519 -382.699835) (xy 166.122895 -382.685512) (xy 166.141666 -382.677803)
			(xy 166.151814 -382.677416) (xy 166.868094 -382.677416) (xy 166.878217 -382.677931) (xy 166.896934 -382.685652)
			(xy 166.911289 -382.699929) (xy 166.919113 -382.718603) (xy 166.919656 -382.728724) (xy 166.919656 -382.886712)
			(xy 166.92007 -382.895899) (xy 166.926582 -382.913082) (xy 166.932356 -382.92024) (xy 166.954108 -382.945921)
			(xy 166.992059 -383.001503) (xy 167.023094 -383.061223) (xy 167.046769 -383.124224) (xy 167.062744 -383.189602)
			(xy 167.070791 -383.256422) (xy 167.070795 -383.323724) (xy 167.062754 -383.390544) (xy 167.046785 -383.455925)
			(xy 167.023116 -383.518928) (xy 166.992086 -383.57865) (xy 166.954142 -383.634236) (xy 166.932356 -383.659888)
			(xy 166.926534 -383.667015) (xy 166.920036 -383.68422) (xy 166.919656 -383.693416) (xy 166.919656 -384.186684)
			(xy 166.920084 -384.195869) (xy 166.926586 -384.213053) (xy 166.932356 -384.220212) (xy 166.954179 -384.245835)
			(xy 166.992127 -384.301425) (xy 167.023159 -384.361153) (xy 167.04683 -384.424161) (xy 167.062801 -384.489547)
			(xy 167.070842 -384.556373) (xy 167.070839 -384.623681) (xy 167.062791 -384.690506) (xy 167.046814 -384.75589)
			(xy 167.023137 -384.818897) (xy 166.9921 -384.878621) (xy 166.954146 -384.934208) (xy 166.932356 -384.95986)
			(xy 166.926546 -384.966995) (xy 166.92004 -384.984194) (xy 166.919656 -384.993388) (xy 166.919656 -385.151376)
			(xy 166.91916 -385.161522) (xy 166.911383 -385.180263) (xy 166.89701 -385.194585) (xy 166.878241 -385.202296)
			(xy 166.868094 -385.202684) (xy 166.151814 -385.202684) (xy 166.141691 -385.202163) (xy 166.122975 -385.194444)
			(xy 166.108619 -385.180169) (xy 166.100795 -385.161496) (xy 166.100252 -385.151376) (xy 166.100252 -384.993388)
			(xy 166.099836 -384.984202) (xy 166.093325 -384.967018) (xy 166.087552 -384.95986) (xy 166.065799 -384.934179)
			(xy 166.027849 -384.878597) (xy 165.996813 -384.818877) (xy 165.973138 -384.755877) (xy 165.957162 -384.690498)
			(xy 165.949115 -384.623678) (xy 165.949111 -384.556376) (xy 165.957152 -384.489555) (xy 165.973122 -384.424175)
			(xy 165.996791 -384.361172) (xy 166.027821 -384.30145) (xy 166.065766 -384.245864) (xy 166.087552 -384.220212)
			(xy 166.093375 -384.213086) (xy 166.099872 -384.19588) (xy 166.100252 -384.186684) (xy 166.100252 -383.693416)
			(xy 166.099823 -383.684231) (xy 166.093321 -383.667047) (xy 166.087552 -383.659888) (xy 166.065728 -383.634265)
			(xy 166.02778 -383.578675) (xy 165.996747 -383.518947) (xy 165.973076 -383.455939) (xy 165.957105 -383.390553)
			(xy 165.949064 -383.323727) (xy 164.846959 -383.323727) (xy 164.847088 -383.32407) (xy 164.863122 -383.38956)
			(xy 164.871196 -383.4565) (xy 164.871195 -383.523924) (xy 164.863117 -383.590864) (xy 164.84708 -383.656353)
			(xy 164.823315 -383.719451) (xy 164.792163 -383.779248) (xy 164.754073 -383.834883) (xy 164.732208 -383.860548)
			(xy 164.726409 -383.867692) (xy 164.719896 -383.884883) (xy 164.719508 -383.894076) (xy 164.719508 -384.051556)
			(xy 164.719048 -384.061675) (xy 164.711316 -384.080376) (xy 164.697013 -384.094691) (xy 164.678318 -384.102439)
			(xy 164.6682 -384.102864) (xy 163.95192 -384.102864) (xy 163.941794 -384.102467) (xy 163.923084 -384.094719)
			(xy 163.908768 -384.080396) (xy 163.901028 -384.061682) (xy 163.900612 -384.051556) (xy 163.900612 -383.894076)
			(xy 163.900211 -383.884888) (xy 163.893691 -383.867704) (xy 163.887912 -383.860548) (xy 163.866063 -383.83487)
			(xy 163.827973 -383.779238) (xy 163.796821 -383.719443) (xy 163.773056 -383.656348) (xy 163.757019 -383.59086)
			(xy 163.748941 -383.523923) (xy 163.74894 -383.456501) (xy 163.757014 -383.389563) (xy 163.773049 -383.324075)
			(xy 163.796811 -383.260979) (xy 163.827961 -383.201183) (xy 163.866049 -383.145549) (xy 163.887912 -383.119884)
			(xy 163.893699 -383.112732) (xy 163.900219 -383.095547) (xy 163.900612 -383.086356) (xy 163.900612 -382.59385)
			(xy 163.900175 -382.584666) (xy 163.89368 -382.567481) (xy 163.887912 -382.560322) (xy 163.866038 -382.534665)
			(xy 163.827949 -382.47903) (xy 163.796798 -382.419232) (xy 163.773034 -382.356134) (xy 163.756998 -382.290644)
			(xy 163.748923 -382.223705) (xy 160.470876 -382.223705) (xy 160.46284 -382.290468) (xy 160.446866 -382.35585)
			(xy 160.423193 -382.418854) (xy 160.392159 -382.478577) (xy 160.354208 -382.534162) (xy 160.33242 -382.559814)
			(xy 160.326637 -382.566969) (xy 160.320114 -382.584152) (xy 160.31972 -382.593342) (xy 160.31972 -383.086864)
			(xy 160.320143 -383.09605) (xy 160.326647 -383.113235) (xy 160.33242 -383.120392) (xy 160.354225 -383.146031)
			(xy 160.392176 -383.201618) (xy 160.42321 -383.261343) (xy 160.446672 -383.323786) (xy 161.548769 -383.323786)
			(xy 161.548772 -383.25636) (xy 161.556851 -383.18942) (xy 161.572889 -383.123929) (xy 161.596656 -383.060831)
			(xy 161.627809 -383.001034) (xy 161.665899 -382.945398) (xy 161.687764 -382.919732) (xy 161.69358 -382.912601)
			(xy 161.700081 -382.895399) (xy 161.700464 -382.886204) (xy 161.700464 -382.728724) (xy 161.701004 -382.718621)
			(xy 161.708727 -382.69995) (xy 161.723007 -382.685656) (xy 161.74167 -382.677914) (xy 161.751772 -382.677416)
			(xy 162.468052 -382.677416) (xy 162.478173 -382.677856) (xy 162.496879 -382.685591) (xy 162.511195 -382.699901)
			(xy 162.51894 -382.718603) (xy 162.51936 -382.728724) (xy 162.51936 -382.886204) (xy 162.519777 -382.89539)
			(xy 162.526287 -382.912574) (xy 162.53206 -382.919732) (xy 162.55389 -382.945426) (xy 162.591982 -383.001055)
			(xy 162.623137 -383.060847) (xy 162.646905 -383.12394) (xy 162.662944 -383.189426) (xy 162.671023 -383.256362)
			(xy 162.671027 -383.323784) (xy 162.662954 -383.39072) (xy 162.646921 -383.456208) (xy 162.623159 -383.519303)
			(xy 162.59201 -383.579098) (xy 162.553923 -383.634731) (xy 162.53206 -383.660396) (xy 162.526278 -383.667551)
			(xy 162.519755 -383.684734) (xy 162.51936 -383.693924) (xy 162.51936 -384.186176) (xy 162.51979 -384.195361)
			(xy 162.526291 -384.212545) (xy 162.53206 -384.219704) (xy 162.553961 -384.245339) (xy 162.592051 -384.300977)
			(xy 162.623202 -384.360777) (xy 162.646966 -384.423878) (xy 162.663 -384.489371) (xy 162.671074 -384.556313)
			(xy 162.671071 -384.623741) (xy 162.662991 -384.690682) (xy 162.64695 -384.756174) (xy 162.62318 -384.819272)
			(xy 162.592023 -384.879069) (xy 162.553928 -384.934703) (xy 162.53206 -384.960368) (xy 162.526247 -384.967501)
			(xy 162.519743 -384.984701) (xy 162.51936 -384.993896) (xy 162.51936 -385.151376) (xy 162.518964 -385.161502)
			(xy 162.511216 -385.180213) (xy 162.496893 -385.194529) (xy 162.478178 -385.202268) (xy 162.468052 -385.202684)
			(xy 161.751772 -385.202684) (xy 161.741659 -385.202238) (xy 161.722978 -385.194488) (xy 161.708683 -385.180179)
			(xy 161.700952 -385.161489) (xy 161.700464 -385.151376) (xy 161.700464 -384.993896) (xy 161.700041 -384.98471)
			(xy 161.693535 -384.967527) (xy 161.687764 -384.960368) (xy 161.665937 -384.934673) (xy 161.627849 -384.879042)
			(xy 161.596699 -384.819249) (xy 161.572934 -384.756157) (xy 161.556897 -384.690671) (xy 161.548819 -384.623737)
			(xy 161.548816 -384.556317) (xy 161.556888 -384.489382) (xy 161.572918 -384.423895) (xy 161.596677 -384.3608)
			(xy 161.627821 -384.301005) (xy 161.665903 -384.24537) (xy 161.687764 -384.219704) (xy 161.693549 -384.212551)
			(xy 161.700069 -384.195366) (xy 161.700464 -384.186176) (xy 161.700464 -383.693924) (xy 161.700028 -383.68474)
			(xy 161.693531 -383.667556) (xy 161.687764 -383.660396) (xy 161.665866 -383.634759) (xy 161.627781 -383.57912)
			(xy 161.596634 -383.519319) (xy 161.572873 -383.456219) (xy 161.556841 -383.390727) (xy 161.548769 -383.323786)
			(xy 160.446672 -383.323786) (xy 160.446884 -383.32435) (xy 160.462857 -383.389734) (xy 160.470901 -383.456558)
			(xy 160.470899 -383.523866) (xy 160.462853 -383.59069) (xy 160.446877 -383.656074) (xy 160.423201 -383.719079)
			(xy 160.392163 -383.778803) (xy 160.35421 -383.834388) (xy 160.33242 -383.86004) (xy 160.326626 -383.867187)
			(xy 160.320109 -383.884376) (xy 160.31972 -383.893568) (xy 160.31972 -384.051556) (xy 160.319248 -384.061673)
			(xy 160.311518 -384.080372) (xy 160.297219 -384.094687) (xy 160.278529 -384.102437) (xy 160.268412 -384.102864)
			(xy 159.551878 -384.102864) (xy 159.54175 -384.102392) (xy 159.523029 -384.094657) (xy 159.508674 -384.080367)
			(xy 159.500855 -384.061681) (xy 159.500316 -384.051556) (xy 159.500316 -383.893568) (xy 159.499918 -383.88438)
			(xy 159.493395 -383.867196) (xy 159.487616 -383.86004) (xy 159.465845 -383.834375) (xy 159.427897 -383.77879)
			(xy 159.396864 -383.719068) (xy 159.373191 -383.656065) (xy 159.357218 -383.590684) (xy 159.349173 -383.523864)
			(xy 159.349172 -383.45656) (xy 159.357214 -383.389739) (xy 159.373184 -383.324358) (xy 159.396854 -383.261354)
			(xy 159.427884 -383.201631) (xy 159.46583 -383.146044) (xy 159.487616 -383.120392) (xy 159.4934 -383.113238)
			(xy 159.499922 -383.096054) (xy 159.500316 -383.086864) (xy 159.500316 -382.593342) (xy 159.499882 -382.584157)
			(xy 159.493384 -382.566973) (xy 159.487616 -382.559814) (xy 159.465819 -382.53417) (xy 159.427872 -382.478582)
			(xy 159.396841 -382.418857) (xy 159.373169 -382.355851) (xy 159.357198 -382.290468) (xy 159.349155 -382.223645)
			(xy 129.670829 -382.223645) (xy 129.662786 -382.290466) (xy 129.646815 -382.355847) (xy 129.623144 -382.418851)
			(xy 129.592113 -382.478575) (xy 129.554167 -382.534162) (xy 129.53238 -382.559814) (xy 129.526593 -382.566966)
			(xy 129.520073 -382.584151) (xy 129.51968 -382.593342) (xy 129.51968 -383.086864) (xy 129.520112 -383.096049)
			(xy 129.526611 -383.113233) (xy 129.53238 -383.120392) (xy 129.554183 -383.146031) (xy 129.59213 -383.20162)
			(xy 129.623162 -383.261346) (xy 129.646598 -383.323727) (xy 130.749242 -383.323727) (xy 130.749246 -383.256419)
			(xy 130.757293 -383.189594) (xy 130.77327 -383.12421) (xy 130.796946 -383.061204) (xy 130.827982 -383.00148)
			(xy 130.865935 -382.945892) (xy 130.887724 -382.92024) (xy 130.893531 -382.913103) (xy 130.900039 -382.895906)
			(xy 130.900424 -382.886712) (xy 130.900424 -382.728724) (xy 130.900842 -382.718568) (xy 130.908634 -382.699812)
			(xy 130.923032 -382.685487) (xy 130.941828 -382.67779) (xy 130.951986 -382.677416) (xy 131.668266 -382.677416)
			(xy 131.678388 -382.677954) (xy 131.697103 -382.685666) (xy 131.71146 -382.699937) (xy 131.719284 -382.718606)
			(xy 131.719828 -382.728724) (xy 131.719828 -382.886712) (xy 131.720226 -382.895901) (xy 131.726747 -382.913085)
			(xy 131.732528 -382.92024) (xy 131.754281 -382.945921) (xy 131.792233 -383.001502) (xy 131.82327 -383.061222)
			(xy 131.846946 -383.124223) (xy 131.862923 -383.189602) (xy 131.87097 -383.256422) (xy 131.870973 -383.323724)
			(xy 131.862932 -383.390545) (xy 131.846962 -383.455926) (xy 131.823292 -383.518929) (xy 131.792261 -383.578651)
			(xy 131.754314 -383.634236) (xy 131.732528 -383.659888) (xy 131.726703 -383.667013) (xy 131.720207 -383.684219)
			(xy 131.719828 -383.693416) (xy 131.719828 -384.186684) (xy 131.720239 -384.195871) (xy 131.726751 -384.213056)
			(xy 131.732528 -384.220212) (xy 131.754352 -384.245834) (xy 131.792302 -384.301424) (xy 131.823336 -384.361152)
			(xy 131.847008 -384.42416) (xy 131.86298 -384.489546) (xy 131.871021 -384.556373) (xy 131.871018 -384.623681)
			(xy 131.86297 -384.690507) (xy 131.846992 -384.755892) (xy 131.823314 -384.818898) (xy 131.792274 -384.878622)
			(xy 131.754319 -384.934208) (xy 131.732528 -384.95986) (xy 131.726715 -384.966993) (xy 131.720212 -384.984193)
			(xy 131.719828 -384.993388) (xy 131.719828 -385.151376) (xy 131.719359 -385.161525) (xy 131.711577 -385.180272)
			(xy 131.697195 -385.194595) (xy 131.678417 -385.202301) (xy 131.668266 -385.202684) (xy 130.951986 -385.202684)
			(xy 130.941861 -385.202185) (xy 130.923145 -385.194457) (xy 130.90879 -385.180175) (xy 130.900967 -385.161498)
			(xy 130.900424 -385.151376) (xy 130.900424 -384.993388) (xy 130.900014 -384.984201) (xy 130.8935 -384.967017)
			(xy 130.887724 -384.95986) (xy 130.865972 -384.934178) (xy 130.828023 -384.878596) (xy 130.796989 -384.818876)
			(xy 130.773315 -384.755876) (xy 130.75734 -384.690497) (xy 130.749294 -384.623678) (xy 130.74929 -384.556376)
			(xy 130.757331 -384.489556) (xy 130.773299 -384.424176) (xy 130.796967 -384.361173) (xy 130.827996 -384.301451)
			(xy 130.865939 -384.245865) (xy 130.887724 -384.220212) (xy 130.893543 -384.213083) (xy 130.900044 -384.19588)
			(xy 130.900424 -384.186684) (xy 130.900424 -383.693416) (xy 130.900001 -383.68423) (xy 130.893495 -383.667046)
			(xy 130.887724 -383.659888) (xy 130.865901 -383.634265) (xy 130.827955 -383.578674) (xy 130.796924 -383.518946)
			(xy 130.773254 -383.455938) (xy 130.757284 -383.390552) (xy 130.749242 -383.323727) (xy 129.646598 -383.323727)
			(xy 129.646833 -383.324352) (xy 129.662804 -383.389735) (xy 129.670846 -383.456559) (xy 129.670845 -383.523865)
			(xy 129.6628 -383.590688) (xy 129.646826 -383.656071) (xy 129.623152 -383.719076) (xy 129.592118 -383.778801)
			(xy 129.554168 -383.834388) (xy 129.53238 -383.86004) (xy 129.526582 -383.867184) (xy 129.520069 -383.884375)
			(xy 129.51968 -383.893568) (xy 129.51968 -384.051556) (xy 129.519242 -384.06171) (xy 129.511457 -384.080465)
			(xy 129.497065 -384.094791) (xy 129.478274 -384.102488) (xy 129.468118 -384.102864) (xy 128.751838 -384.102864)
			(xy 128.741714 -384.102342) (xy 128.722995 -384.094628) (xy 128.708637 -384.080352) (xy 128.700816 -384.061677)
			(xy 128.700276 -384.051556) (xy 128.700276 -383.893568) (xy 128.699886 -383.884379) (xy 128.693359 -383.867194)
			(xy 128.687576 -383.86004) (xy 128.665803 -383.834375) (xy 128.627851 -383.778792) (xy 128.596815 -383.71907)
			(xy 128.57314 -383.656067) (xy 128.557165 -383.590686) (xy 128.549119 -383.523864) (xy 128.549117 -383.45656)
			(xy 128.55716 -383.389738) (xy 128.573133 -383.324356) (xy 128.596805 -383.261352) (xy 128.627839 -383.201629)
			(xy 128.665788 -383.146044) (xy 128.687576 -383.120392) (xy 128.693356 -383.113235) (xy 128.699881 -383.096054)
			(xy 128.700276 -383.086864) (xy 128.700276 -382.593342) (xy 128.699851 -382.584156) (xy 128.693348 -382.566971)
			(xy 128.687576 -382.559814) (xy 128.665777 -382.53417) (xy 128.627826 -382.478584) (xy 128.596792 -382.418859)
			(xy 128.573118 -382.355853) (xy 128.557144 -382.29047) (xy 128.5491 -382.223646) (xy 125.271038 -382.223646)
			(xy 125.262995 -382.290466) (xy 125.247025 -382.355847) (xy 125.223354 -382.418851) (xy 125.192324 -382.478574)
			(xy 125.154378 -382.534161) (xy 125.132592 -382.559814) (xy 125.126806 -382.566967) (xy 125.120285 -382.584151)
			(xy 125.119892 -382.593342) (xy 125.119892 -383.086864) (xy 125.120321 -383.096049) (xy 125.126822 -383.113234)
			(xy 125.132592 -383.120392) (xy 125.154394 -383.146032) (xy 125.192341 -383.201621) (xy 125.223372 -383.261346)
			(xy 125.24683 -383.323787) (xy 126.348923 -383.323787) (xy 126.348926 -383.256359) (xy 126.357006 -383.189418)
			(xy 126.373047 -383.123926) (xy 126.396816 -383.060828) (xy 126.427973 -383.001031) (xy 126.466069 -382.945397)
			(xy 126.487936 -382.919732) (xy 126.493749 -382.912598) (xy 126.500253 -382.895399) (xy 126.500636 -382.886204)
			(xy 126.500636 -382.728724) (xy 126.501036 -382.718599) (xy 126.508783 -382.699889) (xy 126.523105 -382.685572)
			(xy 126.541818 -382.677832) (xy 126.551944 -382.677416) (xy 127.268224 -382.677416) (xy 127.278336 -382.677866)
			(xy 127.297018 -382.685614) (xy 127.311313 -382.699922) (xy 127.319044 -382.718611) (xy 127.319532 -382.728724)
			(xy 127.319532 -382.886204) (xy 127.319956 -382.895389) (xy 127.326462 -382.912573) (xy 127.332232 -382.919732)
			(xy 127.354059 -382.945427) (xy 127.392147 -383.001058) (xy 127.423298 -383.06085) (xy 127.447062 -383.123943)
			(xy 127.463099 -383.189428) (xy 127.471178 -383.256363) (xy 127.471181 -383.323783) (xy 127.463109 -383.390718)
			(xy 127.447078 -383.456205) (xy 127.42332 -383.5193) (xy 127.392175 -383.579096) (xy 127.354093 -383.63473)
			(xy 127.332232 -383.660396) (xy 127.326446 -383.667549) (xy 127.319927 -383.684734) (xy 127.319532 -383.693924)
			(xy 127.319532 -384.186176) (xy 127.319969 -384.19536) (xy 127.326466 -384.212544) (xy 127.332232 -384.219704)
			(xy 127.35413 -384.245341) (xy 127.392216 -384.30098) (xy 127.423363 -384.36078) (xy 127.447124 -384.423881)
			(xy 127.463156 -384.489373) (xy 127.471228 -384.556314) (xy 127.471225 -384.62374) (xy 127.463146 -384.69068)
			(xy 127.447108 -384.756171) (xy 127.423341 -384.819269) (xy 127.392188 -384.879066) (xy 127.354097 -384.934702)
			(xy 127.332232 -384.960368) (xy 127.326416 -384.967499) (xy 127.319915 -384.984701) (xy 127.319532 -384.993896)
			(xy 127.319532 -385.151376) (xy 127.318996 -385.161479) (xy 127.311272 -385.180151) (xy 127.296991 -385.194445)
			(xy 127.278327 -385.202187) (xy 127.268224 -385.202684) (xy 126.551944 -385.202684) (xy 126.541822 -385.202247)
			(xy 126.523117 -385.194511) (xy 126.5088 -385.1802) (xy 126.501056 -385.161497) (xy 126.500636 -385.151376)
			(xy 126.500636 -384.993896) (xy 126.50022 -384.98471) (xy 126.49371 -384.967526) (xy 126.487936 -384.960368)
			(xy 126.466106 -384.934674) (xy 126.428014 -384.879045) (xy 126.39686 -384.819253) (xy 126.373092 -384.756159)
			(xy 126.357053 -384.690673) (xy 126.348974 -384.623738) (xy 126.34897 -384.556316) (xy 126.357043 -384.48938)
			(xy 126.373076 -384.423892) (xy 126.396838 -384.360797) (xy 126.427986 -384.301002) (xy 126.466073 -384.245369)
			(xy 126.487936 -384.219704) (xy 126.493718 -384.212549) (xy 126.50024 -384.195366) (xy 126.500636 -384.186176)
			(xy 126.500636 -383.693924) (xy 126.500206 -383.684739) (xy 126.493705 -383.667555) (xy 126.487936 -383.660396)
			(xy 126.466035 -383.634761) (xy 126.427945 -383.579123) (xy 126.396794 -383.519323) (xy 126.373031 -383.456222)
			(xy 126.356996 -383.390729) (xy 126.348923 -383.323787) (xy 125.24683 -383.323787) (xy 125.247042 -383.324352)
			(xy 125.263013 -383.389736) (xy 125.271056 -383.456559) (xy 125.271054 -383.523865) (xy 125.263009 -383.590688)
			(xy 125.247035 -383.656071) (xy 125.223362 -383.719076) (xy 125.192328 -383.7788) (xy 125.15438 -383.834387)
			(xy 125.132592 -383.86004) (xy 125.126795 -383.867185) (xy 125.120281 -383.884376) (xy 125.119892 -383.893568)
			(xy 125.119892 -384.051556) (xy 125.119442 -384.061708) (xy 125.11166 -384.080461) (xy 125.097271 -384.094786)
			(xy 125.078484 -384.102486) (xy 125.06833 -384.102864) (xy 124.35205 -384.102864) (xy 124.341927 -384.102333)
			(xy 124.323208 -384.094622) (xy 124.30885 -384.080349) (xy 124.301028 -384.061676) (xy 124.300488 -384.051556)
			(xy 124.300488 -383.893568) (xy 124.300096 -383.884379) (xy 124.29357 -383.867194) (xy 124.287788 -383.86004)
			(xy 124.266015 -383.834376) (xy 124.228062 -383.778792) (xy 124.197025 -383.719071) (xy 124.17335 -383.656068)
			(xy 124.157374 -383.590686) (xy 124.149328 -383.523864) (xy 124.149326 -383.45656) (xy 124.15737 -383.389737)
			(xy 124.173342 -383.324355) (xy 124.197016 -383.261351) (xy 124.22805 -383.201629) (xy 124.266 -383.146043)
			(xy 124.287788 -383.120392) (xy 124.293569 -383.113236) (xy 124.300093 -383.096054) (xy 124.300488 -383.086864)
			(xy 124.300488 -382.593342) (xy 124.30006 -382.584157) (xy 124.293559 -382.566972) (xy 124.287788 -382.559814)
			(xy 124.265989 -382.534171) (xy 124.228037 -382.478584) (xy 124.197002 -382.41886) (xy 124.173327 -382.355854)
			(xy 124.157354 -382.29047) (xy 124.14931 -382.223646) (xy 120.87127 -382.223646) (xy 120.87127 -382.223704)
			(xy 120.863195 -382.290642) (xy 120.84716 -382.35613) (xy 120.823397 -382.419227) (xy 120.792247 -382.479023)
			(xy 120.75416 -382.534657) (xy 120.732296 -382.560322) (xy 120.726507 -382.567473) (xy 120.719988 -382.584659)
			(xy 120.719596 -382.59385) (xy 120.719596 -383.086356) (xy 120.720028 -383.095541) (xy 120.726527 -383.112725)
			(xy 120.732296 -383.119884) (xy 120.754176 -383.145536) (xy 120.792264 -383.201173) (xy 120.823415 -383.26097)
			(xy 120.847049 -383.323727) (xy 121.949155 -383.323727) (xy 121.949158 -383.256419) (xy 121.957206 -383.189594)
			(xy 121.973182 -383.12421) (xy 121.996859 -383.061204) (xy 122.027897 -383.001479) (xy 122.06585 -382.945892)
			(xy 122.08764 -382.92024) (xy 122.09345 -382.913104) (xy 122.099955 -382.895906) (xy 122.10034 -382.886712)
			(xy 122.10034 -382.728724) (xy 122.100742 -382.718566) (xy 122.108537 -382.699807) (xy 122.122941 -382.685481)
			(xy 122.141742 -382.677788) (xy 122.151902 -382.677416) (xy 122.868182 -382.677416) (xy 122.878305 -382.677941)
			(xy 122.897021 -382.685658) (xy 122.911377 -382.699932) (xy 122.919201 -382.718604) (xy 122.919744 -382.728724)
			(xy 122.919744 -382.886712) (xy 122.920161 -382.895898) (xy 122.926671 -382.913082) (xy 122.932444 -382.92024)
			(xy 122.954197 -382.945921) (xy 122.992148 -383.001503) (xy 123.023183 -383.061222) (xy 123.046859 -383.124223)
			(xy 123.062835 -383.189602) (xy 123.070882 -383.256422) (xy 123.070886 -383.323724) (xy 123.062845 -383.390545)
			(xy 123.046875 -383.455925) (xy 123.023206 -383.518928) (xy 122.992176 -383.57865) (xy 122.95423 -383.634236)
			(xy 122.932444 -383.659888) (xy 122.926621 -383.667014) (xy 122.920124 -383.684219) (xy 122.919744 -383.693416)
			(xy 122.919744 -384.186684) (xy 122.920174 -384.195869) (xy 122.926675 -384.213053) (xy 122.932444 -384.220212)
			(xy 122.954268 -384.245835) (xy 122.992217 -384.301425) (xy 123.023249 -384.361152) (xy 123.046921 -384.424161)
			(xy 123.062892 -384.489547) (xy 123.070933 -384.556373) (xy 123.07093 -384.623681) (xy 123.062882 -384.690507)
			(xy 123.046905 -384.755891) (xy 123.023227 -384.818897) (xy 122.992189 -384.878622) (xy 122.954235 -384.934208)
			(xy 122.932444 -384.95986) (xy 122.926633 -384.966994) (xy 122.920128 -384.984193) (xy 122.919744 -384.993388)
			(xy 122.919744 -385.151376) (xy 122.91926 -385.161523) (xy 122.91148 -385.180267) (xy 122.897103 -385.194589)
			(xy 122.878331 -385.202298) (xy 122.868182 -385.202684) (xy 122.151902 -385.202684) (xy 122.141778 -385.202172)
			(xy 122.123062 -385.19445) (xy 122.108706 -385.180171) (xy 122.100883 -385.161497) (xy 122.10034 -385.151376)
			(xy 122.10034 -384.993388) (xy 122.099927 -384.984201) (xy 122.093414 -384.967017) (xy 122.08764 -384.95986)
			(xy 122.065888 -384.934179) (xy 122.027938 -384.878596) (xy 121.996903 -384.818877) (xy 121.973228 -384.755876)
			(xy 121.957253 -384.690498) (xy 121.949206 -384.623678) (xy 121.949202 -384.556376) (xy 121.957243 -384.489556)
			(xy 121.973212 -384.424176) (xy 121.996881 -384.361173) (xy 122.02791 -384.30145) (xy 122.065855 -384.245864)
			(xy 122.08764 -384.220212) (xy 122.093461 -384.213085) (xy 122.09996 -384.19588) (xy 122.10034 -384.186684)
			(xy 122.10034 -383.693416) (xy 122.099913 -383.684231) (xy 122.09341 -383.667047) (xy 122.08764 -383.659888)
			(xy 122.065817 -383.634265) (xy 122.027869 -383.578674) (xy 121.996837 -383.518947) (xy 121.973166 -383.455939)
			(xy 121.957196 -383.390553) (xy 121.949155 -383.323727) (xy 120.847049 -383.323727) (xy 120.847178 -383.324069)
			(xy 120.863212 -383.38956) (xy 120.871287 -383.4565) (xy 120.871286 -383.523925) (xy 120.863208 -383.590864)
			(xy 120.847171 -383.656354) (xy 120.823405 -383.719452) (xy 120.792252 -383.779248) (xy 120.754161 -383.834883)
			(xy 120.732296 -383.860548) (xy 120.726496 -383.867691) (xy 120.719984 -383.884883) (xy 120.719596 -383.894076)
			(xy 120.719596 -384.051556) (xy 120.719148 -384.061676) (xy 120.711413 -384.080379) (xy 120.697106 -384.094695)
			(xy 120.678408 -384.102441) (xy 120.668288 -384.102864) (xy 119.952008 -384.102864) (xy 119.941882 -384.102477)
			(xy 119.923171 -384.094724) (xy 119.908855 -384.080399) (xy 119.901116 -384.061683) (xy 119.9007 -384.051556)
			(xy 119.9007 -383.894076) (xy 119.900302 -383.884888) (xy 119.89378 -383.867703) (xy 119.888 -383.860548)
			(xy 119.866152 -383.83487) (xy 119.828063 -383.779237) (xy 119.796911 -383.719443) (xy 119.773146 -383.656348)
			(xy 119.75711 -383.59086) (xy 119.749032 -383.523923) (xy 119.749031 -383.456501) (xy 119.757105 -383.389564)
			(xy 119.773139 -383.324075) (xy 119.796901 -383.260979) (xy 119.82805 -383.201184) (xy 119.866137 -383.145549)
			(xy 119.888 -383.119884) (xy 119.893786 -383.112731) (xy 119.900307 -383.095547) (xy 119.9007 -383.086356)
			(xy 119.9007 -382.59385) (xy 119.900266 -382.584665) (xy 119.893769 -382.567481) (xy 119.888 -382.560322)
			(xy 119.866126 -382.534665) (xy 119.828038 -382.479029) (xy 119.796888 -382.419232) (xy 119.773124 -382.356134)
			(xy 119.757089 -382.290644) (xy 119.749014 -382.223705) (xy 116.470967 -382.223705) (xy 116.46293 -382.290468)
			(xy 116.446957 -382.35585) (xy 116.423283 -382.418855) (xy 116.392248 -382.478577) (xy 116.354297 -382.534163)
			(xy 116.332508 -382.559814) (xy 116.326724 -382.566968) (xy 116.320202 -382.584152) (xy 116.319808 -382.593342)
			(xy 116.319808 -383.086864) (xy 116.320234 -383.09605) (xy 116.326736 -383.113234) (xy 116.332508 -383.120392)
			(xy 116.354313 -383.146031) (xy 116.392265 -383.201618) (xy 116.4233 -383.261343) (xy 116.446764 -383.323787)
			(xy 117.548835 -383.323787) (xy 117.548838 -383.256359) (xy 117.556918 -383.189418) (xy 117.572959 -383.123926)
			(xy 117.59673 -383.060827) (xy 117.627888 -383.00103) (xy 117.665984 -382.945396) (xy 117.687852 -382.919732)
			(xy 117.693666 -382.9126) (xy 117.700169 -382.895399) (xy 117.700552 -382.886204) (xy 117.700552 -382.728724)
			(xy 117.701103 -382.718623) (xy 117.708824 -382.699954) (xy 117.7231 -382.68566) (xy 117.741759 -382.677916)
			(xy 117.75186 -382.677416) (xy 118.46814 -382.677416) (xy 118.478253 -382.677853) (xy 118.496935 -382.685607)
			(xy 118.511229 -382.699918) (xy 118.51896 -382.71861) (xy 118.519448 -382.728724) (xy 118.519448 -382.886204)
			(xy 118.519868 -382.89539) (xy 118.526376 -382.912574) (xy 118.532148 -382.919732) (xy 118.553978 -382.945426)
			(xy 118.592072 -383.001055) (xy 118.623227 -383.060847) (xy 118.646995 -383.12394) (xy 118.663035 -383.189426)
			(xy 118.671114 -383.256362) (xy 118.671118 -383.323784) (xy 118.663045 -383.390721) (xy 118.647011 -383.456208)
			(xy 118.623249 -383.519304) (xy 118.592099 -383.579099) (xy 118.554012 -383.634732) (xy 118.532148 -383.660396)
			(xy 118.526364 -383.66755) (xy 118.519843 -383.684734) (xy 118.519448 -383.693924) (xy 118.519448 -384.186176)
			(xy 118.519881 -384.195361) (xy 118.52638 -384.212545) (xy 118.532148 -384.219704) (xy 118.554049 -384.245339)
			(xy 118.59214 -384.300977) (xy 118.623292 -384.360777) (xy 118.647057 -384.423878) (xy 118.663091 -384.489371)
			(xy 118.671165 -384.556313) (xy 118.671162 -384.623741) (xy 118.663082 -384.690682) (xy 118.647041 -384.756174)
			(xy 118.62327 -384.819273) (xy 118.592112 -384.87907) (xy 118.554016 -384.934704) (xy 118.532148 -384.960368)
			(xy 118.526334 -384.9675) (xy 118.519831 -384.984701) (xy 118.519448 -384.993896) (xy 118.519448 -385.151376)
			(xy 118.518897 -385.161477) (xy 118.511176 -385.180146) (xy 118.4969 -385.19444) (xy 118.478241 -385.202184)
			(xy 118.46814 -385.202684) (xy 117.75186 -385.202684) (xy 117.741747 -385.202247) (xy 117.723065 -385.194493)
			(xy 117.708771 -385.180182) (xy 117.70104 -385.16149) (xy 117.700552 -385.151376) (xy 117.700552 -384.993896)
			(xy 117.700132 -384.98471) (xy 117.693624 -384.967526) (xy 117.687852 -384.960368) (xy 117.666022 -384.934674)
			(xy 117.627928 -384.879045) (xy 117.596773 -384.819253) (xy 117.573005 -384.75616) (xy 117.556965 -384.690674)
			(xy 117.548886 -384.623738) (xy 117.548882 -384.556316) (xy 117.556955 -384.489379) (xy 117.572989 -384.423892)
			(xy 117.596751 -384.360796) (xy 117.627901 -384.301001) (xy 117.665988 -384.245368) (xy 117.687852 -384.219704)
			(xy 117.693636 -384.21255) (xy 117.700157 -384.195366) (xy 117.700552 -384.186176) (xy 117.700552 -383.693924)
			(xy 117.700119 -383.684739) (xy 117.69362 -383.667555) (xy 117.687852 -383.660396) (xy 117.665951 -383.634761)
			(xy 117.62786 -383.579123) (xy 117.596708 -383.519323) (xy 117.572943 -383.456222) (xy 117.556909 -383.390729)
			(xy 117.548835 -383.323787) (xy 116.446764 -383.323787) (xy 116.446975 -383.324349) (xy 116.462948 -383.389733)
			(xy 116.470992 -383.456558) (xy 116.47099 -383.523866) (xy 116.462944 -383.59069) (xy 116.446967 -383.656074)
			(xy 116.423291 -383.719079) (xy 116.392252 -383.778803) (xy 116.354298 -383.834389) (xy 116.332508 -383.86004)
			(xy 116.326713 -383.867186) (xy 116.320197 -383.884376) (xy 116.319808 -383.893568) (xy 116.319808 -384.051556)
			(xy 116.319342 -384.061706) (xy 116.311563 -384.080456) (xy 116.297179 -384.094781) (xy 116.278398 -384.102483)
			(xy 116.268246 -384.102864) (xy 115.551966 -384.102864) (xy 115.541838 -384.102401) (xy 115.523116 -384.094663)
			(xy 115.508761 -384.08037) (xy 115.500943 -384.061682) (xy 115.500404 -384.051556) (xy 115.500404 -383.893568)
			(xy 115.500009 -383.884379) (xy 115.493485 -383.867195) (xy 115.487704 -383.86004) (xy 115.465933 -383.834374)
			(xy 115.427986 -383.778789) (xy 115.396954 -383.719067) (xy 115.373282 -383.656064) (xy 115.357309 -383.590684)
			(xy 115.349264 -383.523864) (xy 115.349262 -383.45656) (xy 115.357305 -383.38974) (xy 115.373275 -383.324359)
			(xy 115.396944 -383.261355) (xy 115.427974 -383.201632) (xy 115.465918 -383.146045) (xy 115.487704 -383.120392)
			(xy 115.493487 -383.113237) (xy 115.50001 -383.096054) (xy 115.500404 -383.086864) (xy 115.500404 -382.593342)
			(xy 115.499973 -382.584157) (xy 115.493474 -382.566973) (xy 115.487704 -382.559814) (xy 115.465908 -382.534169)
			(xy 115.427961 -382.478581) (xy 115.39693 -382.418856) (xy 115.37326 -382.355851) (xy 115.357288 -382.290468)
			(xy 115.349246 -382.223645) (xy 90.070711 -382.223645) (xy 90.062667 -382.290467) (xy 90.046695 -382.355848)
			(xy 90.023023 -382.418852) (xy 89.991991 -382.478576) (xy 89.954043 -382.534162) (xy 89.932256 -382.559814)
			(xy 89.926465 -382.566963) (xy 89.919948 -382.584151) (xy 89.919556 -382.593342) (xy 89.919556 -383.086864)
			(xy 89.919994 -383.096048) (xy 89.926489 -383.113232) (xy 89.932256 -383.120392) (xy 89.95406 -383.146031)
			(xy 89.992008 -383.201619) (xy 90.023041 -383.261345) (xy 90.046478 -383.323726) (xy 91.149124 -383.323726)
			(xy 91.149128 -383.256419) (xy 91.157175 -383.189595) (xy 91.17315 -383.124211) (xy 91.196825 -383.061205)
			(xy 91.227861 -383.001481) (xy 91.265811 -382.945893) (xy 91.2876 -382.92024) (xy 91.293405 -382.9131)
			(xy 91.299914 -382.895906) (xy 91.3003 -382.886712) (xy 91.3003 -382.728724) (xy 91.300741 -382.718571)
			(xy 91.308529 -382.699819) (xy 91.32292 -382.685495) (xy 91.341708 -382.677795) (xy 91.351862 -382.677416)
			(xy 92.068142 -382.677416) (xy 92.078268 -382.677891) (xy 92.096986 -382.685629) (xy 92.11134 -382.699918)
			(xy 92.119162 -382.7186) (xy 92.119704 -382.728724) (xy 92.119704 -382.886712) (xy 92.120108 -382.8959)
			(xy 92.126626 -382.913084) (xy 92.132404 -382.92024) (xy 92.154155 -382.945922) (xy 92.192102 -383.001505)
			(xy 92.223135 -383.061225) (xy 92.246808 -383.124225) (xy 92.262782 -383.189604) (xy 92.270828 -383.256422)
			(xy 92.270831 -383.323724) (xy 92.262791 -383.390543) (xy 92.246824 -383.455923) (xy 92.223157 -383.518926)
			(xy 92.19213 -383.578648) (xy 92.154188 -383.634235) (xy 92.132404 -383.659888) (xy 92.126588 -383.66702)
			(xy 92.120085 -383.68422) (xy 92.119704 -383.693416) (xy 92.119704 -384.186684) (xy 92.120121 -384.19587)
			(xy 92.12663 -384.213055) (xy 92.132404 -384.220212) (xy 92.154226 -384.245836) (xy 92.192171 -384.301427)
			(xy 92.2232 -384.361155) (xy 92.246869 -384.424163) (xy 92.260023 -384.478022) (xy 99.724972 -384.478022)
			(xy 99.724972 -384.276346) (xy 99.725522 -384.259618) (xy 99.734162 -384.227297) (xy 99.750866 -384.19831)
			(xy 99.774498 -384.174629) (xy 99.803451 -384.157865) (xy 99.835753 -384.149157) (xy 99.85248 -384.148584)
			(xy 100.10648 -384.148584) (xy 100.123172 -384.149152) (xy 100.155423 -384.157777) (xy 100.184348 -384.174447)
			(xy 100.207981 -384.198027) (xy 100.224714 -384.226915) (xy 100.233411 -384.259147) (xy 100.233988 -384.275838)
			(xy 100.233988 -384.477514) (xy 100.233431 -384.49424) (xy 100.224782 -384.526554) (xy 100.208076 -384.555535)
			(xy 100.184446 -384.579213) (xy 100.1555 -384.59598) (xy 100.123205 -384.604696) (xy 100.10648 -384.605276)
			(xy 99.85248 -384.605276) (xy 99.835783 -384.604782) (xy 99.803524 -384.596144) (xy 99.774595 -384.579461)
			(xy 99.750963 -384.555866) (xy 99.734233 -384.526963) (xy 99.725544 -384.494719) (xy 99.724972 -384.478022)
			(xy 92.260023 -384.478022) (xy 92.262838 -384.489548) (xy 92.270879 -384.556374) (xy 92.270875 -384.623681)
			(xy 92.262828 -384.690505) (xy 92.246853 -384.755889) (xy 92.223178 -384.818894) (xy 92.192143 -384.878619)
			(xy 92.154193 -384.934207) (xy 92.132404 -384.95986) (xy 92.1266 -384.967) (xy 92.12009 -384.984194)
			(xy 92.119704 -384.993388) (xy 92.119704 -385.151376) (xy 92.119259 -385.161528) (xy 92.111472 -385.180279)
			(xy 92.097082 -385.194603) (xy 92.078296 -385.202305) (xy 92.068142 -385.202684) (xy 91.351862 -385.202684)
			(xy 91.341736 -385.202205) (xy 91.323018 -385.194469) (xy 91.308664 -385.180181) (xy 91.300842 -385.1615)
			(xy 91.3003 -385.151376) (xy 91.3003 -384.993388) (xy 91.299895 -384.9842) (xy 91.293378 -384.967016)
			(xy 91.2876 -384.95986) (xy 91.265849 -384.934178) (xy 91.227901 -384.878595) (xy 91.196869 -384.818875)
			(xy 91.173196 -384.755875) (xy 91.157221 -384.690497) (xy 91.149175 -384.623678) (xy 91.149172 -384.556376)
			(xy 91.157212 -384.489557) (xy 91.17318 -384.424177) (xy 91.196847 -384.361174) (xy 91.227874 -384.301451)
			(xy 91.265816 -384.245865) (xy 91.2876 -384.220212) (xy 91.293416 -384.213081) (xy 91.299919 -384.19588)
			(xy 91.3003 -384.186684) (xy 91.3003 -383.693416) (xy 91.299882 -383.68423) (xy 91.293374 -383.667045)
			(xy 91.2876 -383.659888) (xy 91.265778 -383.634264) (xy 91.227833 -383.578673) (xy 91.196803 -383.518945)
			(xy 91.173134 -383.455937) (xy 91.157165 -383.390552) (xy 91.149124 -383.323726) (xy 90.046478 -383.323726)
			(xy 90.046713 -383.324351) (xy 90.062685 -383.389735) (xy 90.070728 -383.456559) (xy 90.070727 -383.523865)
			(xy 90.062681 -383.590689) (xy 90.046706 -383.656072) (xy 90.023031 -383.719077) (xy 89.991996 -383.778801)
			(xy 89.954045 -383.834388) (xy 89.932256 -383.86004) (xy 89.926454 -383.867181) (xy 89.919944 -383.884375)
			(xy 89.919556 -383.893568) (xy 89.919556 -384.051556) (xy 89.919043 -384.0617) (xy 89.911273 -384.080441)
			(xy 89.896905 -384.094764) (xy 89.87814 -384.102475) (xy 89.867994 -384.102864) (xy 89.151714 -384.102864)
			(xy 89.141589 -384.102362) (xy 89.122869 -384.09464) (xy 89.108512 -384.080358) (xy 89.100692 -384.061679)
			(xy 89.100152 -384.051556) (xy 89.100152 -383.893568) (xy 89.099745 -383.884381) (xy 89.093228 -383.867197)
			(xy 89.087452 -383.86004) (xy 89.06568 -383.834375) (xy 89.02773 -383.778791) (xy 88.996695 -383.719069)
			(xy 88.973021 -383.656066) (xy 88.957046 -383.590685) (xy 88.949001 -383.523864) (xy 88.948999 -383.45656)
			(xy 88.957042 -383.389738) (xy 88.973014 -383.324357) (xy 88.996685 -383.261353) (xy 89.027717 -383.20163)
			(xy 89.065665 -383.146044) (xy 89.087452 -383.120392) (xy 89.093241 -383.113242) (xy 89.099759 -383.096055)
			(xy 89.100152 -383.086864) (xy 89.100152 -382.593342) (xy 89.09971 -382.584158) (xy 89.093217 -382.566975)
			(xy 89.087452 -382.559814) (xy 89.065654 -382.53417) (xy 89.027704 -382.478583) (xy 88.996671 -382.418858)
			(xy 88.972998 -382.355853) (xy 88.957025 -382.290469) (xy 88.948982 -382.223646) (xy 85.670943 -382.223646)
			(xy 85.670943 -382.223704) (xy 85.662867 -382.290643) (xy 85.646832 -382.356132) (xy 85.623067 -382.419228)
			(xy 85.591915 -382.479024) (xy 85.553825 -382.534657) (xy 85.53196 -382.560322) (xy 85.526167 -382.567469)
			(xy 85.519651 -382.584658) (xy 85.51926 -382.59385) (xy 85.51926 -383.086356) (xy 85.5197 -383.09554)
			(xy 85.526194 -383.112724) (xy 85.53196 -383.119884) (xy 85.553841 -383.145536) (xy 85.591932 -383.201171)
			(xy 85.623084 -383.260969) (xy 85.646743 -383.323786) (xy 86.748805 -383.323786) (xy 86.748808 -383.25636)
			(xy 86.756888 -383.189419) (xy 86.772927 -383.123927) (xy 86.796696 -383.060829) (xy 86.827852 -383.001032)
			(xy 86.865945 -382.945397) (xy 86.887812 -382.919732) (xy 86.893621 -382.912596) (xy 86.900128 -382.895398)
			(xy 86.900512 -382.886204) (xy 86.900512 -382.728724) (xy 86.900936 -382.718602) (xy 86.908678 -382.699896)
			(xy 86.922993 -382.685581) (xy 86.941698 -382.677837) (xy 86.95182 -382.677416) (xy 87.6681 -382.677416)
			(xy 87.678224 -382.677816) (xy 87.696931 -382.685568) (xy 87.711246 -382.699889) (xy 87.718988 -382.718599)
			(xy 87.719408 -382.728724) (xy 87.719408 -382.886204) (xy 87.719815 -382.895392) (xy 87.726331 -382.912576)
			(xy 87.732108 -382.919732) (xy 87.753936 -382.945427) (xy 87.792026 -383.001057) (xy 87.823177 -383.060849)
			(xy 87.846943 -383.123942) (xy 87.862981 -383.189428) (xy 87.87106 -383.256363) (xy 87.871063 -383.323783)
			(xy 87.862991 -383.390719) (xy 87.846959 -383.456206) (xy 87.8232 -383.519301) (xy 87.792053 -383.579096)
			(xy 87.75397 -383.634731) (xy 87.732108 -383.660396) (xy 87.726332 -383.667556) (xy 87.719805 -383.684735)
			(xy 87.719408 -383.693924) (xy 87.719408 -384.186176) (xy 87.719828 -384.195362) (xy 87.726335 -384.212547)
			(xy 87.732108 -384.219704) (xy 87.754007 -384.24534) (xy 87.792094 -384.300979) (xy 87.823243 -384.360779)
			(xy 87.847005 -384.42388) (xy 87.863037 -384.489373) (xy 87.87111 -384.556314) (xy 87.871107 -384.62374)
			(xy 87.863028 -384.690681) (xy 87.846989 -384.756172) (xy 87.823221 -384.81927) (xy 87.792066 -384.879067)
			(xy 87.753974 -384.934703) (xy 87.732108 -384.960368) (xy 87.726301 -384.967506) (xy 87.719792 -384.984702)
			(xy 87.719408 -384.993896) (xy 87.719408 -385.151376) (xy 87.718965 -385.161496) (xy 87.711226 -385.180198)
			(xy 87.696918 -385.194512) (xy 87.67822 -385.20226) (xy 87.6681 -385.202684) (xy 86.95182 -385.202684)
			(xy 86.941697 -385.202267) (xy 86.922991 -385.194523) (xy 86.908675 -385.180206) (xy 86.900932 -385.161499)
			(xy 86.900512 -385.151376) (xy 86.900512 -384.993896) (xy 86.900101 -384.984709) (xy 86.893587 -384.967525)
			(xy 86.887812 -384.960368) (xy 86.865983 -384.934674) (xy 86.827892 -384.879044) (xy 86.796739 -384.819252)
			(xy 86.772973 -384.756158) (xy 86.756934 -384.690673) (xy 86.748855 -384.623738) (xy 86.748852 -384.556316)
			(xy 86.756925 -384.48938) (xy 86.772957 -384.423893) (xy 86.796717 -384.360798) (xy 86.827865 -384.301003)
			(xy 86.86595 -384.245369) (xy 86.887812 -384.219704) (xy 86.893591 -384.212546) (xy 86.900116 -384.195365)
			(xy 86.900512 -384.186176) (xy 86.900512 -383.693924) (xy 86.900088 -383.684738) (xy 86.893583 -383.667554)
			(xy 86.887812 -383.660396) (xy 86.865912 -383.63476) (xy 86.827824 -383.579122) (xy 86.796674 -383.519322)
			(xy 86.772911 -383.456221) (xy 86.756878 -383.390728) (xy 86.748805 -383.323786) (xy 85.646743 -383.323786)
			(xy 85.646849 -383.324068) (xy 85.662885 -383.389559) (xy 85.67096 -383.456499) (xy 85.670959 -383.523925)
			(xy 85.662881 -383.590865) (xy 85.646842 -383.656355) (xy 85.623074 -383.719453) (xy 85.59192 -383.77925)
			(xy 85.553826 -383.834883) (xy 85.53196 -383.860548) (xy 85.526156 -383.867687) (xy 85.519647 -383.884883)
			(xy 85.51926 -383.894076) (xy 85.51926 -384.051556) (xy 85.518847 -384.061681) (xy 85.511106 -384.080391)
			(xy 85.496787 -384.094708) (xy 85.478077 -384.102448) (xy 85.467952 -384.102864) (xy 84.751672 -384.102864)
			(xy 84.741543 -384.102506) (xy 84.722832 -384.094742) (xy 84.708517 -384.080407) (xy 84.70078 -384.061685)
			(xy 84.700364 -384.051556) (xy 84.700364 -383.894076) (xy 84.699951 -383.884889) (xy 84.693438 -383.867706)
			(xy 84.687664 -383.860548) (xy 84.665817 -383.834869) (xy 84.62773 -383.779236) (xy 84.596581 -383.719441)
			(xy 84.572817 -383.656346) (xy 84.556782 -383.590859) (xy 84.548705 -383.523923) (xy 84.548704 -383.456501)
			(xy 84.556778 -383.389565) (xy 84.57281 -383.324077) (xy 84.596571 -383.260981) (xy 84.627718 -383.201185)
			(xy 84.665802 -383.14555) (xy 84.687664 -383.119884) (xy 84.693458 -383.112737) (xy 84.699972 -383.095548)
			(xy 84.700364 -383.086356) (xy 84.700364 -382.59385) (xy 84.699916 -382.584667) (xy 84.693427 -382.567483)
			(xy 84.687664 -382.560322) (xy 84.665791 -382.534664) (xy 84.627705 -382.479028) (xy 84.596557 -382.41923)
			(xy 84.572795 -382.356132) (xy 84.556761 -382.290643) (xy 84.548687 -382.223704) (xy 81.271152 -382.223704)
			(xy 81.263076 -382.290642) (xy 81.247041 -382.356131) (xy 81.223277 -382.419228) (xy 81.192126 -382.479023)
			(xy 81.154036 -382.534657) (xy 81.132172 -382.560322) (xy 81.12638 -382.56747) (xy 81.119863 -382.584659)
			(xy 81.119472 -382.59385) (xy 81.119472 -383.086356) (xy 81.11991 -383.09554) (xy 81.126405 -383.112724)
			(xy 81.132172 -383.119884) (xy 81.154053 -383.145536) (xy 81.192143 -383.201172) (xy 81.223294 -383.260969)
			(xy 81.246931 -383.323727) (xy 82.349036 -383.323727) (xy 82.34904 -383.256419) (xy 82.357087 -383.189595)
			(xy 82.373063 -383.124211) (xy 82.396739 -383.061205) (xy 82.427775 -383.00148) (xy 82.465727 -382.945892)
			(xy 82.487516 -382.92024) (xy 82.493322 -382.913102) (xy 82.499831 -382.895906) (xy 82.500216 -382.886712)
			(xy 82.500216 -382.728724) (xy 82.500636 -382.718601) (xy 82.508379 -382.699895) (xy 82.522695 -382.685579)
			(xy 82.541401 -382.677836) (xy 82.551524 -382.677416) (xy 83.268058 -382.677416) (xy 83.278179 -382.67796)
			(xy 83.296895 -382.68567) (xy 83.311252 -382.699938) (xy 83.319076 -382.718606) (xy 83.31962 -382.728724)
			(xy 83.31962 -382.886712) (xy 83.32002 -382.8959) (xy 83.32654 -382.913085) (xy 83.33232 -382.92024)
			(xy 83.354074 -382.945921) (xy 83.392026 -383.001502) (xy 83.423063 -383.061221) (xy 83.44674 -383.124222)
			(xy 83.462717 -383.189601) (xy 83.470764 -383.256421) (xy 83.470767 -383.323724) (xy 83.462726 -383.390545)
			(xy 83.446756 -383.455926) (xy 83.423085 -383.518929) (xy 83.392054 -383.578651) (xy 83.354107 -383.634236)
			(xy 83.33232 -383.659888) (xy 83.326506 -383.667021) (xy 83.320001 -383.684221) (xy 83.31962 -383.693416)
			(xy 83.31962 -384.186684) (xy 83.320033 -384.195871) (xy 83.326544 -384.213056) (xy 83.33232 -384.220212)
			(xy 83.354144 -384.245835) (xy 83.392095 -384.301424) (xy 83.423129 -384.361152) (xy 83.446801 -384.42416)
			(xy 83.462773 -384.489546) (xy 83.470815 -384.556373) (xy 83.470812 -384.623681) (xy 83.462763 -384.690507)
			(xy 83.446785 -384.755892) (xy 83.423107 -384.818898) (xy 83.392067 -384.878622) (xy 83.354111 -384.934208)
			(xy 83.33232 -384.95986) (xy 83.326518 -384.967001) (xy 83.320006 -384.984195) (xy 83.31962 -384.993388)
			(xy 83.31962 -385.151376) (xy 83.319165 -385.161494) (xy 83.311428 -385.180194) (xy 83.297124 -385.194508)
			(xy 83.27843 -385.202258) (xy 83.268312 -385.202684) (xy 82.551778 -385.202684) (xy 82.541653 -385.202192)
			(xy 82.522936 -385.194462) (xy 82.508581 -385.180178) (xy 82.500758 -385.161499) (xy 82.500216 -385.151376)
			(xy 82.500216 -384.993388) (xy 82.499808 -384.984201) (xy 82.493293 -384.967016) (xy 82.487516 -384.95986)
			(xy 82.465765 -384.934178) (xy 82.427816 -384.878595) (xy 82.396783 -384.818876) (xy 82.373109 -384.755875)
			(xy 82.357134 -384.690497) (xy 82.349088 -384.623678) (xy 82.349084 -384.556376) (xy 82.357125 -384.489556)
			(xy 82.373093 -384.424177) (xy 82.396761 -384.361174) (xy 82.427788 -384.301451) (xy 82.465731 -384.245865)
			(xy 82.487516 -384.220212) (xy 82.493334 -384.213082) (xy 82.499835 -384.19588) (xy 82.500216 -384.186684)
			(xy 82.500216 -383.693416) (xy 82.499794 -383.68423) (xy 82.493288 -383.667046) (xy 82.487516 -383.659888)
			(xy 82.465694 -383.634265) (xy 82.427747 -383.578674) (xy 82.396717 -383.518946) (xy 82.373047 -383.455938)
			(xy 82.357077 -383.390552) (xy 82.349036 -383.323727) (xy 81.246931 -383.323727) (xy 81.247059 -383.324068)
			(xy 81.263094 -383.389559) (xy 81.271169 -383.456499) (xy 81.271168 -383.523925) (xy 81.26309 -383.590865)
			(xy 81.247052 -383.656355) (xy 81.223285 -383.719453) (xy 81.19213 -383.779249) (xy 81.154038 -383.834883)
			(xy 81.132172 -383.860548) (xy 81.126369 -383.867688) (xy 81.119859 -383.884883) (xy 81.119472 -383.894076)
			(xy 81.119472 -384.051556) (xy 81.119047 -384.061679) (xy 81.111308 -384.080387) (xy 81.096994 -384.094704)
			(xy 81.078287 -384.102446) (xy 81.068164 -384.102864) (xy 80.351884 -384.102864) (xy 80.341756 -384.102496)
			(xy 80.323045 -384.094736) (xy 80.30873 -384.080405) (xy 80.300992 -384.061685) (xy 80.300576 -384.051556)
			(xy 80.300576 -383.894076) (xy 80.300183 -383.884887) (xy 80.293658 -383.867703) (xy 80.287876 -383.860548)
			(xy 80.266029 -383.834869) (xy 80.227941 -383.779236) (xy 80.196791 -383.719442) (xy 80.173027 -383.656347)
			(xy 80.156991 -383.590859) (xy 80.148914 -383.523923) (xy 80.148913 -383.456501) (xy 80.156987 -383.389564)
			(xy 80.17302 -383.324076) (xy 80.196781 -383.26098) (xy 80.227929 -383.201184) (xy 80.266014 -383.14555)
			(xy 80.287876 -383.119884) (xy 80.293659 -383.112729) (xy 80.300183 -383.095546) (xy 80.300576 -383.086356)
			(xy 80.300576 -382.59385) (xy 80.300147 -382.584665) (xy 80.293647 -382.56748) (xy 80.287876 -382.560322)
			(xy 80.266003 -382.534664) (xy 80.227916 -382.479028) (xy 80.196767 -382.419231) (xy 80.173005 -382.356133)
			(xy 80.156971 -382.290643) (xy 80.148896 -382.223704) (xy 76.870825 -382.223704) (xy 76.862789 -382.290466)
			(xy 76.846818 -382.355847) (xy 76.823147 -382.418851) (xy 76.792117 -382.478575) (xy 76.75417 -382.534162)
			(xy 76.732384 -382.559814) (xy 76.726597 -382.566966) (xy 76.720077 -382.584151) (xy 76.719684 -382.593342)
			(xy 76.719684 -383.086864) (xy 76.720115 -383.096049) (xy 76.726615 -383.113233) (xy 76.732384 -383.120392)
			(xy 76.754187 -383.146031) (xy 76.792134 -383.20162) (xy 76.823165 -383.261346) (xy 76.846624 -383.323787)
			(xy 77.948717 -383.323787) (xy 77.94872 -383.256359) (xy 77.9568 -383.189418) (xy 77.97284 -383.123927)
			(xy 77.99661 -383.060828) (xy 78.027766 -383.001031) (xy 78.065861 -382.945397) (xy 78.087728 -382.919732)
			(xy 78.09354 -382.912598) (xy 78.100045 -382.895399) (xy 78.100428 -382.886204) (xy 78.100428 -382.728724)
			(xy 78.100836 -382.7186) (xy 78.108582 -382.699891) (xy 78.122901 -382.685575) (xy 78.141611 -382.677834)
			(xy 78.151736 -382.677416) (xy 78.868016 -382.677416) (xy 78.878142 -382.677803) (xy 78.896849 -382.685559)
			(xy 78.911163 -382.699885) (xy 78.918905 -382.718598) (xy 78.919324 -382.728724) (xy 78.919324 -382.886204)
			(xy 78.919727 -382.895392) (xy 78.926245 -382.912577) (xy 78.932024 -382.919732) (xy 78.953852 -382.945427)
			(xy 78.99194 -383.001058) (xy 79.023091 -383.06085) (xy 79.046856 -383.123943) (xy 79.062893 -383.189428)
			(xy 79.070972 -383.256363) (xy 79.070975 -383.323783) (xy 79.062903 -383.390719) (xy 79.046872 -383.456205)
			(xy 79.023113 -383.519301) (xy 78.991968 -383.579096) (xy 78.953885 -383.63473) (xy 78.932024 -383.660396)
			(xy 78.926249 -383.667557) (xy 78.919721 -383.684735) (xy 78.919324 -383.693924) (xy 78.919324 -384.186176)
			(xy 78.91974 -384.195363) (xy 78.926249 -384.212547) (xy 78.932024 -384.219704) (xy 78.953922 -384.24534)
			(xy 78.992009 -384.30098) (xy 79.023156 -384.36078) (xy 79.046917 -384.423881) (xy 79.06295 -384.489373)
			(xy 79.071022 -384.556314) (xy 79.071019 -384.62374) (xy 79.06294 -384.69068) (xy 79.046901 -384.756171)
			(xy 79.023134 -384.819269) (xy 78.991981 -384.879067) (xy 78.953889 -384.934702) (xy 78.932024 -384.960368)
			(xy 78.926219 -384.967507) (xy 78.919709 -384.984702) (xy 78.919324 -384.993896) (xy 78.919324 -385.151376)
			(xy 78.918865 -385.161494) (xy 78.911129 -385.180193) (xy 78.896826 -385.194507) (xy 78.878134 -385.202257)
			(xy 78.868016 -385.202684) (xy 78.151736 -385.202684) (xy 78.141614 -385.202254) (xy 78.122908 -385.194515)
			(xy 78.108592 -385.180202) (xy 78.100848 -385.161498) (xy 78.100428 -385.151376) (xy 78.100428 -384.993896)
			(xy 78.100014 -384.984709) (xy 78.093502 -384.967525) (xy 78.087728 -384.960368) (xy 78.065898 -384.934674)
			(xy 78.027807 -384.879044) (xy 77.996653 -384.819252) (xy 77.972886 -384.756159) (xy 77.956847 -384.690673)
			(xy 77.948768 -384.623738) (xy 77.948764 -384.556316) (xy 77.956837 -384.48938) (xy 77.972869 -384.423893)
			(xy 77.996631 -384.360797) (xy 78.027779 -384.301002) (xy 78.065865 -384.245369) (xy 78.087728 -384.219704)
			(xy 78.093509 -384.212548) (xy 78.100032 -384.195366) (xy 78.100428 -384.186176) (xy 78.100428 -383.693924)
			(xy 78.1 -383.684739) (xy 78.093498 -383.667555) (xy 78.087728 -383.660396) (xy 78.065828 -383.63476)
			(xy 78.027738 -383.579122) (xy 77.996587 -383.519322) (xy 77.972824 -383.456221) (xy 77.95679 -383.390728)
			(xy 77.948717 -383.323787) (xy 76.846624 -383.323787) (xy 76.846836 -383.324352) (xy 76.862807 -383.389735)
			(xy 76.870849 -383.456559) (xy 76.870848 -383.523865) (xy 76.862803 -383.590688) (xy 76.846829 -383.656071)
			(xy 76.823155 -383.719076) (xy 76.792121 -383.7788) (xy 76.754172 -383.834388) (xy 76.732384 -383.86004)
			(xy 76.726586 -383.867184) (xy 76.720073 -383.884376) (xy 76.719684 -383.893568) (xy 76.719684 -384.051556)
			(xy 76.719242 -384.061709) (xy 76.711458 -384.080464) (xy 76.697067 -384.094789) (xy 76.678277 -384.102488)
			(xy 76.668122 -384.102864) (xy 75.951842 -384.102864) (xy 75.941718 -384.102339) (xy 75.922999 -384.094626)
			(xy 75.908642 -384.080351) (xy 75.90082 -384.061677) (xy 75.90028 -384.051556) (xy 75.90028 -383.893568)
			(xy 75.89989 -383.884379) (xy 75.893363 -383.867194) (xy 75.88758 -383.86004) (xy 75.865807 -383.834375)
			(xy 75.827855 -383.778792) (xy 75.796819 -383.71907) (xy 75.773143 -383.656067) (xy 75.757168 -383.590686)
			(xy 75.749122 -383.523864) (xy 75.74912 -383.45656) (xy 75.757164 -383.389738) (xy 75.773136 -383.324356)
			(xy 75.796809 -383.261352) (xy 75.827842 -383.201629) (xy 75.865792 -383.146044) (xy 75.88758 -383.120392)
			(xy 75.89336 -383.113235) (xy 75.899885 -383.096054) (xy 75.90028 -383.086864) (xy 75.90028 -382.593342)
			(xy 75.899854 -382.584156) (xy 75.893352 -382.566972) (xy 75.88758 -382.559814) (xy 75.865781 -382.53417)
			(xy 75.82783 -382.478584) (xy 75.796795 -382.418859) (xy 75.773121 -382.355854) (xy 75.757147 -382.29047)
			(xy 75.749104 -382.223646) (xy 72.471064 -382.223646) (xy 72.471064 -382.223704) (xy 72.462989 -382.290642)
			(xy 72.446954 -382.356131) (xy 72.42319 -382.419227) (xy 72.39204 -382.479023) (xy 72.353952 -382.534657)
			(xy 72.332088 -382.560322) (xy 72.326298 -382.567472) (xy 72.31978 -382.584659) (xy 72.319388 -382.59385)
			(xy 72.319388 -383.086356) (xy 72.319822 -383.095541) (xy 72.326319 -383.112725) (xy 72.332088 -383.119884)
			(xy 72.353968 -383.145536) (xy 72.392057 -383.201172) (xy 72.423208 -383.26097) (xy 72.446843 -383.323727)
			(xy 73.548949 -383.323727) (xy 73.548952 -383.256419) (xy 73.556999 -383.189594) (xy 73.572976 -383.12421)
			(xy 73.596652 -383.061204) (xy 73.62769 -383.001479) (xy 73.665642 -382.945892) (xy 73.687432 -382.92024)
			(xy 73.693241 -382.913103) (xy 73.699747 -382.895906) (xy 73.700132 -382.886712) (xy 73.700132 -382.728724)
			(xy 73.700542 -382.718567) (xy 73.708335 -382.699809) (xy 73.722736 -382.685484) (xy 73.741535 -382.677789)
			(xy 73.751694 -382.677416) (xy 74.467974 -382.677416) (xy 74.478096 -382.677947) (xy 74.496812 -382.685662)
			(xy 74.511169 -382.699934) (xy 74.518993 -382.718605) (xy 74.519536 -382.728724) (xy 74.519536 -382.886712)
			(xy 74.519955 -382.895898) (xy 74.526464 -382.913082) (xy 74.532236 -382.92024) (xy 74.553989 -382.945921)
			(xy 74.591941 -383.001503) (xy 74.622977 -383.061222) (xy 74.646653 -383.124223) (xy 74.662629 -383.189602)
			(xy 74.670676 -383.256422) (xy 74.670679 -383.323724) (xy 74.662639 -383.390545) (xy 74.646669 -383.455925)
			(xy 74.622999 -383.518928) (xy 74.591968 -383.578651) (xy 74.554022 -383.634236) (xy 74.532236 -383.659888)
			(xy 74.526412 -383.667013) (xy 74.519915 -383.684219) (xy 74.519536 -383.693416) (xy 74.519536 -384.186684)
			(xy 74.519968 -384.195869) (xy 74.526468 -384.213052) (xy 74.532236 -384.220212) (xy 74.55406 -384.245835)
			(xy 74.592009 -384.301425) (xy 74.623043 -384.361152) (xy 74.646714 -384.424161) (xy 74.662686 -384.489547)
			(xy 74.670727 -384.556373) (xy 74.670724 -384.623681) (xy 74.662676 -384.690507) (xy 74.646698 -384.755891)
			(xy 74.623021 -384.818897) (xy 74.591982 -384.878622) (xy 74.554027 -384.934208) (xy 74.532236 -384.95986)
			(xy 74.526424 -384.966994) (xy 74.51992 -384.984193) (xy 74.519536 -384.993388) (xy 74.519536 -385.151376)
			(xy 74.51906 -385.161524) (xy 74.511279 -385.180269) (xy 74.496899 -385.194592) (xy 74.478124 -385.202299)
			(xy 74.467974 -385.202684) (xy 73.751694 -385.202684) (xy 73.74157 -385.202179) (xy 73.722853 -385.194454)
			(xy 73.708498 -385.180173) (xy 73.700675 -385.161497) (xy 73.700132 -385.151376) (xy 73.700132 -384.993388)
			(xy 73.699721 -384.984201) (xy 73.693207 -384.967017) (xy 73.687432 -384.95986) (xy 73.66568 -384.934178)
			(xy 73.627731 -384.878596) (xy 73.596696 -384.818877) (xy 73.573022 -384.755876) (xy 73.557047 -384.690497)
			(xy 73.549 -384.623678) (xy 73.548996 -384.556376) (xy 73.557037 -384.489556) (xy 73.573006 -384.424176)
			(xy 73.596674 -384.361173) (xy 73.627703 -384.30145) (xy 73.665647 -384.245864) (xy 73.687432 -384.220212)
			(xy 73.693253 -384.213084) (xy 73.699752 -384.19588) (xy 73.700132 -384.186684) (xy 73.700132 -383.693416)
			(xy 73.699707 -383.684231) (xy 73.693203 -383.667046) (xy 73.687432 -383.659888) (xy 73.665609 -383.634265)
			(xy 73.627662 -383.578674) (xy 73.59663 -383.518946) (xy 73.57296 -383.455938) (xy 73.55699 -383.390553)
			(xy 73.548949 -383.323727) (xy 72.446843 -383.323727) (xy 72.446972 -383.324069) (xy 72.463006 -383.38956)
			(xy 72.471081 -383.456499) (xy 72.47108 -383.523925) (xy 72.463002 -383.590864) (xy 72.446964 -383.656354)
			(xy 72.423198 -383.719452) (xy 72.392045 -383.779248) (xy 72.353953 -383.834883) (xy 72.332088 -383.860548)
			(xy 72.326287 -383.86769) (xy 72.319775 -383.884883) (xy 72.319388 -383.894076) (xy 72.319388 -384.051556)
			(xy 72.318948 -384.061677) (xy 72.311212 -384.080382) (xy 72.296902 -384.094698) (xy 72.278201 -384.102443)
			(xy 72.26808 -384.102864) (xy 71.5518 -384.102864) (xy 71.541673 -384.102483) (xy 71.522963 -384.094728)
			(xy 71.508647 -384.0804) (xy 71.500908 -384.061683) (xy 71.500492 -384.051556) (xy 71.500492 -383.894076)
			(xy 71.500095 -383.884887) (xy 71.493572 -383.867703) (xy 71.487792 -383.860548) (xy 71.465944 -383.83487)
			(xy 71.427855 -383.779237) (xy 71.396704 -383.719442) (xy 71.37294 -383.656347) (xy 71.356903 -383.59086)
			(xy 71.348826 -383.523923) (xy 71.348825 -383.456501) (xy 71.356899 -383.389564) (xy 71.372933 -383.324076)
			(xy 71.396695 -383.26098) (xy 71.427843 -383.201184) (xy 71.465929 -383.145549) (xy 71.487792 -383.119884)
			(xy 71.493577 -383.11273) (xy 71.500099 -383.095546) (xy 71.500492 -383.086356) (xy 71.500492 -382.59385)
			(xy 71.50006 -382.584665) (xy 71.493562 -382.56748) (xy 71.487792 -382.560322) (xy 71.465918 -382.534665)
			(xy 71.427831 -382.479029) (xy 71.396681 -382.419231) (xy 71.372918 -382.356134) (xy 71.356883 -382.290644)
			(xy 71.348808 -382.223705) (xy 46.070794 -382.223705) (xy 46.062758 -382.290467) (xy 46.046786 -382.355849)
			(xy 46.023113 -382.418853) (xy 45.99208 -382.478576) (xy 45.954131 -382.534162) (xy 45.932344 -382.559814)
			(xy 45.926552 -382.566962) (xy 45.920036 -382.584151) (xy 45.919644 -382.593342) (xy 45.919644 -383.086864)
			(xy 45.920084 -383.096048) (xy 45.926578 -383.113232) (xy 45.932344 -383.120392) (xy 45.954148 -383.146031)
			(xy 45.992098 -383.201619) (xy 46.023131 -383.261344) (xy 46.04657 -383.323727) (xy 47.149191 -383.323727)
			(xy 47.149195 -383.256419) (xy 47.157243 -383.189593) (xy 47.173221 -383.124208) (xy 47.1969 -383.061202)
			(xy 47.22794 -383.001477) (xy 47.265897 -382.945892) (xy 47.287688 -382.92024) (xy 47.293491 -382.913099)
			(xy 47.300002 -382.895905) (xy 47.300388 -382.886712) (xy 47.300388 -382.728724) (xy 47.300841 -382.718573)
			(xy 47.308626 -382.699823) (xy 47.323013 -382.685499) (xy 47.341797 -382.677797) (xy 47.35195 -382.677416)
			(xy 48.06823 -382.677416) (xy 48.078356 -382.677901) (xy 48.097073 -382.685634) (xy 48.111427 -382.699921)
			(xy 48.11925 -382.718601) (xy 48.119792 -382.728724) (xy 48.119792 -382.886712) (xy 48.120198 -382.8959)
			(xy 48.126715 -382.913084) (xy 48.132492 -382.92024) (xy 48.154243 -382.945922) (xy 48.192191 -383.001505)
			(xy 48.223224 -383.061224) (xy 48.246898 -383.124225) (xy 48.262872 -383.189603) (xy 48.270919 -383.256422)
			(xy 48.270922 -383.323724) (xy 48.262882 -383.390543) (xy 48.246914 -383.455923) (xy 48.223247 -383.518926)
			(xy 48.192219 -383.578649) (xy 48.154277 -383.634236) (xy 48.132492 -383.659888) (xy 48.126675 -383.667018)
			(xy 48.120173 -383.68422) (xy 48.119792 -383.693416) (xy 48.119792 -384.186684) (xy 48.120212 -384.19587)
			(xy 48.126719 -384.213054) (xy 48.132492 -384.220212) (xy 48.154314 -384.245835) (xy 48.19226 -384.301427)
			(xy 48.22329 -384.361155) (xy 48.246959 -384.424163) (xy 48.262929 -384.489548) (xy 48.27097 -384.556373)
			(xy 48.270966 -384.623681) (xy 48.262919 -384.690505) (xy 48.246943 -384.755889) (xy 48.223268 -384.818895)
			(xy 48.192232 -384.87862) (xy 48.154281 -384.934207) (xy 48.132492 -384.95986) (xy 48.126687 -384.966999)
			(xy 48.120177 -384.984194) (xy 48.119792 -384.993388) (xy 48.119792 -385.151376) (xy 48.119359 -385.16153)
			(xy 48.11157 -385.180283) (xy 48.097176 -385.194608) (xy 48.078386 -385.202307) (xy 48.06823 -385.202684)
			(xy 47.35195 -385.202684) (xy 47.341829 -385.202133) (xy 47.323114 -385.194426) (xy 47.308757 -385.18016)
			(xy 47.300932 -385.161493) (xy 47.300388 -385.151376) (xy 47.300388 -384.993388) (xy 47.299986 -384.9842)
			(xy 47.293467 -384.967016) (xy 47.287688 -384.95986) (xy 47.265934 -384.934179) (xy 47.227981 -384.878598)
			(xy 47.196944 -384.818879) (xy 47.173267 -384.755878) (xy 47.15729 -384.690499) (xy 47.149242 -384.623679)
			(xy 47.149239 -384.556376) (xy 47.15728 -384.489554) (xy 47.173251 -384.424174) (xy 47.196921 -384.361171)
			(xy 47.227953 -384.301448) (xy 47.265901 -384.245863) (xy 47.287688 -384.220212) (xy 47.293503 -384.21308)
			(xy 47.300007 -384.195879) (xy 47.300388 -384.186684) (xy 47.300388 -383.693416) (xy 47.299973 -383.684229)
			(xy 47.293463 -383.667045) (xy 47.287688 -383.659888) (xy 47.265863 -383.634266) (xy 47.227913 -383.578676)
			(xy 47.196878 -383.518949) (xy 47.173205 -383.45594) (xy 47.157233 -383.390554) (xy 47.149191 -383.323727)
			(xy 46.04657 -383.323727) (xy 46.046804 -383.32435) (xy 46.062776 -383.389734) (xy 46.070819 -383.456559)
			(xy 46.070818 -383.523865) (xy 46.062772 -383.590689) (xy 46.046797 -383.656073) (xy 46.023121 -383.719078)
			(xy 45.992085 -383.778802) (xy 45.954133 -383.834388) (xy 45.932344 -383.86004) (xy 45.926541 -383.86718)
			(xy 45.920032 -383.884375) (xy 45.919644 -383.893568) (xy 45.919644 -384.051556) (xy 45.919143 -384.061702)
			(xy 45.91137 -384.080445) (xy 45.896998 -384.094768) (xy 45.878229 -384.102477) (xy 45.868082 -384.102864)
			(xy 45.151802 -384.102864) (xy 45.141676 -384.102372) (xy 45.122956 -384.094645) (xy 45.108599 -384.080361)
			(xy 45.100779 -384.06168) (xy 45.10024 -384.051556) (xy 45.10024 -383.893568) (xy 45.099836 -383.88438)
			(xy 45.093317 -383.867197) (xy 45.08754 -383.86004) (xy 45.065768 -383.834375) (xy 45.027819 -383.77879)
			(xy 44.996785 -383.719068) (xy 44.973111 -383.656066) (xy 44.957137 -383.590685) (xy 44.949092 -383.523864)
			(xy 44.94909 -383.45656) (xy 44.957133 -383.389739) (xy 44.973104 -383.324357) (xy 44.996775 -383.261354)
			(xy 45.027806 -383.20163) (xy 45.065753 -383.146044) (xy 45.08754 -383.120392) (xy 45.093328 -383.113241)
			(xy 45.099847 -383.096055) (xy 45.10024 -383.086864) (xy 45.10024 -382.593342) (xy 45.0998 -382.584158)
			(xy 45.093306 -382.566974) (xy 45.08754 -382.559814) (xy 45.065742 -382.53417) (xy 45.027794 -382.478582)
			(xy 44.996761 -382.418858) (xy 44.973088 -382.355852) (xy 44.957116 -382.290469) (xy 44.949073 -382.223645)
			(xy 41.671034 -382.223645) (xy 41.671034 -382.223704) (xy 41.662958 -382.290643) (xy 41.646922 -382.356132)
			(xy 41.623157 -382.419229) (xy 41.592004 -382.479024) (xy 41.553913 -382.534658) (xy 41.532048 -382.560322)
			(xy 41.526253 -382.567468) (xy 41.519739 -382.584658) (xy 41.519348 -382.59385) (xy 41.519348 -383.086356)
			(xy 41.519791 -383.095539) (xy 41.526283 -383.112723) (xy 41.532048 -383.119884) (xy 41.55393 -383.145535)
			(xy 41.592021 -383.201171) (xy 41.623174 -383.260968) (xy 41.646834 -383.323786) (xy 42.748896 -383.323786)
			(xy 42.748899 -383.25636) (xy 42.756978 -383.189419) (xy 42.773018 -383.123928) (xy 42.796786 -383.06083)
			(xy 42.827941 -383.001032) (xy 42.866034 -382.945397) (xy 42.8879 -382.919732) (xy 42.893708 -382.912595)
			(xy 42.900216 -382.895398) (xy 42.9006 -382.886204) (xy 42.9006 -382.728724) (xy 42.901035 -382.718603)
			(xy 42.908776 -382.6999) (xy 42.923086 -382.685585) (xy 42.941787 -382.677839) (xy 42.951908 -382.677416)
			(xy 43.668188 -382.677416) (xy 43.678312 -382.677826) (xy 43.697018 -382.685573) (xy 43.711333 -382.699892)
			(xy 43.719076 -382.7186) (xy 43.719496 -382.728724) (xy 43.719496 -382.886204) (xy 43.719905 -382.895391)
			(xy 43.72642 -382.912575) (xy 43.732196 -382.919732) (xy 43.754025 -382.945426) (xy 43.792115 -383.001057)
			(xy 43.823267 -383.060849) (xy 43.847034 -383.123942) (xy 43.863072 -383.189427) (xy 43.871151 -383.256363)
			(xy 43.871154 -383.323783) (xy 43.863081 -383.390719) (xy 43.84705 -383.456206) (xy 43.823289 -383.519302)
			(xy 43.792143 -383.579097) (xy 43.754058 -383.634731) (xy 43.732196 -383.660396) (xy 43.726418 -383.667554)
			(xy 43.719892 -383.684735) (xy 43.719496 -383.693924) (xy 43.719496 -384.186176) (xy 43.719919 -384.195362)
			(xy 43.726424 -384.212546) (xy 43.732196 -384.219704) (xy 43.754095 -384.24534) (xy 43.792183 -384.300979)
			(xy 43.823333 -384.360779) (xy 43.847095 -384.42388) (xy 43.863128 -384.489372) (xy 43.871201 -384.556314)
			(xy 43.871198 -384.62374) (xy 43.863118 -384.690681) (xy 43.847079 -384.756172) (xy 43.823311 -384.819271)
			(xy 43.792156 -384.879068) (xy 43.754062 -384.934703) (xy 43.732196 -384.960368) (xy 43.726388 -384.967505)
			(xy 43.71988 -384.984702) (xy 43.719496 -384.993896) (xy 43.719496 -385.151376) (xy 43.719064 -385.161497)
			(xy 43.711323 -385.180201) (xy 43.697011 -385.194517) (xy 43.678309 -385.202262) (xy 43.668188 -385.202684)
			(xy 42.951908 -385.202684) (xy 42.941784 -385.202277) (xy 42.923078 -385.194529) (xy 42.908762 -385.180209)
			(xy 42.90102 -385.1615) (xy 42.9006 -385.151376) (xy 42.9006 -384.993896) (xy 42.900192 -384.984709)
			(xy 42.893677 -384.967524) (xy 42.8879 -384.960368) (xy 42.866071 -384.934674) (xy 42.827982 -384.879043)
			(xy 42.796829 -384.819251) (xy 42.773063 -384.756158) (xy 42.757025 -384.690672) (xy 42.748946 -384.623737)
			(xy 42.748943 -384.556317) (xy 42.757015 -384.489381) (xy 42.773047 -384.423894) (xy 42.796807 -384.360798)
			(xy 42.827954 -384.301003) (xy 42.866038 -384.245369) (xy 42.8879 -384.219704) (xy 42.893677 -384.212545)
			(xy 42.900204 -384.195365) (xy 42.9006 -384.186176) (xy 42.9006 -383.693924) (xy 42.900178 -383.684738)
			(xy 42.893673 -383.667554) (xy 42.8879 -383.660396) (xy 42.866001 -383.63476) (xy 42.827913 -383.579121)
			(xy 42.796764 -383.519321) (xy 42.773002 -383.45622) (xy 42.756969 -383.390728) (xy 42.748896 -383.323786)
			(xy 41.646834 -383.323786) (xy 41.64694 -383.324067) (xy 41.662976 -383.389558) (xy 41.671051 -383.456499)
			(xy 41.67105 -383.523925) (xy 41.662971 -383.590865) (xy 41.646933 -383.656356) (xy 41.623164 -383.719454)
			(xy 41.592009 -383.77925) (xy 41.553915 -383.834884) (xy 41.532048 -383.860548) (xy 41.526242 -383.867686)
			(xy 41.519734 -383.884882) (xy 41.519348 -383.894076) (xy 41.519348 -384.051556) (xy 41.518849 -384.06167)
			(xy 41.511124 -384.080363) (xy 41.496834 -384.094677) (xy 41.478153 -384.102432) (xy 41.46804 -384.102864)
			(xy 40.75176 -384.102864) (xy 40.74163 -384.102516) (xy 40.722919 -384.094748) (xy 40.708605 -384.08041)
			(xy 40.700868 -384.061686) (xy 40.700452 -384.051556) (xy 40.700452 -383.894076) (xy 40.700042 -383.884889)
			(xy 40.693527 -383.867705) (xy 40.687752 -383.860548) (xy 40.665902 -383.834871) (xy 40.627809 -383.779239)
			(xy 40.596655 -383.719445) (xy 40.572888 -383.65635) (xy 40.556849 -383.590862) (xy 40.548772 -383.523924)
			(xy 40.54877 -383.4565) (xy 40.556845 -383.389562) (xy 40.572881 -383.324073) (xy 40.596645 -383.260977)
			(xy 40.627797 -383.201182) (xy 40.665887 -383.145548) (xy 40.687752 -383.119884) (xy 40.693544 -383.112736)
			(xy 40.70006 -383.095547) (xy 40.700452 -383.086356) (xy 40.700452 -382.59385) (xy 40.700006 -382.584667)
			(xy 40.693516 -382.567483) (xy 40.687752 -382.560322) (xy 40.665876 -382.534666) (xy 40.627785 -382.479031)
			(xy 40.596631 -382.419234) (xy 40.572865 -382.356136) (xy 40.556829 -382.290645) (xy 40.548753 -382.223705)
			(xy 37.271243 -382.223705) (xy 37.263167 -382.290643) (xy 37.247132 -382.356132) (xy 37.223367 -382.419228)
			(xy 37.192215 -382.479024) (xy 37.154125 -382.534657) (xy 37.13226 -382.560322) (xy 37.126467 -382.567469)
			(xy 37.119951 -382.584658) (xy 37.11956 -382.59385) (xy 37.11956 -383.086356) (xy 37.12 -383.09554)
			(xy 37.126494 -383.112724) (xy 37.13226 -383.119884) (xy 37.154141 -383.145536) (xy 37.192232 -383.201171)
			(xy 37.223384 -383.260969) (xy 37.247021 -383.323727) (xy 38.349127 -383.323727) (xy 38.349131 -383.256419)
			(xy 38.357178 -383.189595) (xy 38.373154 -383.124211) (xy 38.396829 -383.061205) (xy 38.427864 -383.00148)
			(xy 38.465815 -382.945893) (xy 38.487604 -382.92024) (xy 38.493409 -382.913101) (xy 38.499919 -382.895906)
			(xy 38.500304 -382.886712) (xy 38.500304 -382.728724) (xy 38.500741 -382.718571) (xy 38.50853 -382.699818)
			(xy 38.522922 -382.685494) (xy 38.541711 -382.677794) (xy 38.551866 -382.677416) (xy 39.268146 -382.677416)
			(xy 39.278273 -382.677888) (xy 39.29699 -382.685627) (xy 39.311344 -382.699917) (xy 39.319166 -382.7186)
			(xy 39.319708 -382.728724) (xy 39.319708 -382.886712) (xy 39.320111 -382.8959) (xy 39.326629 -382.913084)
			(xy 39.332408 -382.92024) (xy 39.354162 -382.945921) (xy 39.392115 -383.001502) (xy 39.423153 -383.061221)
			(xy 39.44683 -383.124222) (xy 39.462807 -383.189601) (xy 39.470855 -383.256421) (xy 39.470858 -383.323725)
			(xy 39.462817 -383.390546) (xy 39.446846 -383.455926) (xy 39.423175 -383.51893) (xy 39.392143 -383.578652)
			(xy 39.354195 -383.634237) (xy 39.332408 -383.659888) (xy 39.326592 -383.66702) (xy 39.320089 -383.684221)
			(xy 39.319708 -383.693416) (xy 39.319708 -384.186684) (xy 39.320124 -384.195871) (xy 39.326633 -384.213055)
			(xy 39.332408 -384.220212) (xy 39.354233 -384.245834) (xy 39.392184 -384.301424) (xy 39.423219 -384.361151)
			(xy 39.446892 -384.42416) (xy 39.462864 -384.489546) (xy 39.470906 -384.556373) (xy 39.470902 -384.623682)
			(xy 39.462854 -384.690507) (xy 39.446876 -384.755892) (xy 39.423196 -384.818898) (xy 39.392156 -384.878623)
			(xy 39.354199 -384.934209) (xy 39.332408 -384.95986) (xy 39.326604 -384.967) (xy 39.320094 -384.984195)
			(xy 39.319708 -384.993388) (xy 39.319708 -385.151376) (xy 39.319259 -385.161528) (xy 39.311473 -385.180278)
			(xy 39.297085 -385.194602) (xy 39.278299 -385.202304) (xy 39.268146 -385.202684) (xy 38.551866 -385.202684)
			(xy 38.54174 -385.202202) (xy 38.523023 -385.194468) (xy 38.508668 -385.18018) (xy 38.500846 -385.1615)
			(xy 38.500304 -385.151376) (xy 38.500304 -384.993388) (xy 38.499899 -384.9842) (xy 38.493381 -384.967016)
			(xy 38.487604 -384.95986) (xy 38.465853 -384.934178) (xy 38.427905 -384.878595) (xy 38.396872 -384.818875)
			(xy 38.373199 -384.755875) (xy 38.357224 -384.690497) (xy 38.349178 -384.623678) (xy 38.349175 -384.556376)
			(xy 38.357215 -384.489557) (xy 38.373183 -384.424177) (xy 38.39685 -384.361174) (xy 38.427877 -384.301451)
			(xy 38.465819 -384.245865) (xy 38.487604 -384.220212) (xy 38.493421 -384.213081) (xy 38.499923 -384.19588)
			(xy 38.500304 -384.186684) (xy 38.500304 -383.693416) (xy 38.499885 -383.68423) (xy 38.493377 -383.667045)
			(xy 38.487604 -383.659888) (xy 38.465782 -383.634264) (xy 38.427837 -383.578673) (xy 38.396807 -383.518945)
			(xy 38.373138 -383.455937) (xy 38.357168 -383.390552) (xy 38.349127 -383.323727) (xy 37.247021 -383.323727)
			(xy 37.247149 -383.324068) (xy 37.263185 -383.389559) (xy 37.27126 -383.456499) (xy 37.271259 -383.523925)
			(xy 37.263181 -383.590865) (xy 37.247142 -383.656355) (xy 37.223374 -383.719453) (xy 37.19222 -383.77925)
			(xy 37.154126 -383.834883) (xy 37.13226 -383.860548) (xy 37.126456 -383.867687) (xy 37.119947 -383.884883)
			(xy 37.11956 -383.894076) (xy 37.11956 -384.051556) (xy 37.119147 -384.061681) (xy 37.111406 -384.080391)
			(xy 37.097087 -384.094708) (xy 37.078377 -384.102448) (xy 37.068252 -384.102864) (xy 36.351972 -384.102864)
			(xy 36.341843 -384.102506) (xy 36.323132 -384.094742) (xy 36.308817 -384.080407) (xy 36.30108 -384.061685)
			(xy 36.300664 -384.051556) (xy 36.300664 -383.894076) (xy 36.300251 -383.884889) (xy 36.293738 -383.867706)
			(xy 36.287964 -383.860548) (xy 36.266117 -383.834869) (xy 36.22803 -383.779236) (xy 36.196881 -383.719441)
			(xy 36.173117 -383.656346) (xy 36.157082 -383.590859) (xy 36.149005 -383.523923) (xy 36.149004 -383.456501)
			(xy 36.157078 -383.389565) (xy 36.17311 -383.324077) (xy 36.196871 -383.260981) (xy 36.228018 -383.201185)
			(xy 36.266102 -383.14555) (xy 36.287964 -383.119884) (xy 36.293758 -383.112737) (xy 36.300272 -383.095548)
			(xy 36.300664 -383.086356) (xy 36.300664 -382.59385) (xy 36.300216 -382.584667) (xy 36.293727 -382.567483)
			(xy 36.287964 -382.560322) (xy 36.266091 -382.534664) (xy 36.228005 -382.479028) (xy 36.196857 -382.41923)
			(xy 36.173095 -382.356132) (xy 36.157061 -382.290643) (xy 36.148987 -382.223704) (xy 32.870916 -382.223704)
			(xy 32.86288 -382.290466) (xy 32.846909 -382.355848) (xy 32.823237 -382.418852) (xy 32.792206 -382.478575)
			(xy 32.754259 -382.534162) (xy 32.732472 -382.559814) (xy 32.726683 -382.566965) (xy 32.720165 -382.584151)
			(xy 32.719772 -382.593342) (xy 32.719772 -383.086864) (xy 32.720206 -383.096049) (xy 32.726704 -383.113233)
			(xy 32.732472 -383.120392) (xy 32.754275 -383.146031) (xy 32.792223 -383.20162) (xy 32.823255 -383.261345)
			(xy 32.846714 -383.323786) (xy 33.948808 -383.323786) (xy 33.948811 -383.25636) (xy 33.956891 -383.189419)
			(xy 33.972931 -383.123927) (xy 33.996699 -383.060829) (xy 34.027855 -383.001032) (xy 34.065949 -382.945397)
			(xy 34.087816 -382.919732) (xy 34.093626 -382.912596) (xy 34.100132 -382.895398) (xy 34.100516 -382.886204)
			(xy 34.100516 -382.728724) (xy 34.100936 -382.718601) (xy 34.108679 -382.699895) (xy 34.122995 -382.685579)
			(xy 34.141701 -382.677836) (xy 34.151824 -382.677416) (xy 34.868104 -382.677416) (xy 34.878229 -382.677813)
			(xy 34.896935 -382.685566) (xy 34.91125 -382.699888) (xy 34.918992 -382.718599) (xy 34.919412 -382.728724)
			(xy 34.919412 -382.886204) (xy 34.919818 -382.895392) (xy 34.926334 -382.912576) (xy 34.932112 -382.919732)
			(xy 34.95394 -382.945427) (xy 34.992029 -383.001057) (xy 35.023181 -383.060849) (xy 35.046946 -383.123942)
			(xy 35.062984 -383.189428) (xy 35.071063 -383.256363) (xy 35.071066 -383.323783) (xy 35.062994 -383.390719)
			(xy 35.046962 -383.456206) (xy 35.023203 -383.519301) (xy 34.992057 -383.579096) (xy 34.953973 -383.634731)
			(xy 34.932112 -383.660396) (xy 34.926336 -383.667556) (xy 34.919809 -383.684735) (xy 34.919412 -383.693924)
			(xy 34.919412 -384.186176) (xy 34.919831 -384.195362) (xy 34.926338 -384.212547) (xy 34.932112 -384.219704)
			(xy 34.954011 -384.24534) (xy 34.992098 -384.300979) (xy 35.023246 -384.36078) (xy 35.047008 -384.42388)
			(xy 35.06304 -384.489373) (xy 35.071113 -384.556314) (xy 35.07111 -384.62374) (xy 35.063031 -384.690681)
			(xy 35.046992 -384.756172) (xy 35.023224 -384.81927) (xy 34.99207 -384.879067) (xy 34.953978 -384.934703)
			(xy 34.932112 -384.960368) (xy 34.926305 -384.967506) (xy 34.919796 -384.984702) (xy 34.919412 -384.993896)
			(xy 34.919412 -385.151376) (xy 34.918965 -385.161495) (xy 34.911227 -385.180196) (xy 34.89692 -385.194511)
			(xy 34.878223 -385.202259) (xy 34.868104 -385.202684) (xy 34.151824 -385.202684) (xy 34.141701 -385.202264)
			(xy 34.122995 -385.194521) (xy 34.108679 -385.180205) (xy 34.100936 -385.161499) (xy 34.100516 -385.151376)
			(xy 34.100516 -384.993896) (xy 34.100104 -384.984709) (xy 34.093591 -384.967525) (xy 34.087816 -384.960368)
			(xy 34.065987 -384.934674) (xy 34.027896 -384.879044) (xy 33.996743 -384.819252) (xy 33.972976 -384.756159)
			(xy 33.956937 -384.690673) (xy 33.948858 -384.623738) (xy 33.948855 -384.556316) (xy 33.956928 -384.48938)
			(xy 33.97296 -384.423893) (xy 33.996721 -384.360798) (xy 34.027868 -384.301003) (xy 34.065954 -384.245369)
			(xy 34.087816 -384.219704) (xy 34.093595 -384.212547) (xy 34.10012 -384.195365) (xy 34.100516 -384.186176)
			(xy 34.100516 -383.693924) (xy 34.100091 -383.684739) (xy 34.093587 -383.667554) (xy 34.087816 -383.660396)
			(xy 34.065916 -383.63476) (xy 34.027827 -383.579122) (xy 33.996677 -383.519322) (xy 33.972915 -383.456221)
			(xy 33.956881 -383.390728) (xy 33.948808 -383.323786) (xy 32.846714 -383.323786) (xy 32.846926 -383.324351)
			(xy 32.862898 -383.389735) (xy 32.87094 -383.456559) (xy 32.870939 -383.523865) (xy 32.862893 -383.590689)
			(xy 32.846919 -383.656072) (xy 32.823245 -383.719077) (xy 32.79221 -383.778801) (xy 32.75426 -383.834388)
			(xy 32.732472 -383.86004) (xy 32.726672 -383.867183) (xy 32.72016 -383.884375) (xy 32.719772 -383.893568)
			(xy 32.719772 -384.051556) (xy 32.719342 -384.061711) (xy 32.711555 -384.080468) (xy 32.697161 -384.094793)
			(xy 32.678367 -384.10249) (xy 32.66821 -384.102864) (xy 31.95193 -384.102864) (xy 31.941806 -384.102349)
			(xy 31.923086 -384.094632) (xy 31.908729 -384.080354) (xy 31.900908 -384.061678) (xy 31.900368 -384.051556)
			(xy 31.900368 -383.893568) (xy 31.899958 -383.884381) (xy 31.893443 -383.867197) (xy 31.887668 -383.86004)
			(xy 31.865895 -383.834375) (xy 31.827944 -383.778791) (xy 31.796908 -383.71907) (xy 31.773234 -383.656067)
			(xy 31.757259 -383.590686) (xy 31.749213 -383.523864) (xy 31.749211 -383.45656) (xy 31.757254 -383.389738)
			(xy 31.773226 -383.324356) (xy 31.796899 -383.261352) (xy 31.827932 -383.201629) (xy 31.86588 -383.146044)
			(xy 31.887668 -383.120392) (xy 31.893459 -383.113243) (xy 31.899975 -383.096055) (xy 31.900368 -383.086864)
			(xy 31.900368 -382.593342) (xy 31.899923 -382.584159) (xy 31.893432 -382.566975) (xy 31.887668 -382.559814)
			(xy 31.86587 -382.53417) (xy 31.827919 -382.478583) (xy 31.796885 -382.418859) (xy 31.773211 -382.355853)
			(xy 31.757238 -382.29047) (xy 31.749194 -382.223646) (xy 28.471155 -382.223646) (xy 28.471155 -382.223704)
			(xy 28.463079 -382.290642) (xy 28.447044 -382.356131) (xy 28.42328 -382.419228) (xy 28.392129 -382.479023)
			(xy 28.35404 -382.534657) (xy 28.332176 -382.560322) (xy 28.326385 -382.567471) (xy 28.319868 -382.584659)
			(xy 28.319476 -382.59385) (xy 28.319476 -383.086356) (xy 28.319913 -383.09554) (xy 28.326409 -383.112725)
			(xy 28.332176 -383.119884) (xy 28.354057 -383.145536) (xy 28.392146 -383.201172) (xy 28.423298 -383.26097)
			(xy 28.446934 -383.323727) (xy 29.549039 -383.323727) (xy 29.549043 -383.256419) (xy 29.55709 -383.189594)
			(xy 29.573066 -383.12421) (xy 29.596742 -383.061205) (xy 29.627779 -383.00148) (xy 29.665731 -382.945892)
			(xy 29.68752 -382.92024) (xy 29.693327 -382.913102) (xy 29.699835 -382.895906) (xy 29.70022 -382.886712)
			(xy 29.70022 -382.728724) (xy 29.700636 -382.718601) (xy 29.70838 -382.699894) (xy 29.722697 -382.685578)
			(xy 29.741405 -382.677835) (xy 29.751528 -382.677416) (xy 30.468062 -382.677416) (xy 30.478183 -382.677957)
			(xy 30.496899 -382.685668) (xy 30.511256 -382.699938) (xy 30.51908 -382.718606) (xy 30.519624 -382.728724)
			(xy 30.519624 -382.886712) (xy 30.520023 -382.8959) (xy 30.526544 -382.913085) (xy 30.532324 -382.92024)
			(xy 30.554077 -382.945921) (xy 30.59203 -383.001502) (xy 30.623067 -383.061222) (xy 30.646743 -383.124222)
			(xy 30.66272 -383.189601) (xy 30.670767 -383.256421) (xy 30.67077 -383.323724) (xy 30.662729 -383.390545)
			(xy 30.646759 -383.455926) (xy 30.623089 -383.518929) (xy 30.592058 -383.578651) (xy 30.554111 -383.634236)
			(xy 30.532324 -383.659888) (xy 30.52651 -383.667021) (xy 30.520005 -383.684221) (xy 30.519624 -383.693416)
			(xy 30.519624 -384.186684) (xy 30.520036 -384.195871) (xy 30.526548 -384.213056) (xy 30.532324 -384.220212)
			(xy 30.554149 -384.245834) (xy 30.592099 -384.301424) (xy 30.623132 -384.361152) (xy 30.646805 -384.42416)
			(xy 30.662776 -384.489546) (xy 30.670818 -384.556373) (xy 30.670815 -384.623681) (xy 30.662767 -384.690507)
			(xy 30.646789 -384.755892) (xy 30.62311 -384.818898) (xy 30.592071 -384.878622) (xy 30.554115 -384.934209)
			(xy 30.532324 -384.95986) (xy 30.526522 -384.967002) (xy 30.52001 -384.984195) (xy 30.519624 -384.993388)
			(xy 30.519624 -385.151376) (xy 30.519165 -385.161494) (xy 30.511429 -385.180193) (xy 30.497126 -385.194507)
			(xy 30.478434 -385.202257) (xy 30.468316 -385.202684) (xy 29.751782 -385.202684) (xy 29.741657 -385.202189)
			(xy 29.72294 -385.19446) (xy 29.708585 -385.180177) (xy 29.700762 -385.161498) (xy 29.70022 -385.151376)
			(xy 29.70022 -384.993388) (xy 29.699811 -384.984201) (xy 29.693296 -384.967017) (xy 29.68752 -384.95986)
			(xy 29.665769 -384.934178) (xy 29.62782 -384.878596) (xy 29.596786 -384.818876) (xy 29.573112 -384.755875)
			(xy 29.557137 -384.690497) (xy 29.549091 -384.623678) (xy 29.549087 -384.556376) (xy 29.557128 -384.489556)
			(xy 29.573096 -384.424176) (xy 29.596764 -384.361174) (xy 29.627792 -384.301451) (xy 29.665735 -384.245865)
			(xy 29.68752 -384.220212) (xy 29.693339 -384.213083) (xy 29.69984 -384.19588) (xy 29.70022 -384.186684)
			(xy 29.70022 -383.693416) (xy 29.699797 -383.68423) (xy 29.693292 -383.667046) (xy 29.68752 -383.659888)
			(xy 29.665697 -383.634265) (xy 29.627751 -383.578674) (xy 29.59672 -383.518946) (xy 29.57305 -383.455938)
			(xy 29.55708 -383.390552) (xy 29.549039 -383.323727) (xy 28.446934 -383.323727) (xy 28.447062 -383.324068)
			(xy 28.463097 -383.389559) (xy 28.471172 -383.456499) (xy 28.471171 -383.523925) (xy 28.463093 -383.590865)
			(xy 28.447055 -383.656355) (xy 28.423288 -383.719452) (xy 28.392134 -383.779249) (xy 28.354042 -383.834883)
			(xy 28.332176 -383.860548) (xy 28.326374 -383.867689) (xy 28.319863 -383.884883) (xy 28.319476 -383.894076)
			(xy 28.319476 -384.051556) (xy 28.319047 -384.061679) (xy 28.311309 -384.080386) (xy 28.296996 -384.094702)
			(xy 28.27829 -384.102445) (xy 28.268168 -384.102864) (xy 27.551888 -384.102864) (xy 27.54176 -384.102493)
			(xy 27.523049 -384.094734) (xy 27.508734 -384.080404) (xy 27.500996 -384.061684) (xy 27.50058 -384.051556)
			(xy 27.50058 -383.894076) (xy 27.500186 -383.884887) (xy 27.493661 -383.867703) (xy 27.48788 -383.860548)
			(xy 27.466032 -383.834869) (xy 27.427945 -383.779236) (xy 27.396794 -383.719442) (xy 27.37303 -383.656347)
			(xy 27.356994 -383.59086) (xy 27.348917 -383.523923) (xy 27.348916 -383.456501) (xy 27.35699 -383.389564)
			(xy 27.373023 -383.324076) (xy 27.396784 -383.26098) (xy 27.427932 -383.201184) (xy 27.466018 -383.14555)
			(xy 27.48788 -383.119884) (xy 27.493664 -383.112729) (xy 27.500187 -383.095546) (xy 27.50058 -383.086356)
			(xy 27.50058 -382.59385) (xy 27.50015 -382.584665) (xy 27.49365 -382.56748) (xy 27.48788 -382.560322)
			(xy 27.466007 -382.534665) (xy 27.42792 -382.479028) (xy 27.396771 -382.419231) (xy 27.373008 -382.356133)
			(xy 27.356974 -382.290643) (xy 27.348899 -382.223705) (xy 11.050524 -382.223705) (xy 11.050524 -382.269746)
			(xy 11.050058 -382.286478) (xy 11.041396 -382.318803) (xy 11.024673 -382.34779) (xy 11.001026 -382.371469)
			(xy 10.972061 -382.388231) (xy 10.939748 -382.396936) (xy 10.923016 -382.397508) (xy 10.437114 -382.397508)
			(xy 10.42037 -382.396904) (xy 10.388023 -382.388241) (xy 10.359018 -382.371503) (xy 10.335334 -382.34783)
			(xy 10.318582 -382.318833) (xy 10.309904 -382.28649) (xy 10.309352 -382.269746) (xy 0.509016 -382.269746)
			(xy 0.509016 -383.239772) (xy 14.279372 -383.239772) (xy 14.279372 -382.75387) (xy 14.27981 -382.737111)
			(xy 14.288493 -382.704738) (xy 14.305259 -382.675714) (xy 14.328965 -382.65202) (xy 14.357997 -382.635268)
			(xy 14.390375 -382.626602) (xy 14.407134 -382.626108) (xy 14.753082 -382.626108) (xy 14.769827 -382.6267)
			(xy 14.802177 -382.635363) (xy 14.831183 -382.652103) (xy 14.854868 -382.675779) (xy 14.871619 -382.704779)
			(xy 14.880294 -382.737125) (xy 14.880844 -382.75387) (xy 14.880844 -383.239772) (xy 14.880242 -383.256462)
			(xy 14.871621 -383.288708) (xy 14.854957 -383.317631) (xy 14.831384 -383.341263) (xy 14.802503 -383.357998)
			(xy 14.770278 -383.3667) (xy 14.75359 -383.36728) (xy 14.407134 -383.36728) (xy 14.39041 -383.366689)
			(xy 14.358096 -383.358051) (xy 14.329115 -383.341352) (xy 14.305435 -383.317729) (xy 14.288667 -383.288787)
			(xy 14.279951 -383.256495) (xy 14.279372 -383.239772) (xy 0.509016 -383.239772) (xy 0.509016 -385.278122)
			(xy 99.724972 -385.278122) (xy 99.724972 -385.076192) (xy 99.725386 -385.061536) (xy 99.732024 -385.032988)
			(xy 99.744994 -385.006705) (xy 99.763614 -384.984069) (xy 99.77501 -384.974846) (xy 99.78263 -384.967734)
			(xy 99.794998 -384.954222) (xy 99.825736 -384.934322) (xy 99.860842 -384.923912) (xy 99.87915 -384.923284)
			(xy 100.080826 -384.923284) (xy 100.094978 -384.92369) (xy 100.122592 -384.929897) (xy 100.148156 -384.942045)
			(xy 100.170409 -384.959533) (xy 100.179632 -384.970274) (xy 100.186998 -384.97764) (xy 100.19773 -384.986871)
			(xy 100.215209 -385.009131) (xy 100.227364 -385.034689) (xy 100.2336 -385.062295) (xy 100.233988 -385.076446)
			(xy 100.233988 -385.277614) (xy 100.233418 -385.296005) (xy 100.223033 -385.331289) (xy 100.203086 -385.362191)
			(xy 100.189538 -385.374642) (xy 100.182426 -385.382262) (xy 100.173186 -385.39364) (xy 100.150542 -385.412241)
			(xy 100.124267 -385.425215) (xy 100.095732 -385.431886) (xy 100.08108 -385.4323) (xy 99.87915 -385.4323)
			(xy 99.864938 -385.431878) (xy 99.837223 -385.425562) (xy 99.811591 -385.413276) (xy 99.789308 -385.395627)
			(xy 99.78009 -385.384802) (xy 99.77247 -385.377182) (xy 99.761672 -385.367936) (xy 99.744028 -385.345656)
			(xy 99.731734 -385.320034) (xy 99.725395 -385.292331) (xy 99.724972 -385.278122) (xy 0.509016 -385.278122)
			(xy 0.509016 -385.583938) (xy 100.447856 -385.583938) (xy 100.447856 -384.720338) (xy 100.448346 -384.690354)
			(xy 100.456174 -384.630898) (xy 100.471695 -384.572973) (xy 100.494644 -384.517569) (xy 100.524628 -384.465635)
			(xy 100.561134 -384.418059) (xy 100.603539 -384.375654) (xy 100.651115 -384.339148) (xy 100.703049 -384.309164)
			(xy 100.758453 -384.286215) (xy 100.816378 -384.270694) (xy 100.875834 -384.262866) (xy 100.935802 -384.262866)
			(xy 100.995258 -384.270694) (xy 101.053183 -384.286215) (xy 101.108587 -384.309164) (xy 101.160521 -384.339148)
			(xy 101.208097 -384.375654) (xy 101.250502 -384.418059) (xy 101.287008 -384.465635) (xy 101.309704 -384.504946)
			(xy 101.5746 -384.504946) (xy 101.5746 -384.303778) (xy 101.575165 -384.287032) (xy 101.583836 -384.254682)
			(xy 101.600583 -384.225677) (xy 101.624264 -384.201993) (xy 101.653267 -384.185242) (xy 101.685616 -384.176567)
			(xy 101.702362 -384.176016) (xy 101.956362 -384.176016) (xy 101.973113 -384.176569) (xy 102.005476 -384.185231)
			(xy 102.034494 -384.201974) (xy 102.058189 -384.225658) (xy 102.074946 -384.254668) (xy 102.083624 -384.287027)
			(xy 102.084124 -384.303778) (xy 102.084124 -384.504946) (xy 102.083655 -384.521699) (xy 102.074972 -384.554062)
			(xy 102.058208 -384.583074) (xy 102.034507 -384.60676) (xy 102.005484 -384.623504) (xy 101.973116 -384.632166)
			(xy 101.956362 -384.632708) (xy 101.702362 -384.632708) (xy 101.685616 -384.632149) (xy 101.653266 -384.623475)
			(xy 101.624262 -384.606726) (xy 101.600579 -384.583044) (xy 101.583828 -384.554041) (xy 101.575152 -384.521692)
			(xy 101.5746 -384.504946) (xy 101.309704 -384.504946) (xy 101.316992 -384.517569) (xy 101.339941 -384.572973)
			(xy 101.355462 -384.630898) (xy 101.36329 -384.690354) (xy 101.36378 -384.720338) (xy 101.36378 -385.305046)
			(xy 101.5746 -385.305046) (xy 101.5746 -385.103878) (xy 101.574968 -385.089175) (xy 101.581674 -385.060544)
			(xy 101.594729 -385.034195) (xy 101.613445 -385.011514) (xy 101.624892 -385.002278) (xy 101.632512 -384.995166)
			(xy 101.644894 -384.981668) (xy 101.675625 -384.961762) (xy 101.710726 -384.951347) (xy 101.729032 -384.950716)
			(xy 101.930708 -384.950716) (xy 101.94486 -384.951123) (xy 101.972475 -384.957328) (xy 101.998039 -384.969475)
			(xy 102.020292 -384.986964) (xy 102.029514 -384.997706) (xy 102.03688 -385.005072) (xy 102.047652 -385.014281)
			(xy 102.065204 -385.036523) (xy 102.077425 -385.062085) (xy 102.083715 -385.089712) (xy 102.084124 -385.103878)
			(xy 102.084124 -385.305046) (xy 102.083654 -385.319283) (xy 104.635826 -385.319283) (xy 104.635826 -385.259317)
			(xy 104.643653 -385.199864) (xy 104.659172 -385.141942) (xy 104.682119 -385.08654) (xy 104.7121 -385.034608)
			(xy 104.748603 -384.987032) (xy 104.791004 -384.944628) (xy 104.838576 -384.908121) (xy 104.890506 -384.878136)
			(xy 104.945906 -384.855184) (xy 105.003827 -384.83966) (xy 105.063279 -384.831828) (xy 105.093262 -384.831336)
			(xy 105.956862 -384.831336) (xy 105.986849 -384.831807) (xy 106.046311 -384.83963) (xy 106.104243 -384.855149)
			(xy 106.159653 -384.878097) (xy 106.211594 -384.908081) (xy 106.259176 -384.944589) (xy 106.301586 -384.986995)
			(xy 106.338098 -385.034574) (xy 106.368087 -385.086513) (xy 106.391039 -385.141921) (xy 106.406562 -385.199852)
			(xy 106.414391 -385.259313) (xy 106.414391 -385.319287) (xy 106.406562 -385.378748) (xy 106.391039 -385.436679)
			(xy 106.368087 -385.492087) (xy 106.338098 -385.544026) (xy 106.301586 -385.591605) (xy 106.259176 -385.634011)
			(xy 106.211594 -385.670519) (xy 106.159653 -385.700503) (xy 106.104243 -385.723451) (xy 106.046311 -385.73897)
			(xy 105.986849 -385.746793) (xy 105.956862 -385.74726) (xy 105.093262 -385.74726) (xy 105.063279 -385.746772)
			(xy 105.003827 -385.73894) (xy 104.945906 -385.723416) (xy 104.890506 -385.700464) (xy 104.838576 -385.670479)
			(xy 104.791004 -385.633972) (xy 104.748603 -385.591568) (xy 104.7121 -385.543992) (xy 104.682119 -385.49206)
			(xy 104.659172 -385.436658) (xy 104.643653 -385.378736) (xy 104.635826 -385.319283) (xy 102.083654 -385.319283)
			(xy 102.083516 -385.323455) (xy 102.073048 -385.358754) (xy 102.053011 -385.389643) (xy 102.03942 -385.402074)
			(xy 102.032308 -385.409694) (xy 102.023062 -385.421068) (xy 102.000422 -385.439673) (xy 101.974148 -385.45265)
			(xy 101.945614 -385.45932) (xy 101.930962 -385.459732) (xy 101.729032 -385.459732) (xy 101.71482 -385.459311)
			(xy 101.687106 -385.452992) (xy 101.661474 -385.440705) (xy 101.639191 -385.423058) (xy 101.629972 -385.412234)
			(xy 101.622352 -385.404614) (xy 101.611446 -385.39537) (xy 101.593678 -385.372982) (xy 101.581321 -385.347209)
			(xy 101.574991 -385.319337) (xy 101.5746 -385.305046) (xy 101.36378 -385.305046) (xy 101.36378 -385.583938)
			(xy 101.36329 -385.613922) (xy 101.355462 -385.673378) (xy 101.339941 -385.731303) (xy 101.316992 -385.786707)
			(xy 101.287008 -385.838641) (xy 101.250502 -385.886217) (xy 101.208097 -385.928622) (xy 101.160521 -385.965128)
			(xy 101.108587 -385.995112) (xy 101.053183 -386.018061) (xy 100.995258 -386.033582) (xy 100.935802 -386.04141)
			(xy 100.875834 -386.04141) (xy 100.816378 -386.033582) (xy 100.758453 -386.018061) (xy 100.703049 -385.995112)
			(xy 100.651115 -385.965128) (xy 100.603539 -385.928622) (xy 100.561134 -385.886217) (xy 100.524628 -385.838641)
			(xy 100.494644 -385.786707) (xy 100.471695 -385.731303) (xy 100.456174 -385.673378) (xy 100.448346 -385.613922)
			(xy 100.447856 -385.583938) (xy 0.509016 -385.583938) (xy 0.509016 -386.078222) (xy 99.724972 -386.078222)
			(xy 99.724972 -385.876546) (xy 99.725522 -385.859818) (xy 99.734162 -385.827497) (xy 99.750866 -385.79851)
			(xy 99.774498 -385.774829) (xy 99.803451 -385.758065) (xy 99.835753 -385.749357) (xy 99.85248 -385.748784)
			(xy 100.10648 -385.748784) (xy 100.123172 -385.749352) (xy 100.155423 -385.757977) (xy 100.184348 -385.774647)
			(xy 100.207981 -385.798227) (xy 100.224714 -385.827115) (xy 100.233411 -385.859347) (xy 100.233988 -385.876038)
			(xy 100.233988 -386.077714) (xy 100.233431 -386.09444) (xy 100.230565 -386.105146) (xy 101.5746 -386.105146)
			(xy 101.5746 -385.903978) (xy 101.575165 -385.887232) (xy 101.583836 -385.854882) (xy 101.600583 -385.825877)
			(xy 101.624264 -385.802193) (xy 101.653267 -385.785442) (xy 101.685616 -385.776767) (xy 101.702362 -385.776216)
			(xy 101.956362 -385.776216) (xy 101.973113 -385.776769) (xy 102.005476 -385.785431) (xy 102.034494 -385.802174)
			(xy 102.058189 -385.825858) (xy 102.074946 -385.854868) (xy 102.083624 -385.887227) (xy 102.084124 -385.903978)
			(xy 102.084124 -386.105146) (xy 102.083655 -386.121899) (xy 102.074972 -386.154262) (xy 102.058208 -386.183274)
			(xy 102.034507 -386.20696) (xy 102.005484 -386.223704) (xy 101.973116 -386.232366) (xy 101.956362 -386.232908)
			(xy 101.702362 -386.232908) (xy 101.685616 -386.232349) (xy 101.653266 -386.223675) (xy 101.624262 -386.206926)
			(xy 101.600579 -386.183244) (xy 101.583828 -386.154241) (xy 101.575152 -386.121892) (xy 101.5746 -386.105146)
			(xy 100.230565 -386.105146) (xy 100.224782 -386.126754) (xy 100.208076 -386.155735) (xy 100.184446 -386.179413)
			(xy 100.1555 -386.19618) (xy 100.123205 -386.204896) (xy 100.10648 -386.205476) (xy 99.85248 -386.205476)
			(xy 99.835783 -386.204982) (xy 99.803524 -386.196344) (xy 99.774595 -386.179661) (xy 99.750963 -386.156066)
			(xy 99.734233 -386.127163) (xy 99.725544 -386.094919) (xy 99.724972 -386.078222) (xy 0.509016 -386.078222)
			(xy 0.509016 -388.37489) (xy 1.56972 -388.37489) (xy 1.56972 -387.51129) (xy 1.57021 -387.481322)
			(xy 1.578033 -387.4219) (xy 1.593546 -387.364007) (xy 1.616482 -387.308634) (xy 1.646449 -387.256728)
			(xy 1.682936 -387.209178) (xy 1.725316 -387.166798) (xy 1.772866 -387.130311) (xy 1.824772 -387.100344)
			(xy 1.880145 -387.077408) (xy 1.938038 -387.061895) (xy 1.99746 -387.054072) (xy 2.057396 -387.054072)
			(xy 2.116818 -387.061895) (xy 2.174711 -387.077408) (xy 2.230084 -387.100344) (xy 2.260396 -387.117844)
			(xy 104.819196 -387.117844) (xy 104.819196 -386.715508) (xy 104.819628 -386.705355) (xy 104.82742 -386.686603)
			(xy 104.841814 -386.67228) (xy 104.860603 -386.664579) (xy 104.870758 -386.6642) (xy 105.277412 -386.6642)
			(xy 105.287521 -386.664676) (xy 105.3062 -386.672417) (xy 105.320494 -386.686717) (xy 105.328228 -386.705398)
			(xy 105.32872 -386.715508) (xy 105.32872 -387.117844) (xy 105.328673 -387.11886) (xy 105.720896 -387.11886)
			(xy 105.720896 -386.716524) (xy 105.721341 -386.706372) (xy 105.729128 -386.687621) (xy 105.743518 -386.673297)
			(xy 105.762304 -386.665595) (xy 105.772458 -386.665216) (xy 106.179112 -386.665216) (xy 106.189237 -386.665606)
			(xy 106.207944 -386.673361) (xy 106.222259 -386.687686) (xy 106.230001 -386.706398) (xy 106.23042 -386.716524)
			(xy 106.23042 -387.11886) (xy 106.229952 -387.128977) (xy 106.22222 -387.147676) (xy 106.20792 -387.161991)
			(xy 106.189229 -387.169741) (xy 106.179112 -387.170168) (xy 105.772458 -387.170168) (xy 105.76233 -387.169708)
			(xy 105.743609 -387.161968) (xy 105.729254 -387.147674) (xy 105.721435 -387.128986) (xy 105.720896 -387.11886)
			(xy 105.328673 -387.11886) (xy 105.328251 -387.127953) (xy 105.320503 -387.146628) (xy 105.306202 -387.160921)
			(xy 105.287521 -387.168658) (xy 105.277412 -387.169152) (xy 104.870758 -387.169152) (xy 104.860628 -387.168708)
			(xy 104.841904 -387.160965) (xy 104.827549 -387.146666) (xy 104.819733 -387.127972) (xy 104.819196 -387.117844)
			(xy 2.260396 -387.117844) (xy 2.28199 -387.130311) (xy 2.32954 -387.166798) (xy 2.37192 -387.209178)
			(xy 2.408407 -387.256728) (xy 2.438374 -387.308634) (xy 2.46131 -387.364007) (xy 2.476823 -387.4219)
			(xy 2.484646 -387.481322) (xy 2.485136 -387.51129) (xy 2.485136 -387.6167) (xy 2.737104 -387.6167)
			(xy 2.737104 -387.210046) (xy 2.737663 -387.199927) (xy 2.745369 -387.181213) (xy 2.759633 -387.166857)
			(xy 2.778296 -387.15903) (xy 2.788412 -387.158484) (xy 3.190748 -387.158484) (xy 3.200858 -387.158946)
			(xy 3.219534 -387.166696) (xy 3.233826 -387.181) (xy 3.241562 -387.199682) (xy 3.242056 -387.209792)
			(xy 3.242056 -387.6167) (xy 3.241516 -387.626802) (xy 3.233789 -387.645469) (xy 3.21951 -387.659762)
			(xy 3.200849 -387.667507) (xy 3.190748 -387.668008) (xy 2.788412 -387.668008) (xy 2.778291 -387.667574)
			(xy 2.759589 -387.659832) (xy 2.745275 -387.645521) (xy 2.737528 -387.626821) (xy 2.737104 -387.6167)
			(xy 2.485136 -387.6167) (xy 2.485136 -388.37489) (xy 2.484646 -388.404858) (xy 2.476823 -388.46428)
			(xy 2.46131 -388.522173) (xy 2.438374 -388.577546) (xy 2.408407 -388.629452) (xy 2.374535 -388.673594)
			(xy 2.739136 -388.673594) (xy 2.739136 -388.26694) (xy 2.73955 -388.256816) (xy 2.747291 -388.238106)
			(xy 2.761609 -388.223789) (xy 2.78032 -388.216049) (xy 2.790444 -388.215632) (xy 3.193034 -388.215632)
			(xy 3.203162 -388.216098) (xy 3.221882 -388.223836) (xy 3.236237 -388.238128) (xy 3.236921 -388.239762)
			(xy 5.479288 -388.239762) (xy 5.479288 -387.75386) (xy 5.479799 -387.737165) (xy 5.488439 -387.704911)
			(xy 5.505121 -387.675985) (xy 5.528712 -387.652354) (xy 5.557609 -387.635623) (xy 5.589848 -387.626928)
			(xy 5.606542 -387.626352) (xy 5.952998 -387.626352) (xy 5.969726 -387.626884) (xy 6.002046 -387.635532)
			(xy 6.03103 -387.652242) (xy 6.05471 -387.675877) (xy 6.071475 -387.70483) (xy 6.080184 -387.737133)
			(xy 6.08076 -387.75386) (xy 6.08076 -388.239762) (xy 6.080231 -388.256515) (xy 6.071567 -388.288882)
			(xy 6.05482 -388.317902) (xy 6.031131 -388.341598) (xy 6.002115 -388.358353) (xy 5.969751 -388.367026)
			(xy 5.952998 -388.367524) (xy 5.60705 -388.367524) (xy 5.590296 -388.367059) (xy 5.557934 -388.358374)
			(xy 5.528921 -388.34161) (xy 5.505236 -388.317908) (xy 5.488492 -388.288885) (xy 5.47983 -388.256516)
			(xy 5.479288 -388.239762) (xy 3.236921 -388.239762) (xy 3.244057 -388.256814) (xy 3.244596 -388.26694)
			(xy 3.244596 -388.673594) (xy 3.244063 -388.683747) (xy 3.236296 -388.70251) (xy 3.221943 -388.716874)
			(xy 3.203187 -388.724655) (xy 3.193034 -388.725156) (xy 2.790698 -388.725156) (xy 2.780526 -388.724738)
			(xy 2.76173 -388.716951) (xy 2.747345 -388.702564) (xy 2.739561 -388.683767) (xy 2.739136 -388.673594)
			(xy 2.374535 -388.673594) (xy 2.37192 -388.677002) (xy 2.32954 -388.719382) (xy 2.28199 -388.755869)
			(xy 2.230084 -388.785836) (xy 2.174711 -388.808772) (xy 2.116818 -388.824285) (xy 2.057396 -388.832108)
			(xy 1.99746 -388.832108) (xy 1.938038 -388.824285) (xy 1.880145 -388.808772) (xy 1.824772 -388.785836)
			(xy 1.772866 -388.755869) (xy 1.725316 -388.719382) (xy 1.682936 -388.677002) (xy 1.646449 -388.629452)
			(xy 1.616482 -388.577546) (xy 1.593546 -388.522173) (xy 1.578033 -388.46428) (xy 1.57021 -388.404858)
			(xy 1.56972 -388.37489) (xy 0.509016 -388.37489) (xy 0.509016 -390.064752) (xy 101.746812 -390.064752)
			(xy 101.746812 -389.424418) (xy 101.74734 -389.414296) (xy 101.755057 -389.39558) (xy 101.76933 -389.381224)
			(xy 101.788001 -389.3734) (xy 101.79812 -389.372856) (xy 102.455218 -389.372856) (xy 102.465379 -389.373319)
			(xy 102.484152 -389.381103) (xy 102.498518 -389.395478) (xy 102.506288 -389.414256) (xy 102.50678 -389.424418)
			(xy 102.50678 -390.064752) (xy 102.746556 -390.064752) (xy 102.746556 -389.424418) (xy 102.746979 -389.414245)
			(xy 102.754761 -389.395447) (xy 102.769147 -389.381061) (xy 102.787945 -389.373279) (xy 102.798118 -389.372856)
			(xy 103.455216 -389.372856) (xy 103.465366 -389.373307) (xy 103.48411 -389.3811) (xy 103.498431 -389.395487)
			(xy 103.506138 -389.414266) (xy 103.506524 -389.424418) (xy 103.506524 -390.064752) (xy 104.24668 -390.064752)
			(xy 104.24668 -389.424418) (xy 104.247079 -389.414242) (xy 104.254866 -389.39544) (xy 104.26926 -389.381053)
			(xy 104.288066 -389.373275) (xy 104.298242 -389.372856) (xy 104.95534 -389.372856) (xy 104.965491 -389.373288)
			(xy 104.984236 -389.381089) (xy 104.998556 -389.395481) (xy 105.006263 -389.414265) (xy 105.006648 -389.424418)
			(xy 105.006648 -390.064752) (xy 105.006146 -390.074865) (xy 104.998422 -390.093559) (xy 104.984133 -390.107873)
			(xy 104.965453 -390.115628) (xy 104.95534 -390.11606) (xy 104.298242 -390.11606) (xy 104.288118 -390.115539)
			(xy 104.269398 -390.107825) (xy 104.25504 -390.093549) (xy 104.247219 -390.074873) (xy 104.24668 -390.064752)
			(xy 103.506524 -390.064752) (xy 103.506045 -390.074868) (xy 103.498317 -390.093566) (xy 103.48402 -390.107881)
			(xy 103.465332 -390.115633) (xy 103.455216 -390.11606) (xy 102.798118 -390.11606) (xy 102.787992 -390.115559)
			(xy 102.769272 -390.107837) (xy 102.754915 -390.093555) (xy 102.747095 -390.074875) (xy 102.746556 -390.064752)
			(xy 102.50678 -390.064752) (xy 102.506339 -390.074905) (xy 102.498555 -390.093661) (xy 102.484164 -390.107986)
			(xy 102.465373 -390.115684) (xy 102.455218 -390.11606) (xy 101.79812 -390.11606) (xy 101.787994 -390.115667)
			(xy 101.769283 -390.107918) (xy 101.754967 -390.093594) (xy 101.747228 -390.074878) (xy 101.746812 -390.064752)
			(xy 0.509016 -390.064752) (xy 0.509016 -398.164722) (xy 3.141726 -398.164722) (xy 3.141726 -398.035362)
			(xy 3.149849 -397.906256) (xy 3.166062 -397.777916) (xy 3.190302 -397.650846) (xy 3.222472 -397.52555)
			(xy 3.262447 -397.40252) (xy 3.310068 -397.282244) (xy 3.365147 -397.165195) (xy 3.427467 -397.051835)
			(xy 3.496782 -396.942612) (xy 3.572818 -396.837957) (xy 3.655276 -396.738283) (xy 3.743829 -396.643983)
			(xy 3.838129 -396.55543) (xy 3.937803 -396.472972) (xy 4.042458 -396.396936) (xy 4.151681 -396.327621)
			(xy 4.265041 -396.265301) (xy 4.38209 -396.210222) (xy 4.502366 -396.162601) (xy 4.625396 -396.122626)
			(xy 4.750692 -396.090456) (xy 4.877762 -396.066216) (xy 5.006102 -396.050003) (xy 5.135208 -396.04188)
			(xy 5.199888 -396.041372) (xy 6.800088 -396.041372) (xy 6.864769 -396.041866) (xy 6.993875 -396.049988)
			(xy 7.122217 -396.066201) (xy 7.249287 -396.090441) (xy 7.374584 -396.122612) (xy 7.497614 -396.162587)
			(xy 7.617892 -396.210208) (xy 7.734942 -396.265287) (xy 7.848302 -396.327608) (xy 7.957526 -396.396923)
			(xy 8.062181 -396.47296) (xy 8.161856 -396.555418) (xy 8.256157 -396.643972) (xy 8.344711 -396.738272)
			(xy 8.427169 -396.837947) (xy 8.503206 -396.942603) (xy 8.572521 -397.051826) (xy 8.634842 -397.165187)
			(xy 8.689921 -397.282236) (xy 8.737543 -397.402514) (xy 8.777518 -397.525544) (xy 8.809688 -397.650841)
			(xy 8.833928 -397.777911) (xy 8.839736 -397.823885) (xy 27.348879 -397.823885) (xy 27.348883 -397.756458)
			(xy 27.356962 -397.689518) (xy 27.373001 -397.624027) (xy 27.396769 -397.560929) (xy 27.427923 -397.501131)
			(xy 27.466014 -397.445496) (xy 27.48788 -397.41983) (xy 27.493686 -397.412692) (xy 27.500196 -397.395496)
			(xy 27.50058 -397.386302) (xy 27.50058 -396.89405) (xy 27.50015 -396.884865) (xy 27.49365 -396.86768)
			(xy 27.48788 -396.860522) (xy 27.466007 -396.834865) (xy 27.42792 -396.779228) (xy 27.396771 -396.719431)
			(xy 27.373008 -396.656333) (xy 27.356974 -396.590843) (xy 27.348899 -396.523905) (xy 27.3489 -396.45648)
			(xy 27.356976 -396.389542) (xy 27.373012 -396.324053) (xy 27.396777 -396.260955) (xy 27.427928 -396.201159)
			(xy 27.466016 -396.145524) (xy 27.48788 -396.119858) (xy 27.493675 -396.112711) (xy 27.500191 -396.095522)
			(xy 27.50058 -396.08633) (xy 27.50058 -395.92885) (xy 27.501069 -395.918722) (xy 27.508787 -395.899994)
			(xy 27.523074 -395.885635) (xy 27.541762 -395.877821) (xy 27.551888 -395.877288) (xy 28.268168 -395.877288)
			(xy 28.278319 -395.877747) (xy 28.297068 -395.88553) (xy 28.311392 -395.899915) (xy 28.319095 -395.918698)
			(xy 28.319476 -395.92885) (xy 28.319476 -396.08633) (xy 28.319877 -396.095518) (xy 28.326398 -396.112702)
			(xy 28.332176 -396.119858) (xy 28.354031 -396.145531) (xy 28.392122 -396.201164) (xy 28.423274 -396.260959)
			(xy 28.44704 -396.324055) (xy 28.463077 -396.389543) (xy 28.471154 -396.456481) (xy 28.471155 -396.523904)
			(xy 28.463079 -396.590842) (xy 28.447044 -396.656331) (xy 28.42328 -396.719428) (xy 28.392129 -396.779223)
			(xy 28.35404 -396.834857) (xy 28.332176 -396.860522) (xy 28.326385 -396.867671) (xy 28.319868 -396.884859)
			(xy 28.319476 -396.89405) (xy 28.319476 -397.386302) (xy 28.31989 -397.395489) (xy 28.326402 -397.412673)
			(xy 28.332176 -397.41983) (xy 28.354003 -397.445526) (xy 28.392095 -397.501155) (xy 28.420857 -397.556356)
			(xy 29.549071 -397.556356) (xy 29.557114 -397.489534) (xy 29.573085 -397.424153) (xy 29.596756 -397.361149)
			(xy 29.627787 -397.301425) (xy 29.665733 -397.245838) (xy 29.68752 -397.220186) (xy 29.693307 -397.213034)
			(xy 29.699827 -397.195849) (xy 29.70022 -397.186658) (xy 29.70022 -397.028924) (xy 29.700641 -397.018769)
			(xy 29.708433 -397.000013) (xy 29.72283 -396.985688) (xy 29.741625 -396.977991) (xy 29.751782 -396.977616)
			(xy 30.468062 -396.977616) (xy 30.478183 -396.978157) (xy 30.496899 -396.985868) (xy 30.511256 -397.000138)
			(xy 30.51908 -397.018806) (xy 30.519624 -397.028924) (xy 30.519624 -397.186658) (xy 30.520049 -397.195844)
			(xy 30.526552 -397.213029) (xy 30.532324 -397.220186) (xy 30.554123 -397.24583) (xy 30.592074 -397.301416)
			(xy 30.623108 -397.361141) (xy 30.646782 -397.424147) (xy 30.662756 -397.48953) (xy 30.6708 -397.556354)
			(xy 30.670799 -397.623661) (xy 30.662753 -397.690485) (xy 30.646778 -397.755868) (xy 30.623102 -397.818873)
			(xy 30.620528 -397.823826) (xy 31.749174 -397.823826) (xy 31.749178 -397.756517) (xy 31.757226 -397.689691)
			(xy 31.773204 -397.624307) (xy 31.796882 -397.5613) (xy 31.827922 -397.501576) (xy 31.865877 -397.44599)
			(xy 31.887668 -397.420338) (xy 31.893482 -397.413205) (xy 31.899984 -397.396005) (xy 31.900368 -397.38681)
			(xy 31.900368 -396.893542) (xy 31.899923 -396.884359) (xy 31.893432 -396.867175) (xy 31.887668 -396.860014)
			(xy 31.86587 -396.83437) (xy 31.827919 -396.778783) (xy 31.796885 -396.719059) (xy 31.773211 -396.656053)
			(xy 31.757238 -396.59067) (xy 31.749194 -396.523846) (xy 31.749195 -396.456539) (xy 31.757241 -396.389716)
			(xy 31.773216 -396.324332) (xy 31.796891 -396.261327) (xy 31.827927 -396.201604) (xy 31.865879 -396.146018)
			(xy 31.887668 -396.120366) (xy 31.89347 -396.113225) (xy 31.899979 -396.096031) (xy 31.900368 -396.086838)
			(xy 31.900368 -395.92885) (xy 31.900805 -395.918678) (xy 31.90858 -395.899879) (xy 31.922962 -395.885491)
			(xy 31.941758 -395.877709) (xy 31.95193 -395.877288) (xy 32.66821 -395.877288) (xy 32.678388 -395.877657)
			(xy 32.697193 -395.885455) (xy 32.711579 -395.899858) (xy 32.719355 -395.918671) (xy 32.719772 -395.92885)
			(xy 32.719772 -396.086838) (xy 32.72017 -396.096026) (xy 32.726693 -396.11321) (xy 32.732472 -396.120366)
			(xy 32.75425 -396.146026) (xy 32.792198 -396.201612) (xy 32.823231 -396.261334) (xy 32.846904 -396.324338)
			(xy 32.862877 -396.389719) (xy 32.870922 -396.45654) (xy 32.870923 -396.523845) (xy 32.86288 -396.590666)
			(xy 32.846909 -396.656048) (xy 32.823237 -396.719052) (xy 32.792206 -396.778775) (xy 32.754259 -396.834362)
			(xy 32.732472 -396.860014) (xy 32.726683 -396.867165) (xy 32.720165 -396.884351) (xy 32.719772 -396.893542)
			(xy 32.719772 -397.38681) (xy 32.720183 -397.395997) (xy 32.726697 -397.413181) (xy 32.732472 -397.420338)
			(xy 32.754222 -397.446021) (xy 32.792171 -397.501603) (xy 32.820593 -397.556296) (xy 33.948839 -397.556296)
			(xy 33.956914 -397.489358) (xy 33.972949 -397.423869) (xy 33.996713 -397.360773) (xy 34.027863 -397.300977)
			(xy 34.065952 -397.245343) (xy 34.087816 -397.219678) (xy 34.093606 -397.212528) (xy 34.100124 -397.195341)
			(xy 34.100516 -397.18615) (xy 34.100516 -397.028924) (xy 34.100936 -397.018801) (xy 34.108679 -397.000095)
			(xy 34.122995 -396.985779) (xy 34.141701 -396.978036) (xy 34.151824 -396.977616) (xy 34.868104 -396.977616)
			(xy 34.878229 -396.978013) (xy 34.896935 -396.985766) (xy 34.91125 -397.000088) (xy 34.918992 -397.018799)
			(xy 34.919412 -397.028924) (xy 34.919412 -397.18615) (xy 34.919843 -397.195335) (xy 34.926342 -397.21252)
			(xy 34.932112 -397.219678) (xy 34.953985 -397.245335) (xy 34.992073 -397.300971) (xy 35.023223 -397.360769)
			(xy 35.046986 -397.423867) (xy 35.06302 -397.489356) (xy 35.071095 -397.556295) (xy 35.071094 -397.62372)
			(xy 35.063017 -397.690658) (xy 35.046981 -397.756148) (xy 35.023216 -397.819245) (xy 35.020799 -397.823884)
			(xy 36.148967 -397.823884) (xy 36.148971 -397.756458) (xy 36.15705 -397.689518) (xy 36.173088 -397.624028)
			(xy 36.196855 -397.560929) (xy 36.228008 -397.501132) (xy 36.266099 -397.445496) (xy 36.287964 -397.41983)
			(xy 36.293781 -397.412699) (xy 36.300282 -397.395497) (xy 36.300664 -397.386302) (xy 36.300664 -396.89405)
			(xy 36.300216 -396.884867) (xy 36.293727 -396.867683) (xy 36.287964 -396.860522) (xy 36.266091 -396.834864)
			(xy 36.228005 -396.779228) (xy 36.196857 -396.71943) (xy 36.173095 -396.656332) (xy 36.157061 -396.590843)
			(xy 36.148987 -396.523904) (xy 36.148988 -396.456481) (xy 36.157064 -396.389542) (xy 36.1731 -396.324053)
			(xy 36.196863 -396.260956) (xy 36.228013 -396.201159) (xy 36.266101 -396.145524) (xy 36.287964 -396.119858)
			(xy 36.293769 -396.112719) (xy 36.300277 -396.095523) (xy 36.300664 -396.08633) (xy 36.300664 -395.92885)
			(xy 36.301168 -395.918724) (xy 36.308884 -395.899999) (xy 36.323166 -395.88564) (xy 36.341848 -395.877823)
			(xy 36.351972 -395.877288) (xy 37.068252 -395.877288) (xy 37.078402 -395.877761) (xy 37.097151 -395.885538)
			(xy 37.111475 -395.899919) (xy 37.119179 -395.918699) (xy 37.11956 -395.92885) (xy 37.11956 -396.08633)
			(xy 37.119965 -396.095518) (xy 37.126483 -396.112701) (xy 37.13226 -396.119858) (xy 37.154116 -396.145531)
			(xy 37.192207 -396.201163) (xy 37.223361 -396.260958) (xy 37.247127 -396.324054) (xy 37.263164 -396.389543)
			(xy 37.271242 -396.456481) (xy 37.271243 -396.523904) (xy 37.263167 -396.590843) (xy 37.247132 -396.656332)
			(xy 37.223367 -396.719428) (xy 37.192215 -396.779224) (xy 37.154125 -396.834857) (xy 37.13226 -396.860522)
			(xy 37.126467 -396.867669) (xy 37.119951 -396.884858) (xy 37.11956 -396.89405) (xy 37.11956 -397.386302)
			(xy 37.119978 -397.395488) (xy 37.126487 -397.412672) (xy 37.13226 -397.41983) (xy 37.154088 -397.445525)
			(xy 37.192181 -397.501155) (xy 37.220943 -397.556356) (xy 38.349159 -397.556356) (xy 38.357201 -397.489534)
			(xy 38.373172 -397.424153) (xy 38.396842 -397.361149) (xy 38.427873 -397.301426) (xy 38.465818 -397.245839)
			(xy 38.487604 -397.220186) (xy 38.493389 -397.213033) (xy 38.499911 -397.195848) (xy 38.500304 -397.186658)
			(xy 38.500304 -397.028924) (xy 38.500741 -397.018771) (xy 38.50853 -397.000018) (xy 38.522922 -396.985694)
			(xy 38.541711 -396.977994) (xy 38.551866 -396.977616) (xy 39.268146 -396.977616) (xy 39.278273 -396.978088)
			(xy 39.29699 -396.985827) (xy 39.311344 -397.000117) (xy 39.319166 -397.0188) (xy 39.319708 -397.028924)
			(xy 39.319708 -397.186658) (xy 39.320136 -397.195843) (xy 39.326637 -397.213028) (xy 39.332408 -397.220186)
			(xy 39.354207 -397.245829) (xy 39.392159 -397.301416) (xy 39.423195 -397.36114) (xy 39.446869 -397.424146)
			(xy 39.462843 -397.48953) (xy 39.470887 -397.556354) (xy 39.470887 -397.623661) (xy 39.462841 -397.690485)
			(xy 39.446865 -397.755869) (xy 39.423189 -397.818874) (xy 39.420585 -397.823885) (xy 40.548734 -397.823885)
			(xy 40.548737 -397.756458) (xy 40.556817 -397.689516) (xy 40.572859 -397.624024) (xy 40.596629 -397.560925)
			(xy 40.627787 -397.501128) (xy 40.665884 -397.445494) (xy 40.687752 -397.41983) (xy 40.693567 -397.412698)
			(xy 40.700069 -397.395497) (xy 40.700452 -397.386302) (xy 40.700452 -396.89405) (xy 40.700006 -396.884867)
			(xy 40.693516 -396.867683) (xy 40.687752 -396.860522) (xy 40.665876 -396.834866) (xy 40.627785 -396.779231)
			(xy 40.596631 -396.719434) (xy 40.572865 -396.656336) (xy 40.556829 -396.590845) (xy 40.548753 -396.523905)
			(xy 40.548754 -396.45648) (xy 40.556832 -396.38954) (xy 40.57287 -396.32405) (xy 40.596638 -396.260952)
			(xy 40.627792 -396.201156) (xy 40.665886 -396.145522) (xy 40.687752 -396.119858) (xy 40.693555 -396.112718)
			(xy 40.700065 -396.095523) (xy 40.700452 -396.08633) (xy 40.700452 -395.92885) (xy 40.700968 -395.918725)
			(xy 40.708682 -395.900003) (xy 40.722959 -395.885644) (xy 40.741638 -395.877825) (xy 40.75176 -395.877288)
			(xy 41.46804 -395.877288) (xy 41.478195 -395.877689) (xy 41.496946 -395.885495) (xy 41.511268 -395.899898)
			(xy 41.518968 -395.918693) (xy 41.519348 -395.92885) (xy 41.519348 -396.08633) (xy 41.519755 -396.095517)
			(xy 41.526272 -396.112701) (xy 41.532048 -396.119858) (xy 41.553904 -396.14553) (xy 41.591996 -396.201163)
			(xy 41.62315 -396.260957) (xy 41.646917 -396.324053) (xy 41.662955 -396.389542) (xy 41.671033 -396.456481)
			(xy 41.671034 -396.523904) (xy 41.662958 -396.590843) (xy 41.646922 -396.656332) (xy 41.623157 -396.719429)
			(xy 41.592004 -396.779224) (xy 41.553913 -396.834858) (xy 41.532048 -396.860522) (xy 41.526253 -396.867668)
			(xy 41.519739 -396.884858) (xy 41.519348 -396.89405) (xy 41.519348 -397.386302) (xy 41.519769 -397.395488)
			(xy 41.526276 -397.412672) (xy 41.532048 -397.41983) (xy 41.553876 -397.445525) (xy 41.59197 -397.501154)
			(xy 41.620702 -397.556296) (xy 42.748927 -397.556296) (xy 42.757002 -397.489358) (xy 42.773037 -397.42387)
			(xy 42.7968 -397.360774) (xy 42.827949 -397.300978) (xy 42.866037 -397.245343) (xy 42.8879 -397.219678)
			(xy 42.893688 -397.212527) (xy 42.900208 -397.195341) (xy 42.9006 -397.18615) (xy 42.9006 -397.028924)
			(xy 42.901035 -397.018803) (xy 42.908776 -397.0001) (xy 42.923086 -396.985785) (xy 42.941787 -396.978039)
			(xy 42.951908 -396.977616) (xy 43.668188 -396.977616) (xy 43.678312 -396.978026) (xy 43.697018 -396.985773)
			(xy 43.711333 -397.000092) (xy 43.719076 -397.0188) (xy 43.719496 -397.028924) (xy 43.719496 -397.18615)
			(xy 43.719931 -397.195335) (xy 43.726427 -397.212519) (xy 43.732196 -397.219678) (xy 43.75407 -397.245335)
			(xy 43.792159 -397.300971) (xy 43.823309 -397.360768) (xy 43.847073 -397.423866) (xy 43.863108 -397.489356)
			(xy 43.871183 -397.556295) (xy 43.871182 -397.62372) (xy 43.863105 -397.690659) (xy 43.847068 -397.756148)
			(xy 43.823303 -397.819246) (xy 43.820917 -397.823825) (xy 44.949053 -397.823825) (xy 44.949057 -397.756517)
			(xy 44.957105 -397.689692) (xy 44.973082 -397.624308) (xy 44.996759 -397.561302) (xy 45.027796 -397.501577)
			(xy 45.06575 -397.44599) (xy 45.08754 -397.420338) (xy 45.09335 -397.413203) (xy 45.099856 -397.396004)
			(xy 45.10024 -397.38681) (xy 45.10024 -396.893542) (xy 45.0998 -396.884358) (xy 45.093306 -396.867174)
			(xy 45.08754 -396.860014) (xy 45.065742 -396.83437) (xy 45.027794 -396.778782) (xy 44.996761 -396.719058)
			(xy 44.973088 -396.656052) (xy 44.957116 -396.590669) (xy 44.949073 -396.523845) (xy 44.949074 -396.45654)
			(xy 44.957119 -396.389716) (xy 44.973093 -396.324333) (xy 44.996767 -396.261328) (xy 45.027801 -396.201605)
			(xy 45.065751 -396.146018) (xy 45.08754 -396.120366) (xy 45.093339 -396.113222) (xy 45.099851 -396.096031)
			(xy 45.10024 -396.086838) (xy 45.10024 -395.92885) (xy 45.100705 -395.918681) (xy 45.108474 -395.899887)
			(xy 45.122847 -395.885501) (xy 45.141634 -395.877714) (xy 45.151802 -395.877288) (xy 45.868082 -395.877288)
			(xy 45.878259 -395.87768) (xy 45.897063 -395.885468) (xy 45.91145 -395.899864) (xy 45.919227 -395.918673)
			(xy 45.919644 -395.92885) (xy 45.919644 -396.086838) (xy 45.920049 -396.096026) (xy 45.926568 -396.113209)
			(xy 45.932344 -396.120366) (xy 45.954122 -396.146026) (xy 45.992072 -396.201611) (xy 46.023107 -396.261333)
			(xy 46.046781 -396.324337) (xy 46.062755 -396.389718) (xy 46.070801 -396.45654) (xy 46.070801 -396.523845)
			(xy 46.062758 -396.590667) (xy 46.046786 -396.656049) (xy 46.023113 -396.719053) (xy 45.99208 -396.778776)
			(xy 45.954131 -396.834362) (xy 45.932344 -396.860014) (xy 45.926552 -396.867162) (xy 45.920036 -396.884351)
			(xy 45.919644 -396.893542) (xy 45.919644 -397.38681) (xy 45.920062 -397.395996) (xy 45.926572 -397.41318)
			(xy 45.932344 -397.420338) (xy 45.954095 -397.446021) (xy 45.992046 -397.501602) (xy 46.020501 -397.556355)
			(xy 47.149223 -397.556355) (xy 47.157267 -397.489532) (xy 47.17324 -397.42415) (xy 47.196914 -397.361146)
			(xy 47.227949 -397.301423) (xy 47.265899 -397.245837) (xy 47.287688 -397.220186) (xy 47.293472 -397.213032)
			(xy 47.299994 -397.195848) (xy 47.300388 -397.186658) (xy 47.300388 -397.028924) (xy 47.300841 -397.018773)
			(xy 47.308626 -397.000023) (xy 47.323013 -396.985699) (xy 47.341797 -396.977997) (xy 47.35195 -396.977616)
			(xy 48.06823 -396.977616) (xy 48.078356 -396.978101) (xy 48.097073 -396.985834) (xy 48.111427 -397.000121)
			(xy 48.11925 -397.018801) (xy 48.119792 -397.028924) (xy 48.119792 -397.186658) (xy 48.120224 -397.195843)
			(xy 48.126723 -397.213027) (xy 48.132492 -397.220186) (xy 48.154289 -397.24583) (xy 48.192235 -397.301419)
			(xy 48.223266 -397.361144) (xy 48.246937 -397.424149) (xy 48.262908 -397.489532) (xy 48.270951 -397.556355)
			(xy 48.27095 -397.62366) (xy 48.262906 -397.690483) (xy 48.246933 -397.755865) (xy 48.22326 -397.81887)
			(xy 48.192227 -397.878594) (xy 48.154279 -397.934181) (xy 48.132492 -397.959834) (xy 48.126698 -397.966981)
			(xy 48.120182 -397.98417) (xy 48.119792 -397.993362) (xy 48.119792 -398.486884) (xy 48.120212 -398.49607)
			(xy 48.126719 -398.513254) (xy 48.132492 -398.520412) (xy 48.154314 -398.546035) (xy 48.19226 -398.601627)
			(xy 48.22329 -398.661355) (xy 48.246959 -398.724363) (xy 48.262929 -398.789748) (xy 48.27097 -398.856573)
			(xy 48.270966 -398.923881) (xy 48.262919 -398.990705) (xy 48.246943 -399.056089) (xy 48.223268 -399.119095)
			(xy 48.192232 -399.17882) (xy 48.154281 -399.234407) (xy 48.132492 -399.26006) (xy 48.126687 -399.267199)
			(xy 48.120177 -399.284394) (xy 48.119792 -399.293588) (xy 48.119792 -399.451576) (xy 48.119359 -399.46173)
			(xy 48.11157 -399.480483) (xy 48.097176 -399.494808) (xy 48.078386 -399.502507) (xy 48.06823 -399.502884)
			(xy 47.35195 -399.502884) (xy 47.341829 -399.502333) (xy 47.323114 -399.494626) (xy 47.308757 -399.48036)
			(xy 47.300932 -399.461693) (xy 47.300388 -399.451576) (xy 47.300388 -399.293588) (xy 47.299986 -399.2844)
			(xy 47.293467 -399.267216) (xy 47.287688 -399.26006) (xy 47.265934 -399.234379) (xy 47.227981 -399.178798)
			(xy 47.196944 -399.119079) (xy 47.173267 -399.056078) (xy 47.15729 -398.990699) (xy 47.149242 -398.923879)
			(xy 47.149239 -398.856576) (xy 47.15728 -398.789754) (xy 47.173251 -398.724374) (xy 47.196921 -398.661371)
			(xy 47.227953 -398.601648) (xy 47.265901 -398.546063) (xy 47.287688 -398.520412) (xy 47.293503 -398.51328)
			(xy 47.300007 -398.496079) (xy 47.300388 -398.486884) (xy 47.300388 -397.993362) (xy 47.299999 -397.984172)
			(xy 47.293471 -397.966988) (xy 47.287688 -397.959834) (xy 47.265909 -397.934174) (xy 47.227956 -397.87859)
			(xy 47.19692 -397.818868) (xy 47.173244 -397.755864) (xy 47.157269 -397.690483) (xy 47.149224 -397.62366)
			(xy 47.149223 -397.556355) (xy 46.020501 -397.556355) (xy 46.023082 -397.561322) (xy 46.046757 -397.624322)
			(xy 46.062733 -397.689701) (xy 46.070781 -397.75652) (xy 46.070784 -397.823823) (xy 46.062744 -397.890643)
			(xy 46.046774 -397.956023) (xy 46.023105 -398.019026) (xy 45.992075 -398.078748) (xy 45.95413 -398.134334)
			(xy 45.932344 -398.159986) (xy 45.926522 -398.167113) (xy 45.920024 -398.184318) (xy 45.919644 -398.193514)
			(xy 45.919644 -398.351502) (xy 45.919237 -398.361676) (xy 45.911448 -398.380474) (xy 45.897057 -398.39486)
			(xy 45.878256 -398.402641) (xy 45.868082 -398.403064) (xy 45.151802 -398.403064) (xy 45.141645 -398.402565)
			(xy 45.122876 -398.394792) (xy 45.108511 -398.380427) (xy 45.100736 -398.361659) (xy 45.10024 -398.351502)
			(xy 45.10024 -398.193514) (xy 45.099814 -398.184329) (xy 45.093311 -398.167145) (xy 45.08754 -398.159986)
			(xy 45.065715 -398.134365) (xy 45.027767 -398.078774) (xy 44.996735 -398.019046) (xy 44.973065 -397.956037)
			(xy 44.957094 -397.890651) (xy 44.949053 -397.823825) (xy 43.820917 -397.823825) (xy 43.792151 -397.879042)
			(xy 43.754061 -397.934677) (xy 43.732196 -397.960342) (xy 43.726399 -397.967487) (xy 43.719885 -397.984678)
			(xy 43.719496 -397.99387) (xy 43.719496 -398.486376) (xy 43.719919 -398.495562) (xy 43.726424 -398.512746)
			(xy 43.732196 -398.519904) (xy 43.754095 -398.54554) (xy 43.792183 -398.601179) (xy 43.823333 -398.660979)
			(xy 43.847095 -398.72408) (xy 43.863128 -398.789572) (xy 43.871201 -398.856514) (xy 43.871198 -398.92394)
			(xy 43.863118 -398.990881) (xy 43.847079 -399.056372) (xy 43.823311 -399.119471) (xy 43.792156 -399.179268)
			(xy 43.754062 -399.234903) (xy 43.732196 -399.260568) (xy 43.726388 -399.267705) (xy 43.71988 -399.284902)
			(xy 43.719496 -399.294096) (xy 43.719496 -399.451576) (xy 43.719064 -399.461697) (xy 43.711323 -399.480401)
			(xy 43.697011 -399.494717) (xy 43.678309 -399.502462) (xy 43.668188 -399.502884) (xy 42.951908 -399.502884)
			(xy 42.941784 -399.502477) (xy 42.923078 -399.494729) (xy 42.908762 -399.480409) (xy 42.90102 -399.4617)
			(xy 42.9006 -399.451576) (xy 42.9006 -399.294096) (xy 42.900192 -399.284909) (xy 42.893677 -399.267724)
			(xy 42.8879 -399.260568) (xy 42.866071 -399.234874) (xy 42.827982 -399.179243) (xy 42.796829 -399.119451)
			(xy 42.773063 -399.056358) (xy 42.757025 -398.990872) (xy 42.748946 -398.923937) (xy 42.748943 -398.856517)
			(xy 42.757015 -398.789581) (xy 42.773047 -398.724094) (xy 42.796807 -398.660998) (xy 42.827954 -398.601203)
			(xy 42.866038 -398.545569) (xy 42.8879 -398.519904) (xy 42.893677 -398.512745) (xy 42.900204 -398.495565)
			(xy 42.9006 -398.486376) (xy 42.9006 -397.99387) (xy 42.900204 -397.984681) (xy 42.893681 -397.967497)
			(xy 42.8879 -397.960342) (xy 42.866046 -397.934669) (xy 42.827957 -397.879035) (xy 42.796806 -397.81924)
			(xy 42.773041 -397.756144) (xy 42.757005 -397.690656) (xy 42.748928 -397.623719) (xy 42.748927 -397.556296)
			(xy 41.620702 -397.556296) (xy 41.623125 -397.560946) (xy 41.646894 -397.624039) (xy 41.662933 -397.689525)
			(xy 41.671013 -397.756461) (xy 41.671016 -397.823882) (xy 41.662944 -397.890819) (xy 41.646911 -397.956307)
			(xy 41.623148 -398.019402) (xy 41.591999 -398.079197) (xy 41.553912 -398.13483) (xy 41.532048 -398.160494)
			(xy 41.526265 -398.167649) (xy 41.519744 -398.184832) (xy 41.519348 -398.194022) (xy 41.519348 -398.351502)
			(xy 41.518875 -398.36163) (xy 41.511144 -398.380354) (xy 41.496853 -398.39471) (xy 41.478166 -398.402527)
			(xy 41.46804 -398.403064) (xy 40.75176 -398.403064) (xy 40.741599 -398.40271) (xy 40.722839 -398.394895)
			(xy 40.708515 -398.380477) (xy 40.700824 -398.361666) (xy 40.700452 -398.351502) (xy 40.700452 -398.194022)
			(xy 40.70002 -398.184837) (xy 40.69352 -398.167653) (xy 40.687752 -398.160494) (xy 40.665849 -398.13486)
			(xy 40.627758 -398.079223) (xy 40.596606 -398.019423) (xy 40.572842 -397.956321) (xy 40.556807 -397.890828)
			(xy 40.548734 -397.823885) (xy 39.420585 -397.823885) (xy 39.392151 -397.878597) (xy 39.354198 -397.934183)
			(xy 39.332408 -397.959834) (xy 39.326615 -397.966982) (xy 39.320098 -397.98417) (xy 39.319708 -397.993362)
			(xy 39.319708 -398.486884) (xy 39.320124 -398.496071) (xy 39.326633 -398.513255) (xy 39.332408 -398.520412)
			(xy 39.354233 -398.546034) (xy 39.392184 -398.601624) (xy 39.423219 -398.661351) (xy 39.446892 -398.72436)
			(xy 39.462864 -398.789746) (xy 39.470906 -398.856573) (xy 39.470902 -398.923882) (xy 39.462854 -398.990707)
			(xy 39.446876 -399.056092) (xy 39.423196 -399.119098) (xy 39.392156 -399.178823) (xy 39.354199 -399.234409)
			(xy 39.332408 -399.26006) (xy 39.326604 -399.2672) (xy 39.320094 -399.284395) (xy 39.319708 -399.293588)
			(xy 39.319708 -399.451576) (xy 39.319259 -399.461728) (xy 39.311473 -399.480478) (xy 39.297085 -399.494802)
			(xy 39.278299 -399.502504) (xy 39.268146 -399.502884) (xy 38.551866 -399.502884) (xy 38.54174 -399.502402)
			(xy 38.523023 -399.494668) (xy 38.508668 -399.48038) (xy 38.500846 -399.4617) (xy 38.500304 -399.451576)
			(xy 38.500304 -399.293588) (xy 38.499899 -399.2844) (xy 38.493381 -399.267216) (xy 38.487604 -399.26006)
			(xy 38.465853 -399.234378) (xy 38.427905 -399.178795) (xy 38.396872 -399.119075) (xy 38.373199 -399.056075)
			(xy 38.357224 -398.990697) (xy 38.349178 -398.923878) (xy 38.349175 -398.856576) (xy 38.357215 -398.789757)
			(xy 38.373183 -398.724377) (xy 38.39685 -398.661374) (xy 38.427877 -398.601651) (xy 38.465819 -398.546065)
			(xy 38.487604 -398.520412) (xy 38.493421 -398.513281) (xy 38.499923 -398.49608) (xy 38.500304 -398.486884)
			(xy 38.500304 -397.993362) (xy 38.499911 -397.984173) (xy 38.493385 -397.966989) (xy 38.487604 -397.959834)
			(xy 38.465827 -397.934173) (xy 38.42788 -397.878587) (xy 38.396849 -397.818865) (xy 38.373177 -397.755861)
			(xy 38.357204 -397.69048) (xy 38.34916 -397.623659) (xy 38.349159 -397.556356) (xy 37.220943 -397.556356)
			(xy 37.223335 -397.560946) (xy 37.247103 -397.624039) (xy 37.263142 -397.689525) (xy 37.271222 -397.756461)
			(xy 37.271225 -397.823882) (xy 37.263153 -397.890819) (xy 37.24712 -397.956306) (xy 37.223358 -398.019402)
			(xy 37.19221 -398.079196) (xy 37.154123 -398.134829) (xy 37.13226 -398.160494) (xy 37.126478 -398.16765)
			(xy 37.119956 -398.184832) (xy 37.11956 -398.194022) (xy 37.11956 -398.351502) (xy 37.119075 -398.361629)
			(xy 37.111347 -398.38035) (xy 37.09706 -398.394706) (xy 37.078376 -398.402525) (xy 37.068252 -398.403064)
			(xy 36.351972 -398.403064) (xy 36.341812 -398.402701) (xy 36.323052 -398.394889) (xy 36.308728 -398.380474)
			(xy 36.301036 -398.361665) (xy 36.300664 -398.351502) (xy 36.300664 -398.194022) (xy 36.300229 -398.184838)
			(xy 36.293731 -398.167654) (xy 36.287964 -398.160494) (xy 36.266064 -398.134859) (xy 36.227979 -398.079219)
			(xy 36.196832 -398.019419) (xy 36.173071 -397.956318) (xy 36.15704 -397.890825) (xy 36.148967 -397.823884)
			(xy 35.020799 -397.823884) (xy 34.992065 -397.879042) (xy 34.953976 -397.934677) (xy 34.932112 -397.960342)
			(xy 34.926316 -397.967488) (xy 34.919801 -397.984678) (xy 34.919412 -397.99387) (xy 34.919412 -398.486376)
			(xy 34.919831 -398.495562) (xy 34.926338 -398.512747) (xy 34.932112 -398.519904) (xy 34.954011 -398.54554)
			(xy 34.992098 -398.601179) (xy 35.023246 -398.66098) (xy 35.047008 -398.72408) (xy 35.06304 -398.789573)
			(xy 35.071113 -398.856514) (xy 35.07111 -398.92394) (xy 35.063031 -398.990881) (xy 35.046992 -399.056372)
			(xy 35.023224 -399.11947) (xy 34.99207 -399.179267) (xy 34.953978 -399.234903) (xy 34.932112 -399.260568)
			(xy 34.926305 -399.267706) (xy 34.919796 -399.284902) (xy 34.919412 -399.294096) (xy 34.919412 -399.451576)
			(xy 34.918965 -399.461695) (xy 34.911227 -399.480396) (xy 34.89692 -399.494711) (xy 34.878223 -399.502459)
			(xy 34.868104 -399.502884) (xy 34.151824 -399.502884) (xy 34.141701 -399.502464) (xy 34.122995 -399.494721)
			(xy 34.108679 -399.480405) (xy 34.100936 -399.461699) (xy 34.100516 -399.451576) (xy 34.100516 -399.294096)
			(xy 34.100104 -399.284909) (xy 34.093591 -399.267725) (xy 34.087816 -399.260568) (xy 34.065987 -399.234874)
			(xy 34.027896 -399.179244) (xy 33.996743 -399.119452) (xy 33.972976 -399.056359) (xy 33.956937 -398.990873)
			(xy 33.948858 -398.923938) (xy 33.948855 -398.856516) (xy 33.956928 -398.78958) (xy 33.97296 -398.724093)
			(xy 33.996721 -398.660998) (xy 34.027868 -398.601203) (xy 34.065954 -398.545569) (xy 34.087816 -398.519904)
			(xy 34.093595 -398.512747) (xy 34.10012 -398.495565) (xy 34.100516 -398.486376) (xy 34.100516 -397.99387)
			(xy 34.100117 -397.984682) (xy 34.093595 -397.967498) (xy 34.087816 -397.960342) (xy 34.065961 -397.934669)
			(xy 34.027871 -397.879036) (xy 33.996719 -397.819241) (xy 33.972954 -397.756145) (xy 33.956917 -397.690657)
			(xy 33.94884 -397.623719) (xy 33.948839 -397.556296) (xy 32.820593 -397.556296) (xy 32.823205 -397.561323)
			(xy 32.84688 -397.624323) (xy 32.862855 -397.689702) (xy 32.870902 -397.756521) (xy 32.870905 -397.823822)
			(xy 32.862865 -397.890642) (xy 32.846897 -397.956022) (xy 32.823229 -398.019025) (xy 32.7922 -398.078747)
			(xy 32.754257 -398.134334) (xy 32.732472 -398.159986) (xy 32.726653 -398.167115) (xy 32.720152 -398.184318)
			(xy 32.719772 -398.193514) (xy 32.719772 -398.351502) (xy 32.719268 -398.361659) (xy 32.711495 -398.380426)
			(xy 32.697133 -398.394791) (xy 32.678367 -398.402567) (xy 32.66821 -398.403064) (xy 31.95193 -398.403064)
			(xy 31.941761 -398.402611) (xy 31.922967 -398.394837) (xy 31.908581 -398.38046) (xy 31.900795 -398.361671)
			(xy 31.900368 -398.351502) (xy 31.900368 -398.193514) (xy 31.899936 -398.184329) (xy 31.893436 -398.167146)
			(xy 31.887668 -398.159986) (xy 31.865842 -398.134365) (xy 31.827892 -398.078775) (xy 31.796859 -398.019047)
			(xy 31.773187 -397.956039) (xy 31.757216 -397.890652) (xy 31.749174 -397.823826) (xy 30.620528 -397.823826)
			(xy 30.592066 -397.878596) (xy 30.554113 -397.934182) (xy 30.532324 -397.959834) (xy 30.526533 -397.966984)
			(xy 30.520014 -397.984171) (xy 30.519624 -397.993362) (xy 30.519624 -398.486884) (xy 30.520036 -398.496071)
			(xy 30.526548 -398.513256) (xy 30.532324 -398.520412) (xy 30.554149 -398.546034) (xy 30.592099 -398.601624)
			(xy 30.623132 -398.661352) (xy 30.646805 -398.72436) (xy 30.662776 -398.789746) (xy 30.670818 -398.856573)
			(xy 30.670815 -398.923881) (xy 30.662767 -398.990707) (xy 30.646789 -399.056092) (xy 30.62311 -399.119098)
			(xy 30.592071 -399.178822) (xy 30.554115 -399.234409) (xy 30.532324 -399.26006) (xy 30.526522 -399.267202)
			(xy 30.52001 -399.284395) (xy 30.519624 -399.293588) (xy 30.519624 -399.451576) (xy 30.519159 -399.461726)
			(xy 30.511376 -399.480473) (xy 30.496993 -399.494796) (xy 30.478213 -399.502501) (xy 30.468062 -399.502884)
			(xy 29.751782 -399.502884) (xy 29.741657 -399.502389) (xy 29.72294 -399.49466) (xy 29.708585 -399.480377)
			(xy 29.700762 -399.461698) (xy 29.70022 -399.451576) (xy 29.70022 -399.293588) (xy 29.699811 -399.284401)
			(xy 29.693296 -399.267217) (xy 29.68752 -399.26006) (xy 29.665769 -399.234378) (xy 29.62782 -399.178796)
			(xy 29.596786 -399.119076) (xy 29.573112 -399.056075) (xy 29.557137 -398.990697) (xy 29.549091 -398.923878)
			(xy 29.549087 -398.856576) (xy 29.557128 -398.789756) (xy 29.573096 -398.724376) (xy 29.596764 -398.661374)
			(xy 29.627792 -398.601651) (xy 29.665735 -398.546065) (xy 29.68752 -398.520412) (xy 29.693339 -398.513283)
			(xy 29.69984 -398.49608) (xy 29.70022 -398.486884) (xy 29.70022 -397.993362) (xy 29.699824 -397.984173)
			(xy 29.6933 -397.966989) (xy 29.68752 -397.959834) (xy 29.665743 -397.934174) (xy 29.627795 -397.878588)
			(xy 29.596762 -397.818865) (xy 29.57309 -397.755862) (xy 29.557116 -397.690481) (xy 29.549072 -397.623659)
			(xy 29.549071 -397.556356) (xy 28.420857 -397.556356) (xy 28.423249 -397.560947) (xy 28.447016 -397.62404)
			(xy 28.463055 -397.689526) (xy 28.471134 -397.756461) (xy 28.471138 -397.823882) (xy 28.463065 -397.890818)
			(xy 28.447033 -397.956305) (xy 28.423272 -398.019401) (xy 28.392124 -398.079196) (xy 28.354039 -398.134829)
			(xy 28.332176 -398.160494) (xy 28.326397 -398.167651) (xy 28.319873 -398.184833) (xy 28.319476 -398.194022)
			(xy 28.319476 -398.351502) (xy 28.318975 -398.361627) (xy 28.31125 -398.380345) (xy 28.296968 -398.394701)
			(xy 28.27829 -398.402523) (xy 28.268168 -398.403064) (xy 27.551888 -398.403064) (xy 27.541729 -398.402688)
			(xy 27.522969 -398.394881) (xy 27.508645 -398.38047) (xy 27.500952 -398.361664) (xy 27.50058 -398.351502)
			(xy 27.50058 -398.194022) (xy 27.500164 -398.184835) (xy 27.493655 -398.167651) (xy 27.48788 -398.160494)
			(xy 27.465979 -398.134859) (xy 27.427893 -398.07922) (xy 27.396745 -398.019419) (xy 27.372984 -397.956318)
			(xy 27.356952 -397.890826) (xy 27.348879 -397.823885) (xy 8.839736 -397.823885) (xy 8.850142 -397.906253)
			(xy 8.858264 -398.035359) (xy 8.858264 -398.164721) (xy 8.850142 -398.293827) (xy 8.833928 -398.422169)
			(xy 8.809688 -398.549239) (xy 8.777518 -398.674536) (xy 8.737543 -398.797566) (xy 8.689921 -398.917844)
			(xy 8.634842 -399.034893) (xy 8.572521 -399.148254) (xy 8.503206 -399.257477) (xy 8.427169 -399.362133)
			(xy 8.344711 -399.461808) (xy 8.256157 -399.556108) (xy 8.161856 -399.644662) (xy 8.062181 -399.72712)
			(xy 7.957526 -399.803157) (xy 7.848302 -399.872472) (xy 7.734942 -399.934793) (xy 7.617892 -399.989872)
			(xy 7.497614 -400.037493) (xy 7.374584 -400.077468) (xy 7.249287 -400.109639) (xy 7.122217 -400.133879)
			(xy 6.993875 -400.150092) (xy 6.864769 -400.158214) (xy 6.800088 -400.158712) (xy 5.199888 -400.158712)
			(xy 5.135208 -400.158204) (xy 5.006102 -400.150081) (xy 4.877762 -400.133868) (xy 4.750692 -400.109628)
			(xy 4.625396 -400.077458) (xy 4.502366 -400.037483) (xy 4.38209 -399.989862) (xy 4.265041 -399.934783)
			(xy 4.151681 -399.872463) (xy 4.042458 -399.803148) (xy 3.937803 -399.727112) (xy 3.838129 -399.644654)
			(xy 3.743829 -399.556101) (xy 3.655276 -399.461801) (xy 3.572818 -399.362127) (xy 3.496782 -399.257472)
			(xy 3.427467 -399.148249) (xy 3.365147 -399.034889) (xy 3.310068 -398.91784) (xy 3.262447 -398.797564)
			(xy 3.222472 -398.674534) (xy 3.190302 -398.549238) (xy 3.166062 -398.422168) (xy 3.149849 -398.293828)
			(xy 3.141726 -398.164722) (xy 0.509016 -398.164722) (xy 0.509016 -401.723796) (xy 27.348891 -401.723796)
			(xy 27.348893 -401.656371) (xy 27.35697 -401.589432) (xy 27.373007 -401.523942) (xy 27.396773 -401.460844)
			(xy 27.427925 -401.401047) (xy 27.466015 -401.345412) (xy 27.48788 -401.319746) (xy 27.49368 -401.312603)
			(xy 27.500193 -401.295411) (xy 27.50058 -401.286218) (xy 27.50058 -400.793966) (xy 27.500191 -400.784777)
			(xy 27.493663 -400.767592) (xy 27.48788 -400.760438) (xy 27.466023 -400.734768) (xy 27.427935 -400.679133)
			(xy 27.396785 -400.619338) (xy 27.373022 -400.556241) (xy 27.356986 -400.490753) (xy 27.34891 -400.423816)
			(xy 27.34891 -400.356393) (xy 27.356985 -400.289456) (xy 27.373019 -400.223967) (xy 27.396782 -400.160871)
			(xy 27.42793 -400.101074) (xy 27.466017 -400.04544) (xy 27.48788 -400.019774) (xy 27.493668 -400.012622)
			(xy 27.500188 -399.995437) (xy 27.50058 -399.986246) (xy 27.50058 -399.828766) (xy 27.501 -399.818632)
			(xy 27.508746 -399.799903) (xy 27.523053 -399.785546) (xy 27.541756 -399.777735) (xy 27.551888 -399.777204)
			(xy 28.268168 -399.777204) (xy 28.278321 -399.777648) (xy 28.297073 -399.785433) (xy 28.311398 -399.799824)
			(xy 28.319098 -399.818612) (xy 28.319476 -399.828766) (xy 28.319476 -399.986246) (xy 28.319918 -399.99543)
			(xy 28.32641 -400.012614) (xy 28.332176 -400.019774) (xy 28.354047 -400.045434) (xy 28.392137 -400.101069)
			(xy 28.423289 -400.160865) (xy 28.447053 -400.223963) (xy 28.463089 -400.289453) (xy 28.471165 -400.356392)
			(xy 28.471165 -400.423817) (xy 28.463088 -400.490756) (xy 28.447051 -400.556246) (xy 28.423285 -400.619343)
			(xy 28.392132 -400.679139) (xy 28.354041 -400.734773) (xy 28.332176 -400.760438) (xy 28.326378 -400.767582)
			(xy 28.319865 -400.784774) (xy 28.319476 -400.793966) (xy 28.319476 -401.286218) (xy 28.319883 -401.295405)
			(xy 28.326399 -401.31259) (xy 28.332176 -401.319746) (xy 28.354019 -401.345429) (xy 28.39211 -401.40106)
			(xy 28.423263 -401.460854) (xy 28.446989 -401.523838) (xy 29.549051 -401.523838) (xy 29.549053 -401.456532)
			(xy 29.557098 -401.389708) (xy 29.573073 -401.324325) (xy 29.596747 -401.26132) (xy 29.627782 -401.201596)
			(xy 29.665732 -401.146008) (xy 29.68752 -401.120356) (xy 29.69332 -401.113213) (xy 29.699832 -401.096021)
			(xy 29.70022 -401.086828) (xy 29.70022 -400.92884) (xy 29.700655 -400.918686) (xy 29.708441 -400.899931)
			(xy 29.722834 -400.885605) (xy 29.741626 -400.877908) (xy 29.751782 -400.877532) (xy 30.468062 -400.877532)
			(xy 30.478185 -400.878058) (xy 30.496904 -400.885771) (xy 30.511261 -400.900046) (xy 30.519083 -400.91872)
			(xy 30.519624 -400.92884) (xy 30.519624 -401.086828) (xy 30.520015 -401.096017) (xy 30.526542 -401.113202)
			(xy 30.532324 -401.120356) (xy 30.554093 -401.146024) (xy 30.592045 -401.201607) (xy 30.623081 -401.261328)
			(xy 30.646757 -401.324331) (xy 30.662732 -401.389711) (xy 30.670778 -401.456533) (xy 30.67078 -401.523837)
			(xy 30.662738 -401.590659) (xy 30.646766 -401.65604) (xy 30.623093 -401.719044) (xy 30.620654 -401.723737)
			(xy 31.749186 -401.723737) (xy 31.749188 -401.65643) (xy 31.757235 -401.589605) (xy 31.773211 -401.524221)
			(xy 31.796887 -401.461216) (xy 31.827925 -401.401492) (xy 31.865878 -401.345906) (xy 31.887668 -401.320254)
			(xy 31.893475 -401.313116) (xy 31.899981 -401.29592) (xy 31.900368 -401.286726) (xy 31.900368 -400.793458)
			(xy 31.899963 -400.784271) (xy 31.893444 -400.767087) (xy 31.887668 -400.75993) (xy 31.865885 -400.734273)
			(xy 31.827935 -400.678688) (xy 31.796899 -400.618966) (xy 31.773225 -400.555962) (xy 31.757251 -400.49058)
			(xy 31.749206 -400.423757) (xy 31.749205 -400.356452) (xy 31.757249 -400.289629) (xy 31.773222 -400.224247)
			(xy 31.796896 -400.161243) (xy 31.82793 -400.10152) (xy 31.86588 -400.045934) (xy 31.887668 -400.020282)
			(xy 31.893463 -400.013136) (xy 31.899977 -399.995946) (xy 31.900368 -399.986754) (xy 31.900368 -399.828766)
			(xy 31.900806 -399.818602) (xy 31.908597 -399.799827) (xy 31.92298 -399.785462) (xy 31.941766 -399.777694)
			(xy 31.95193 -399.777204) (xy 32.66821 -399.777204) (xy 32.678364 -399.777725) (xy 32.697127 -399.785496)
			(xy 32.711491 -399.799853) (xy 32.719271 -399.818612) (xy 32.719772 -399.828766) (xy 32.719772 -399.986754)
			(xy 32.720211 -399.995938) (xy 32.726705 -400.013122) (xy 32.732472 -400.020282) (xy 32.754265 -400.045929)
			(xy 32.792213 -400.101517) (xy 32.823246 -400.161241) (xy 32.846918 -400.224246) (xy 32.86289 -400.289629)
			(xy 32.870933 -400.356452) (xy 32.870933 -400.423757) (xy 32.862888 -400.49058) (xy 32.846915 -400.555962)
			(xy 32.823242 -400.618967) (xy 32.792209 -400.678691) (xy 32.75426 -400.734278) (xy 32.732472 -400.75993)
			(xy 32.726677 -400.767076) (xy 32.720162 -400.784266) (xy 32.719772 -400.793458) (xy 32.719772 -401.286726)
			(xy 32.720176 -401.295914) (xy 32.726695 -401.313098) (xy 32.732472 -401.320254) (xy 32.754237 -401.345924)
			(xy 32.792186 -401.401508) (xy 32.82322 -401.46123) (xy 32.846893 -401.524232) (xy 32.862868 -401.589612)
			(xy 32.870913 -401.656432) (xy 32.870915 -401.723735) (xy 32.862873 -401.790556) (xy 32.846903 -401.855937)
			(xy 32.823233 -401.91894) (xy 32.792203 -401.978663) (xy 32.754258 -402.03425) (xy 32.732472 -402.059902)
			(xy 32.726688 -402.067056) (xy 32.720167 -402.08424) (xy 32.719772 -402.09343) (xy 32.719772 -402.251418)
			(xy 32.719282 -402.261576) (xy 32.711503 -402.280343) (xy 32.697137 -402.294708) (xy 32.678368 -402.302483)
			(xy 32.66821 -402.30298) (xy 31.95193 -402.30298) (xy 31.941763 -402.302512) (xy 31.922972 -402.29474)
			(xy 31.908587 -402.280368) (xy 31.900798 -402.261585) (xy 31.900368 -402.251418) (xy 31.900368 -402.09343)
			(xy 31.899928 -402.084246) (xy 31.893434 -402.067062) (xy 31.887668 -402.059902) (xy 31.865858 -402.034268)
			(xy 31.827908 -401.97868) (xy 31.796874 -401.918954) (xy 31.773201 -401.855947) (xy 31.757229 -401.790562)
			(xy 31.749186 -401.723737) (xy 30.620654 -401.723737) (xy 30.59206 -401.778767) (xy 30.554112 -401.834352)
			(xy 30.532324 -401.860004) (xy 30.526546 -401.867163) (xy 30.520019 -401.884343) (xy 30.519624 -401.893532)
			(xy 30.519624 -402.3868) (xy 30.520029 -402.395988) (xy 30.526546 -402.413172) (xy 30.532324 -402.420328)
			(xy 30.554114 -402.445978) (xy 30.592063 -402.501565) (xy 30.623097 -402.561289) (xy 30.64677 -402.624293)
			(xy 30.662743 -402.689676) (xy 30.670787 -402.756499) (xy 30.670787 -402.823804) (xy 30.670778 -402.823878)
			(xy 33.948799 -402.823878) (xy 33.948804 -402.75645) (xy 33.956885 -402.689508) (xy 33.972926 -402.624016)
			(xy 33.996696 -402.560917) (xy 34.027853 -402.50112) (xy 34.065949 -402.445485) (xy 34.087816 -402.41982)
			(xy 34.093631 -402.412688) (xy 34.100134 -402.395487) (xy 34.100516 -402.386292) (xy 34.100516 -401.89404)
			(xy 34.100083 -401.884855) (xy 34.093585 -401.867671) (xy 34.087816 -401.860512) (xy 34.065932 -401.834863)
			(xy 34.027843 -401.779227) (xy 33.996692 -401.719428) (xy 33.972928 -401.656329) (xy 33.956894 -401.590838)
			(xy 33.948819 -401.523898) (xy 33.948821 -401.456472) (xy 33.956899 -401.389532) (xy 33.972937 -401.324042)
			(xy 33.996704 -401.260944) (xy 34.027858 -401.201147) (xy 34.06595 -401.145513) (xy 34.087816 -401.119848)
			(xy 34.093619 -401.112707) (xy 34.100129 -401.095513) (xy 34.100516 -401.08632) (xy 34.100516 -400.92884)
			(xy 34.100949 -400.918718) (xy 34.108687 -400.900012) (xy 34.122999 -400.885696) (xy 34.141702 -400.877952)
			(xy 34.151824 -400.877532) (xy 34.868104 -400.877532) (xy 34.878231 -400.877914) (xy 34.89694 -400.885669)
			(xy 34.911256 -400.899997) (xy 34.918995 -400.918713) (xy 34.919412 -400.92884) (xy 34.919412 -401.08632)
			(xy 34.91981 -401.095509) (xy 34.926332 -401.112693) (xy 34.932112 -401.119848) (xy 34.953956 -401.14553)
			(xy 34.992044 -401.201162) (xy 35.023195 -401.260956) (xy 35.04696 -401.324051) (xy 35.062997 -401.389538)
			(xy 35.071074 -401.456474) (xy 35.071076 -401.523896) (xy 35.063002 -401.590833) (xy 35.046969 -401.65632)
			(xy 35.023208 -401.719416) (xy 35.020926 -401.723796) (xy 36.148978 -401.723796) (xy 36.14898 -401.656371)
			(xy 36.157058 -401.589432) (xy 36.173095 -401.523942) (xy 36.19686 -401.460845) (xy 36.228011 -401.401047)
			(xy 36.2661 -401.345412) (xy 36.287964 -401.319746) (xy 36.293774 -401.312611) (xy 36.300279 -401.295412)
			(xy 36.300664 -401.286218) (xy 36.300664 -400.793966) (xy 36.300256 -400.784779) (xy 36.293739 -400.767595)
			(xy 36.287964 -400.760438) (xy 36.266107 -400.734767) (xy 36.228021 -400.679133) (xy 36.196872 -400.619337)
			(xy 36.173109 -400.556241) (xy 36.157074 -400.490753) (xy 36.148998 -400.423816) (xy 36.148998 -400.356393)
			(xy 36.157072 -400.289456) (xy 36.173106 -400.223968) (xy 36.196868 -400.160871) (xy 36.228016 -400.101075)
			(xy 36.266102 -400.04544) (xy 36.287964 -400.019774) (xy 36.293762 -400.01263) (xy 36.300274 -399.995438)
			(xy 36.300664 -399.986246) (xy 36.300664 -399.828766) (xy 36.301099 -399.818634) (xy 36.308843 -399.799908)
			(xy 36.323145 -399.785552) (xy 36.341842 -399.777738) (xy 36.351972 -399.777204) (xy 37.068252 -399.777204)
			(xy 37.078404 -399.777661) (xy 37.097156 -399.785442) (xy 37.111481 -399.799828) (xy 37.119181 -399.818613)
			(xy 37.11956 -399.828766) (xy 37.11956 -399.986246) (xy 37.120005 -399.995429) (xy 37.126496 -400.012613)
			(xy 37.13226 -400.019774) (xy 37.154131 -400.045434) (xy 37.192222 -400.101068) (xy 37.223375 -400.160865)
			(xy 37.247141 -400.223962) (xy 37.263177 -400.289453) (xy 37.271253 -400.356392) (xy 37.271252 -400.423817)
			(xy 37.263175 -400.490756) (xy 37.247138 -400.556246) (xy 37.223371 -400.619344) (xy 37.192218 -400.67914)
			(xy 37.154126 -400.734773) (xy 37.13226 -400.760438) (xy 37.12646 -400.76758) (xy 37.119948 -400.784773)
			(xy 37.11956 -400.793966) (xy 37.11956 -401.286218) (xy 37.11997 -401.295405) (xy 37.126485 -401.312589)
			(xy 37.13226 -401.319746) (xy 37.154104 -401.345428) (xy 37.192196 -401.40106) (xy 37.22335 -401.460853)
			(xy 37.247117 -401.523948) (xy 37.263155 -401.589435) (xy 37.271233 -401.656372) (xy 37.271235 -401.723795)
			(xy 37.263161 -401.790732) (xy 37.247127 -401.856221) (xy 37.223363 -401.919317) (xy 37.192213 -401.979112)
			(xy 37.154124 -402.034745) (xy 37.13226 -402.06041) (xy 37.126472 -402.067561) (xy 37.119953 -402.084747)
			(xy 37.11956 -402.093938) (xy 37.11956 -402.251418) (xy 37.119088 -402.261546) (xy 37.111355 -402.280268)
			(xy 37.097064 -402.294623) (xy 37.078378 -402.302442) (xy 37.068252 -402.30298) (xy 36.351972 -402.30298)
			(xy 36.341814 -402.302601) (xy 36.323057 -402.294792) (xy 36.308734 -402.280383) (xy 36.301038 -402.261579)
			(xy 36.300664 -402.251418) (xy 36.300664 -402.093938) (xy 36.300221 -402.084755) (xy 36.293729 -402.067571)
			(xy 36.287964 -402.06041) (xy 36.26608 -402.034762) (xy 36.227994 -401.979124) (xy 36.196846 -401.919325)
			(xy 36.173085 -401.856226) (xy 36.157052 -401.790735) (xy 36.148978 -401.723796) (xy 35.020926 -401.723796)
			(xy 34.99206 -401.779212) (xy 34.953974 -401.834847) (xy 34.932112 -401.860512) (xy 34.926329 -401.867667)
			(xy 34.919806 -401.88485) (xy 34.919412 -401.89404) (xy 34.919412 -402.386292) (xy 34.919823 -402.395479)
			(xy 34.926336 -402.412664) (xy 34.932112 -402.41982) (xy 34.953928 -402.445524) (xy 34.992018 -402.501154)
			(xy 35.02317 -402.560944) (xy 35.046936 -402.624036) (xy 35.062975 -402.68952) (xy 35.071054 -402.756454)
			(xy 35.071059 -402.823818) (xy 38.349119 -402.823818) (xy 38.349123 -402.75651) (xy 38.357172 -402.689685)
			(xy 38.373149 -402.6243) (xy 38.396825 -402.561294) (xy 38.427862 -402.501569) (xy 38.465814 -402.445981)
			(xy 38.487604 -402.420328) (xy 38.493414 -402.413192) (xy 38.499921 -402.395995) (xy 38.500304 -402.3868)
			(xy 38.500304 -401.893532) (xy 38.499878 -401.884347) (xy 38.493375 -401.867162) (xy 38.487604 -401.860004)
			(xy 38.465798 -401.834368) (xy 38.427852 -401.778778) (xy 38.396821 -401.719052) (xy 38.373151 -401.656045)
			(xy 38.357181 -401.590662) (xy 38.349139 -401.523838) (xy 38.34914 -401.456532) (xy 38.357186 -401.389709)
			(xy 38.37316 -401.324326) (xy 38.396834 -401.261321) (xy 38.427867 -401.201596) (xy 38.465816 -401.146009)
			(xy 38.487604 -401.120356) (xy 38.493402 -401.113212) (xy 38.499916 -401.096021) (xy 38.500304 -401.086828)
			(xy 38.500304 -400.92884) (xy 38.500755 -400.918688) (xy 38.508538 -400.899936) (xy 38.522926 -400.885611)
			(xy 38.541712 -400.87791) (xy 38.551866 -400.877532) (xy 39.268146 -400.877532) (xy 39.278275 -400.877989)
			(xy 39.296995 -400.88573) (xy 39.31135 -400.900025) (xy 39.319169 -400.918714) (xy 39.319708 -400.92884)
			(xy 39.319708 -401.086828) (xy 39.320103 -401.096017) (xy 39.326627 -401.113201) (xy 39.332408 -401.120356)
			(xy 39.354178 -401.146024) (xy 39.392131 -401.201607) (xy 39.423168 -401.261328) (xy 39.446844 -401.32433)
			(xy 39.46282 -401.389711) (xy 39.470866 -401.456533) (xy 39.470868 -401.523837) (xy 39.462825 -401.590659)
			(xy 39.446853 -401.656041) (xy 39.42318 -401.719045) (xy 39.420711 -401.723797) (xy 40.548745 -401.723797)
			(xy 40.548747 -401.65637) (xy 40.556826 -401.58943) (xy 40.572865 -401.523939) (xy 40.596634 -401.460841)
			(xy 40.62779 -401.401044) (xy 40.665885 -401.34541) (xy 40.687752 -401.319746) (xy 40.69356 -401.312609)
			(xy 40.700067 -401.295412) (xy 40.700452 -401.286218) (xy 40.700452 -400.793966) (xy 40.700046 -400.784779)
			(xy 40.693528 -400.767595) (xy 40.687752 -400.760438) (xy 40.665892 -400.734769) (xy 40.6278 -400.679136)
			(xy 40.596646 -400.619341) (xy 40.572879 -400.556244) (xy 40.556842 -400.490755) (xy 40.548764 -400.423817)
			(xy 40.548764 -400.356392) (xy 40.55684 -400.289454) (xy 40.572876 -400.223964) (xy 40.596642 -400.160867)
			(xy 40.627795 -400.101072) (xy 40.665887 -400.045438) (xy 40.687752 -400.019774) (xy 40.693549 -400.012629)
			(xy 40.700062 -399.995438) (xy 40.700452 -399.986246) (xy 40.700452 -399.828766) (xy 40.700899 -399.818636)
			(xy 40.70864 -399.799911) (xy 40.722939 -399.785556) (xy 40.741632 -399.77774) (xy 40.75176 -399.777204)
			(xy 41.46804 -399.777204) (xy 41.478197 -399.777589) (xy 41.496951 -399.785399) (xy 41.511273 -399.799806)
			(xy 41.518971 -399.818606) (xy 41.519348 -399.828766) (xy 41.519348 -399.986246) (xy 41.519796 -399.995429)
			(xy 41.526285 -400.012613) (xy 41.532048 -400.019774) (xy 41.55392 -400.045433) (xy 41.592012 -400.101068)
			(xy 41.623165 -400.160864) (xy 41.646931 -400.223962) (xy 41.662968 -400.289452) (xy 41.671044 -400.356392)
			(xy 41.671043 -400.423817) (xy 41.662966 -400.490757) (xy 41.646928 -400.556247) (xy 41.623161 -400.619344)
			(xy 41.592007 -400.67914) (xy 41.553914 -400.734774) (xy 41.532048 -400.760438) (xy 41.526246 -400.767579)
			(xy 41.519736 -400.784773) (xy 41.519348 -400.793966) (xy 41.519348 -401.286218) (xy 41.519761 -401.295405)
			(xy 41.526274 -401.312588) (xy 41.532048 -401.319746) (xy 41.553892 -401.345428) (xy 41.591985 -401.401059)
			(xy 41.62314 -401.460852) (xy 41.646907 -401.523947) (xy 41.662946 -401.589435) (xy 41.671024 -401.656372)
			(xy 41.671026 -401.723795) (xy 41.662952 -401.790733) (xy 41.646917 -401.856221) (xy 41.623153 -401.919317)
			(xy 41.592002 -401.979113) (xy 41.553912 -402.034746) (xy 41.532048 -402.06041) (xy 41.526258 -402.06756)
			(xy 41.519741 -402.084747) (xy 41.519348 -402.093938) (xy 41.519348 -402.251418) (xy 41.518888 -402.261547)
			(xy 41.511152 -402.280271) (xy 41.496858 -402.294627) (xy 41.478167 -402.302444) (xy 41.46804 -402.30298)
			(xy 40.75176 -402.30298) (xy 40.741601 -402.302611) (xy 40.722844 -402.294798) (xy 40.708521 -402.280385)
			(xy 40.700826 -402.26158) (xy 40.700452 -402.251418) (xy 40.700452 -402.093938) (xy 40.700012 -402.084754)
			(xy 40.693518 -402.06757) (xy 40.687752 -402.06041) (xy 40.665865 -402.034763) (xy 40.627773 -401.979127)
			(xy 40.59662 -401.919329) (xy 40.572855 -401.85623) (xy 40.55682 -401.790738) (xy 40.548745 -401.723797)
			(xy 39.420711 -401.723797) (xy 39.392146 -401.778768) (xy 39.354196 -401.834353) (xy 39.332408 -401.860004)
			(xy 39.326628 -401.867161) (xy 39.320103 -401.884342) (xy 39.319708 -401.893532) (xy 39.319708 -402.3868)
			(xy 39.320116 -402.395987) (xy 39.326631 -402.413172) (xy 39.332408 -402.420328) (xy 39.35415 -402.446018)
			(xy 39.392104 -402.501598) (xy 39.423142 -402.561316) (xy 39.44682 -402.624315) (xy 39.462798 -402.689694)
			(xy 39.470847 -402.756513) (xy 39.470851 -402.823815) (xy 39.470843 -402.823878) (xy 42.748887 -402.823878)
			(xy 42.748892 -402.75645) (xy 42.756972 -402.689509) (xy 42.773013 -402.624017) (xy 42.796782 -402.560918)
			(xy 42.827939 -402.501121) (xy 42.866033 -402.445485) (xy 42.8879 -402.41982) (xy 42.893713 -402.412686)
			(xy 42.900218 -402.395487) (xy 42.9006 -402.386292) (xy 42.9006 -401.89404) (xy 42.900171 -401.884855)
			(xy 42.89367 -401.86767) (xy 42.8879 -401.860512) (xy 42.866016 -401.834863) (xy 42.827928 -401.779226)
			(xy 42.796778 -401.719428) (xy 42.773015 -401.656329) (xy 42.756981 -401.590838) (xy 42.748907 -401.523898)
			(xy 42.748909 -401.456472) (xy 42.756987 -401.389533) (xy 42.773024 -401.324043) (xy 42.796791 -401.260945)
			(xy 42.827944 -401.201148) (xy 42.866035 -401.145513) (xy 42.8879 -401.119848) (xy 42.893701 -401.112706)
			(xy 42.900213 -401.095513) (xy 42.9006 -401.08632) (xy 42.9006 -400.92884) (xy 42.901049 -400.91872)
			(xy 42.908784 -400.900017) (xy 42.923091 -400.885702) (xy 42.941788 -400.877955) (xy 42.951908 -400.877532)
			(xy 43.668188 -400.877532) (xy 43.678314 -400.877927) (xy 43.697023 -400.885677) (xy 43.711339 -400.9)
			(xy 43.719079 -400.918714) (xy 43.719496 -400.92884) (xy 43.719496 -401.08632) (xy 43.719897 -401.095508)
			(xy 43.726417 -401.112692) (xy 43.732196 -401.119848) (xy 43.75404 -401.145529) (xy 43.79213 -401.201162)
			(xy 43.823282 -401.260955) (xy 43.847047 -401.32405) (xy 43.863084 -401.389537) (xy 43.871162 -401.456474)
			(xy 43.871164 -401.523896) (xy 43.86309 -401.590833) (xy 43.847056 -401.656321) (xy 43.823294 -401.719417)
			(xy 43.821044 -401.723737) (xy 44.949064 -401.723737) (xy 44.949066 -401.65643) (xy 44.957113 -401.589606)
			(xy 44.973088 -401.524222) (xy 44.996763 -401.461217) (xy 45.027799 -401.401493) (xy 45.065751 -401.345906)
			(xy 45.08754 -401.320254) (xy 45.093344 -401.313114) (xy 45.099853 -401.295919) (xy 45.10024 -401.286726)
			(xy 45.10024 -400.793458) (xy 45.099841 -400.78427) (xy 45.093319 -400.767086) (xy 45.08754 -400.75993)
			(xy 45.065758 -400.734273) (xy 45.027809 -400.678687) (xy 44.996776 -400.618964) (xy 44.973103 -400.55596)
			(xy 44.957129 -400.490579) (xy 44.949085 -400.423757) (xy 44.949084 -400.356452) (xy 44.957128 -400.28963)
			(xy 44.9731 -400.224248) (xy 44.996772 -400.161244) (xy 45.027805 -400.101521) (xy 45.065753 -400.045934)
			(xy 45.08754 -400.020282) (xy 45.093332 -400.013134) (xy 45.099848 -399.995945) (xy 45.10024 -399.986754)
			(xy 45.10024 -399.828766) (xy 45.100706 -399.818606) (xy 45.108492 -399.799835) (xy 45.122866 -399.785471)
			(xy 45.141641 -399.777698) (xy 45.151802 -399.777204) (xy 45.868082 -399.777204) (xy 45.878234 -399.777747)
			(xy 45.896997 -399.785509) (xy 45.911361 -399.79986) (xy 45.919143 -399.818614) (xy 45.919644 -399.828766)
			(xy 45.919644 -399.986754) (xy 45.920089 -399.995937) (xy 45.92658 -400.013121) (xy 45.932344 -400.020282)
			(xy 45.954138 -400.045929) (xy 45.992088 -400.101516) (xy 46.023122 -400.16124) (xy 46.046795 -400.224245)
			(xy 46.062768 -400.289628) (xy 46.070812 -400.356452) (xy 46.070811 -400.423757) (xy 46.062766 -400.490581)
			(xy 46.046792 -400.555963) (xy 46.023118 -400.618968) (xy 45.992083 -400.678692) (xy 45.954132 -400.734278)
			(xy 45.932344 -400.75993) (xy 45.926545 -400.767073) (xy 45.920033 -400.784266) (xy 45.919644 -400.793458)
			(xy 45.919644 -401.286726) (xy 45.920054 -401.295913) (xy 45.926569 -401.313097) (xy 45.932344 -401.320254)
			(xy 45.95411 -401.345924) (xy 45.992061 -401.401507) (xy 46.023096 -401.461228) (xy 46.046771 -401.524231)
			(xy 46.062746 -401.589611) (xy 46.070792 -401.656432) (xy 46.070794 -401.723735) (xy 46.062752 -401.790557)
			(xy 46.046781 -401.855938) (xy 46.02311 -401.918941) (xy 45.992078 -401.978664) (xy 45.954131 -402.03425)
			(xy 45.932344 -402.059902) (xy 45.926557 -402.067054) (xy 45.920038 -402.084239) (xy 45.919644 -402.09343)
			(xy 45.919644 -402.251418) (xy 45.919181 -402.261579) (xy 45.911397 -402.280352) (xy 45.897022 -402.294718)
			(xy 45.878244 -402.302488) (xy 45.868082 -402.30298) (xy 45.151802 -402.30298) (xy 45.141647 -402.302465)
			(xy 45.122881 -402.294695) (xy 45.108516 -402.280336) (xy 45.100739 -402.261573) (xy 45.10024 -402.251418)
			(xy 45.10024 -402.09343) (xy 45.099806 -402.084246) (xy 45.093308 -402.067061) (xy 45.08754 -402.059902)
			(xy 45.06573 -402.034268) (xy 45.027782 -401.978679) (xy 44.99675 -401.918953) (xy 44.973078 -401.855946)
			(xy 44.957107 -401.790561) (xy 44.949064 -401.723737) (xy 43.821044 -401.723737) (xy 43.792146 -401.779213)
			(xy 43.754059 -401.834847) (xy 43.732196 -401.860512) (xy 43.726411 -401.867666) (xy 43.71989 -401.88485)
			(xy 43.719496 -401.89404) (xy 43.719496 -402.386292) (xy 43.719911 -402.395479) (xy 43.726421 -402.412663)
			(xy 43.732196 -402.41982) (xy 43.754013 -402.445524) (xy 43.792103 -402.501153) (xy 43.823256 -402.560944)
			(xy 43.847023 -402.624036) (xy 43.863062 -402.68952) (xy 43.871142 -402.756454) (xy 43.871146 -402.823874)
			(xy 43.863075 -402.890809) (xy 43.847045 -402.956295) (xy 43.823286 -403.01939) (xy 43.792141 -403.079185)
			(xy 43.754057 -403.134819) (xy 43.732196 -403.160484) (xy 43.726381 -403.167616) (xy 43.719877 -403.184817)
			(xy 43.719496 -403.194012) (xy 43.719496 -403.351492) (xy 43.719077 -403.361614) (xy 43.711331 -403.380319)
			(xy 43.697015 -403.394633) (xy 43.67831 -403.402378) (xy 43.668188 -403.4028) (xy 42.951908 -403.4028)
			(xy 42.941786 -403.402377) (xy 42.923083 -403.394632) (xy 42.908768 -403.380317) (xy 42.901023 -403.361614)
			(xy 42.9006 -403.351492) (xy 42.9006 -403.194012) (xy 42.900184 -403.184825) (xy 42.893674 -403.167641)
			(xy 42.8879 -403.160484) (xy 42.865989 -403.134858) (xy 42.827902 -403.079218) (xy 42.796753 -403.019416)
			(xy 42.772992 -402.956314) (xy 42.756959 -402.89082) (xy 42.748887 -402.823878) (xy 39.470843 -402.823878)
			(xy 39.462811 -402.890635) (xy 39.446841 -402.956016) (xy 39.423172 -403.019018) (xy 39.392141 -403.07874)
			(xy 39.354194 -403.134325) (xy 39.332408 -403.159976) (xy 39.326598 -403.167111) (xy 39.320091 -403.184309)
			(xy 39.319708 -403.193504) (xy 39.319708 -403.351492) (xy 39.319272 -403.361645) (xy 39.311481 -403.380395)
			(xy 39.297088 -403.394719) (xy 39.278301 -403.40242) (xy 39.268146 -403.4028) (xy 38.551866 -403.4028)
			(xy 38.541742 -403.402303) (xy 38.523028 -403.394571) (xy 38.508674 -403.380289) (xy 38.500849 -403.361613)
			(xy 38.500304 -403.351492) (xy 38.500304 -403.193504) (xy 38.499891 -403.184317) (xy 38.493379 -403.167133)
			(xy 38.487604 -403.159976) (xy 38.46577 -403.134362) (xy 38.427825 -403.078769) (xy 38.396796 -403.01904)
			(xy 38.373127 -402.956031) (xy 38.357159 -402.890644) (xy 38.349119 -402.823818) (xy 35.071059 -402.823818)
			(xy 35.071059 -402.823874) (xy 35.062988 -402.890809) (xy 35.046958 -402.956295) (xy 35.023199 -403.01939)
			(xy 34.992055 -403.079185) (xy 34.953973 -403.134819) (xy 34.932112 -403.160484) (xy 34.926299 -403.167617)
			(xy 34.919794 -403.184817) (xy 34.919412 -403.194012) (xy 34.919412 -403.351492) (xy 34.918978 -403.361612)
			(xy 34.911234 -403.380314) (xy 34.896924 -403.394628) (xy 34.878224 -403.402375) (xy 34.868104 -403.4028)
			(xy 34.151824 -403.4028) (xy 34.141703 -403.402365) (xy 34.123 -403.394624) (xy 34.108685 -403.380314)
			(xy 34.100939 -403.361613) (xy 34.100516 -403.351492) (xy 34.100516 -403.194012) (xy 34.100096 -403.184826)
			(xy 34.093589 -403.167642) (xy 34.087816 -403.160484) (xy 34.065904 -403.134858) (xy 34.027816 -403.079218)
			(xy 33.996666 -403.019417) (xy 33.972904 -402.956315) (xy 33.956872 -402.890821) (xy 33.948799 -402.823878)
			(xy 30.670778 -402.823878) (xy 30.662742 -402.890627) (xy 30.646769 -402.956009) (xy 30.623096 -403.019014)
			(xy 30.592062 -403.078738) (xy 30.554112 -403.134324) (xy 30.532324 -403.159976) (xy 30.526515 -403.167113)
			(xy 30.520007 -403.18431) (xy 30.519624 -403.193504) (xy 30.519624 -403.351492) (xy 30.519172 -403.361643)
			(xy 30.511384 -403.38039) (xy 30.496997 -403.394713) (xy 30.478214 -403.402417) (xy 30.468062 -403.4028)
			(xy 29.751782 -403.4028) (xy 29.741659 -403.40229) (xy 29.722945 -403.394563) (xy 29.708591 -403.380285)
			(xy 29.700765 -403.361612) (xy 29.70022 -403.351492) (xy 29.70022 -403.193504) (xy 29.699804 -403.184318)
			(xy 29.693294 -403.167133) (xy 29.68752 -403.159976) (xy 29.665734 -403.134322) (xy 29.627785 -403.078736)
			(xy 29.596752 -403.019013) (xy 29.573079 -402.956008) (xy 29.557106 -402.890626) (xy 29.549061 -402.823804)
			(xy 29.549061 -402.756499) (xy 29.557105 -402.689677) (xy 29.573078 -402.624294) (xy 29.59675 -402.56129)
			(xy 29.627784 -402.501566) (xy 29.665732 -402.44598) (xy 29.68752 -402.420328) (xy 29.693332 -402.413194)
			(xy 29.699837 -402.395995) (xy 29.70022 -402.3868) (xy 29.70022 -401.893532) (xy 29.69979 -401.884347)
			(xy 29.69329 -401.867163) (xy 29.68752 -401.860004) (xy 29.665713 -401.834368) (xy 29.627766 -401.778779)
			(xy 29.596735 -401.719053) (xy 29.573064 -401.656046) (xy 29.557093 -401.590662) (xy 29.549051 -401.523838)
			(xy 28.446989 -401.523838) (xy 28.44703 -401.523948) (xy 28.463067 -401.589436) (xy 28.471145 -401.656372)
			(xy 28.471147 -401.723795) (xy 28.463073 -401.790732) (xy 28.447039 -401.85622) (xy 28.423277 -401.919316)
			(xy 28.392127 -401.979111) (xy 28.354039 -402.034745) (xy 28.332176 -402.06041) (xy 28.32639 -402.067562)
			(xy 28.31987 -402.084748) (xy 28.319476 -402.093938) (xy 28.319476 -402.251418) (xy 28.318989 -402.261544)
			(xy 28.311258 -402.280263) (xy 28.296972 -402.294618) (xy 28.278291 -402.302439) (xy 28.268168 -402.30298)
			(xy 27.551888 -402.30298) (xy 27.541731 -402.302588) (xy 27.522974 -402.294785) (xy 27.50865 -402.280379)
			(xy 27.500954 -402.261578) (xy 27.50058 -402.251418) (xy 27.50058 -402.093938) (xy 27.500156 -402.084752)
			(xy 27.493653 -402.067567) (xy 27.48788 -402.06041) (xy 27.465995 -402.034762) (xy 27.427908 -401.979125)
			(xy 27.39676 -401.919326) (xy 27.372998 -401.856227) (xy 27.356964 -401.790736) (xy 27.348891 -401.723796)
			(xy 0.509016 -401.723796) (xy 0.509016 -411.590998) (xy 17.015968 -411.590998) (xy 17.015968 -405.332946)
			(xy 17.016425 -405.308835) (xy 17.023969 -405.261207) (xy 17.038877 -405.215347) (xy 17.060781 -405.172387)
			(xy 17.089143 -405.133387) (xy 17.105884 -405.11603) (xy 17.152874 -405.06904) (xy 17.170291 -405.052336)
			(xy 17.209358 -405.024007) (xy 17.252365 -405.002117) (xy 17.298258 -404.987199) (xy 17.345916 -404.97962)
			(xy 17.370044 -404.979124) (xy 21.469096 -404.979124) (xy 21.493193 -404.979584) (xy 21.540795 -404.987109)
			(xy 21.586638 -405.001976) (xy 21.629597 -405.02382) (xy 21.668618 -405.052104) (xy 21.686012 -405.068786)
			(xy 21.733002 -405.115776) (xy 21.749767 -405.133161) (xy 21.778218 -405.172183) (xy 21.800195 -405.215185)
			(xy 21.815153 -405.261103) (xy 21.822723 -405.308799) (xy 21.823172 -405.332946) (xy 21.823172 -405.623707)
			(xy 27.348902 -405.623707) (xy 27.348902 -405.556284) (xy 27.356979 -405.489345) (xy 27.373014 -405.423856)
			(xy 27.396778 -405.360759) (xy 27.427928 -405.300963) (xy 27.466016 -405.245328) (xy 27.48788 -405.219662)
			(xy 27.493673 -405.212514) (xy 27.50019 -405.195326) (xy 27.50058 -405.186134) (xy 27.50058 -404.693882)
			(xy 27.500183 -404.684693) (xy 27.493661 -404.667509) (xy 27.48788 -404.660354) (xy 27.466038 -404.634671)
			(xy 27.42795 -404.579038) (xy 27.3968 -404.519244) (xy 27.373035 -404.45615) (xy 27.356999 -404.390663)
			(xy 27.348922 -404.323727) (xy 27.34892 -404.256306) (xy 27.356993 -404.189369) (xy 27.373025 -404.123882)
			(xy 27.396786 -404.060786) (xy 27.427933 -404.00099) (xy 27.466018 -403.945356) (xy 27.48788 -403.91969)
			(xy 27.493661 -403.912534) (xy 27.500186 -403.895352) (xy 27.50058 -403.886162) (xy 27.50058 -403.728682)
			(xy 27.501013 -403.718549) (xy 27.508754 -403.69982) (xy 27.523057 -403.685463) (xy 27.541757 -403.677651)
			(xy 27.551888 -403.67712) (xy 28.268168 -403.67712) (xy 28.278323 -403.677548) (xy 28.297078 -403.685337)
			(xy 28.311404 -403.699732) (xy 28.319101 -403.718525) (xy 28.319476 -403.728682) (xy 28.319476 -403.886162)
			(xy 28.31991 -403.895347) (xy 28.326408 -403.912531) (xy 28.332176 -403.91969) (xy 28.354062 -403.945337)
			(xy 28.392152 -404.000974) (xy 28.423303 -404.060772) (xy 28.447067 -404.123871) (xy 28.463102 -404.189363)
			(xy 28.471176 -404.256304) (xy 28.471174 -404.323729) (xy 28.463096 -404.39067) (xy 28.447057 -404.45616)
			(xy 28.42329 -404.519258) (xy 28.392135 -404.579055) (xy 28.354042 -404.634689) (xy 28.332176 -404.660354)
			(xy 28.326371 -404.667493) (xy 28.319862 -404.684688) (xy 28.319476 -404.693882) (xy 28.319476 -405.186134)
			(xy 28.319875 -405.195322) (xy 28.326397 -405.212506) (xy 28.332176 -405.219662) (xy 28.354035 -405.245332)
			(xy 28.392125 -405.300965) (xy 28.423278 -405.36076) (xy 28.447043 -405.423857) (xy 28.46308 -405.489345)
			(xy 28.471157 -405.556284) (xy 28.471157 -405.623707) (xy 28.463081 -405.690646) (xy 28.447046 -405.756135)
			(xy 28.423281 -405.819231) (xy 28.39213 -405.879027) (xy 28.35404 -405.934661) (xy 28.332176 -405.960326)
			(xy 28.326383 -405.967474) (xy 28.319867 -405.984662) (xy 28.319476 -405.993854) (xy 28.319476 -406.151334)
			(xy 28.319002 -406.161461) (xy 28.311266 -406.18018) (xy 28.296976 -406.194534) (xy 28.278293 -406.202355)
			(xy 28.268168 -406.202896) (xy 27.551888 -406.202896) (xy 27.541733 -406.202488) (xy 27.522979 -406.194688)
			(xy 27.508656 -406.180287) (xy 27.500957 -406.161492) (xy 27.50058 -406.151334) (xy 27.50058 -405.993854)
			(xy 27.500148 -405.984669) (xy 27.49365 -405.967484) (xy 27.48788 -405.960326) (xy 27.466011 -405.934665)
			(xy 27.427924 -405.87903) (xy 27.396774 -405.819233) (xy 27.373011 -405.756135) (xy 27.356977 -405.690646)
			(xy 27.348902 -405.623707) (xy 21.823172 -405.623707) (xy 21.823172 -406.72373) (xy 29.549042 -406.72373)
			(xy 29.549045 -406.656422) (xy 29.557092 -406.589598) (xy 29.573068 -406.524214) (xy 29.596744 -406.461208)
			(xy 29.627779 -406.401484) (xy 29.665731 -406.345896) (xy 29.68752 -406.320244) (xy 29.693325 -406.313105)
			(xy 29.699834 -406.29591) (xy 29.70022 -406.286716) (xy 29.70022 -405.793448) (xy 29.699782 -405.784264)
			(xy 29.693287 -405.767079) (xy 29.68752 -405.75992) (xy 29.665729 -405.734271) (xy 29.627781 -405.678684)
			(xy 29.596749 -405.618959) (xy 29.573078 -405.555955) (xy 29.557105 -405.490572) (xy 29.549062 -405.423749)
			(xy 29.549062 -405.356444) (xy 29.557107 -405.289622) (xy 29.573079 -405.22424) (xy 29.596752 -405.161235)
			(xy 29.627784 -405.101511) (xy 29.665733 -405.045924) (xy 29.68752 -405.020272) (xy 29.693313 -405.013125)
			(xy 29.699829 -404.995936) (xy 29.70022 -404.986744) (xy 29.70022 -404.828756) (xy 29.700586 -404.818597)
			(xy 29.7084 -404.799839) (xy 29.722814 -404.785517) (xy 29.74162 -404.777822) (xy 29.751782 -404.777448)
			(xy 30.468062 -404.777448) (xy 30.478187 -404.777958) (xy 30.496909 -404.785675) (xy 30.511267 -404.799954)
			(xy 30.519086 -404.818634) (xy 30.519624 -404.828756) (xy 30.519624 -404.986744) (xy 30.520008 -404.995934)
			(xy 30.526539 -405.013118) (xy 30.532324 -405.020272) (xy 30.554109 -405.045927) (xy 30.59206 -405.101512)
			(xy 30.623096 -405.161235) (xy 30.64677 -405.224239) (xy 30.662745 -405.289621) (xy 30.67079 -405.356444)
			(xy 30.67079 -405.42375) (xy 30.662746 -405.490573) (xy 30.646772 -405.555955) (xy 30.623098 -405.61896)
			(xy 30.620661 -405.623649) (xy 31.749197 -405.623649) (xy 31.749198 -405.556342) (xy 31.757243 -405.489519)
			(xy 31.773217 -405.424136) (xy 31.796892 -405.361131) (xy 31.827928 -405.301408) (xy 31.865879 -405.245822)
			(xy 31.887668 -405.22017) (xy 31.893468 -405.213028) (xy 31.899979 -405.195835) (xy 31.900368 -405.186642)
			(xy 31.900368 -404.693374) (xy 31.899955 -404.684187) (xy 31.893441 -404.667004) (xy 31.887668 -404.659846)
			(xy 31.865901 -404.634176) (xy 31.82795 -404.578593) (xy 31.796914 -404.518872) (xy 31.773239 -404.45587)
			(xy 31.757263 -404.39049) (xy 31.749217 -404.323668) (xy 31.749215 -404.256365) (xy 31.757257 -404.189543)
			(xy 31.773229 -404.124162) (xy 31.7969 -404.061158) (xy 31.827933 -404.001435) (xy 31.865881 -403.94585)
			(xy 31.887668 -403.920198) (xy 31.893456 -403.913047) (xy 31.899974 -403.895861) (xy 31.900368 -403.88667)
			(xy 31.900368 -403.728682) (xy 31.90075 -403.718506) (xy 31.908547 -403.699705) (xy 31.922945 -403.68532)
			(xy 31.941753 -403.677541) (xy 31.95193 -403.67712) (xy 32.66821 -403.67712) (xy 32.678366 -403.677625)
			(xy 32.697132 -403.685399) (xy 32.711496 -403.699761) (xy 32.719273 -403.718526) (xy 32.719772 -403.728682)
			(xy 32.719772 -403.88667) (xy 32.720203 -403.895855) (xy 32.726703 -403.913039) (xy 32.732472 -403.920198)
			(xy 32.754281 -403.945832) (xy 32.792229 -404.001422) (xy 32.82326 -404.061148) (xy 32.846931 -404.124155)
			(xy 32.862902 -404.189539) (xy 32.870945 -404.256363) (xy 32.870943 -404.32367) (xy 32.862897 -404.390494)
			(xy 32.846922 -404.455877) (xy 32.823247 -404.518882) (xy 32.792212 -404.578607) (xy 32.754261 -404.634194)
			(xy 32.732472 -404.659846) (xy 32.72667 -404.666987) (xy 32.720159 -404.684181) (xy 32.719772 -404.693374)
			(xy 32.719772 -405.186642) (xy 32.720168 -405.195831) (xy 32.726692 -405.213014) (xy 32.732472 -405.22017)
			(xy 32.754254 -405.245827) (xy 32.792202 -405.301413) (xy 32.823235 -405.361136) (xy 32.846907 -405.42414)
			(xy 32.862881 -405.489521) (xy 32.870925 -405.556343) (xy 32.870926 -405.623648) (xy 32.862882 -405.69047)
			(xy 32.84691 -405.755851) (xy 32.823239 -405.818856) (xy 32.792207 -405.878579) (xy 32.754259 -405.934166)
			(xy 32.732472 -405.959818) (xy 32.726682 -405.966967) (xy 32.720164 -405.984155) (xy 32.719772 -405.993346)
			(xy 32.719772 -406.151334) (xy 32.719295 -406.161493) (xy 32.711511 -406.180261) (xy 32.697141 -406.194624)
			(xy 32.678369 -406.202399) (xy 32.66821 -406.202896) (xy 31.95193 -406.202896) (xy 31.941778 -406.202343)
			(xy 31.923016 -406.194585) (xy 31.908651 -406.180237) (xy 31.900869 -406.161485) (xy 31.900368 -406.151334)
			(xy 31.900368 -405.993346) (xy 31.899921 -405.984163) (xy 31.893431 -405.966979) (xy 31.887668 -405.959818)
			(xy 31.865874 -405.934171) (xy 31.827923 -405.878584) (xy 31.796888 -405.81886) (xy 31.773215 -405.755855)
			(xy 31.757241 -405.690472) (xy 31.749197 -405.623649) (xy 30.620661 -405.623649) (xy 30.592063 -405.678683)
			(xy 30.554113 -405.734268) (xy 30.532324 -405.75992) (xy 30.526539 -405.767074) (xy 30.520017 -405.784258)
			(xy 30.519624 -405.793448) (xy 30.519624 -406.286716) (xy 30.520021 -406.295905) (xy 30.526543 -406.313089)
			(xy 30.532324 -406.320244) (xy 30.554081 -406.345922) (xy 30.592034 -406.401503) (xy 30.62307 -406.461223)
			(xy 30.646746 -406.524224) (xy 30.662723 -406.589604) (xy 30.67077 -406.656424) (xy 30.670773 -406.723728)
			(xy 30.670766 -406.723789) (xy 33.948811 -406.723789) (xy 33.948814 -406.656363) (xy 33.956893 -406.589422)
			(xy 33.972932 -406.523931) (xy 33.996701 -406.460833) (xy 34.027856 -406.401036) (xy 34.06595 -406.345401)
			(xy 34.087816 -406.319736) (xy 34.093624 -406.312599) (xy 34.100131 -406.295402) (xy 34.100516 -406.286208)
			(xy 34.100516 -405.793956) (xy 34.100123 -405.784767) (xy 34.093597 -405.767583) (xy 34.087816 -405.760428)
			(xy 34.065948 -405.734766) (xy 34.027858 -405.679132) (xy 33.996706 -405.619335) (xy 33.972942 -405.556238)
			(xy 33.956906 -405.490748) (xy 33.94883 -405.423809) (xy 33.948831 -405.356385) (xy 33.956907 -405.289446)
			(xy 33.972944 -405.223957) (xy 33.996709 -405.160859) (xy 34.027861 -405.101063) (xy 34.065951 -405.045429)
			(xy 34.087816 -405.019764) (xy 34.093612 -405.012619) (xy 34.100127 -404.995428) (xy 34.100516 -404.986236)
			(xy 34.100516 -404.828756) (xy 34.10095 -404.818642) (xy 34.108705 -404.79996) (xy 34.123017 -404.785666)
			(xy 34.14171 -404.777936) (xy 34.151824 -404.777448) (xy 34.868104 -404.777448) (xy 34.878207 -404.777981)
			(xy 34.896875 -404.78571) (xy 34.911168 -404.799992) (xy 34.918911 -404.818654) (xy 34.919412 -404.828756)
			(xy 34.919412 -404.986236) (xy 34.919802 -404.995425) (xy 34.926329 -405.01261) (xy 34.932112 -405.019764)
			(xy 34.953972 -405.045433) (xy 34.99206 -405.101067) (xy 35.02321 -405.160863) (xy 35.046974 -405.223959)
			(xy 35.063009 -405.289448) (xy 35.071085 -405.356385) (xy 35.071085 -405.423809) (xy 35.06301 -405.490746)
			(xy 35.046976 -405.556235) (xy 35.023212 -405.619332) (xy 35.020933 -405.623707) (xy 36.14899 -405.623707)
			(xy 36.14899 -405.556284) (xy 36.157066 -405.489346) (xy 36.173101 -405.423857) (xy 36.196864 -405.36076)
			(xy 36.228014 -405.300963) (xy 36.266101 -405.245328) (xy 36.287964 -405.219662) (xy 36.293767 -405.212522)
			(xy 36.300276 -405.195327) (xy 36.300664 -405.186134) (xy 36.300664 -404.693882) (xy 36.300248 -404.684696)
			(xy 36.293737 -404.667512) (xy 36.287964 -404.660354) (xy 36.266123 -404.63467) (xy 36.228036 -404.579038)
			(xy 36.196886 -404.519244) (xy 36.173122 -404.456149) (xy 36.157087 -404.390663) (xy 36.149009 -404.323727)
			(xy 36.149007 -404.256306) (xy 36.157081 -404.18937) (xy 36.173113 -404.123882) (xy 36.196873 -404.060787)
			(xy 36.228019 -404.000991) (xy 36.266103 -403.945356) (xy 36.287964 -403.91969) (xy 36.293755 -403.912541)
			(xy 36.300271 -403.895353) (xy 36.300664 -403.886162) (xy 36.300664 -403.728682) (xy 36.301112 -403.718551)
			(xy 36.30885 -403.699825) (xy 36.323149 -403.685468) (xy 36.341843 -403.677654) (xy 36.351972 -403.67712)
			(xy 37.068252 -403.67712) (xy 37.078405 -403.677561) (xy 37.097161 -403.685345) (xy 37.111486 -403.699736)
			(xy 37.119184 -403.718527) (xy 37.11956 -403.728682) (xy 37.11956 -403.886162) (xy 37.119998 -403.895346)
			(xy 37.126493 -403.91253) (xy 37.13226 -403.91969) (xy 37.154147 -403.945337) (xy 37.192238 -404.000973)
			(xy 37.22339 -404.060771) (xy 37.247154 -404.123871) (xy 37.26319 -404.189362) (xy 37.271264 -404.256303)
			(xy 37.271262 -404.32373) (xy 37.263184 -404.39067) (xy 37.247145 -404.456161) (xy 37.223376 -404.519259)
			(xy 37.192221 -404.579055) (xy 37.154127 -404.634689) (xy 37.13226 -404.660354) (xy 37.126453 -404.667492)
			(xy 37.119946 -404.684688) (xy 37.11956 -404.693882) (xy 37.11956 -405.186134) (xy 37.119963 -405.195322)
			(xy 37.126483 -405.212506) (xy 37.13226 -405.219662) (xy 37.154119 -405.245331) (xy 37.192211 -405.300964)
			(xy 37.223364 -405.36076) (xy 37.24713 -405.423856) (xy 37.263168 -405.489345) (xy 37.271245 -405.556284)
			(xy 37.271245 -405.623707) (xy 37.263169 -405.690646) (xy 37.247133 -405.756135) (xy 37.223368 -405.819232)
			(xy 37.192216 -405.879028) (xy 37.154125 -405.934661) (xy 37.13226 -405.960326) (xy 37.126465 -405.967472)
			(xy 37.11995 -405.984662) (xy 37.11956 -405.993854) (xy 37.11956 -406.151334) (xy 37.119101 -406.161463)
			(xy 37.111362 -406.180185) (xy 37.097068 -406.19454) (xy 37.078379 -406.202358) (xy 37.068252 -406.202896)
			(xy 36.351972 -406.202896) (xy 36.341816 -406.202501) (xy 36.323062 -406.194696) (xy 36.308739 -406.180291)
			(xy 36.301041 -406.161493) (xy 36.300664 -406.151334) (xy 36.300664 -405.993854) (xy 36.300214 -405.984671)
			(xy 36.293726 -405.967487) (xy 36.287964 -405.960326) (xy 36.266095 -405.934665) (xy 36.228009 -405.879029)
			(xy 36.196861 -405.819232) (xy 36.173099 -405.756135) (xy 36.157065 -405.690645) (xy 36.14899 -405.623707)
			(xy 35.020933 -405.623707) (xy 34.992063 -405.679128) (xy 34.953975 -405.734763) (xy 34.932112 -405.760428)
			(xy 34.926322 -405.767578) (xy 34.919803 -405.784765) (xy 34.919412 -405.793956) (xy 34.919412 -406.286208)
			(xy 34.919816 -406.295396) (xy 34.926334 -406.31258) (xy 34.932112 -406.319736) (xy 34.953944 -406.345427)
			(xy 34.992033 -406.401058) (xy 35.023184 -406.460851) (xy 35.04695 -406.523945) (xy 35.062987 -406.58943)
			(xy 35.071065 -406.656366) (xy 35.071068 -406.723729) (xy 38.34913 -406.723729) (xy 38.349133 -406.656422)
			(xy 38.35718 -406.589598) (xy 38.373155 -406.524215) (xy 38.39683 -406.461209) (xy 38.427865 -406.401484)
			(xy 38.465815 -406.345897) (xy 38.487604 -406.320244) (xy 38.493407 -406.313104) (xy 38.499918 -406.295909)
			(xy 38.500304 -406.286716) (xy 38.500304 -405.793448) (xy 38.49987 -405.784263) (xy 38.493373 -405.767079)
			(xy 38.487604 -405.75992) (xy 38.465813 -405.734271) (xy 38.427867 -405.678683) (xy 38.396836 -405.618959)
			(xy 38.373165 -405.555954) (xy 38.357193 -405.490572) (xy 38.34915 -405.423749) (xy 38.34915 -405.356445)
			(xy 38.357194 -405.289622) (xy 38.373167 -405.22424) (xy 38.396838 -405.161236) (xy 38.42787 -405.101512)
			(xy 38.465817 -405.045925) (xy 38.487604 -405.020272) (xy 38.493395 -405.013123) (xy 38.499913 -404.995935)
			(xy 38.500304 -404.986744) (xy 38.500304 -404.828756) (xy 38.500686 -404.818599) (xy 38.508497 -404.799844)
			(xy 38.522905 -404.785523) (xy 38.541706 -404.777825) (xy 38.551866 -404.777448) (xy 39.268146 -404.777448)
			(xy 39.278277 -404.777889) (xy 39.297 -404.785634) (xy 39.311355 -404.799934) (xy 39.319171 -404.818627)
			(xy 39.319708 -404.828756) (xy 39.319708 -404.986744) (xy 39.320095 -404.995934) (xy 39.326624 -405.013118)
			(xy 39.332408 -405.020272) (xy 39.354193 -405.045927) (xy 39.392146 -405.101512) (xy 39.423182 -405.161234)
			(xy 39.446858 -405.224239) (xy 39.462832 -405.289621) (xy 39.470878 -405.356444) (xy 39.470878 -405.42375)
			(xy 39.462833 -405.490573) (xy 39.446859 -405.555956) (xy 39.423185 -405.61896) (xy 39.420718 -405.623708)
			(xy 40.548756 -405.623708) (xy 40.548757 -405.556283) (xy 40.556834 -405.489343) (xy 40.572872 -405.423853)
			(xy 40.596639 -405.360756) (xy 40.627793 -405.30096) (xy 40.665886 -405.245326) (xy 40.687752 -405.219662)
			(xy 40.693554 -405.212521) (xy 40.700064 -405.195327) (xy 40.700452 -405.186134) (xy 40.700452 -404.693882)
			(xy 40.700039 -404.684695) (xy 40.693526 -404.667512) (xy 40.687752 -404.660354) (xy 40.665908 -404.634672)
			(xy 40.627815 -404.579041) (xy 40.59666 -404.519248) (xy 40.572893 -404.456153) (xy 40.556854 -404.390665)
			(xy 40.548776 -404.323728) (xy 40.548774 -404.256305) (xy 40.556848 -404.189367) (xy 40.572883 -404.123879)
			(xy 40.596647 -404.060783) (xy 40.627798 -404.000987) (xy 40.665888 -403.945354) (xy 40.687752 -403.91969)
			(xy 40.693542 -403.91254) (xy 40.700059 -403.895353) (xy 40.700452 -403.886162) (xy 40.700452 -403.728682)
			(xy 40.700912 -403.718553) (xy 40.708648 -403.699829) (xy 40.722942 -403.685473) (xy 40.741633 -403.677656)
			(xy 40.75176 -403.67712) (xy 41.46804 -403.67712) (xy 41.478199 -403.677489) (xy 41.496956 -403.685302)
			(xy 41.511279 -403.699715) (xy 41.518974 -403.71852) (xy 41.519348 -403.728682) (xy 41.519348 -403.886162)
			(xy 41.519788 -403.895346) (xy 41.526282 -403.91253) (xy 41.532048 -403.91969) (xy 41.553935 -403.945337)
			(xy 41.592027 -404.000973) (xy 41.62318 -404.060771) (xy 41.646945 -404.12387) (xy 41.66298 -404.189362)
			(xy 41.671055 -404.256303) (xy 41.671053 -404.32373) (xy 41.662974 -404.39067) (xy 41.646935 -404.456161)
			(xy 41.623166 -404.519259) (xy 41.59201 -404.579056) (xy 41.553915 -404.63469) (xy 41.532048 -404.660354)
			(xy 41.52624 -404.667491) (xy 41.519733 -404.684688) (xy 41.519348 -404.693882) (xy 41.519348 -405.186134)
			(xy 41.519754 -405.195321) (xy 41.526272 -405.212505) (xy 41.532048 -405.219662) (xy 41.553908 -405.245331)
			(xy 41.592 -405.300964) (xy 41.623154 -405.360759) (xy 41.646921 -405.423856) (xy 41.662958 -405.489345)
			(xy 41.671036 -405.556283) (xy 41.671036 -405.623708) (xy 41.66296 -405.690646) (xy 41.646924 -405.756136)
			(xy 41.623158 -405.819233) (xy 41.592005 -405.879028) (xy 41.553913 -405.934662) (xy 41.532048 -405.960326)
			(xy 41.526251 -405.967471) (xy 41.519738 -405.984662) (xy 41.519348 -405.993854) (xy 41.519348 -406.151334)
			(xy 41.518901 -406.161464) (xy 41.51116 -406.180189) (xy 41.496861 -406.194544) (xy 41.478168 -406.20236)
			(xy 41.46804 -406.202896) (xy 40.75176 -406.202896) (xy 40.741603 -406.202511) (xy 40.722849 -406.194701)
			(xy 40.708527 -406.180294) (xy 40.700829 -406.161494) (xy 40.700452 -406.151334) (xy 40.700452 -405.993854)
			(xy 40.700004 -405.984671) (xy 40.693515 -405.967487) (xy 40.687752 -405.960326) (xy 40.66588 -405.934667)
			(xy 40.627788 -405.879032) (xy 40.596635 -405.819236) (xy 40.572869 -405.756138) (xy 40.556832 -405.690648)
			(xy 40.548756 -405.623708) (xy 39.420718 -405.623708) (xy 39.392149 -405.678683) (xy 39.354197 -405.734269)
			(xy 39.332408 -405.75992) (xy 39.326621 -405.767072) (xy 39.3201 -405.784257) (xy 39.319708 -405.793448)
			(xy 39.319708 -406.286716) (xy 39.320109 -406.295904) (xy 39.326629 -406.313088) (xy 39.332408 -406.320244)
			(xy 39.354166 -406.345921) (xy 39.392119 -406.401503) (xy 39.423157 -406.461222) (xy 39.446834 -406.524224)
			(xy 39.46281 -406.589604) (xy 39.470858 -406.656424) (xy 39.470861 -406.723728) (xy 39.470854 -406.723789)
			(xy 42.748899 -406.723789) (xy 42.748901 -406.656363) (xy 42.756981 -406.589422) (xy 42.773019 -406.523932)
			(xy 42.796787 -406.460833) (xy 42.827942 -406.401036) (xy 42.866034 -406.345401) (xy 42.8879 -406.319736)
			(xy 42.893706 -406.312598) (xy 42.900215 -406.295402) (xy 42.9006 -406.286208) (xy 42.9006 -405.793956)
			(xy 42.900211 -405.784767) (xy 42.893683 -405.767582) (xy 42.8879 -405.760428) (xy 42.866032 -405.734766)
			(xy 42.827944 -405.679131) (xy 42.796793 -405.619334) (xy 42.773029 -405.556237) (xy 42.756994 -405.490748)
			(xy 42.748918 -405.423809) (xy 42.748919 -405.356385) (xy 42.756995 -405.289446) (xy 42.773031 -405.223957)
			(xy 42.796795 -405.16086) (xy 42.827947 -405.101064) (xy 42.866036 -405.045429) (xy 42.8879 -405.019764)
			(xy 42.893694 -405.012617) (xy 42.90021 -404.995428) (xy 42.9006 -404.986236) (xy 42.9006 -404.828756)
			(xy 42.901049 -404.818644) (xy 42.908801 -404.799965) (xy 42.923109 -404.785672) (xy 42.941796 -404.777939)
			(xy 42.951908 -404.777448) (xy 43.668188 -404.777448) (xy 43.67829 -404.777994) (xy 43.696958 -404.785718)
			(xy 43.711251 -404.799995) (xy 43.718995 -404.818655) (xy 43.719496 -404.828756) (xy 43.719496 -404.986236)
			(xy 43.71989 -404.995425) (xy 43.726415 -405.012609) (xy 43.732196 -405.019764) (xy 43.754056 -405.045432)
			(xy 43.792145 -405.101066) (xy 43.823296 -405.160862) (xy 43.847061 -405.223959) (xy 43.863097 -405.289447)
			(xy 43.871173 -405.356385) (xy 43.871173 -405.423809) (xy 43.863098 -405.490747) (xy 43.847063 -405.556236)
			(xy 43.823299 -405.619332) (xy 43.792148 -405.679128) (xy 43.75406 -405.734763) (xy 43.732196 -405.760428)
			(xy 43.726405 -405.767577) (xy 43.719887 -405.784765) (xy 43.719496 -405.793956) (xy 43.719496 -406.286208)
			(xy 43.719903 -406.295395) (xy 43.726419 -406.31258) (xy 43.732196 -406.319736) (xy 43.754029 -406.345427)
			(xy 43.792119 -406.401058) (xy 43.823271 -406.46085) (xy 43.847037 -406.523944) (xy 43.863075 -406.58943)
			(xy 43.871153 -406.656365) (xy 43.871156 -406.72373) (xy 47.149194 -406.72373) (xy 47.149197 -406.656422)
			(xy 47.157245 -406.589596) (xy 47.173223 -406.524212) (xy 47.196901 -406.461206) (xy 47.227941 -406.401481)
			(xy 47.265897 -406.345896) (xy 47.287688 -406.320244) (xy 47.293489 -406.313102) (xy 47.300002 -406.295909)
			(xy 47.300388 -406.286716) (xy 47.300388 -405.793448) (xy 47.299958 -405.784263) (xy 47.293458 -405.767078)
			(xy 47.287688 -405.75992) (xy 47.265895 -405.734272) (xy 47.227943 -405.678686) (xy 47.196907 -405.618962)
			(xy 47.173232 -405.555957) (xy 47.157258 -405.490574) (xy 47.149214 -405.42375) (xy 47.149214 -405.356444)
			(xy 47.157259 -405.28962) (xy 47.173234 -405.224237) (xy 47.19691 -405.161232) (xy 47.227946 -405.101509)
			(xy 47.265899 -405.045924) (xy 47.287688 -405.020272) (xy 47.293478 -405.013122) (xy 47.299997 -404.995935)
			(xy 47.300388 -404.986744) (xy 47.300388 -404.828756) (xy 47.300785 -404.818601) (xy 47.308593 -404.79985)
			(xy 47.322997 -404.785528) (xy 47.341792 -404.777828) (xy 47.35195 -404.777448) (xy 48.06823 -404.777448)
			(xy 48.07836 -404.777902) (xy 48.097083 -404.785641) (xy 48.111439 -404.799937) (xy 48.119255 -404.818629)
			(xy 48.119792 -404.828756) (xy 48.119792 -404.986744) (xy 48.120183 -404.995933) (xy 48.12671 -405.013117)
			(xy 48.132492 -405.020272) (xy 48.154275 -405.045928) (xy 48.192222 -405.101514) (xy 48.223254 -405.161238)
			(xy 48.246925 -405.224242) (xy 48.262897 -405.289623) (xy 48.270941 -405.356445) (xy 48.270942 -405.423749)
			(xy 48.262899 -405.490571) (xy 48.246927 -405.555952) (xy 48.223256 -405.618957) (xy 48.192225 -405.67868)
			(xy 48.154279 -405.734267) (xy 48.132492 -405.75992) (xy 48.126704 -405.767071) (xy 48.120184 -405.784257)
			(xy 48.119792 -405.793448) (xy 48.119792 -406.286716) (xy 48.120196 -406.295904) (xy 48.126714 -406.313088)
			(xy 48.132492 -406.320244) (xy 48.154247 -406.345922) (xy 48.192195 -406.401506) (xy 48.223228 -406.461226)
			(xy 48.246901 -406.524227) (xy 48.262876 -406.589606) (xy 48.270922 -406.656425) (xy 48.270925 -406.723727)
			(xy 48.262884 -406.790547) (xy 48.246916 -406.855927) (xy 48.223248 -406.91893) (xy 48.19222 -406.978653)
			(xy 48.154277 -407.034239) (xy 48.132492 -407.059892) (xy 48.126715 -407.067051) (xy 48.120189 -407.084231)
			(xy 48.119792 -407.09342) (xy 48.119792 -407.251408) (xy 48.119385 -407.261564) (xy 48.111585 -407.280318)
			(xy 48.097184 -407.294641) (xy 48.078388 -407.302339) (xy 48.06823 -407.302716) (xy 47.35195 -407.302716)
			(xy 47.341821 -407.302231) (xy 47.323093 -407.294512) (xy 47.308733 -407.280224) (xy 47.30092 -407.261534)
			(xy 47.300388 -407.251408) (xy 47.300388 -407.09342) (xy 47.299971 -407.084233) (xy 47.293462 -407.067049)
			(xy 47.287688 -407.059892) (xy 47.265867 -407.034266) (xy 47.227916 -406.978677) (xy 47.196882 -406.91895)
			(xy 47.173209 -406.855942) (xy 47.157236 -406.790556) (xy 47.149194 -406.72373) (xy 43.871156 -406.72373)
			(xy 43.871156 -406.723787) (xy 43.863084 -406.790723) (xy 43.847051 -406.85621) (xy 43.823291 -406.919306)
			(xy 43.792143 -406.979101) (xy 43.754058 -407.034735) (xy 43.732196 -407.0604) (xy 43.726416 -407.067557)
			(xy 43.719892 -407.084739) (xy 43.719496 -407.093928) (xy 43.719496 -407.251408) (xy 43.71909 -407.261531)
			(xy 43.711339 -407.280236) (xy 43.697019 -407.29455) (xy 43.678312 -407.302294) (xy 43.668188 -407.302716)
			(xy 42.951908 -407.302716) (xy 42.941802 -407.302209) (xy 42.923127 -407.294477) (xy 42.908832 -407.280187)
			(xy 42.901094 -407.261514) (xy 42.9006 -407.251408) (xy 42.9006 -407.093928) (xy 42.900176 -407.084742)
			(xy 42.893672 -407.067558) (xy 42.8879 -407.0604) (xy 42.866005 -407.034761) (xy 42.827917 -406.979122)
			(xy 42.796768 -406.919323) (xy 42.773005 -406.856222) (xy 42.756972 -406.79073) (xy 42.748899 -406.723789)
			(xy 39.470854 -406.723789) (xy 39.462819 -406.790549) (xy 39.446848 -406.85593) (xy 39.423176 -406.918933)
			(xy 39.392144 -406.978656) (xy 39.354195 -407.034241) (xy 39.332408 -407.059892) (xy 39.326633 -407.067053)
			(xy 39.320105 -407.084231) (xy 39.319708 -407.09342) (xy 39.319708 -407.251408) (xy 39.319285 -407.261562)
			(xy 39.311488 -407.280313) (xy 39.297092 -407.294635) (xy 39.278302 -407.302336) (xy 39.268146 -407.302716)
			(xy 38.551866 -407.302716) (xy 38.541732 -407.3023) (xy 38.523001 -407.294553) (xy 38.508645 -407.280245)
			(xy 38.500835 -407.261541) (xy 38.500304 -407.251408) (xy 38.500304 -407.09342) (xy 38.499883 -407.084234)
			(xy 38.493377 -407.06705) (xy 38.487604 -407.059892) (xy 38.465786 -407.034265) (xy 38.42784 -406.978674)
			(xy 38.39681 -406.918947) (xy 38.373141 -406.855939) (xy 38.357171 -406.790554) (xy 38.34913 -406.723729)
			(xy 35.071068 -406.723729) (xy 35.071068 -406.723786) (xy 35.062996 -406.790722) (xy 35.046964 -406.856209)
			(xy 35.023204 -406.919305) (xy 34.992058 -406.9791) (xy 34.953974 -407.034735) (xy 34.932112 -407.0604)
			(xy 34.926334 -407.067559) (xy 34.919808 -407.084739) (xy 34.919412 -407.093928) (xy 34.919412 -407.251408)
			(xy 34.918922 -407.261516) (xy 34.911184 -407.280192) (xy 34.896888 -407.294486) (xy 34.878212 -407.302222)
			(xy 34.868104 -407.302716) (xy 34.151824 -407.302716) (xy 34.141705 -407.302265) (xy 34.123005 -407.294528)
			(xy 34.10869 -407.280222) (xy 34.100941 -407.261527) (xy 34.100516 -407.251408) (xy 34.100516 -407.093928)
			(xy 34.100089 -407.084743) (xy 34.093586 -407.067558) (xy 34.087816 -407.0604) (xy 34.06592 -407.034761)
			(xy 34.027831 -406.979123) (xy 33.996681 -406.919323) (xy 33.972918 -406.856223) (xy 33.956884 -406.790731)
			(xy 33.948811 -406.723789) (xy 30.670766 -406.723789) (xy 30.662731 -406.790549) (xy 30.646761 -406.855929)
			(xy 30.62309 -406.918933) (xy 30.592058 -406.978655) (xy 30.554111 -407.03424) (xy 30.532324 -407.059892)
			(xy 30.526551 -407.067054) (xy 30.520022 -407.084232) (xy 30.519624 -407.09342) (xy 30.519624 -407.251408)
			(xy 30.519185 -407.26156) (xy 30.511392 -407.280307) (xy 30.497001 -407.29463) (xy 30.478216 -407.302333)
			(xy 30.468062 -407.302716) (xy 29.751782 -407.302716) (xy 29.741649 -407.302287) (xy 29.722919 -407.294545)
			(xy 29.708561 -407.280241) (xy 29.700751 -407.261539) (xy 29.70022 -407.251408) (xy 29.70022 -407.09342)
			(xy 29.699796 -407.084234) (xy 29.693291 -407.06705) (xy 29.68752 -407.059892) (xy 29.665701 -407.034265)
			(xy 29.627755 -406.978675) (xy 29.596724 -406.918948) (xy 29.573054 -406.85594) (xy 29.557084 -406.790555)
			(xy 29.549042 -406.72373) (xy 21.823172 -406.72373) (xy 21.823172 -409.523886) (xy 27.348881 -409.523886)
			(xy 27.348884 -409.45646) (xy 27.356963 -409.38952) (xy 27.373002 -409.324029) (xy 27.396769 -409.26093)
			(xy 27.427923 -409.201133) (xy 27.466015 -409.145498) (xy 27.48788 -409.119832) (xy 27.493686 -409.112693)
			(xy 27.500196 -409.095498) (xy 27.50058 -409.086304) (xy 27.50058 -408.594052) (xy 27.500149 -408.584867)
			(xy 27.49365 -408.567682) (xy 27.48788 -408.560524) (xy 27.466009 -408.534865) (xy 27.427922 -408.479229)
			(xy 27.396772 -408.419432) (xy 27.37301 -408.356334) (xy 27.356975 -408.290845) (xy 27.3489 -408.223906)
			(xy 27.348901 -408.156482) (xy 27.356977 -408.089544) (xy 27.373013 -408.024054) (xy 27.396777 -407.960957)
			(xy 27.427928 -407.901161) (xy 27.466016 -407.845526) (xy 27.48788 -407.81986) (xy 27.493674 -407.812713)
			(xy 27.500191 -407.795524) (xy 27.50058 -407.786332) (xy 27.50058 -407.628852) (xy 27.501045 -407.618743)
			(xy 27.508795 -407.600067) (xy 27.523098 -407.585775) (xy 27.541778 -407.578038) (xy 27.551888 -407.577544)
			(xy 28.268168 -407.577544) (xy 28.278268 -407.57811) (xy 28.296935 -407.585826) (xy 28.311229 -407.600098)
			(xy 28.318975 -407.618753) (xy 28.319476 -407.628852) (xy 28.319476 -407.786332) (xy 28.319876 -407.79552)
			(xy 28.326397 -407.812704) (xy 28.332176 -407.81986) (xy 28.354033 -407.845531) (xy 28.392123 -407.901164)
			(xy 28.423276 -407.96096) (xy 28.447042 -408.024056) (xy 28.463078 -408.089544) (xy 28.471155 -408.156482)
			(xy 28.471156 -408.223906) (xy 28.46308 -408.290844) (xy 28.447045 -408.356333) (xy 28.423281 -408.419429)
			(xy 28.39213 -408.479225) (xy 28.35404 -408.534859) (xy 28.332176 -408.560524) (xy 28.326384 -408.567672)
			(xy 28.319867 -408.584861) (xy 28.319476 -408.594052) (xy 28.319476 -409.086304) (xy 28.319889 -409.095491)
			(xy 28.326401 -409.112675) (xy 28.332176 -409.119832) (xy 28.354005 -409.145526) (xy 28.392097 -409.201156)
			(xy 28.42325 -409.260948) (xy 28.447018 -409.324041) (xy 28.463056 -409.389527) (xy 28.471135 -409.456462)
			(xy 28.471139 -409.523884) (xy 28.463066 -409.59082) (xy 28.447034 -409.656307) (xy 28.423273 -409.719403)
			(xy 28.392125 -409.779198) (xy 28.354039 -409.834831) (xy 28.332176 -409.860496) (xy 28.326396 -409.867653)
			(xy 28.319872 -409.884835) (xy 28.319476 -409.894024) (xy 28.319476 -410.051504) (xy 28.319087 -410.06163)
			(xy 28.311333 -410.080338) (xy 28.297008 -410.094653) (xy 28.278294 -410.102394) (xy 28.268168 -410.102812)
			(xy 27.551888 -410.102812) (xy 27.54178 -410.102325) (xy 27.523104 -410.094585) (xy 27.50881 -410.080289)
			(xy 27.501074 -410.061612) (xy 27.50058 -410.051504) (xy 27.50058 -409.894024) (xy 27.500163 -409.884837)
			(xy 27.493655 -409.867653) (xy 27.48788 -409.860496) (xy 27.465981 -409.83486) (xy 27.427895 -409.77922)
			(xy 27.396747 -409.71942) (xy 27.372986 -409.656319) (xy 27.356953 -409.590827) (xy 27.348881 -409.523886)
			(xy 21.823172 -409.523886) (xy 21.823172 -410.623641) (xy 29.549054 -410.623641) (xy 29.549055 -410.556335)
			(xy 29.5571 -410.489512) (xy 29.573074 -410.424129) (xy 29.596748 -410.361124) (xy 29.627782 -410.301399)
			(xy 29.665732 -410.245812) (xy 29.68752 -410.22016) (xy 29.693318 -410.213016) (xy 29.699831 -410.195825)
			(xy 29.70022 -410.186632) (xy 29.70022 -409.693364) (xy 29.699823 -409.684176) (xy 29.6933 -409.666992)
			(xy 29.68752 -409.659836) (xy 29.665745 -409.634174) (xy 29.627797 -409.578588) (xy 29.596764 -409.518866)
			(xy 29.573091 -409.455863) (xy 29.557118 -409.390482) (xy 29.549073 -409.323661) (xy 29.549072 -409.256357)
			(xy 29.557115 -409.189536) (xy 29.573086 -409.124154) (xy 29.596757 -409.06115) (xy 29.627787 -409.001427)
			(xy 29.665734 -408.94584) (xy 29.68752 -408.920188) (xy 29.693306 -408.913036) (xy 29.699827 -408.895851)
			(xy 29.70022 -408.88666) (xy 29.70022 -408.728672) (xy 29.700599 -408.718514) (xy 29.708408 -408.699757)
			(xy 29.722817 -408.685434) (xy 29.741621 -408.677738) (xy 29.751782 -408.677364) (xy 30.468062 -408.677364)
			(xy 30.478189 -408.677859) (xy 30.496914 -408.685578) (xy 30.511272 -408.699863) (xy 30.519089 -408.718547)
			(xy 30.519624 -408.728672) (xy 30.519624 -408.88666) (xy 30.520048 -408.895846) (xy 30.526551 -408.913031)
			(xy 30.532324 -408.920188) (xy 30.554125 -408.94583) (xy 30.592075 -409.001417) (xy 30.62311 -409.061142)
			(xy 30.646784 -409.124148) (xy 30.662757 -409.189531) (xy 30.670801 -409.256356) (xy 30.6708 -409.323662)
			(xy 30.662754 -409.390486) (xy 30.646779 -409.45587) (xy 30.623103 -409.518875) (xy 30.62053 -409.523827)
			(xy 31.749176 -409.523827) (xy 31.749179 -409.456519) (xy 31.757227 -409.389693) (xy 31.773205 -409.324309)
			(xy 31.796883 -409.261302) (xy 31.827922 -409.201578) (xy 31.865877 -409.145992) (xy 31.887668 -409.12034)
			(xy 31.893481 -409.113207) (xy 31.899984 -409.096007) (xy 31.900368 -409.086812) (xy 31.900368 -408.593544)
			(xy 31.899922 -408.584361) (xy 31.893432 -408.567177) (xy 31.887668 -408.560016) (xy 31.865872 -408.534371)
			(xy 31.827921 -408.478784) (xy 31.796887 -408.41906) (xy 31.773213 -408.356054) (xy 31.75724 -408.290671)
			(xy 31.749196 -408.223847) (xy 31.749197 -408.156541) (xy 31.757242 -408.089717) (xy 31.773217 -408.024334)
			(xy 31.796892 -407.961329) (xy 31.827927 -407.901606) (xy 31.865879 -407.84602) (xy 31.887668 -407.820368)
			(xy 31.893469 -407.813226) (xy 31.899979 -407.796033) (xy 31.900368 -407.78684) (xy 31.900368 -407.628852)
			(xy 31.900782 -407.618699) (xy 31.908587 -407.599952) (xy 31.922985 -407.585631) (xy 31.941775 -407.577927)
			(xy 31.95193 -407.577544) (xy 32.66821 -407.577544) (xy 32.678338 -407.578019) (xy 32.69706 -407.58575)
			(xy 32.711416 -407.60004) (xy 32.719234 -407.618727) (xy 32.719772 -407.628852) (xy 32.719772 -407.78684)
			(xy 32.720169 -407.796028) (xy 32.726693 -407.813212) (xy 32.732472 -407.820368) (xy 32.754252 -407.846027)
			(xy 32.7922 -407.901612) (xy 32.823233 -407.961335) (xy 32.846906 -408.024339) (xy 32.862879 -408.08972)
			(xy 32.870924 -408.156542) (xy 32.870924 -408.223846) (xy 32.862881 -408.290668) (xy 32.846909 -408.35605)
			(xy 32.823238 -408.419054) (xy 32.792206 -408.478777) (xy 32.754259 -408.534364) (xy 32.732472 -408.560016)
			(xy 32.726682 -408.567166) (xy 32.720164 -408.584353) (xy 32.719772 -408.593544) (xy 32.719772 -409.086812)
			(xy 32.720183 -409.095999) (xy 32.726697 -409.113183) (xy 32.732472 -409.12034) (xy 32.754224 -409.146022)
			(xy 32.792173 -409.201604) (xy 32.823207 -409.261324) (xy 32.846881 -409.324324) (xy 32.862857 -409.389703)
			(xy 32.870903 -409.456522) (xy 32.870907 -409.523824) (xy 32.862866 -409.590644) (xy 32.846897 -409.656024)
			(xy 32.823229 -409.719027) (xy 32.792201 -409.778749) (xy 32.754257 -409.834336) (xy 32.732472 -409.859988)
			(xy 32.726652 -409.867116) (xy 32.720152 -409.88432) (xy 32.719772 -409.893516) (xy 32.719772 -410.051504)
			(xy 32.719381 -410.061662) (xy 32.711579 -410.08042) (xy 32.697172 -410.094744) (xy 32.67837 -410.102438)
			(xy 32.66821 -410.102812) (xy 31.95193 -410.102812) (xy 31.941812 -410.102251) (xy 31.923101 -410.094542)
			(xy 31.908745 -410.080279) (xy 31.900916 -410.061619) (xy 31.900368 -410.051504) (xy 31.900368 -409.893516)
			(xy 31.899935 -409.884332) (xy 31.893436 -409.867148) (xy 31.887668 -409.859988) (xy 31.865844 -409.834366)
			(xy 31.827894 -409.778775) (xy 31.796861 -409.719048) (xy 31.773189 -409.65604) (xy 31.757217 -409.590654)
			(xy 31.749176 -409.523827) (xy 30.62053 -409.523827) (xy 30.592066 -409.578598) (xy 30.554113 -409.634184)
			(xy 30.532324 -409.659836) (xy 30.526532 -409.666985) (xy 30.520014 -409.684172) (xy 30.519624 -409.693364)
			(xy 30.519624 -410.186632) (xy 30.520014 -410.195821) (xy 30.526541 -410.213006) (xy 30.532324 -410.22016)
			(xy 30.554097 -410.245825) (xy 30.592049 -410.301408) (xy 30.623085 -410.36113) (xy 30.64676 -410.424133)
			(xy 30.662735 -410.489514) (xy 30.670781 -410.556336) (xy 30.670783 -410.62364) (xy 30.670776 -410.623701)
			(xy 33.948822 -410.623701) (xy 33.948823 -410.556275) (xy 33.956901 -410.489336) (xy 33.972939 -410.423846)
			(xy 33.996705 -410.360748) (xy 34.027859 -410.300951) (xy 34.065951 -410.245317) (xy 34.087816 -410.219652)
			(xy 34.093617 -410.21251) (xy 34.100129 -410.195317) (xy 34.100516 -410.186124) (xy 34.100516 -409.693872)
			(xy 34.100116 -409.684684) (xy 34.093595 -409.6675) (xy 34.087816 -409.660344) (xy 34.065963 -409.634669)
			(xy 34.027873 -409.579037) (xy 33.996721 -409.519242) (xy 33.972955 -409.456146) (xy 33.956919 -409.390658)
			(xy 33.948842 -409.323721) (xy 33.948841 -409.256297) (xy 33.956915 -409.18936) (xy 33.97295 -409.123871)
			(xy 33.996714 -409.060775) (xy 34.027864 -409.000979) (xy 34.065952 -408.945345) (xy 34.087816 -408.91968)
			(xy 34.093605 -408.91253) (xy 34.100124 -408.895343) (xy 34.100516 -408.886152) (xy 34.100516 -408.728672)
			(xy 34.100962 -408.718559) (xy 34.108712 -408.699878) (xy 34.123021 -408.685583) (xy 34.141711 -408.677852)
			(xy 34.151824 -408.677364) (xy 34.868104 -408.677364) (xy 34.878209 -408.677881) (xy 34.89688 -408.685613)
			(xy 34.911173 -408.6999) (xy 34.918914 -408.718568) (xy 34.919412 -408.728672) (xy 34.919412 -408.886152)
			(xy 34.919842 -408.895337) (xy 34.926342 -408.912522) (xy 34.932112 -408.91968) (xy 34.953987 -408.945336)
			(xy 34.992075 -409.000972) (xy 35.023224 -409.06077) (xy 35.046987 -409.123868) (xy 35.063022 -409.189358)
			(xy 35.071096 -409.256297) (xy 35.071095 -409.323721) (xy 35.063018 -409.39066) (xy 35.046982 -409.45615)
			(xy 35.023217 -409.519247) (xy 35.0208 -409.523886) (xy 36.148969 -409.523886) (xy 36.148972 -409.45646)
			(xy 36.157051 -409.38952) (xy 36.173089 -409.324029) (xy 36.196856 -409.260931) (xy 36.228009 -409.201134)
			(xy 36.266099 -409.145498) (xy 36.287964 -409.119832) (xy 36.29378 -409.112701) (xy 36.300281 -409.095499)
			(xy 36.300664 -409.086304) (xy 36.300664 -408.594052) (xy 36.300215 -408.584869) (xy 36.293727 -408.567685)
			(xy 36.287964 -408.560524) (xy 36.266093 -408.534865) (xy 36.228007 -408.479228) (xy 36.196859 -408.419431)
			(xy 36.173097 -408.356334) (xy 36.157063 -408.290844) (xy 36.148988 -408.223906) (xy 36.148989 -408.156482)
			(xy 36.157065 -408.089544) (xy 36.1731 -408.024055) (xy 36.196864 -407.960958) (xy 36.228014 -407.901161)
			(xy 36.266101 -407.845526) (xy 36.287964 -407.81986) (xy 36.293768 -407.81272) (xy 36.300276 -407.795525)
			(xy 36.300664 -407.786332) (xy 36.300664 -407.628852) (xy 36.301145 -407.618745) (xy 36.308892 -407.600072)
			(xy 36.323189 -407.585781) (xy 36.341864 -407.578041) (xy 36.351972 -407.577544) (xy 37.068252 -407.577544)
			(xy 37.078351 -407.578123) (xy 37.097017 -407.585835) (xy 37.111312 -407.600102) (xy 37.119058 -407.618754)
			(xy 37.11956 -407.628852) (xy 37.11956 -407.786332) (xy 37.119964 -407.79552) (xy 37.126483 -407.812703)
			(xy 37.13226 -407.81986) (xy 37.154118 -407.845531) (xy 37.192209 -407.901164) (xy 37.223362 -407.960959)
			(xy 37.247129 -408.024055) (xy 37.263166 -408.089544) (xy 37.271243 -408.156482) (xy 37.271244 -408.223906)
			(xy 37.263168 -408.290844) (xy 37.247132 -408.356333) (xy 37.223367 -408.41943) (xy 37.192215 -408.479226)
			(xy 37.154125 -408.534859) (xy 37.13226 -408.560524) (xy 37.126466 -408.567671) (xy 37.119951 -408.58486)
			(xy 37.11956 -408.594052) (xy 37.11956 -409.086304) (xy 37.119977 -409.09549) (xy 37.126487 -409.112674)
			(xy 37.13226 -409.119832) (xy 37.15409 -409.145526) (xy 37.192182 -409.201155) (xy 37.223337 -409.260947)
			(xy 37.247105 -409.32404) (xy 37.263144 -409.389526) (xy 37.271223 -409.456462) (xy 37.271227 -409.523884)
			(xy 37.263154 -409.59082) (xy 37.247121 -409.656308) (xy 37.223359 -409.719403) (xy 37.19221 -409.779198)
			(xy 37.154123 -409.834831) (xy 37.13226 -409.860496) (xy 37.126478 -409.867651) (xy 37.119955 -409.884834)
			(xy 37.11956 -409.894024) (xy 37.11956 -410.051504) (xy 37.119186 -410.061632) (xy 37.111429 -410.080343)
			(xy 37.097099 -410.094659) (xy 37.07838 -410.102396) (xy 37.068252 -410.102812) (xy 36.351972 -410.102812)
			(xy 36.341863 -410.102338) (xy 36.323186 -410.094594) (xy 36.308893 -410.080293) (xy 36.301157 -410.061613)
			(xy 36.300664 -410.051504) (xy 36.300664 -409.894024) (xy 36.300228 -409.88484) (xy 36.293731 -409.867656)
			(xy 36.287964 -409.860496) (xy 36.266066 -409.834859) (xy 36.227981 -409.77922) (xy 36.196834 -409.719419)
			(xy 36.173073 -409.656319) (xy 36.157041 -409.590827) (xy 36.148969 -409.523886) (xy 35.0208 -409.523886)
			(xy 34.992066 -409.579044) (xy 34.953976 -409.634679) (xy 34.932112 -409.660344) (xy 34.926316 -409.667489)
			(xy 34.9198 -409.68468) (xy 34.919412 -409.693872) (xy 34.919412 -410.186124) (xy 34.919808 -410.195313)
			(xy 34.926331 -410.212497) (xy 34.932112 -410.219652) (xy 34.95396 -410.24533) (xy 34.992048 -410.300963)
			(xy 35.023199 -410.360758) (xy 35.046964 -410.423853) (xy 35.063 -410.48934) (xy 35.071077 -410.556277)
			(xy 35.071078 -410.623641) (xy 38.349141 -410.623641) (xy 38.349143 -410.556335) (xy 38.357188 -410.489512)
			(xy 38.373162 -410.424129) (xy 38.396835 -410.361124) (xy 38.427868 -410.3014) (xy 38.465816 -410.245813)
			(xy 38.487604 -410.22016) (xy 38.493401 -410.213015) (xy 38.499915 -410.195824) (xy 38.500304 -410.186632)
			(xy 38.500304 -409.693364) (xy 38.49991 -409.684175) (xy 38.493385 -409.666991) (xy 38.487604 -409.659836)
			(xy 38.465829 -409.634174) (xy 38.427882 -409.578588) (xy 38.39685 -409.518865) (xy 38.373178 -409.455862)
			(xy 38.357206 -409.390482) (xy 38.349161 -409.323661) (xy 38.34916 -409.256357) (xy 38.357202 -409.189536)
			(xy 38.373173 -409.124155) (xy 38.396843 -409.061151) (xy 38.427873 -409.001428) (xy 38.465818 -408.945841)
			(xy 38.487604 -408.920188) (xy 38.493389 -408.913034) (xy 38.49991 -408.89585) (xy 38.500304 -408.88666)
			(xy 38.500304 -408.728672) (xy 38.500699 -408.718516) (xy 38.508504 -408.699762) (xy 38.522909 -408.685439)
			(xy 38.541707 -408.677741) (xy 38.551866 -408.677364) (xy 39.268146 -408.677364) (xy 39.278279 -408.67779)
			(xy 39.297005 -408.685537) (xy 39.311361 -408.699842) (xy 39.319174 -408.718541) (xy 39.319708 -408.728672)
			(xy 39.319708 -408.88666) (xy 39.320136 -408.895845) (xy 39.326637 -408.91303) (xy 39.332408 -408.920188)
			(xy 39.354209 -408.94583) (xy 39.392161 -409.001416) (xy 39.423197 -409.061141) (xy 39.446871 -409.124147)
			(xy 39.462845 -409.189531) (xy 39.470889 -409.256356) (xy 39.470888 -409.323663) (xy 39.462842 -409.390487)
			(xy 39.446866 -409.45587) (xy 39.423189 -409.518876) (xy 39.420585 -409.523887) (xy 40.548735 -409.523887)
			(xy 40.548738 -409.456459) (xy 40.556818 -409.389518) (xy 40.572859 -409.324026) (xy 40.59663 -409.260927)
			(xy 40.627788 -409.20113) (xy 40.665884 -409.145496) (xy 40.687752 -409.119832) (xy 40.693566 -409.1127)
			(xy 40.700069 -409.095499) (xy 40.700452 -409.086304) (xy 40.700452 -408.594052) (xy 40.700005 -408.584869)
			(xy 40.693516 -408.567685) (xy 40.687752 -408.560524) (xy 40.665878 -408.534866) (xy 40.627786 -408.479232)
			(xy 40.596633 -408.419435) (xy 40.572867 -408.356337) (xy 40.556831 -408.290847) (xy 40.548755 -408.223907)
			(xy 40.548755 -408.156481) (xy 40.556833 -408.089542) (xy 40.572871 -408.024051) (xy 40.596638 -407.960954)
			(xy 40.627793 -407.901158) (xy 40.665886 -407.845524) (xy 40.687752 -407.81986) (xy 40.693554 -407.812719)
			(xy 40.700064 -407.795525) (xy 40.700452 -407.786332) (xy 40.700452 -407.628852) (xy 40.700945 -407.618746)
			(xy 40.708689 -407.600076) (xy 40.722983 -407.585785) (xy 40.741654 -407.578043) (xy 40.75176 -407.577544)
			(xy 41.46804 -407.577544) (xy 41.478144 -407.578051) (xy 41.496813 -407.585791) (xy 41.511104 -407.600081)
			(xy 41.518847 -407.618748) (xy 41.519348 -407.628852) (xy 41.519348 -407.786332) (xy 41.519755 -407.795519)
			(xy 41.526272 -407.812703) (xy 41.532048 -407.81986) (xy 41.553906 -407.845531) (xy 41.591998 -407.901163)
			(xy 41.623152 -407.960958) (xy 41.646919 -408.024055) (xy 41.662957 -408.089543) (xy 41.671034 -408.156482)
			(xy 41.671035 -408.223906) (xy 41.662959 -408.290845) (xy 41.646923 -408.356334) (xy 41.623157 -408.419431)
			(xy 41.592004 -408.479226) (xy 41.553913 -408.53486) (xy 41.532048 -408.560524) (xy 41.526252 -408.56767)
			(xy 41.519739 -408.58486) (xy 41.519348 -408.594052) (xy 41.519348 -409.086304) (xy 41.519768 -409.09549)
			(xy 41.526276 -409.112674) (xy 41.532048 -409.119832) (xy 41.553878 -409.145526) (xy 41.591972 -409.201155)
			(xy 41.623127 -409.260947) (xy 41.646895 -409.32404) (xy 41.662935 -409.389526) (xy 41.671014 -409.456462)
			(xy 41.671018 -409.523884) (xy 41.662945 -409.590821) (xy 41.646911 -409.656308) (xy 41.623149 -409.719404)
			(xy 41.591999 -409.779199) (xy 41.553912 -409.834832) (xy 41.532048 -409.860496) (xy 41.526264 -409.86765)
			(xy 41.519743 -409.884834) (xy 41.519348 -409.894024) (xy 41.519348 -410.051504) (xy 41.518819 -410.061607)
			(xy 41.511089 -410.080276) (xy 41.496806 -410.094569) (xy 41.478143 -410.102312) (xy 41.46804 -410.102812)
			(xy 40.75176 -410.102812) (xy 40.74165 -410.102348) (xy 40.722973 -410.094599) (xy 40.70868 -410.080296)
			(xy 40.700945 -410.061614) (xy 40.700452 -410.051504) (xy 40.700452 -409.894024) (xy 40.700019 -409.884839)
			(xy 40.69352 -409.867655) (xy 40.687752 -409.860496) (xy 40.665851 -409.834861) (xy 40.62776 -409.779223)
			(xy 40.596608 -409.719423) (xy 40.572843 -409.656322) (xy 40.556809 -409.590829) (xy 40.548735 -409.523887)
			(xy 39.420585 -409.523887) (xy 39.392152 -409.578599) (xy 39.354198 -409.634185) (xy 39.332408 -409.659836)
			(xy 39.326615 -409.666984) (xy 39.320098 -409.684172) (xy 39.319708 -409.693364) (xy 39.319708 -410.186632)
			(xy 39.320101 -410.195821) (xy 39.326626 -410.213005) (xy 39.332408 -410.22016) (xy 39.354182 -410.245824)
			(xy 39.392134 -410.301408) (xy 39.423171 -410.361129) (xy 39.446847 -410.424132) (xy 39.462823 -410.489513)
			(xy 39.470869 -410.556336) (xy 39.470871 -410.62364) (xy 39.470864 -410.6237) (xy 42.74891 -410.6237)
			(xy 42.748911 -410.556276) (xy 42.756989 -410.489336) (xy 42.773026 -410.423846) (xy 42.796792 -410.360749)
			(xy 42.827944 -410.300952) (xy 42.866035 -410.245317) (xy 42.8879 -410.219652) (xy 42.893699 -410.212509)
			(xy 42.900212 -410.195317) (xy 42.9006 -410.186124) (xy 42.9006 -409.693872) (xy 42.900204 -409.684683)
			(xy 42.89368 -409.667499) (xy 42.8879 -409.660344) (xy 42.866048 -409.634669) (xy 42.827959 -409.579036)
			(xy 42.796808 -409.519241) (xy 42.773043 -409.456145) (xy 42.757006 -409.390658) (xy 42.74893 -409.32372)
			(xy 42.748928 -409.256298) (xy 42.757003 -409.18936) (xy 42.773037 -409.123872) (xy 42.7968 -409.060775)
			(xy 42.827949 -409.00098) (xy 42.866037 -408.945345) (xy 42.8879 -408.91968) (xy 42.893688 -408.912528)
			(xy 42.900208 -408.895343) (xy 42.9006 -408.886152) (xy 42.9006 -408.728672) (xy 42.901062 -408.718561)
			(xy 42.908809 -408.699883) (xy 42.923113 -408.685589) (xy 42.941797 -408.677855) (xy 42.951908 -408.677364)
			(xy 43.668188 -408.677364) (xy 43.678292 -408.677894) (xy 43.696963 -408.685621) (xy 43.711257 -408.699904)
			(xy 43.718998 -408.718569) (xy 43.719496 -408.728672) (xy 43.719496 -408.886152) (xy 43.71993 -408.895337)
			(xy 43.726427 -408.912521) (xy 43.732196 -408.91968) (xy 43.754072 -408.945335) (xy 43.792161 -409.000971)
			(xy 43.823311 -409.060769) (xy 43.847075 -409.123867) (xy 43.863109 -409.189357) (xy 43.871184 -409.256297)
			(xy 43.871183 -409.323721) (xy 43.863106 -409.390661) (xy 43.847069 -409.45615) (xy 43.823304 -409.519248)
			(xy 43.792151 -409.579044) (xy 43.754061 -409.634679) (xy 43.732196 -409.660344) (xy 43.726398 -409.667488)
			(xy 43.719884 -409.684679) (xy 43.719496 -409.693872) (xy 43.719496 -410.186124) (xy 43.719895 -410.195312)
			(xy 43.726417 -410.212497) (xy 43.732196 -410.219652) (xy 43.754044 -410.24533) (xy 43.792134 -410.300963)
			(xy 43.823285 -410.360757) (xy 43.847051 -410.423852) (xy 43.863087 -410.48934) (xy 43.871165 -410.556277)
			(xy 43.871166 -410.623642) (xy 47.149205 -410.623642) (xy 47.149207 -410.556334) (xy 47.157253 -410.48951)
			(xy 47.173229 -410.424126) (xy 47.196906 -410.361121) (xy 47.227944 -410.301397) (xy 47.265898 -410.245812)
			(xy 47.287688 -410.22016) (xy 47.293483 -410.213013) (xy 47.299999 -410.195824) (xy 47.300388 -410.186632)
			(xy 47.300388 -409.693364) (xy 47.299998 -409.684175) (xy 47.293471 -409.66699) (xy 47.287688 -409.659836)
			(xy 47.265911 -409.634175) (xy 47.227958 -409.578591) (xy 47.196922 -409.518869) (xy 47.173246 -409.455866)
			(xy 47.157271 -409.390484) (xy 47.149225 -409.323662) (xy 47.149224 -409.256357) (xy 47.157268 -409.189534)
			(xy 47.173241 -409.124152) (xy 47.196914 -409.061148) (xy 47.227949 -409.001425) (xy 47.2659 -408.945839)
			(xy 47.287688 -408.920188) (xy 47.293471 -408.913033) (xy 47.299994 -408.89585) (xy 47.300388 -408.88666)
			(xy 47.300388 -408.728672) (xy 47.300798 -408.718518) (xy 47.308601 -408.699767) (xy 47.323001 -408.685445)
			(xy 47.341793 -408.677744) (xy 47.35195 -408.677364) (xy 48.06823 -408.677364) (xy 48.078362 -408.677803)
			(xy 48.097088 -408.685545) (xy 48.111444 -408.699846) (xy 48.119258 -408.718542) (xy 48.119792 -408.728672)
			(xy 48.119792 -408.88666) (xy 48.120223 -408.895845) (xy 48.126722 -408.913029) (xy 48.132492 -408.920188)
			(xy 48.154291 -408.945831) (xy 48.192237 -409.001419) (xy 48.223268 -409.061145) (xy 48.246939 -409.12415)
			(xy 48.26291 -409.189533) (xy 48.270953 -409.256356) (xy 48.270952 -409.323662) (xy 48.262907 -409.390485)
			(xy 48.246933 -409.455867) (xy 48.223261 -409.518872) (xy 48.192228 -409.578596) (xy 48.15428 -409.634183)
			(xy 48.132492 -409.659836) (xy 48.126697 -409.666982) (xy 48.120182 -409.684172) (xy 48.119792 -409.693364)
			(xy 48.119792 -410.186632) (xy 48.120188 -410.195821) (xy 48.126712 -410.213005) (xy 48.132492 -410.22016)
			(xy 48.154263 -410.245825) (xy 48.19221 -410.301411) (xy 48.223243 -410.361133) (xy 48.246915 -410.424135)
			(xy 48.262888 -410.489516) (xy 48.270933 -410.556336) (xy 48.270934 -410.62364) (xy 48.262892 -410.690461)
			(xy 48.246922 -410.755842) (xy 48.223252 -410.818845) (xy 48.192223 -410.878569) (xy 48.154278 -410.934155)
			(xy 48.132492 -410.959808) (xy 48.126709 -410.966963) (xy 48.120186 -410.984146) (xy 48.119792 -410.993336)
			(xy 48.119792 -411.151324) (xy 48.119398 -411.161481) (xy 48.111593 -411.180235) (xy 48.097188 -411.194558)
			(xy 48.078389 -411.202255) (xy 48.06823 -411.202632) (xy 47.35195 -411.202632) (xy 47.341823 -411.202132)
			(xy 47.323098 -411.194415) (xy 47.308739 -411.180132) (xy 47.300923 -411.161448) (xy 47.300388 -411.151324)
			(xy 47.300388 -410.993336) (xy 47.299963 -410.98415) (xy 47.29346 -410.966966) (xy 47.287688 -410.959808)
			(xy 47.265883 -410.934169) (xy 47.227932 -410.878582) (xy 47.196896 -410.818857) (xy 47.173222 -410.755851)
			(xy 47.157249 -410.690466) (xy 47.149205 -410.623642) (xy 43.871166 -410.623642) (xy 43.871166 -410.623699)
			(xy 43.863092 -410.690636) (xy 43.847058 -410.756125) (xy 43.823295 -410.819221) (xy 43.792146 -410.879017)
			(xy 43.754059 -410.934651) (xy 43.732196 -410.960316) (xy 43.72641 -410.967468) (xy 43.719889 -410.984653)
			(xy 43.719496 -410.993844) (xy 43.719496 -411.151324) (xy 43.719035 -411.161435) (xy 43.711288 -411.180114)
			(xy 43.696984 -411.194408) (xy 43.678299 -411.202142) (xy 43.668188 -411.202632) (xy 42.951908 -411.202632)
			(xy 42.941804 -411.202109) (xy 42.923132 -411.19438) (xy 42.908838 -411.180095) (xy 42.901097 -411.161428)
			(xy 42.9006 -411.151324) (xy 42.9006 -410.993844) (xy 42.900169 -410.984659) (xy 42.89367 -410.967474)
			(xy 42.8879 -410.960316) (xy 42.86602 -410.934664) (xy 42.827932 -410.879027) (xy 42.796782 -410.819229)
			(xy 42.773019 -410.756131) (xy 42.756984 -410.69064) (xy 42.74891 -410.6237) (xy 39.470864 -410.6237)
			(xy 39.462827 -410.690463) (xy 39.446854 -410.755845) (xy 39.423181 -410.818849) (xy 39.392147 -410.878572)
			(xy 39.354196 -410.934157) (xy 39.332408 -410.959808) (xy 39.326626 -410.966964) (xy 39.320103 -410.984146)
			(xy 39.319708 -410.993336) (xy 39.319708 -411.151324) (xy 39.319298 -411.161479) (xy 39.311496 -411.18023)
			(xy 39.297096 -411.194552) (xy 39.278303 -411.202253) (xy 39.268146 -411.202632) (xy 38.551866 -411.202632)
			(xy 38.541734 -411.202201) (xy 38.523006 -411.194456) (xy 38.50865 -411.180153) (xy 38.500837 -411.161454)
			(xy 38.500304 -411.151324) (xy 38.500304 -410.993336) (xy 38.499876 -410.984151) (xy 38.493375 -410.966966)
			(xy 38.487604 -410.959808) (xy 38.465802 -410.934168) (xy 38.427856 -410.878579) (xy 38.396825 -410.818854)
			(xy 38.373155 -410.755848) (xy 38.357184 -410.690464) (xy 38.349141 -410.623641) (xy 35.071078 -410.623641)
			(xy 35.071078 -410.623699) (xy 35.063004 -410.690636) (xy 35.046971 -410.756124) (xy 35.023209 -410.81922)
			(xy 34.992061 -410.879016) (xy 34.953975 -410.934651) (xy 34.932112 -410.960316) (xy 34.926328 -410.96747)
			(xy 34.919805 -410.984654) (xy 34.919412 -410.993844) (xy 34.919412 -411.151324) (xy 34.918935 -411.161433)
			(xy 34.911192 -411.180109) (xy 34.896893 -411.194403) (xy 34.878213 -411.202139) (xy 34.868104 -411.202632)
			(xy 34.151824 -411.202632) (xy 34.141721 -411.202096) (xy 34.123049 -411.194372) (xy 34.108755 -411.180091)
			(xy 34.101013 -411.161427) (xy 34.100516 -411.151324) (xy 34.100516 -410.993844) (xy 34.100081 -410.98466)
			(xy 34.093584 -410.967475) (xy 34.087816 -410.960316) (xy 34.065936 -410.934664) (xy 34.027846 -410.879028)
			(xy 33.996696 -410.81923) (xy 33.972932 -410.756131) (xy 33.956897 -410.690641) (xy 33.948822 -410.623701)
			(xy 30.670776 -410.623701) (xy 30.66274 -410.690462) (xy 30.646767 -410.755844) (xy 30.623095 -410.818848)
			(xy 30.592061 -410.878571) (xy 30.554112 -410.934156) (xy 30.532324 -410.959808) (xy 30.526544 -410.966965)
			(xy 30.520019 -410.984146) (xy 30.519624 -410.993336) (xy 30.519624 -411.151324) (xy 30.519199 -411.161477)
			(xy 30.5114 -411.180225) (xy 30.497005 -411.194547) (xy 30.478217 -411.20225) (xy 30.468062 -411.202632)
			(xy 29.751782 -411.202632) (xy 29.741651 -411.202188) (xy 29.722924 -411.194449) (xy 29.708567 -411.180149)
			(xy 29.700753 -411.161453) (xy 29.70022 -411.151324) (xy 29.70022 -410.993336) (xy 29.699788 -410.984151)
			(xy 29.693289 -410.966967) (xy 29.68752 -410.959808) (xy 29.665717 -410.934169) (xy 29.62777 -410.87858)
			(xy 29.596738 -410.818854) (xy 29.573067 -410.755848) (xy 29.557096 -410.690465) (xy 29.549054 -410.623641)
			(xy 21.823172 -410.623641) (xy 21.823172 -411.868874) (xy 21.821902 -411.870144) (xy 21.804497 -411.886865)
			(xy 21.765437 -411.915211) (xy 21.722429 -411.937109) (xy 21.676529 -411.95202) (xy 21.628863 -411.959579)
			(xy 21.604732 -411.96006) (xy 17.38503 -411.96006) (xy 17.360922 -411.959596) (xy 17.313305 -411.952021)
			(xy 17.267456 -411.9371) (xy 17.224502 -411.915199) (xy 17.185496 -411.886856) (xy 17.168114 -411.870144)
			(xy 17.105884 -411.807914) (xy 17.089164 -411.79054) (xy 17.060827 -411.751532) (xy 17.038932 -411.708574)
			(xy 17.02402 -411.662723) (xy 17.016455 -411.615105) (xy 17.015968 -411.590998) (xy 0.509016 -411.590998)
			(xy 0.509016 -416.589972) (xy 0.509537 -416.645741) (xy 0.517873 -416.756967) (xy 0.534497 -416.867259)
			(xy 0.559316 -416.976001) (xy 0.592193 -417.082584) (xy 0.632942 -417.186412) (xy 0.681337 -417.286904)
			(xy 0.682829 -417.289488) (xy 53.073808 -417.289488) (xy 53.073808 -394.27912) (xy 66.477388 -394.27912)
			(xy 66.525648 -394.32738) (xy 66.525648 -397.823885) (xy 71.348788 -397.823885) (xy 71.348792 -397.756458)
			(xy 71.356871 -397.689518) (xy 71.372911 -397.624026) (xy 71.396679 -397.560928) (xy 71.427833 -397.501131)
			(xy 71.465926 -397.445495) (xy 71.487792 -397.41983) (xy 71.4936 -397.412693) (xy 71.500108 -397.395496)
			(xy 71.500492 -397.386302) (xy 71.500492 -396.89405) (xy 71.50006 -396.884865) (xy 71.493562 -396.86768)
			(xy 71.487792 -396.860522) (xy 71.465918 -396.834865) (xy 71.427831 -396.779229) (xy 71.396681 -396.719431)
			(xy 71.372918 -396.656334) (xy 71.356883 -396.590844) (xy 71.348808 -396.523905) (xy 71.348809 -396.45648)
			(xy 71.356886 -396.389542) (xy 71.372922 -396.324052) (xy 71.396687 -396.260955) (xy 71.427838 -396.201158)
			(xy 71.465928 -396.145523) (xy 71.487792 -396.119858) (xy 71.493588 -396.112712) (xy 71.500103 -396.095522)
			(xy 71.500492 -396.08633) (xy 71.500492 -395.92885) (xy 71.501066 -395.918732) (xy 71.508769 -395.900021)
			(xy 71.523028 -395.885665) (xy 71.541686 -395.877836) (xy 71.5518 -395.877288) (xy 72.26808 -395.877288)
			(xy 72.278231 -395.877738) (xy 72.296981 -395.885524) (xy 72.311305 -395.899912) (xy 72.319007 -395.918697)
			(xy 72.319388 -395.92885) (xy 72.319388 -396.08633) (xy 72.319786 -396.095518) (xy 72.326308 -396.112703)
			(xy 72.332088 -396.119858) (xy 72.353943 -396.145531) (xy 72.392032 -396.201164) (xy 72.423184 -396.260959)
			(xy 72.446949 -396.324055) (xy 72.462986 -396.389543) (xy 72.471063 -396.456481) (xy 72.471064 -396.523904)
			(xy 72.462989 -396.590842) (xy 72.446954 -396.656331) (xy 72.42319 -396.719427) (xy 72.39204 -396.779223)
			(xy 72.353952 -396.834857) (xy 72.332088 -396.860522) (xy 72.326298 -396.867672) (xy 72.31978 -396.884859)
			(xy 72.319388 -396.89405) (xy 72.319388 -397.386302) (xy 72.3198 -397.395489) (xy 72.326313 -397.412673)
			(xy 72.332088 -397.41983) (xy 72.353915 -397.445526) (xy 72.392006 -397.501156) (xy 72.420766 -397.556355)
			(xy 73.54898 -397.556355) (xy 73.557023 -397.489534) (xy 73.572995 -397.424152) (xy 73.596666 -397.361148)
			(xy 73.627698 -397.301425) (xy 73.665645 -397.245838) (xy 73.687432 -397.220186) (xy 73.693221 -397.213036)
			(xy 73.69974 -397.195849) (xy 73.700132 -397.186658) (xy 73.700132 -397.028924) (xy 73.700542 -397.018767)
			(xy 73.708335 -397.000009) (xy 73.722736 -396.985684) (xy 73.741535 -396.977989) (xy 73.751694 -396.977616)
			(xy 74.467974 -396.977616) (xy 74.478096 -396.978147) (xy 74.496812 -396.985862) (xy 74.511169 -397.000134)
			(xy 74.518993 -397.018805) (xy 74.519536 -397.028924) (xy 74.519536 -397.186658) (xy 74.519981 -397.195841)
			(xy 74.526472 -397.213025) (xy 74.532236 -397.220186) (xy 74.554034 -397.24583) (xy 74.591984 -397.301417)
			(xy 74.623019 -397.361141) (xy 74.646692 -397.424147) (xy 74.662665 -397.48953) (xy 74.670709 -397.556354)
			(xy 74.670708 -397.623661) (xy 74.662662 -397.690484) (xy 74.646687 -397.755867) (xy 74.623012 -397.818872)
			(xy 74.620438 -397.823826) (xy 75.749084 -397.823826) (xy 75.749087 -397.756517) (xy 75.757136 -397.689691)
			(xy 75.773114 -397.624306) (xy 75.796793 -397.5613) (xy 75.827833 -397.501576) (xy 75.865789 -397.44599)
			(xy 75.88758 -397.420338) (xy 75.893383 -397.413197) (xy 75.899895 -397.396003) (xy 75.90028 -397.38681)
			(xy 75.90028 -396.893542) (xy 75.899854 -396.884356) (xy 75.893352 -396.867172) (xy 75.88758 -396.860014)
			(xy 75.865781 -396.83437) (xy 75.82783 -396.778784) (xy 75.796795 -396.719059) (xy 75.773121 -396.656054)
			(xy 75.757147 -396.59067) (xy 75.749104 -396.523846) (xy 75.749104 -396.456539) (xy 75.75715 -396.389715)
			(xy 75.773125 -396.324332) (xy 75.796801 -396.261327) (xy 75.827838 -396.201603) (xy 75.86579 -396.146018)
			(xy 75.88758 -396.120366) (xy 75.893371 -396.113217) (xy 75.89989 -396.096029) (xy 75.90028 -396.086838)
			(xy 75.90028 -395.92885) (xy 75.900706 -395.918676) (xy 75.908482 -395.899875) (xy 75.922868 -395.885487)
			(xy 75.941668 -395.877707) (xy 75.951842 -395.877288) (xy 76.668122 -395.877288) (xy 76.678301 -395.877647)
			(xy 76.697106 -395.885449) (xy 76.711492 -395.899855) (xy 76.719267 -395.91867) (xy 76.719684 -395.92885)
			(xy 76.719684 -396.086838) (xy 76.720079 -396.096027) (xy 76.726604 -396.113211) (xy 76.732384 -396.120366)
			(xy 76.754161 -396.146026) (xy 76.792109 -396.201612) (xy 76.823141 -396.261335) (xy 76.846814 -396.324338)
			(xy 76.862787 -396.389719) (xy 76.870831 -396.456541) (xy 76.870832 -396.523844) (xy 76.862789 -396.590666)
			(xy 76.846818 -396.656047) (xy 76.823147 -396.719051) (xy 76.792117 -396.778775) (xy 76.75417 -396.834362)
			(xy 76.732384 -396.860014) (xy 76.726597 -396.867166) (xy 76.720077 -396.884351) (xy 76.719684 -396.893542)
			(xy 76.719684 -397.38681) (xy 76.720093 -397.395997) (xy 76.726608 -397.413181) (xy 76.732384 -397.420338)
			(xy 76.754133 -397.446021) (xy 76.792082 -397.501604) (xy 76.820503 -397.556296) (xy 77.948748 -397.556296)
			(xy 77.956824 -397.489358) (xy 77.972859 -397.423869) (xy 77.996623 -397.360772) (xy 78.027774 -397.300977)
			(xy 78.065864 -397.245343) (xy 78.087728 -397.219678) (xy 78.09352 -397.21253) (xy 78.100037 -397.195341)
			(xy 78.100428 -397.18615) (xy 78.100428 -397.028924) (xy 78.100836 -397.0188) (xy 78.108582 -397.000091)
			(xy 78.122901 -396.985775) (xy 78.141611 -396.978034) (xy 78.151736 -396.977616) (xy 78.868016 -396.977616)
			(xy 78.878142 -396.978003) (xy 78.896849 -396.985759) (xy 78.911163 -397.000085) (xy 78.918905 -397.018798)
			(xy 78.919324 -397.028924) (xy 78.919324 -397.18615) (xy 78.919753 -397.195335) (xy 78.926253 -397.21252)
			(xy 78.932024 -397.219678) (xy 78.953897 -397.245336) (xy 78.991984 -397.300972) (xy 79.023133 -397.360769)
			(xy 79.046895 -397.423867) (xy 79.062929 -397.489357) (xy 79.071004 -397.556296) (xy 79.071003 -397.62372)
			(xy 79.062927 -397.690658) (xy 79.046891 -397.756147) (xy 79.023127 -397.819245) (xy 79.02071 -397.823885)
			(xy 80.148876 -397.823885) (xy 80.14888 -397.756458) (xy 80.156959 -397.689518) (xy 80.172998 -397.624027)
			(xy 80.196765 -397.560929) (xy 80.227919 -397.501131) (xy 80.266011 -397.445496) (xy 80.287876 -397.41983)
			(xy 80.293682 -397.412691) (xy 80.300192 -397.395496) (xy 80.300576 -397.386302) (xy 80.300576 -396.89405)
			(xy 80.300147 -396.884865) (xy 80.293647 -396.86768) (xy 80.287876 -396.860522) (xy 80.266003 -396.834864)
			(xy 80.227916 -396.779228) (xy 80.196767 -396.719431) (xy 80.173005 -396.656333) (xy 80.156971 -396.590843)
			(xy 80.148896 -396.523904) (xy 80.148897 -396.45648) (xy 80.156973 -396.389542) (xy 80.173009 -396.324053)
			(xy 80.196773 -396.260955) (xy 80.227924 -396.201159) (xy 80.266012 -396.145524) (xy 80.287876 -396.119858)
			(xy 80.29367 -396.112711) (xy 80.300187 -396.095522) (xy 80.300576 -396.08633) (xy 80.300576 -395.92885)
			(xy 80.301069 -395.918722) (xy 80.308787 -395.899995) (xy 80.323072 -395.885636) (xy 80.341759 -395.877821)
			(xy 80.351884 -395.877288) (xy 81.068164 -395.877288) (xy 81.078314 -395.877751) (xy 81.097063 -395.885532)
			(xy 81.111388 -395.899917) (xy 81.119091 -395.918698) (xy 81.119472 -395.92885) (xy 81.119472 -396.08633)
			(xy 81.119874 -396.095518) (xy 81.126394 -396.112702) (xy 81.132172 -396.119858) (xy 81.154027 -396.145531)
			(xy 81.192118 -396.201164) (xy 81.223271 -396.260959) (xy 81.247037 -396.324054) (xy 81.263074 -396.389543)
			(xy 81.271151 -396.456481) (xy 81.271152 -396.523904) (xy 81.263076 -396.590842) (xy 81.247041 -396.656331)
			(xy 81.223277 -396.719428) (xy 81.192126 -396.779223) (xy 81.154036 -396.834857) (xy 81.132172 -396.860522)
			(xy 81.12638 -396.86767) (xy 81.119863 -396.884859) (xy 81.119472 -396.89405) (xy 81.119472 -397.386302)
			(xy 81.119887 -397.395489) (xy 81.126398 -397.412673) (xy 81.132172 -397.41983) (xy 81.154 -397.445526)
			(xy 81.192091 -397.501155) (xy 81.220853 -397.556356) (xy 82.349068 -397.556356) (xy 82.357111 -397.489534)
			(xy 82.373082 -397.424153) (xy 82.396753 -397.361149) (xy 82.427783 -397.301425) (xy 82.46573 -397.245838)
			(xy 82.487516 -397.220186) (xy 82.493303 -397.213034) (xy 82.499823 -397.195849) (xy 82.500216 -397.186658)
			(xy 82.500216 -397.028924) (xy 82.500641 -397.018769) (xy 82.508432 -397.000014) (xy 82.522828 -396.98569)
			(xy 82.541621 -396.977992) (xy 82.551778 -396.977616) (xy 83.268058 -396.977616) (xy 83.278179 -396.97816)
			(xy 83.296895 -396.98587) (xy 83.311252 -397.000138) (xy 83.319076 -397.018806) (xy 83.31962 -397.028924)
			(xy 83.31962 -397.186658) (xy 83.320046 -397.195844) (xy 83.326548 -397.213028) (xy 83.33232 -397.220186)
			(xy 83.354119 -397.24583) (xy 83.39207 -397.301416) (xy 83.423105 -397.361141) (xy 83.446779 -397.424146)
			(xy 83.462753 -397.48953) (xy 83.470796 -397.556354) (xy 83.470796 -397.623661) (xy 83.46275 -397.690485)
			(xy 83.446775 -397.755868) (xy 83.423099 -397.818873) (xy 83.420495 -397.823884) (xy 84.548667 -397.823884)
			(xy 84.548671 -397.756458) (xy 84.55675 -397.689518) (xy 84.572788 -397.624028) (xy 84.596555 -397.560929)
			(xy 84.627708 -397.501132) (xy 84.665799 -397.445496) (xy 84.687664 -397.41983) (xy 84.693481 -397.412699)
			(xy 84.699982 -397.395497) (xy 84.700364 -397.386302) (xy 84.700364 -396.89405) (xy 84.699916 -396.884867)
			(xy 84.693427 -396.867683) (xy 84.687664 -396.860522) (xy 84.665791 -396.834864) (xy 84.627705 -396.779228)
			(xy 84.596557 -396.71943) (xy 84.572795 -396.656332) (xy 84.556761 -396.590843) (xy 84.548687 -396.523904)
			(xy 84.548688 -396.456481) (xy 84.556764 -396.389542) (xy 84.5728 -396.324053) (xy 84.596563 -396.260956)
			(xy 84.627713 -396.201159) (xy 84.665801 -396.145524) (xy 84.687664 -396.119858) (xy 84.693469 -396.112719)
			(xy 84.699977 -396.095523) (xy 84.700364 -396.08633) (xy 84.700364 -395.92885) (xy 84.700868 -395.918724)
			(xy 84.708584 -395.899999) (xy 84.722866 -395.88564) (xy 84.741548 -395.877823) (xy 84.751672 -395.877288)
			(xy 85.467952 -395.877288) (xy 85.478102 -395.877761) (xy 85.496851 -395.885538) (xy 85.511175 -395.899919)
			(xy 85.518879 -395.918699) (xy 85.51926 -395.92885) (xy 85.51926 -396.08633) (xy 85.519665 -396.095518)
			(xy 85.526183 -396.112701) (xy 85.53196 -396.119858) (xy 85.553816 -396.145531) (xy 85.591907 -396.201163)
			(xy 85.623061 -396.260958) (xy 85.646827 -396.324054) (xy 85.662864 -396.389543) (xy 85.670942 -396.456481)
			(xy 85.670943 -396.523904) (xy 85.662867 -396.590843) (xy 85.646832 -396.656332) (xy 85.623067 -396.719428)
			(xy 85.591915 -396.779224) (xy 85.553825 -396.834857) (xy 85.53196 -396.860522) (xy 85.526167 -396.867669)
			(xy 85.519651 -396.884858) (xy 85.51926 -396.89405) (xy 85.51926 -397.386302) (xy 85.519678 -397.395488)
			(xy 85.526187 -397.412672) (xy 85.53196 -397.41983) (xy 85.553788 -397.445525) (xy 85.591881 -397.501155)
			(xy 85.620612 -397.556296) (xy 86.748836 -397.556296) (xy 86.756911 -397.489358) (xy 86.772946 -397.423869)
			(xy 86.79671 -397.360773) (xy 86.82786 -397.300977) (xy 86.865948 -397.245343) (xy 86.887812 -397.219678)
			(xy 86.893602 -397.212528) (xy 86.90012 -397.195341) (xy 86.900512 -397.18615) (xy 86.900512 -397.028924)
			(xy 86.900936 -397.018802) (xy 86.908678 -397.000096) (xy 86.922993 -396.985781) (xy 86.941698 -396.978037)
			(xy 86.95182 -396.977616) (xy 87.6681 -396.977616) (xy 87.678224 -396.978016) (xy 87.696931 -396.985768)
			(xy 87.711246 -397.000089) (xy 87.718988 -397.018799) (xy 87.719408 -397.028924) (xy 87.719408 -397.18615)
			(xy 87.71984 -397.195335) (xy 87.726338 -397.21252) (xy 87.732108 -397.219678) (xy 87.753982 -397.245335)
			(xy 87.792069 -397.300971) (xy 87.823219 -397.360769) (xy 87.846982 -397.423866) (xy 87.863017 -397.489356)
			(xy 87.871092 -397.556295) (xy 87.871091 -397.62372) (xy 87.863014 -397.690658) (xy 87.846978 -397.756148)
			(xy 87.823213 -397.819245) (xy 87.820827 -397.823826) (xy 88.948962 -397.823826) (xy 88.948966 -397.756517)
			(xy 88.957014 -397.689692) (xy 88.972991 -397.624307) (xy 88.996669 -397.561301) (xy 89.027707 -397.501577)
			(xy 89.065661 -397.44599) (xy 89.087452 -397.420338) (xy 89.093264 -397.413204) (xy 89.099768 -397.396005)
			(xy 89.100152 -397.38681) (xy 89.100152 -396.893542) (xy 89.09971 -396.884358) (xy 89.093217 -396.867175)
			(xy 89.087452 -396.860014) (xy 89.065654 -396.83437) (xy 89.027704 -396.778783) (xy 88.996671 -396.719058)
			(xy 88.972998 -396.656053) (xy 88.957025 -396.590669) (xy 88.948982 -396.523846) (xy 88.948983 -396.456539)
			(xy 88.957028 -396.389716) (xy 88.973003 -396.324333) (xy 88.996677 -396.261328) (xy 89.027712 -396.201604)
			(xy 89.065663 -396.146018) (xy 89.087452 -396.120366) (xy 89.093252 -396.113223) (xy 89.099763 -396.096031)
			(xy 89.100152 -396.086838) (xy 89.100152 -395.92885) (xy 89.100605 -395.91868) (xy 89.108376 -395.899884)
			(xy 89.122753 -395.885496) (xy 89.141544 -395.877712) (xy 89.151714 -395.877288) (xy 89.867994 -395.877288)
			(xy 89.878171 -395.87767) (xy 89.896976 -395.885462) (xy 89.911362 -395.899861) (xy 89.919139 -395.918672)
			(xy 89.919556 -395.92885) (xy 89.919556 -396.086838) (xy 89.919958 -396.096026) (xy 89.926478 -396.11321)
			(xy 89.932256 -396.120366) (xy 89.954034 -396.146026) (xy 89.991983 -396.201611) (xy 90.023017 -396.261334)
			(xy 90.046691 -396.324337) (xy 90.062665 -396.389719) (xy 90.07071 -396.45654) (xy 90.070711 -396.523845)
			(xy 90.062667 -396.590667) (xy 90.046695 -396.656048) (xy 90.023023 -396.719052) (xy 89.991991 -396.778776)
			(xy 89.954043 -396.834362) (xy 89.932256 -396.860014) (xy 89.926465 -396.867163) (xy 89.919948 -396.884351)
			(xy 89.919556 -396.893542) (xy 89.919556 -397.38681) (xy 89.919971 -397.395996) (xy 89.926482 -397.41318)
			(xy 89.932256 -397.420338) (xy 89.954006 -397.446021) (xy 89.991957 -397.501603) (xy 90.020411 -397.556356)
			(xy 91.149156 -397.556356) (xy 91.157198 -397.489535) (xy 91.173169 -397.424153) (xy 91.196839 -397.361149)
			(xy 91.227869 -397.301426) (xy 91.265814 -397.245839) (xy 91.2876 -397.220186) (xy 91.293385 -397.213033)
			(xy 91.299907 -397.195848) (xy 91.3003 -397.186658) (xy 91.3003 -397.028924) (xy 91.300741 -397.018771)
			(xy 91.308529 -397.000019) (xy 91.32292 -396.985695) (xy 91.341708 -396.977995) (xy 91.351862 -396.977616)
			(xy 92.068142 -396.977616) (xy 92.078268 -396.978091) (xy 92.096986 -396.985829) (xy 92.11134 -397.000118)
			(xy 92.119162 -397.0188) (xy 92.119704 -397.028924) (xy 92.119704 -397.186658) (xy 92.120133 -397.195843)
			(xy 92.126634 -397.213028) (xy 92.132404 -397.220186) (xy 92.1542 -397.245831) (xy 92.192146 -397.301419)
			(xy 92.223176 -397.361144) (xy 92.246847 -397.42415) (xy 92.262818 -397.489532) (xy 92.27086 -397.556355)
			(xy 92.270859 -397.62366) (xy 92.262815 -397.690483) (xy 92.246842 -397.755865) (xy 92.22317 -397.81887)
			(xy 92.220595 -397.823825) (xy 115.349226 -397.823825) (xy 115.349229 -397.756518) (xy 115.357277 -397.689693)
			(xy 115.373253 -397.624309) (xy 115.396928 -397.561303) (xy 115.427964 -397.501578) (xy 115.465915 -397.445991)
			(xy 115.487704 -397.420338) (xy 115.49351 -397.413199) (xy 115.500019 -397.396004) (xy 115.500404 -397.38681)
			(xy 115.500404 -396.893542) (xy 115.499973 -396.884357) (xy 115.493474 -396.867173) (xy 115.487704 -396.860014)
			(xy 115.465908 -396.834369) (xy 115.427961 -396.778781) (xy 115.39693 -396.719056) (xy 115.37326 -396.656051)
			(xy 115.357288 -396.590668) (xy 115.349246 -396.523845) (xy 115.349247 -396.45654) (xy 115.357291 -396.389717)
			(xy 115.373264 -396.324335) (xy 115.396937 -396.26133) (xy 115.427969 -396.201606) (xy 115.465917 -396.146019)
			(xy 115.487704 -396.120366) (xy 115.493498 -396.113219) (xy 115.500014 -396.09603) (xy 115.500404 -396.086838)
			(xy 115.500404 -395.92885) (xy 115.500904 -395.918686) (xy 115.508666 -395.899899) (xy 115.523028 -395.885513)
			(xy 115.541803 -395.87772) (xy 115.551966 -395.877288) (xy 116.268246 -395.877288) (xy 116.278427 -395.877627)
			(xy 116.297232 -395.885437) (xy 116.311617 -395.899849) (xy 116.319392 -395.918668) (xy 116.319808 -395.92885)
			(xy 116.319808 -396.086838) (xy 116.320198 -396.096027) (xy 116.326725 -396.113212) (xy 116.332508 -396.120366)
			(xy 116.354288 -396.146026) (xy 116.39224 -396.20161) (xy 116.423277 -396.261332) (xy 116.446952 -396.324335)
			(xy 116.462928 -396.389717) (xy 116.470973 -396.45654) (xy 116.470974 -396.523845) (xy 116.46293 -396.590668)
			(xy 116.446957 -396.65605) (xy 116.423283 -396.719055) (xy 116.392248 -396.778777) (xy 116.354297 -396.834363)
			(xy 116.332508 -396.860014) (xy 116.326724 -396.867168) (xy 116.320202 -396.884352) (xy 116.319808 -396.893542)
			(xy 116.319808 -397.38681) (xy 116.320212 -397.395998) (xy 116.32673 -397.413182) (xy 116.332508 -397.420338)
			(xy 116.35426 -397.44602) (xy 116.392213 -397.501601) (xy 116.42064 -397.556296) (xy 117.548866 -397.556296)
			(xy 117.556942 -397.489357) (xy 117.572978 -397.423868) (xy 117.596743 -397.360771) (xy 117.627896 -397.300976)
			(xy 117.665987 -397.245342) (xy 117.687852 -397.219678) (xy 117.693647 -397.212532) (xy 117.700161 -397.195342)
			(xy 117.700552 -397.18615) (xy 117.700552 -397.028924) (xy 117.701103 -397.018823) (xy 117.708824 -397.000154)
			(xy 117.7231 -396.98586) (xy 117.741759 -396.978116) (xy 117.75186 -396.977616) (xy 118.46814 -396.977616)
			(xy 118.478253 -396.978053) (xy 118.496935 -396.985807) (xy 118.511229 -397.000118) (xy 118.51896 -397.01881)
			(xy 118.519448 -397.028924) (xy 118.519448 -397.18615) (xy 118.519894 -397.195333) (xy 118.526384 -397.212517)
			(xy 118.532148 -397.219678) (xy 118.554024 -397.245334) (xy 118.592115 -397.300969) (xy 118.623269 -397.360766)
			(xy 118.647035 -397.423864) (xy 118.663071 -397.489355) (xy 118.671147 -397.556295) (xy 118.671146 -397.62372)
			(xy 118.663068 -397.69066) (xy 118.64703 -397.75615) (xy 118.623262 -397.819248) (xy 118.620846 -397.823885)
			(xy 119.748994 -397.823885) (xy 119.748998 -397.756458) (xy 119.757077 -397.689517) (xy 119.773117 -397.624026)
			(xy 119.796885 -397.560928) (xy 119.828041 -397.50113) (xy 119.866134 -397.445495) (xy 119.888 -397.41983)
			(xy 119.893809 -397.412693) (xy 119.900316 -397.395496) (xy 119.9007 -397.386302) (xy 119.9007 -396.89405)
			(xy 119.900266 -396.884865) (xy 119.893769 -396.867681) (xy 119.888 -396.860522) (xy 119.866126 -396.834865)
			(xy 119.828038 -396.779229) (xy 119.796888 -396.719432) (xy 119.773124 -396.656334) (xy 119.757089 -396.590844)
			(xy 119.749014 -396.523905) (xy 119.749015 -396.45648) (xy 119.757092 -396.389541) (xy 119.773128 -396.324052)
			(xy 119.796894 -396.260954) (xy 119.828046 -396.201158) (xy 119.866135 -396.145523) (xy 119.888 -396.119858)
			(xy 119.893797 -396.112713) (xy 119.900311 -396.095522) (xy 119.9007 -396.08633) (xy 119.9007 -395.92885)
			(xy 119.901266 -395.918731) (xy 119.90897 -395.900019) (xy 119.923232 -395.885662) (xy 119.941893 -395.877834)
			(xy 119.952008 -395.877288) (xy 120.668288 -395.877288) (xy 120.678408 -395.877725) (xy 120.697109 -395.885467)
			(xy 120.711424 -395.899777) (xy 120.719171 -395.918476) (xy 120.719596 -395.928596) (xy 120.719596 -396.08633)
			(xy 120.719992 -396.095519) (xy 120.726516 -396.112703) (xy 120.732296 -396.119858) (xy 120.75415 -396.145531)
			(xy 120.79224 -396.201165) (xy 120.823391 -396.26096) (xy 120.847156 -396.324055) (xy 120.863192 -396.389544)
			(xy 120.871269 -396.456481) (xy 120.87127 -396.523904) (xy 120.863195 -396.590842) (xy 120.84716 -396.65633)
			(xy 120.823397 -396.719427) (xy 120.792247 -396.779223) (xy 120.75416 -396.834857) (xy 120.732296 -396.860522)
			(xy 120.726507 -396.867673) (xy 120.719988 -396.884859) (xy 120.719596 -396.89405) (xy 120.719596 -397.386302)
			(xy 120.720006 -397.395489) (xy 120.72652 -397.412673) (xy 120.732296 -397.41983) (xy 120.754123 -397.445526)
			(xy 120.792213 -397.501156) (xy 120.820972 -397.556355) (xy 121.949186 -397.556355) (xy 121.95723 -397.489533)
			(xy 121.973202 -397.424152) (xy 121.996873 -397.361148) (xy 122.027905 -397.301425) (xy 122.065853 -397.245838)
			(xy 122.08764 -397.220186) (xy 122.09343 -397.213036) (xy 122.099948 -397.195849) (xy 122.10034 -397.186658)
			(xy 122.10034 -397.028924) (xy 122.100736 -397.018798) (xy 122.108484 -397.000087) (xy 122.122807 -396.985771)
			(xy 122.141522 -396.978032) (xy 122.151648 -396.977616) (xy 122.868182 -396.977616) (xy 122.878305 -396.978141)
			(xy 122.897021 -396.985858) (xy 122.911377 -397.000132) (xy 122.919201 -397.018804) (xy 122.919744 -397.028924)
			(xy 122.919744 -397.186658) (xy 122.920187 -397.195841) (xy 122.926679 -397.213026) (xy 122.932444 -397.220186)
			(xy 122.954242 -397.24583) (xy 122.992192 -397.301417) (xy 123.023225 -397.361142) (xy 123.046898 -397.424147)
			(xy 123.062871 -397.489531) (xy 123.070915 -397.556354) (xy 123.070914 -397.623661) (xy 123.062868 -397.690484)
			(xy 123.046894 -397.755867) (xy 123.023219 -397.818872) (xy 123.020645 -397.823826) (xy 124.14929 -397.823826)
			(xy 124.149293 -397.756517) (xy 124.157342 -397.689691) (xy 124.17332 -397.624306) (xy 124.197 -397.5613)
			(xy 124.22804 -397.501575) (xy 124.265997 -397.44599) (xy 124.287788 -397.420338) (xy 124.293592 -397.413198)
			(xy 124.300103 -397.396004) (xy 124.300488 -397.38681) (xy 124.300488 -396.893542) (xy 124.30006 -396.884357)
			(xy 124.293559 -396.867172) (xy 124.287788 -396.860014) (xy 124.265989 -396.834371) (xy 124.228037 -396.778784)
			(xy 124.197002 -396.71906) (xy 124.173327 -396.656054) (xy 124.157354 -396.59067) (xy 124.14931 -396.523846)
			(xy 124.14931 -396.456539) (xy 124.157356 -396.389715) (xy 124.173332 -396.324332) (xy 124.197008 -396.261327)
			(xy 124.228045 -396.201603) (xy 124.265998 -396.146018) (xy 124.287788 -396.120366) (xy 124.29358 -396.113218)
			(xy 124.300098 -396.09603) (xy 124.300488 -396.086838) (xy 124.300488 -395.92885) (xy 124.300906 -395.918675)
			(xy 124.308684 -395.899872) (xy 124.323072 -395.885484) (xy 124.341875 -395.877706) (xy 124.35205 -395.877288)
			(xy 125.06833 -395.877288) (xy 125.07851 -395.87764) (xy 125.097315 -395.885445) (xy 125.1117 -395.899852)
			(xy 125.119475 -395.91867) (xy 125.119892 -395.92885) (xy 125.119892 -396.086838) (xy 125.120286 -396.096027)
			(xy 125.126811 -396.113211) (xy 125.132592 -396.120366) (xy 125.154369 -396.146027) (xy 125.192316 -396.201613)
			(xy 125.223348 -396.261335) (xy 125.24702 -396.324339) (xy 125.262993 -396.389719) (xy 125.271037 -396.456541)
			(xy 125.271038 -396.523844) (xy 125.262995 -396.590666) (xy 125.247025 -396.656047) (xy 125.223354 -396.719051)
			(xy 125.192324 -396.778774) (xy 125.154378 -396.834361) (xy 125.132592 -396.860014) (xy 125.126806 -396.867167)
			(xy 125.120285 -396.884351) (xy 125.119892 -396.893542) (xy 125.119892 -397.38681) (xy 125.120299 -397.395998)
			(xy 125.126815 -397.413182) (xy 125.132592 -397.420338) (xy 125.154341 -397.446021) (xy 125.192289 -397.501604)
			(xy 125.22071 -397.556296) (xy 126.348954 -397.556296) (xy 126.35703 -397.489357) (xy 126.373065 -397.423869)
			(xy 126.39683 -397.360772) (xy 126.427981 -397.300976) (xy 126.466071 -397.245343) (xy 126.487936 -397.219678)
			(xy 126.493729 -397.21253) (xy 126.500245 -397.195342) (xy 126.500636 -397.18615) (xy 126.500636 -397.028924)
			(xy 126.501036 -397.018799) (xy 126.508783 -397.000089) (xy 126.523105 -396.985772) (xy 126.541818 -396.978032)
			(xy 126.551944 -396.977616) (xy 127.268224 -396.977616) (xy 127.278336 -396.978066) (xy 127.297018 -396.985814)
			(xy 127.311313 -397.000122) (xy 127.319044 -397.018811) (xy 127.319532 -397.028924) (xy 127.319532 -397.18615)
			(xy 127.319981 -397.195333) (xy 127.326469 -397.212517) (xy 127.332232 -397.219678) (xy 127.354105 -397.245336)
			(xy 127.392191 -397.300972) (xy 127.423339 -397.36077) (xy 127.447102 -397.423867) (xy 127.463135 -397.489357)
			(xy 127.47121 -397.556296) (xy 127.471209 -397.623719) (xy 127.463133 -397.690658) (xy 127.447097 -397.756147)
			(xy 127.423333 -397.819244) (xy 127.420946 -397.823826) (xy 128.54908 -397.823826) (xy 128.549084 -397.756517)
			(xy 128.557132 -397.689691) (xy 128.57311 -397.624306) (xy 128.596789 -397.5613) (xy 128.627829 -397.501576)
			(xy 128.665785 -397.445989) (xy 128.687576 -397.420338) (xy 128.693379 -397.413197) (xy 128.69989 -397.396003)
			(xy 128.700276 -397.38681) (xy 128.700276 -396.893542) (xy 128.699851 -396.884356) (xy 128.693348 -396.867171)
			(xy 128.687576 -396.860014) (xy 128.665777 -396.83437) (xy 128.627826 -396.778784) (xy 128.596792 -396.719059)
			(xy 128.573118 -396.656053) (xy 128.557144 -396.59067) (xy 128.5491 -396.523846) (xy 128.549101 -396.456539)
			(xy 128.557147 -396.389715) (xy 128.573122 -396.324332) (xy 128.596798 -396.261327) (xy 128.627834 -396.201604)
			(xy 128.665787 -396.146018) (xy 128.687576 -396.120366) (xy 128.693367 -396.113216) (xy 128.699886 -396.096029)
			(xy 128.700276 -396.086838) (xy 128.700276 -395.92885) (xy 128.700706 -395.918677) (xy 128.708481 -395.899876)
			(xy 128.722866 -395.885488) (xy 128.741665 -395.877708) (xy 128.751838 -395.877288) (xy 129.468118 -395.877288)
			(xy 129.478297 -395.87765) (xy 129.497102 -395.885451) (xy 129.511487 -395.899856) (xy 129.519263 -395.91867)
			(xy 129.51968 -395.92885) (xy 129.51968 -396.086838) (xy 129.520076 -396.096027) (xy 129.5266 -396.113211)
			(xy 129.53238 -396.120366) (xy 129.554157 -396.146026) (xy 129.592105 -396.201612) (xy 129.623138 -396.261335)
			(xy 129.64681 -396.324338) (xy 129.662784 -396.389719) (xy 129.670828 -396.456541) (xy 129.670829 -396.523844)
			(xy 129.662786 -396.590666) (xy 129.646815 -396.656047) (xy 129.623144 -396.719051) (xy 129.592113 -396.778775)
			(xy 129.554167 -396.834362) (xy 129.53238 -396.860014) (xy 129.526593 -396.867166) (xy 129.520073 -396.884351)
			(xy 129.51968 -396.893542) (xy 129.51968 -397.38681) (xy 129.52009 -397.395997) (xy 129.526604 -397.413181)
			(xy 129.53238 -397.420338) (xy 129.55413 -397.446021) (xy 129.592078 -397.501604) (xy 129.620531 -397.556356)
			(xy 130.749274 -397.556356) (xy 130.757317 -397.489534) (xy 130.773288 -397.424152) (xy 130.796959 -397.361148)
			(xy 130.827991 -397.301425) (xy 130.865937 -397.245838) (xy 130.887724 -397.220186) (xy 130.893512 -397.213035)
			(xy 130.900031 -397.195849) (xy 130.900424 -397.186658) (xy 130.900424 -397.028924) (xy 130.900842 -397.018768)
			(xy 130.908634 -397.000012) (xy 130.923032 -396.985687) (xy 130.941828 -396.97799) (xy 130.951986 -396.977616)
			(xy 131.668266 -396.977616) (xy 131.678388 -396.978154) (xy 131.697103 -396.985866) (xy 131.71146 -397.000137)
			(xy 131.719284 -397.018806) (xy 131.719828 -397.028924) (xy 131.719828 -397.186658) (xy 131.720252 -397.195844)
			(xy 131.726756 -397.213029) (xy 131.732528 -397.220186) (xy 131.754326 -397.24583) (xy 131.792277 -397.301417)
			(xy 131.823312 -397.361141) (xy 131.846985 -397.424147) (xy 131.862959 -397.48953) (xy 131.871003 -397.556354)
			(xy 131.871002 -397.623661) (xy 131.862956 -397.690485) (xy 131.846981 -397.755868) (xy 131.823306 -397.818873)
			(xy 131.792269 -397.878596) (xy 131.754317 -397.934182) (xy 131.732528 -397.959834) (xy 131.726726 -397.966975)
			(xy 131.720217 -397.984169) (xy 131.719828 -397.993362) (xy 131.719828 -398.486884) (xy 131.720239 -398.496071)
			(xy 131.726751 -398.513256) (xy 131.732528 -398.520412) (xy 131.754352 -398.546034) (xy 131.792302 -398.601624)
			(xy 131.823336 -398.661352) (xy 131.847008 -398.72436) (xy 131.86298 -398.789746) (xy 131.871021 -398.856573)
			(xy 131.871018 -398.923881) (xy 131.86297 -398.990707) (xy 131.846992 -399.056092) (xy 131.823314 -399.119098)
			(xy 131.792274 -399.178822) (xy 131.754319 -399.234408) (xy 131.732528 -399.26006) (xy 131.726715 -399.267193)
			(xy 131.720212 -399.284393) (xy 131.719828 -399.293588) (xy 131.719828 -399.451576) (xy 131.719359 -399.461725)
			(xy 131.711577 -399.480472) (xy 131.697195 -399.494795) (xy 131.678417 -399.502501) (xy 131.668266 -399.502884)
			(xy 130.951986 -399.502884) (xy 130.941861 -399.502385) (xy 130.923145 -399.494657) (xy 130.90879 -399.480375)
			(xy 130.900967 -399.461698) (xy 130.900424 -399.451576) (xy 130.900424 -399.293588) (xy 130.900014 -399.284401)
			(xy 130.8935 -399.267217) (xy 130.887724 -399.26006) (xy 130.865972 -399.234378) (xy 130.828023 -399.178796)
			(xy 130.796989 -399.119076) (xy 130.773315 -399.056076) (xy 130.75734 -398.990697) (xy 130.749294 -398.923878)
			(xy 130.74929 -398.856576) (xy 130.757331 -398.789756) (xy 130.773299 -398.724376) (xy 130.796967 -398.661373)
			(xy 130.827996 -398.601651) (xy 130.865939 -398.546065) (xy 130.887724 -398.520412) (xy 130.893543 -398.513283)
			(xy 130.900044 -398.49608) (xy 130.900424 -398.486884) (xy 130.900424 -397.993362) (xy 130.900027 -397.984174)
			(xy 130.893504 -397.96699) (xy 130.887724 -397.959834) (xy 130.865946 -397.934174) (xy 130.827998 -397.878588)
			(xy 130.796965 -397.818865) (xy 130.773293 -397.755862) (xy 130.75732 -397.690481) (xy 130.749275 -397.62366)
			(xy 130.749274 -397.556356) (xy 129.620531 -397.556356) (xy 129.623112 -397.561323) (xy 129.646786 -397.624324)
			(xy 129.662761 -397.689702) (xy 129.670808 -397.756521) (xy 129.670811 -397.823822) (xy 129.662771 -397.890642)
			(xy 129.646803 -397.956022) (xy 129.623135 -398.019025) (xy 129.592108 -398.078747) (xy 129.554165 -398.134333)
			(xy 129.53238 -398.159986) (xy 129.526562 -398.167116) (xy 129.520061 -398.184318) (xy 129.51968 -398.193514)
			(xy 129.51968 -398.351502) (xy 129.519169 -398.361658) (xy 129.511397 -398.380423) (xy 129.497037 -398.394788)
			(xy 129.478274 -398.402565) (xy 129.468118 -398.403064) (xy 128.751838 -398.403064) (xy 128.741669 -398.402605)
			(xy 128.722876 -398.394833) (xy 128.70849 -398.380458) (xy 128.700703 -398.361671) (xy 128.700276 -398.351502)
			(xy 128.700276 -398.193514) (xy 128.699865 -398.184327) (xy 128.693352 -398.167142) (xy 128.687576 -398.159986)
			(xy 128.66575 -398.134365) (xy 128.627799 -398.078775) (xy 128.596766 -398.019048) (xy 128.573093 -397.956039)
			(xy 128.557122 -397.890652) (xy 128.54908 -397.823826) (xy 127.420946 -397.823826) (xy 127.392183 -397.879041)
			(xy 127.354095 -397.934676) (xy 127.332232 -397.960342) (xy 127.326427 -397.967481) (xy 127.319919 -397.984676)
			(xy 127.319532 -397.99387) (xy 127.319532 -398.486376) (xy 127.319969 -398.49556) (xy 127.326466 -398.512744)
			(xy 127.332232 -398.519904) (xy 127.35413 -398.545541) (xy 127.392216 -398.60118) (xy 127.423363 -398.66098)
			(xy 127.447124 -398.724081) (xy 127.463156 -398.789573) (xy 127.471228 -398.856514) (xy 127.471225 -398.92394)
			(xy 127.463146 -398.99088) (xy 127.447108 -399.056371) (xy 127.423341 -399.119469) (xy 127.392188 -399.179266)
			(xy 127.354097 -399.234902) (xy 127.332232 -399.260568) (xy 127.326416 -399.267699) (xy 127.319915 -399.284901)
			(xy 127.319532 -399.294096) (xy 127.319532 -399.451576) (xy 127.318996 -399.461679) (xy 127.311272 -399.480351)
			(xy 127.296991 -399.494645) (xy 127.278327 -399.502387) (xy 127.268224 -399.502884) (xy 126.551944 -399.502884)
			(xy 126.541822 -399.502447) (xy 126.523117 -399.494711) (xy 126.5088 -399.4804) (xy 126.501056 -399.461697)
			(xy 126.500636 -399.451576) (xy 126.500636 -399.294096) (xy 126.50022 -399.28491) (xy 126.49371 -399.267726)
			(xy 126.487936 -399.260568) (xy 126.466106 -399.234874) (xy 126.428014 -399.179245) (xy 126.39686 -399.119453)
			(xy 126.373092 -399.056359) (xy 126.357053 -398.990873) (xy 126.348974 -398.923938) (xy 126.34897 -398.856516)
			(xy 126.357043 -398.78958) (xy 126.373076 -398.724092) (xy 126.396838 -398.660997) (xy 126.427986 -398.601202)
			(xy 126.466073 -398.545569) (xy 126.487936 -398.519904) (xy 126.493718 -398.512749) (xy 126.50024 -398.495566)
			(xy 126.500636 -398.486376) (xy 126.500636 -397.99387) (xy 126.500232 -397.984682) (xy 126.493713 -397.967498)
			(xy 126.487936 -397.960342) (xy 126.466081 -397.934669) (xy 126.427989 -397.879037) (xy 126.396836 -397.819242)
			(xy 126.37307 -397.756146) (xy 126.357032 -397.690657) (xy 126.348955 -397.623719) (xy 126.348954 -397.556296)
			(xy 125.22071 -397.556296) (xy 125.223323 -397.561324) (xy 125.246996 -397.624324) (xy 125.262971 -397.689702)
			(xy 125.271018 -397.756521) (xy 125.271021 -397.823822) (xy 125.262981 -397.890642) (xy 125.247013 -397.956021)
			(xy 125.223346 -398.019024) (xy 125.192319 -398.078747) (xy 125.154377 -398.134334) (xy 125.132592 -398.159986)
			(xy 125.126775 -398.167117) (xy 125.120273 -398.184318) (xy 125.119892 -398.193514) (xy 125.119892 -398.351502)
			(xy 125.119369 -398.361656) (xy 125.111599 -398.38042) (xy 125.097243 -398.394784) (xy 125.078484 -398.402563)
			(xy 125.06833 -398.403064) (xy 124.35205 -398.403064) (xy 124.341882 -398.402595) (xy 124.323089 -398.394827)
			(xy 124.308702 -398.380455) (xy 124.300915 -398.36167) (xy 124.300488 -398.351502) (xy 124.300488 -398.193514)
			(xy 124.300074 -398.184327) (xy 124.293563 -398.167143) (xy 124.287788 -398.159986) (xy 124.265961 -398.134365)
			(xy 124.228011 -398.078775) (xy 124.196976 -398.019048) (xy 124.173304 -397.956039) (xy 124.157332 -397.890653)
			(xy 124.14929 -397.823826) (xy 123.020645 -397.823826) (xy 122.992184 -397.878596) (xy 122.954233 -397.934182)
			(xy 122.932444 -397.959834) (xy 122.926644 -397.966976) (xy 122.920133 -397.984169) (xy 122.919744 -397.993362)
			(xy 122.919744 -398.486884) (xy 122.920174 -398.496069) (xy 122.926675 -398.513253) (xy 122.932444 -398.520412)
			(xy 122.954268 -398.546035) (xy 122.992217 -398.601625) (xy 123.023249 -398.661352) (xy 123.046921 -398.724361)
			(xy 123.062892 -398.789747) (xy 123.070933 -398.856573) (xy 123.07093 -398.923881) (xy 123.062882 -398.990707)
			(xy 123.046905 -399.056091) (xy 123.023227 -399.119097) (xy 122.992189 -399.178822) (xy 122.954235 -399.234408)
			(xy 122.932444 -399.26006) (xy 122.926633 -399.267194) (xy 122.920128 -399.284393) (xy 122.919744 -399.293588)
			(xy 122.919744 -399.451576) (xy 122.919196 -399.461678) (xy 122.911475 -399.480347) (xy 122.897197 -399.494641)
			(xy 122.878537 -399.502385) (xy 122.868436 -399.502884) (xy 122.151902 -399.502884) (xy 122.141778 -399.502372)
			(xy 122.123062 -399.49465) (xy 122.108706 -399.480371) (xy 122.100883 -399.461697) (xy 122.10034 -399.451576)
			(xy 122.10034 -399.293588) (xy 122.099927 -399.284401) (xy 122.093414 -399.267217) (xy 122.08764 -399.26006)
			(xy 122.065888 -399.234379) (xy 122.027938 -399.178796) (xy 121.996903 -399.119077) (xy 121.973228 -399.056076)
			(xy 121.957253 -398.990698) (xy 121.949206 -398.923878) (xy 121.949202 -398.856576) (xy 121.957243 -398.789756)
			(xy 121.973212 -398.724376) (xy 121.996881 -398.661373) (xy 122.02791 -398.60165) (xy 122.065855 -398.546064)
			(xy 122.08764 -398.520412) (xy 122.093461 -398.513285) (xy 122.09996 -398.49608) (xy 122.10034 -398.486884)
			(xy 122.10034 -397.993362) (xy 122.099939 -397.984174) (xy 122.093418 -397.96699) (xy 122.08764 -397.959834)
			(xy 122.065862 -397.934174) (xy 122.027913 -397.878588) (xy 121.996879 -397.818866) (xy 121.973206 -397.755863)
			(xy 121.957232 -397.690481) (xy 121.949187 -397.62366) (xy 121.949186 -397.556355) (xy 120.820972 -397.556355)
			(xy 120.823365 -397.560948) (xy 120.847132 -397.624041) (xy 120.86317 -397.689526) (xy 120.871249 -397.756461)
			(xy 120.871253 -397.823882) (xy 120.86318 -397.890818) (xy 120.847149 -397.956305) (xy 120.823389 -398.0194)
			(xy 120.792242 -398.079195) (xy 120.754158 -398.134829) (xy 120.732296 -398.160494) (xy 120.726519 -398.167653)
			(xy 120.719993 -398.184833) (xy 120.719596 -398.194022) (xy 120.719596 -398.351502) (xy 120.719076 -398.361624)
			(xy 120.711354 -398.380339) (xy 120.697079 -398.394694) (xy 120.678408 -398.402519) (xy 120.668288 -398.403064)
			(xy 119.952008 -398.403064) (xy 119.941882 -398.402677) (xy 119.923171 -398.394924) (xy 119.908855 -398.380599)
			(xy 119.901116 -398.361883) (xy 119.9007 -398.351756) (xy 119.9007 -398.194022) (xy 119.900279 -398.184836)
			(xy 119.893773 -398.167651) (xy 119.888 -398.160494) (xy 119.866099 -398.13486) (xy 119.828011 -398.079221)
			(xy 119.796862 -398.01942) (xy 119.7731 -397.956319) (xy 119.757067 -397.890826) (xy 119.748994 -397.823885)
			(xy 118.620846 -397.823885) (xy 118.592108 -397.879044) (xy 118.554014 -397.934678) (xy 118.532148 -397.960342)
			(xy 118.526345 -397.967482) (xy 118.519835 -397.984677) (xy 118.519448 -397.99387) (xy 118.519448 -398.486376)
			(xy 118.519881 -398.495561) (xy 118.52638 -398.512745) (xy 118.532148 -398.519904) (xy 118.554049 -398.545539)
			(xy 118.59214 -398.601177) (xy 118.623292 -398.660977) (xy 118.647057 -398.724078) (xy 118.663091 -398.789571)
			(xy 118.671165 -398.856513) (xy 118.671162 -398.923941) (xy 118.663082 -398.990882) (xy 118.647041 -399.056374)
			(xy 118.62327 -399.119473) (xy 118.592112 -399.17927) (xy 118.554016 -399.234904) (xy 118.532148 -399.260568)
			(xy 118.526334 -399.2677) (xy 118.519831 -399.284901) (xy 118.519448 -399.294096) (xy 118.519448 -399.451576)
			(xy 118.518897 -399.461677) (xy 118.511176 -399.480346) (xy 118.4969 -399.49464) (xy 118.478241 -399.502384)
			(xy 118.46814 -399.502884) (xy 117.75186 -399.502884) (xy 117.741747 -399.502447) (xy 117.723065 -399.494693)
			(xy 117.708771 -399.480382) (xy 117.70104 -399.46169) (xy 117.700552 -399.451576) (xy 117.700552 -399.294096)
			(xy 117.700132 -399.28491) (xy 117.693624 -399.267726) (xy 117.687852 -399.260568) (xy 117.666022 -399.234874)
			(xy 117.627928 -399.179245) (xy 117.596773 -399.119453) (xy 117.573005 -399.05636) (xy 117.556965 -398.990874)
			(xy 117.548886 -398.923938) (xy 117.548882 -398.856516) (xy 117.556955 -398.789579) (xy 117.572989 -398.724092)
			(xy 117.596751 -398.660996) (xy 117.627901 -398.601201) (xy 117.665988 -398.545568) (xy 117.687852 -398.519904)
			(xy 117.693636 -398.51275) (xy 117.700157 -398.495566) (xy 117.700552 -398.486376) (xy 117.700552 -397.99387)
			(xy 117.700145 -397.984683) (xy 117.693628 -397.967499) (xy 117.687852 -397.960342) (xy 117.665996 -397.93467)
			(xy 117.627904 -397.879037) (xy 117.59675 -397.819243) (xy 117.572983 -397.756147) (xy 117.556945 -397.690658)
			(xy 117.548867 -397.623719) (xy 117.548866 -397.556296) (xy 116.42064 -397.556296) (xy 116.423251 -397.56132)
			(xy 116.446929 -397.624321) (xy 116.462906 -397.6897) (xy 116.470954 -397.75652) (xy 116.470957 -397.823823)
			(xy 116.462916 -397.890644) (xy 116.446945 -397.956025) (xy 116.423275 -398.019028) (xy 116.392243 -398.07875)
			(xy 116.354295 -398.134335) (xy 116.332508 -398.159986) (xy 116.326693 -398.167118) (xy 116.320189 -398.184319)
			(xy 116.319808 -398.193514) (xy 116.319808 -398.351502) (xy 116.319269 -398.361654) (xy 116.311503 -398.380415)
			(xy 116.297152 -398.394778) (xy 116.278398 -398.402561) (xy 116.268246 -398.403064) (xy 115.551966 -398.403064)
			(xy 115.541806 -398.402595) (xy 115.523037 -398.394809) (xy 115.508673 -398.380436) (xy 115.500899 -398.361662)
			(xy 115.500404 -398.351502) (xy 115.500404 -398.193514) (xy 115.499986 -398.184328) (xy 115.493478 -398.167143)
			(xy 115.487704 -398.159986) (xy 115.46588 -398.134364) (xy 115.427935 -398.078772) (xy 115.396905 -398.019044)
			(xy 115.373236 -397.956036) (xy 115.357267 -397.89065) (xy 115.349226 -397.823825) (xy 92.220595 -397.823825)
			(xy 92.192138 -397.878594) (xy 92.154191 -397.934181) (xy 92.132404 -397.959834) (xy 92.126611 -397.966982)
			(xy 92.120094 -397.98417) (xy 92.119704 -397.993362) (xy 92.119704 -398.486884) (xy 92.120121 -398.49607)
			(xy 92.12663 -398.513255) (xy 92.132404 -398.520412) (xy 92.154226 -398.546036) (xy 92.192171 -398.601627)
			(xy 92.2232 -398.661355) (xy 92.246869 -398.724363) (xy 92.262838 -398.789748) (xy 92.270879 -398.856574)
			(xy 92.270875 -398.923881) (xy 92.262828 -398.990705) (xy 92.246853 -399.056089) (xy 92.223178 -399.119094)
			(xy 92.192143 -399.178819) (xy 92.154193 -399.234407) (xy 92.132404 -399.26006) (xy 92.1266 -399.2672)
			(xy 92.12009 -399.284394) (xy 92.119704 -399.293588) (xy 92.119704 -399.451576) (xy 92.119259 -399.461728)
			(xy 92.111472 -399.480479) (xy 92.097082 -399.494803) (xy 92.078296 -399.502505) (xy 92.068142 -399.502884)
			(xy 91.351862 -399.502884) (xy 91.341736 -399.502405) (xy 91.323018 -399.494669) (xy 91.308664 -399.480381)
			(xy 91.300842 -399.4617) (xy 91.3003 -399.451576) (xy 91.3003 -399.293588) (xy 91.299895 -399.2844)
			(xy 91.293378 -399.267216) (xy 91.2876 -399.26006) (xy 91.265849 -399.234378) (xy 91.227901 -399.178795)
			(xy 91.196869 -399.119075) (xy 91.173196 -399.056075) (xy 91.157221 -398.990697) (xy 91.149175 -398.923878)
			(xy 91.149172 -398.856576) (xy 91.157212 -398.789757) (xy 91.17318 -398.724377) (xy 91.196847 -398.661374)
			(xy 91.227874 -398.601651) (xy 91.265816 -398.546065) (xy 91.2876 -398.520412) (xy 91.293416 -398.513281)
			(xy 91.299919 -398.49608) (xy 91.3003 -398.486884) (xy 91.3003 -397.993362) (xy 91.299908 -397.984173)
			(xy 91.293382 -397.966989) (xy 91.2876 -397.959834) (xy 91.265823 -397.934173) (xy 91.227877 -397.878587)
			(xy 91.196845 -397.818864) (xy 91.173174 -397.755861) (xy 91.157201 -397.69048) (xy 91.149157 -397.623659)
			(xy 91.149156 -397.556356) (xy 90.020411 -397.556356) (xy 90.022992 -397.561322) (xy 90.046667 -397.624323)
			(xy 90.062643 -397.689701) (xy 90.07069 -397.75652) (xy 90.070693 -397.823822) (xy 90.062653 -397.890643)
			(xy 90.046684 -397.956023) (xy 90.023015 -398.019026) (xy 89.991986 -398.078748) (xy 89.954041 -398.134334)
			(xy 89.932256 -398.159986) (xy 89.926435 -398.167114) (xy 89.919936 -398.184318) (xy 89.919556 -398.193514)
			(xy 89.919556 -398.351502) (xy 89.919138 -398.361674) (xy 89.911351 -398.38047) (xy 89.896964 -398.394855)
			(xy 89.878167 -398.402639) (xy 89.867994 -398.403064) (xy 89.151714 -398.403064) (xy 89.141544 -398.402625)
			(xy 89.122749 -398.394845) (xy 89.108364 -398.380464) (xy 89.100578 -398.361672) (xy 89.100152 -398.351502)
			(xy 89.100152 -398.193514) (xy 89.099724 -398.184329) (xy 89.093221 -398.167145) (xy 89.087452 -398.159986)
			(xy 89.065626 -398.134365) (xy 89.027678 -398.078774) (xy 88.996645 -398.019047) (xy 88.972974 -397.956038)
			(xy 88.957004 -397.890652) (xy 88.948962 -397.823826) (xy 87.820827 -397.823826) (xy 87.792062 -397.879042)
			(xy 87.753972 -397.934677) (xy 87.732108 -397.960342) (xy 87.726312 -397.967488) (xy 87.719797 -397.984678)
			(xy 87.719408 -397.99387) (xy 87.719408 -398.486376) (xy 87.719828 -398.495562) (xy 87.726335 -398.512747)
			(xy 87.732108 -398.519904) (xy 87.754007 -398.54554) (xy 87.792094 -398.601179) (xy 87.823243 -398.660979)
			(xy 87.847005 -398.72408) (xy 87.863037 -398.789573) (xy 87.87111 -398.856514) (xy 87.871107 -398.92394)
			(xy 87.863028 -398.990881) (xy 87.846989 -399.056372) (xy 87.823221 -399.11947) (xy 87.792066 -399.179267)
			(xy 87.753974 -399.234903) (xy 87.732108 -399.260568) (xy 87.726301 -399.267706) (xy 87.719792 -399.284902)
			(xy 87.719408 -399.294096) (xy 87.719408 -399.451576) (xy 87.718965 -399.461696) (xy 87.711226 -399.480398)
			(xy 87.696918 -399.494712) (xy 87.67822 -399.50246) (xy 87.6681 -399.502884) (xy 86.95182 -399.502884)
			(xy 86.941697 -399.502467) (xy 86.922991 -399.494723) (xy 86.908675 -399.480406) (xy 86.900932 -399.461699)
			(xy 86.900512 -399.451576) (xy 86.900512 -399.294096) (xy 86.900101 -399.284909) (xy 86.893587 -399.267725)
			(xy 86.887812 -399.260568) (xy 86.865983 -399.234874) (xy 86.827892 -399.179244) (xy 86.796739 -399.119452)
			(xy 86.772973 -399.056358) (xy 86.756934 -398.990873) (xy 86.748855 -398.923938) (xy 86.748852 -398.856516)
			(xy 86.756925 -398.78958) (xy 86.772957 -398.724093) (xy 86.796717 -398.660998) (xy 86.827865 -398.601203)
			(xy 86.86595 -398.545569) (xy 86.887812 -398.519904) (xy 86.893591 -398.512746) (xy 86.900116 -398.495565)
			(xy 86.900512 -398.486376) (xy 86.900512 -397.99387) (xy 86.900114 -397.984682) (xy 86.893592 -397.967497)
			(xy 86.887812 -397.960342) (xy 86.865957 -397.934669) (xy 86.827868 -397.879036) (xy 86.796716 -397.819241)
			(xy 86.772951 -397.756145) (xy 86.756914 -397.690657) (xy 86.748837 -397.623719) (xy 86.748836 -397.556296)
			(xy 85.620612 -397.556296) (xy 85.623035 -397.560946) (xy 85.646803 -397.624039) (xy 85.662842 -397.689525)
			(xy 85.670922 -397.756461) (xy 85.670925 -397.823882) (xy 85.662853 -397.890819) (xy 85.64682 -397.956306)
			(xy 85.623058 -398.019402) (xy 85.59191 -398.079196) (xy 85.553823 -398.134829) (xy 85.53196 -398.160494)
			(xy 85.526178 -398.16765) (xy 85.519656 -398.184832) (xy 85.51926 -398.194022) (xy 85.51926 -398.351502)
			(xy 85.518775 -398.361629) (xy 85.511047 -398.38035) (xy 85.49676 -398.394706) (xy 85.478076 -398.402525)
			(xy 85.467952 -398.403064) (xy 84.751672 -398.403064) (xy 84.741512 -398.402701) (xy 84.722752 -398.394889)
			(xy 84.708428 -398.380474) (xy 84.700736 -398.361665) (xy 84.700364 -398.351502) (xy 84.700364 -398.194022)
			(xy 84.699929 -398.184838) (xy 84.693431 -398.167654) (xy 84.687664 -398.160494) (xy 84.665764 -398.134859)
			(xy 84.627679 -398.079219) (xy 84.596532 -398.019419) (xy 84.572771 -397.956318) (xy 84.55674 -397.890825)
			(xy 84.548667 -397.823884) (xy 83.420495 -397.823884) (xy 83.392062 -397.878597) (xy 83.35411 -397.934182)
			(xy 83.33232 -397.959834) (xy 83.326529 -397.966983) (xy 83.32001 -397.984171) (xy 83.31962 -397.993362)
			(xy 83.31962 -398.486884) (xy 83.320033 -398.496071) (xy 83.326544 -398.513256) (xy 83.33232 -398.520412)
			(xy 83.354144 -398.546035) (xy 83.392095 -398.601624) (xy 83.423129 -398.661352) (xy 83.446801 -398.72436)
			(xy 83.462773 -398.789746) (xy 83.470815 -398.856573) (xy 83.470812 -398.923881) (xy 83.462763 -398.990707)
			(xy 83.446785 -399.056092) (xy 83.423107 -399.119098) (xy 83.392067 -399.178822) (xy 83.354111 -399.234408)
			(xy 83.33232 -399.26006) (xy 83.326518 -399.267201) (xy 83.320006 -399.284395) (xy 83.31962 -399.293588)
			(xy 83.31962 -399.451576) (xy 83.319159 -399.461726) (xy 83.311375 -399.480474) (xy 83.296991 -399.494798)
			(xy 83.27821 -399.502502) (xy 83.268058 -399.502884) (xy 82.551778 -399.502884) (xy 82.541653 -399.502392)
			(xy 82.522936 -399.494662) (xy 82.508581 -399.480378) (xy 82.500758 -399.461699) (xy 82.500216 -399.451576)
			(xy 82.500216 -399.293588) (xy 82.499808 -399.284401) (xy 82.493293 -399.267216) (xy 82.487516 -399.26006)
			(xy 82.465765 -399.234378) (xy 82.427816 -399.178795) (xy 82.396783 -399.119076) (xy 82.373109 -399.056075)
			(xy 82.357134 -398.990697) (xy 82.349088 -398.923878) (xy 82.349084 -398.856576) (xy 82.357125 -398.789756)
			(xy 82.373093 -398.724377) (xy 82.396761 -398.661374) (xy 82.427788 -398.601651) (xy 82.465731 -398.546065)
			(xy 82.487516 -398.520412) (xy 82.493334 -398.513282) (xy 82.499835 -398.49608) (xy 82.500216 -398.486884)
			(xy 82.500216 -397.993362) (xy 82.499821 -397.984173) (xy 82.493296 -397.966989) (xy 82.487516 -397.959834)
			(xy 82.465739 -397.934174) (xy 82.427791 -397.878588) (xy 82.396759 -397.818865) (xy 82.373086 -397.755862)
			(xy 82.357113 -397.690481) (xy 82.349069 -397.623659) (xy 82.349068 -397.556356) (xy 81.220853 -397.556356)
			(xy 81.223245 -397.560947) (xy 81.247013 -397.62404) (xy 81.263052 -397.689525) (xy 81.271131 -397.756461)
			(xy 81.271135 -397.823882) (xy 81.263062 -397.890818) (xy 81.24703 -397.956306) (xy 81.223269 -398.019401)
			(xy 81.192121 -398.079196) (xy 81.154035 -398.134829) (xy 81.132172 -398.160494) (xy 81.126392 -398.167651)
			(xy 81.119868 -398.184832) (xy 81.119472 -398.194022) (xy 81.119472 -398.351502) (xy 81.118975 -398.361627)
			(xy 81.111249 -398.380346) (xy 81.096966 -398.394702) (xy 81.078287 -398.402523) (xy 81.068164 -398.403064)
			(xy 80.351884 -398.403064) (xy 80.341724 -398.402691) (xy 80.322965 -398.394883) (xy 80.30864 -398.380471)
			(xy 80.300948 -398.361664) (xy 80.300576 -398.351502) (xy 80.300576 -398.194022) (xy 80.300161 -398.184835)
			(xy 80.293651 -398.16765) (xy 80.287876 -398.160494) (xy 80.265976 -398.134859) (xy 80.22789 -398.07922)
			(xy 80.196742 -398.019419) (xy 80.172981 -397.956318) (xy 80.156949 -397.890826) (xy 80.148876 -397.823885)
			(xy 79.02071 -397.823885) (xy 78.991976 -397.879041) (xy 78.953888 -397.934676) (xy 78.932024 -397.960342)
			(xy 78.92623 -397.967489) (xy 78.919713 -397.984678) (xy 78.919324 -397.99387) (xy 78.919324 -398.486376)
			(xy 78.91974 -398.495563) (xy 78.926249 -398.512747) (xy 78.932024 -398.519904) (xy 78.953922 -398.54554)
			(xy 78.992009 -398.60118) (xy 79.023156 -398.66098) (xy 79.046917 -398.724081) (xy 79.06295 -398.789573)
			(xy 79.071022 -398.856514) (xy 79.071019 -398.92394) (xy 79.06294 -398.99088) (xy 79.046901 -399.056371)
			(xy 79.023134 -399.119469) (xy 78.991981 -399.179267) (xy 78.953889 -399.234902) (xy 78.932024 -399.260568)
			(xy 78.926219 -399.267707) (xy 78.919709 -399.284902) (xy 78.919324 -399.294096) (xy 78.919324 -399.451576)
			(xy 78.918865 -399.461694) (xy 78.911129 -399.480393) (xy 78.896826 -399.494707) (xy 78.878134 -399.502457)
			(xy 78.868016 -399.502884) (xy 78.151736 -399.502884) (xy 78.141614 -399.502454) (xy 78.122908 -399.494715)
			(xy 78.108592 -399.480402) (xy 78.100848 -399.461698) (xy 78.100428 -399.451576) (xy 78.100428 -399.294096)
			(xy 78.100014 -399.284909) (xy 78.093502 -399.267725) (xy 78.087728 -399.260568) (xy 78.065898 -399.234874)
			(xy 78.027807 -399.179244) (xy 77.996653 -399.119452) (xy 77.972886 -399.056359) (xy 77.956847 -398.990873)
			(xy 77.948768 -398.923938) (xy 77.948764 -398.856516) (xy 77.956837 -398.78958) (xy 77.972869 -398.724093)
			(xy 77.996631 -398.660997) (xy 78.027779 -398.601202) (xy 78.065865 -398.545569) (xy 78.087728 -398.519904)
			(xy 78.093509 -398.512748) (xy 78.100032 -398.495566) (xy 78.100428 -398.486376) (xy 78.100428 -397.99387)
			(xy 78.100026 -397.984682) (xy 78.093506 -397.967498) (xy 78.087728 -397.960342) (xy 78.065873 -397.934669)
			(xy 78.027782 -397.879036) (xy 77.996629 -397.819241) (xy 77.972863 -397.756146) (xy 77.956826 -397.690657)
			(xy 77.948749 -397.623719) (xy 77.948748 -397.556296) (xy 76.820503 -397.556296) (xy 76.823115 -397.561323)
			(xy 76.846789 -397.624324) (xy 76.862764 -397.689702) (xy 76.870811 -397.756521) (xy 76.870814 -397.823822)
			(xy 76.862774 -397.890642) (xy 76.846806 -397.956022) (xy 76.823139 -398.019024) (xy 76.792111 -398.078747)
			(xy 76.754168 -398.134333) (xy 76.732384 -398.159986) (xy 76.726567 -398.167116) (xy 76.720065 -398.184318)
			(xy 76.719684 -398.193514) (xy 76.719684 -398.351502) (xy 76.719169 -398.361657) (xy 76.711398 -398.380422)
			(xy 76.697039 -398.394787) (xy 76.678277 -398.402565) (xy 76.668122 -398.403064) (xy 75.951842 -398.403064)
			(xy 75.941673 -398.402602) (xy 75.92288 -398.394831) (xy 75.908494 -398.380457) (xy 75.900707 -398.36167)
			(xy 75.90028 -398.351502) (xy 75.90028 -398.193514) (xy 75.899868 -398.184327) (xy 75.893356 -398.167142)
			(xy 75.88758 -398.159986) (xy 75.865754 -398.134365) (xy 75.827803 -398.078775) (xy 75.79677 -398.019048)
			(xy 75.773097 -397.956039) (xy 75.757126 -397.890653) (xy 75.749084 -397.823826) (xy 74.620438 -397.823826)
			(xy 74.591977 -397.878596) (xy 74.554025 -397.934182) (xy 74.532236 -397.959834) (xy 74.526435 -397.966975)
			(xy 74.519925 -397.984169) (xy 74.519536 -397.993362) (xy 74.519536 -398.486884) (xy 74.519968 -398.496069)
			(xy 74.526468 -398.513252) (xy 74.532236 -398.520412) (xy 74.55406 -398.546035) (xy 74.592009 -398.601625)
			(xy 74.623043 -398.661352) (xy 74.646714 -398.724361) (xy 74.662686 -398.789747) (xy 74.670727 -398.856573)
			(xy 74.670724 -398.923881) (xy 74.662676 -398.990707) (xy 74.646698 -399.056091) (xy 74.623021 -399.119097)
			(xy 74.591982 -399.178822) (xy 74.554027 -399.234408) (xy 74.532236 -399.26006) (xy 74.526424 -399.267194)
			(xy 74.51992 -399.284393) (xy 74.519536 -399.293588) (xy 74.519536 -399.451576) (xy 74.51906 -399.461724)
			(xy 74.511279 -399.480469) (xy 74.496899 -399.494792) (xy 74.478124 -399.502499) (xy 74.467974 -399.502884)
			(xy 73.751694 -399.502884) (xy 73.74157 -399.502379) (xy 73.722853 -399.494654) (xy 73.708498 -399.480373)
			(xy 73.700675 -399.461697) (xy 73.700132 -399.451576) (xy 73.700132 -399.293588) (xy 73.699721 -399.284401)
			(xy 73.693207 -399.267217) (xy 73.687432 -399.26006) (xy 73.66568 -399.234378) (xy 73.627731 -399.178796)
			(xy 73.596696 -399.119077) (xy 73.573022 -399.056076) (xy 73.557047 -398.990697) (xy 73.549 -398.923878)
			(xy 73.548996 -398.856576) (xy 73.557037 -398.789756) (xy 73.573006 -398.724376) (xy 73.596674 -398.661373)
			(xy 73.627703 -398.60165) (xy 73.665647 -398.546064) (xy 73.687432 -398.520412) (xy 73.693253 -398.513284)
			(xy 73.699752 -398.49608) (xy 73.700132 -398.486884) (xy 73.700132 -397.993362) (xy 73.699733 -397.984174)
			(xy 73.693211 -397.96699) (xy 73.687432 -397.959834) (xy 73.665654 -397.934174) (xy 73.627705 -397.878588)
			(xy 73.596672 -397.818866) (xy 73.572999 -397.755862) (xy 73.557026 -397.690481) (xy 73.548981 -397.62366)
			(xy 73.54898 -397.556355) (xy 72.420766 -397.556355) (xy 72.423159 -397.560948) (xy 72.446926 -397.62404)
			(xy 72.462964 -397.689526) (xy 72.471043 -397.756461) (xy 72.471047 -397.823882) (xy 72.462974 -397.890818)
			(xy 72.446942 -397.956305) (xy 72.423182 -398.0194) (xy 72.392035 -398.079195) (xy 72.35395 -398.134829)
			(xy 72.332088 -398.160494) (xy 72.32631 -398.167652) (xy 72.319785 -398.184833) (xy 72.319388 -398.194022)
			(xy 72.319388 -398.351502) (xy 72.318876 -398.361625) (xy 72.311153 -398.380341) (xy 72.296875 -398.394696)
			(xy 72.278201 -398.40252) (xy 72.26808 -398.403064) (xy 71.5518 -398.403064) (xy 71.541641 -398.402678)
			(xy 71.522882 -398.394875) (xy 71.508557 -398.380467) (xy 71.500864 -398.361663) (xy 71.500492 -398.351502)
			(xy 71.500492 -398.194022) (xy 71.500073 -398.184836) (xy 71.493566 -398.167651) (xy 71.487792 -398.160494)
			(xy 71.465891 -398.134859) (xy 71.427804 -398.07922) (xy 71.396655 -398.01942) (xy 71.372894 -397.956319)
			(xy 71.356861 -397.890826) (xy 71.348788 -397.823885) (xy 66.525648 -397.823885) (xy 66.525648 -401.723796)
			(xy 71.3488 -401.723796) (xy 71.348802 -401.656371) (xy 71.35688 -401.589431) (xy 71.372917 -401.523941)
			(xy 71.396683 -401.460843) (xy 71.427836 -401.401046) (xy 71.465927 -401.345411) (xy 71.487792 -401.319746)
			(xy 71.493593 -401.312604) (xy 71.500105 -401.295411) (xy 71.500492 -401.286218) (xy 71.500492 -400.793966)
			(xy 71.5001 -400.784777) (xy 71.493574 -400.767592) (xy 71.487792 -400.760438) (xy 71.465934 -400.734768)
			(xy 71.427846 -400.679134) (xy 71.396695 -400.619338) (xy 71.372931 -400.556242) (xy 71.356896 -400.490754)
			(xy 71.348819 -400.423816) (xy 71.348819 -400.356393) (xy 71.356894 -400.289455) (xy 71.372928 -400.223967)
			(xy 71.396692 -400.16087) (xy 71.427841 -400.101074) (xy 71.465929 -400.045439) (xy 71.487792 -400.019774)
			(xy 71.493581 -400.012623) (xy 71.500101 -399.995437) (xy 71.500492 -399.986246) (xy 71.500492 -399.828766)
			(xy 71.500997 -399.818643) (xy 71.508727 -399.79993) (xy 71.523007 -399.785577) (xy 71.54168 -399.77775)
			(xy 71.5518 -399.777204) (xy 72.26808 -399.777204) (xy 72.278233 -399.777638) (xy 72.296986 -399.785428)
			(xy 72.31131 -399.799821) (xy 72.31901 -399.818611) (xy 72.319388 -399.828766) (xy 72.319388 -399.986246)
			(xy 72.319827 -399.99543) (xy 72.326321 -400.012615) (xy 72.332088 -400.019774) (xy 72.353958 -400.045434)
			(xy 72.392048 -400.101069) (xy 72.423199 -400.160866) (xy 72.446963 -400.223963) (xy 72.462999 -400.289453)
			(xy 72.471074 -400.356392) (xy 72.471074 -400.423817) (xy 72.462997 -400.490756) (xy 72.44696 -400.556245)
			(xy 72.423195 -400.619342) (xy 72.392043 -400.679139) (xy 72.353953 -400.734773) (xy 72.332088 -400.760438)
			(xy 72.326291 -400.767583) (xy 72.319777 -400.784774) (xy 72.319388 -400.793966) (xy 72.319388 -401.286218)
			(xy 72.319792 -401.295406) (xy 72.32631 -401.31259) (xy 72.332088 -401.319746) (xy 72.353931 -401.345429)
			(xy 72.392021 -401.401061) (xy 72.423173 -401.460854) (xy 72.446939 -401.523949) (xy 72.462977 -401.589436)
			(xy 72.471054 -401.656372) (xy 72.471056 -401.723795) (xy 72.462982 -401.790732) (xy 72.446949 -401.85622)
			(xy 72.423187 -401.919316) (xy 72.392038 -401.979111) (xy 72.353951 -402.034745) (xy 72.332088 -402.06041)
			(xy 72.326303 -402.067564) (xy 72.319782 -402.084748) (xy 72.319388 -402.093938) (xy 72.319388 -402.251418)
			(xy 72.318889 -402.261542) (xy 72.311161 -402.280259) (xy 72.296879 -402.294614) (xy 72.278202 -402.302437)
			(xy 72.26808 -402.30298) (xy 71.5518 -402.30298) (xy 71.541643 -402.302578) (xy 71.522887 -402.294779)
			(xy 71.508563 -402.280376) (xy 71.500867 -402.261577) (xy 71.500492 -402.251418) (xy 71.500492 -402.093938)
			(xy 71.500065 -402.084753) (xy 71.493563 -402.067568) (xy 71.487792 -402.06041) (xy 71.465907 -402.034762)
			(xy 71.427819 -401.979125) (xy 71.39667 -401.919326) (xy 71.372907 -401.856227) (xy 71.356874 -401.790736)
			(xy 71.3488 -401.723796) (xy 66.525648 -401.723796) (xy 66.525648 -402.823818) (xy 73.54894 -402.823818)
			(xy 73.548944 -402.75651) (xy 73.556993 -402.689684) (xy 73.572971 -402.624299) (xy 73.596649 -402.561293)
			(xy 73.627687 -402.501568) (xy 73.665642 -402.44598) (xy 73.687432 -402.420328) (xy 73.693246 -402.413195)
			(xy 73.699749 -402.395995) (xy 73.700132 -402.3868) (xy 73.700132 -401.893532) (xy 73.699699 -401.884347)
			(xy 73.6932 -401.867163) (xy 73.687432 -401.860004) (xy 73.665625 -401.834368) (xy 73.627677 -401.778779)
			(xy 73.596645 -401.719053) (xy 73.572974 -401.656047) (xy 73.557002 -401.590662) (xy 73.54896 -401.523838)
			(xy 73.548962 -401.456532) (xy 73.557008 -401.389708) (xy 73.572982 -401.324325) (xy 73.596657 -401.261319)
			(xy 73.627692 -401.201595) (xy 73.665643 -401.146008) (xy 73.687432 -401.120356) (xy 73.693234 -401.113215)
			(xy 73.699745 -401.096021) (xy 73.700132 -401.086828) (xy 73.700132 -400.92884) (xy 73.700555 -400.918685)
			(xy 73.708343 -400.899927) (xy 73.722741 -400.885601) (xy 73.741537 -400.877906) (xy 73.751694 -400.877532)
			(xy 74.467974 -400.877532) (xy 74.478098 -400.878047) (xy 74.496817 -400.885765) (xy 74.511174 -400.900043)
			(xy 74.518996 -400.918719) (xy 74.519536 -400.92884) (xy 74.519536 -401.086828) (xy 74.519947 -401.096015)
			(xy 74.526462 -401.113198) (xy 74.532236 -401.120356) (xy 74.554005 -401.146024) (xy 74.591956 -401.201608)
			(xy 74.622991 -401.261329) (xy 74.646666 -401.324331) (xy 74.662641 -401.389712) (xy 74.670687 -401.456533)
			(xy 74.670689 -401.523837) (xy 74.662647 -401.590659) (xy 74.646675 -401.65604) (xy 74.623004 -401.719044)
			(xy 74.620565 -401.723737) (xy 75.749095 -401.723737) (xy 75.749097 -401.65643) (xy 75.757144 -401.589605)
			(xy 75.773121 -401.524221) (xy 75.796798 -401.461215) (xy 75.827836 -401.401492) (xy 75.86579 -401.345906)
			(xy 75.88758 -401.320254) (xy 75.893376 -401.313108) (xy 75.899892 -401.295918) (xy 75.90028 -401.286726)
			(xy 75.90028 -400.793458) (xy 75.899895 -400.784268) (xy 75.893364 -400.767084) (xy 75.88758 -400.75993)
			(xy 75.865797 -400.734274) (xy 75.827845 -400.678689) (xy 75.79681 -400.618966) (xy 75.773135 -400.555962)
			(xy 75.75716 -400.49058) (xy 75.749115 -400.423757) (xy 75.749114 -400.356452) (xy 75.757158 -400.289629)
			(xy 75.773132 -400.224247) (xy 75.796806 -400.161242) (xy 75.827841 -400.101519) (xy 75.865791 -400.045934)
			(xy 75.88758 -400.020282) (xy 75.893364 -400.013128) (xy 75.899887 -399.995944) (xy 75.90028 -399.986754)
			(xy 75.90028 -399.828766) (xy 75.900637 -399.818587) (xy 75.908441 -399.799783) (xy 75.922847 -399.785398)
			(xy 75.941662 -399.777622) (xy 75.951842 -399.777204) (xy 76.668122 -399.777204) (xy 76.678277 -399.777714)
			(xy 76.69704 -399.78549) (xy 76.711404 -399.79985) (xy 76.719183 -399.818611) (xy 76.719684 -399.828766)
			(xy 76.719684 -399.986754) (xy 76.72012 -399.995938) (xy 76.726616 -400.013123) (xy 76.732384 -400.020282)
			(xy 76.754177 -400.04593) (xy 76.792124 -400.101517) (xy 76.823156 -400.161242) (xy 76.846827 -400.224247)
			(xy 76.862799 -400.289629) (xy 76.870842 -400.356452) (xy 76.870842 -400.423757) (xy 76.862798 -400.49058)
			(xy 76.846825 -400.555962) (xy 76.823152 -400.618967) (xy 76.792119 -400.678691) (xy 76.754171 -400.734278)
			(xy 76.732384 -400.75993) (xy 76.72659 -400.767077) (xy 76.720074 -400.784266) (xy 76.719684 -400.793458)
			(xy 76.719684 -401.286726) (xy 76.720085 -401.295914) (xy 76.726605 -401.313098) (xy 76.732384 -401.320254)
			(xy 76.754149 -401.345924) (xy 76.792097 -401.401509) (xy 76.82313 -401.46123) (xy 76.846803 -401.524232)
			(xy 76.862777 -401.589612) (xy 76.870823 -401.656432) (xy 76.870825 -401.723735) (xy 76.862783 -401.790556)
			(xy 76.846813 -401.855936) (xy 76.823144 -401.91894) (xy 76.792114 -401.978663) (xy 76.75417 -402.03425)
			(xy 76.732384 -402.059902) (xy 76.726602 -402.067058) (xy 76.720079 -402.08424) (xy 76.719684 -402.09343)
			(xy 76.719684 -402.251418) (xy 76.719182 -402.261574) (xy 76.711406 -402.28034) (xy 76.697043 -402.294704)
			(xy 76.678278 -402.302481) (xy 76.668122 -402.30298) (xy 75.951842 -402.30298) (xy 75.941675 -402.302502)
			(xy 75.922885 -402.294734) (xy 75.908499 -402.280365) (xy 75.90071 -402.261584) (xy 75.90028 -402.251418)
			(xy 75.90028 -402.09343) (xy 75.89986 -402.084244) (xy 75.893354 -402.067059) (xy 75.88758 -402.059902)
			(xy 75.865769 -402.034268) (xy 75.827819 -401.97868) (xy 75.796784 -401.918954) (xy 75.773111 -401.855947)
			(xy 75.757138 -401.790562) (xy 75.749095 -401.723737) (xy 74.620565 -401.723737) (xy 74.591971 -401.778767)
			(xy 74.554023 -401.834352) (xy 74.532236 -401.860004) (xy 74.526447 -401.867155) (xy 74.51993 -401.884341)
			(xy 74.519536 -401.893532) (xy 74.519536 -402.3868) (xy 74.519961 -402.395985) (xy 74.526466 -402.413169)
			(xy 74.532236 -402.420328) (xy 74.553977 -402.446019) (xy 74.591929 -402.501599) (xy 74.622966 -402.561317)
			(xy 74.646642 -402.624317) (xy 74.662619 -402.689694) (xy 74.670668 -402.756513) (xy 74.670672 -402.823815)
			(xy 74.670664 -402.823878) (xy 77.948708 -402.823878) (xy 77.948713 -402.75645) (xy 77.956794 -402.689508)
			(xy 77.972835 -402.624016) (xy 77.996606 -402.560917) (xy 78.027764 -402.501119) (xy 78.06586 -402.445485)
			(xy 78.087728 -402.41982) (xy 78.093545 -402.412689) (xy 78.100047 -402.395488) (xy 78.100428 -402.386292)
			(xy 78.100428 -401.89404) (xy 78.099992 -401.884856) (xy 78.093496 -401.867671) (xy 78.087728 -401.860512)
			(xy 78.065843 -401.834863) (xy 78.027753 -401.779227) (xy 77.996602 -401.719429) (xy 77.972838 -401.65633)
			(xy 77.956803 -401.590838) (xy 77.948728 -401.523898) (xy 77.94873 -401.456472) (xy 77.956808 -401.389532)
			(xy 77.972847 -401.324041) (xy 77.996614 -401.260944) (xy 78.027769 -401.201147) (xy 78.065862 -401.145513)
			(xy 78.087728 -401.119848) (xy 78.093533 -401.112709) (xy 78.100042 -401.095514) (xy 78.100428 -401.08632)
			(xy 78.100428 -400.92884) (xy 78.10085 -400.918717) (xy 78.10859 -400.900009) (xy 78.122905 -400.885692)
			(xy 78.141613 -400.87795) (xy 78.151736 -400.877532) (xy 78.868016 -400.877532) (xy 78.878144 -400.877903)
			(xy 78.896854 -400.885663) (xy 78.911169 -400.899993) (xy 78.918908 -400.918712) (xy 78.919324 -400.92884)
			(xy 78.919324 -401.08632) (xy 78.919719 -401.095509) (xy 78.926243 -401.112693) (xy 78.932024 -401.119848)
			(xy 78.953867 -401.14553) (xy 78.991955 -401.201163) (xy 79.023105 -401.260957) (xy 79.04687 -401.324051)
			(xy 79.062906 -401.389538) (xy 79.070983 -401.456474) (xy 79.070985 -401.523896) (xy 79.062911 -401.590832)
			(xy 79.046879 -401.65632) (xy 79.023118 -401.719416) (xy 79.020837 -401.723796) (xy 80.148888 -401.723796)
			(xy 80.14889 -401.656371) (xy 80.156967 -401.589432) (xy 80.173004 -401.523942) (xy 80.19677 -401.460844)
			(xy 80.227922 -401.401047) (xy 80.266012 -401.345412) (xy 80.287876 -401.319746) (xy 80.293675 -401.312603)
			(xy 80.300189 -401.295411) (xy 80.300576 -401.286218) (xy 80.300576 -400.793966) (xy 80.300187 -400.784776)
			(xy 80.293659 -400.767592) (xy 80.287876 -400.760438) (xy 80.266019 -400.734767) (xy 80.227931 -400.679133)
			(xy 80.196782 -400.619337) (xy 80.173018 -400.556241) (xy 80.156983 -400.490753) (xy 80.148907 -400.423816)
			(xy 80.148907 -400.356393) (xy 80.156982 -400.289456) (xy 80.173016 -400.223967) (xy 80.196778 -400.160871)
			(xy 80.227927 -400.101075) (xy 80.266013 -400.04544) (xy 80.287876 -400.019774) (xy 80.293663 -400.012622)
			(xy 80.300184 -399.995437) (xy 80.300576 -399.986246) (xy 80.300576 -399.828766) (xy 80.301 -399.818633)
			(xy 80.308745 -399.799904) (xy 80.323051 -399.785548) (xy 80.341753 -399.777736) (xy 80.351884 -399.777204)
			(xy 81.068164 -399.777204) (xy 81.078316 -399.777651) (xy 81.097069 -399.785436) (xy 81.111393 -399.799825)
			(xy 81.119094 -399.818612) (xy 81.119472 -399.828766) (xy 81.119472 -399.986246) (xy 81.119914 -399.99543)
			(xy 81.126406 -400.012614) (xy 81.132172 -400.019774) (xy 81.154043 -400.045434) (xy 81.192133 -400.101069)
			(xy 81.223285 -400.160865) (xy 81.24705 -400.223963) (xy 81.263086 -400.289453) (xy 81.271162 -400.356392)
			(xy 81.271161 -400.423817) (xy 81.263085 -400.490756) (xy 81.247048 -400.556246) (xy 81.223282 -400.619343)
			(xy 81.192129 -400.679139) (xy 81.154037 -400.734773) (xy 81.132172 -400.760438) (xy 81.126373 -400.767581)
			(xy 81.11986 -400.784773) (xy 81.119472 -400.793966) (xy 81.119472 -401.286218) (xy 81.11988 -401.295405)
			(xy 81.126396 -401.312589) (xy 81.132172 -401.319746) (xy 81.154015 -401.345429) (xy 81.192107 -401.40106)
			(xy 81.22326 -401.460854) (xy 81.247026 -401.523948) (xy 81.263064 -401.589435) (xy 81.271142 -401.656372)
			(xy 81.271144 -401.723795) (xy 81.26307 -401.790732) (xy 81.247036 -401.85622) (xy 81.223273 -401.919316)
			(xy 81.192124 -401.979112) (xy 81.154036 -402.034745) (xy 81.132172 -402.06041) (xy 81.126385 -402.067562)
			(xy 81.119865 -402.084747) (xy 81.119472 -402.093938) (xy 81.119472 -402.251418) (xy 81.118989 -402.261544)
			(xy 81.111257 -402.280264) (xy 81.09697 -402.294619) (xy 81.078288 -402.30244) (xy 81.068164 -402.30298)
			(xy 80.351884 -402.30298) (xy 80.341726 -402.302591) (xy 80.32297 -402.294787) (xy 80.308646 -402.28038)
			(xy 80.30095 -402.261578) (xy 80.300576 -402.251418) (xy 80.300576 -402.093938) (xy 80.300153 -402.084752)
			(xy 80.293649 -402.067567) (xy 80.287876 -402.06041) (xy 80.265991 -402.034762) (xy 80.227905 -401.979125)
			(xy 80.196756 -401.919326) (xy 80.172994 -401.856227) (xy 80.156961 -401.790736) (xy 80.148888 -401.723796)
			(xy 79.020837 -401.723796) (xy 78.991971 -401.779212) (xy 78.953886 -401.834846) (xy 78.932024 -401.860512)
			(xy 78.926243 -401.867668) (xy 78.919718 -401.88485) (xy 78.919324 -401.89404) (xy 78.919324 -402.386292)
			(xy 78.919733 -402.395479) (xy 78.926247 -402.412664) (xy 78.932024 -402.41982) (xy 78.95384 -402.445525)
			(xy 78.991929 -402.501154) (xy 79.02308 -402.560945) (xy 79.046846 -402.624037) (xy 79.062884 -402.689521)
			(xy 79.070963 -402.756454) (xy 79.070968 -402.823818) (xy 82.349028 -402.823818) (xy 82.349032 -402.75651)
			(xy 82.357081 -402.689684) (xy 82.373058 -402.6243) (xy 82.396735 -402.561293) (xy 82.427773 -402.501568)
			(xy 82.465726 -402.44598) (xy 82.487516 -402.420328) (xy 82.493327 -402.413193) (xy 82.499833 -402.395995)
			(xy 82.500216 -402.3868) (xy 82.500216 -401.893532) (xy 82.499787 -401.884347) (xy 82.493286 -401.867163)
			(xy 82.487516 -401.860004) (xy 82.465709 -401.834368) (xy 82.427763 -401.778778) (xy 82.396731 -401.719052)
			(xy 82.373061 -401.656046) (xy 82.35709 -401.590662) (xy 82.349048 -401.523838) (xy 82.34905 -401.456532)
			(xy 82.357095 -401.389708) (xy 82.37307 -401.324325) (xy 82.396744 -401.26132) (xy 82.427778 -401.201596)
			(xy 82.465728 -401.146008) (xy 82.487516 -401.120356) (xy 82.493316 -401.113213) (xy 82.499828 -401.096021)
			(xy 82.500216 -401.086828) (xy 82.500216 -400.92884) (xy 82.500655 -400.918687) (xy 82.50844 -400.899932)
			(xy 82.522832 -400.885607) (xy 82.541623 -400.877908) (xy 82.551778 -400.877532) (xy 83.268058 -400.877532)
			(xy 83.278181 -400.878061) (xy 83.2969 -400.885773) (xy 83.311257 -400.900047) (xy 83.319079 -400.91872)
			(xy 83.31962 -400.92884) (xy 83.31962 -401.086828) (xy 83.320012 -401.096017) (xy 83.326538 -401.113202)
			(xy 83.33232 -401.120356) (xy 83.354089 -401.146024) (xy 83.392041 -401.201607) (xy 83.423078 -401.261328)
			(xy 83.446753 -401.324331) (xy 83.462729 -401.389711) (xy 83.470775 -401.456533) (xy 83.470777 -401.523837)
			(xy 83.462734 -401.590659) (xy 83.446762 -401.656041) (xy 83.42309 -401.719044) (xy 83.420621 -401.723796)
			(xy 84.548678 -401.723796) (xy 84.54868 -401.656371) (xy 84.556758 -401.589432) (xy 84.572795 -401.523942)
			(xy 84.59656 -401.460845) (xy 84.627711 -401.401047) (xy 84.6658 -401.345412) (xy 84.687664 -401.319746)
			(xy 84.693474 -401.312611) (xy 84.699979 -401.295412) (xy 84.700364 -401.286218) (xy 84.700364 -400.793966)
			(xy 84.699956 -400.784779) (xy 84.693439 -400.767595) (xy 84.687664 -400.760438) (xy 84.665807 -400.734767)
			(xy 84.627721 -400.679133) (xy 84.596572 -400.619337) (xy 84.572809 -400.556241) (xy 84.556774 -400.490753)
			(xy 84.548698 -400.423816) (xy 84.548698 -400.356393) (xy 84.556772 -400.289456) (xy 84.572806 -400.223968)
			(xy 84.596568 -400.160871) (xy 84.627716 -400.101075) (xy 84.665802 -400.04544) (xy 84.687664 -400.019774)
			(xy 84.693462 -400.01263) (xy 84.699974 -399.995438) (xy 84.700364 -399.986246) (xy 84.700364 -399.828766)
			(xy 84.700799 -399.818634) (xy 84.708543 -399.799908) (xy 84.722845 -399.785552) (xy 84.741542 -399.777738)
			(xy 84.751672 -399.777204) (xy 85.467952 -399.777204) (xy 85.478104 -399.777661) (xy 85.496856 -399.785442)
			(xy 85.511181 -399.799828) (xy 85.518881 -399.818613) (xy 85.51926 -399.828766) (xy 85.51926 -399.986246)
			(xy 85.519705 -399.995429) (xy 85.526196 -400.012613) (xy 85.53196 -400.019774) (xy 85.553831 -400.045434)
			(xy 85.591922 -400.101068) (xy 85.623075 -400.160865) (xy 85.646841 -400.223962) (xy 85.662877 -400.289453)
			(xy 85.670953 -400.356392) (xy 85.670952 -400.423817) (xy 85.662875 -400.490756) (xy 85.646838 -400.556246)
			(xy 85.623071 -400.619344) (xy 85.591918 -400.67914) (xy 85.553826 -400.734773) (xy 85.53196 -400.760438)
			(xy 85.52616 -400.76758) (xy 85.519648 -400.784773) (xy 85.51926 -400.793966) (xy 85.51926 -401.286218)
			(xy 85.51967 -401.295405) (xy 85.526185 -401.312589) (xy 85.53196 -401.319746) (xy 85.553804 -401.345428)
			(xy 85.591896 -401.40106) (xy 85.62305 -401.460853) (xy 85.646817 -401.523948) (xy 85.662855 -401.589435)
			(xy 85.670933 -401.656372) (xy 85.670935 -401.723795) (xy 85.662861 -401.790732) (xy 85.646827 -401.856221)
			(xy 85.623063 -401.919317) (xy 85.591913 -401.979112) (xy 85.553824 -402.034745) (xy 85.53196 -402.06041)
			(xy 85.526172 -402.067561) (xy 85.519653 -402.084747) (xy 85.51926 -402.093938) (xy 85.51926 -402.251418)
			(xy 85.518788 -402.261546) (xy 85.511055 -402.280268) (xy 85.496764 -402.294623) (xy 85.478078 -402.302442)
			(xy 85.467952 -402.30298) (xy 84.751672 -402.30298) (xy 84.741514 -402.302601) (xy 84.722757 -402.294792)
			(xy 84.708434 -402.280383) (xy 84.700738 -402.261579) (xy 84.700364 -402.251418) (xy 84.700364 -402.093938)
			(xy 84.699921 -402.084755) (xy 84.693429 -402.067571) (xy 84.687664 -402.06041) (xy 84.66578 -402.034762)
			(xy 84.627694 -401.979124) (xy 84.596546 -401.919325) (xy 84.572785 -401.856226) (xy 84.556752 -401.790735)
			(xy 84.548678 -401.723796) (xy 83.420621 -401.723796) (xy 83.392057 -401.778767) (xy 83.354108 -401.834352)
			(xy 83.33232 -401.860004) (xy 83.326542 -401.867162) (xy 83.320015 -401.884343) (xy 83.31962 -401.893532)
			(xy 83.31962 -402.3868) (xy 83.320026 -402.395988) (xy 83.326542 -402.413172) (xy 83.33232 -402.420328)
			(xy 83.354062 -402.446018) (xy 83.392015 -402.501598) (xy 83.423052 -402.561316) (xy 83.44673 -402.624316)
			(xy 83.462707 -402.689694) (xy 83.470756 -402.756513) (xy 83.47076 -402.823815) (xy 83.470752 -402.823878)
			(xy 86.748796 -402.823878) (xy 86.748801 -402.75645) (xy 86.756882 -402.689508) (xy 86.772922 -402.624016)
			(xy 86.796693 -402.560918) (xy 86.82785 -402.50112) (xy 86.865945 -402.445485) (xy 86.887812 -402.41982)
			(xy 86.893626 -402.412687) (xy 86.90013 -402.395487) (xy 86.900512 -402.386292) (xy 86.900512 -401.89404)
			(xy 86.90008 -401.884855) (xy 86.893581 -401.867671) (xy 86.887812 -401.860512) (xy 86.865928 -401.834863)
			(xy 86.827839 -401.779227) (xy 86.796689 -401.719428) (xy 86.772925 -401.656329) (xy 86.756891 -401.590838)
			(xy 86.748816 -401.523898) (xy 86.748818 -401.456472) (xy 86.756896 -401.389532) (xy 86.772934 -401.324042)
			(xy 86.796701 -401.260944) (xy 86.827855 -401.201148) (xy 86.865946 -401.145513) (xy 86.887812 -401.119848)
			(xy 86.893615 -401.112707) (xy 86.900125 -401.095513) (xy 86.900512 -401.08632) (xy 86.900512 -400.92884)
			(xy 86.900949 -400.918719) (xy 86.908686 -400.900014) (xy 86.922997 -400.885698) (xy 86.941699 -400.877953)
			(xy 86.95182 -400.877532) (xy 87.6681 -400.877532) (xy 87.678226 -400.877917) (xy 87.696936 -400.885671)
			(xy 87.711252 -400.899997) (xy 87.718991 -400.918713) (xy 87.719408 -400.92884) (xy 87.719408 -401.08632)
			(xy 87.719807 -401.095508) (xy 87.726328 -401.112693) (xy 87.732108 -401.119848) (xy 87.753952 -401.14553)
			(xy 87.792041 -401.201162) (xy 87.823192 -401.260956) (xy 87.846957 -401.324051) (xy 87.862994 -401.389538)
			(xy 87.871071 -401.456474) (xy 87.871073 -401.523896) (xy 87.862999 -401.590833) (xy 87.846966 -401.656321)
			(xy 87.823204 -401.719417) (xy 87.820954 -401.723737) (xy 115.349237 -401.723737) (xy 115.349239 -401.65643)
			(xy 115.357285 -401.589607) (xy 115.373259 -401.524224) (xy 115.396933 -401.461219) (xy 115.427967 -401.401494)
			(xy 115.465916 -401.345907) (xy 115.487704 -401.320254) (xy 115.493503 -401.313111) (xy 115.500016 -401.295919)
			(xy 115.500404 -401.286726) (xy 115.500404 -400.793458) (xy 115.500013 -400.784269) (xy 115.493486 -400.767085)
			(xy 115.487704 -400.75993) (xy 115.465923 -400.734273) (xy 115.427977 -400.678686) (xy 115.396945 -400.618963)
			(xy 115.373273 -400.555959) (xy 115.357301 -400.490578) (xy 115.349257 -400.423756) (xy 115.349256 -400.356453)
			(xy 115.357299 -400.289631) (xy 115.373271 -400.22425) (xy 115.396941 -400.161245) (xy 115.427972 -400.101522)
			(xy 115.465918 -400.045935) (xy 115.487704 -400.020282) (xy 115.493491 -400.01313) (xy 115.500011 -399.995945)
			(xy 115.500404 -399.986754) (xy 115.500404 -399.828766) (xy 115.500905 -399.81861) (xy 115.508684 -399.799847)
			(xy 115.523047 -399.785484) (xy 115.54181 -399.777705) (xy 115.551966 -399.777204) (xy 116.268246 -399.777204)
			(xy 116.278403 -399.777695) (xy 116.297166 -399.785478) (xy 116.311529 -399.799844) (xy 116.319307 -399.818609)
			(xy 116.319808 -399.828766) (xy 116.319808 -399.986754) (xy 116.320238 -399.995939) (xy 116.326738 -400.013124)
			(xy 116.332508 -400.020282) (xy 116.354303 -400.045929) (xy 116.392255 -400.101515) (xy 116.423291 -400.161238)
			(xy 116.446966 -400.224244) (xy 116.46294 -400.289627) (xy 116.470985 -400.356451) (xy 116.470984 -400.423758)
			(xy 116.462939 -400.490582) (xy 116.446963 -400.555965) (xy 116.423288 -400.61897) (xy 116.392251 -400.678693)
			(xy 116.354298 -400.734279) (xy 116.332508 -400.75993) (xy 116.326717 -400.767079) (xy 116.320199 -400.784267)
			(xy 116.319808 -400.793458) (xy 116.319808 -401.286726) (xy 116.320204 -401.295915) (xy 116.326727 -401.313099)
			(xy 116.332508 -401.320254) (xy 116.354276 -401.345923) (xy 116.392229 -401.401506) (xy 116.423266 -401.461227)
			(xy 116.446942 -401.524229) (xy 116.462918 -401.58961) (xy 116.470965 -401.656431) (xy 116.470967 -401.723736)
			(xy 116.462924 -401.790558) (xy 116.446952 -401.855939) (xy 116.423279 -401.918943) (xy 116.392246 -401.978666)
			(xy 116.354296 -402.034251) (xy 116.332508 -402.059902) (xy 116.326729 -402.06706) (xy 116.320204 -402.084241)
			(xy 116.319808 -402.09343) (xy 116.319808 -402.251418) (xy 116.319283 -402.261571) (xy 116.311511 -402.280332)
			(xy 116.297156 -402.294695) (xy 116.278399 -402.302477) (xy 116.268246 -402.30298) (xy 115.551966 -402.30298)
			(xy 115.541808 -402.302495) (xy 115.523042 -402.294713) (xy 115.508678 -402.280345) (xy 115.500902 -402.261576)
			(xy 115.500404 -402.251418) (xy 115.500404 -402.09343) (xy 115.499978 -402.084244) (xy 115.493475 -402.06706)
			(xy 115.487704 -402.059902) (xy 115.465896 -402.034267) (xy 115.42795 -401.978677) (xy 115.396919 -401.918951)
			(xy 115.373249 -401.855944) (xy 115.357279 -401.79056) (xy 115.349237 -401.723737) (xy 87.820954 -401.723737)
			(xy 87.792056 -401.779212) (xy 87.75397 -401.834847) (xy 87.732108 -401.860512) (xy 87.726325 -401.867667)
			(xy 87.719802 -401.88485) (xy 87.719408 -401.89404) (xy 87.719408 -402.386292) (xy 87.71982 -402.395479)
			(xy 87.726332 -402.412663) (xy 87.732108 -402.41982) (xy 87.753925 -402.445524) (xy 87.792014 -402.501153)
			(xy 87.823166 -402.560944) (xy 87.846933 -402.624036) (xy 87.862972 -402.68952) (xy 87.871051 -402.756454)
			(xy 87.871055 -402.823874) (xy 87.871055 -402.823878) (xy 117.548826 -402.823878) (xy 117.548831 -402.75645)
			(xy 117.556912 -402.689507) (xy 117.572954 -402.624015) (xy 117.596726 -402.560916) (xy 117.627885 -402.501119)
			(xy 117.665983 -402.445484) (xy 117.687852 -402.41982) (xy 117.693671 -402.412691) (xy 117.700171 -402.395488)
			(xy 117.700552 -402.386292) (xy 117.700552 -401.89404) (xy 117.700111 -401.884856) (xy 117.693618 -401.867672)
			(xy 117.687852 -401.860512) (xy 117.665967 -401.834864) (xy 117.627875 -401.779228) (xy 117.596722 -401.71943)
			(xy 117.572957 -401.656331) (xy 117.556921 -401.590839) (xy 117.548846 -401.523898) (xy 117.548848 -401.456472)
			(xy 117.556927 -401.389531) (xy 117.572966 -401.32404) (xy 117.596735 -401.260943) (xy 117.627891 -401.201146)
			(xy 117.665985 -401.145512) (xy 117.687852 -401.119848) (xy 117.69366 -401.112711) (xy 117.700166 -401.095514)
			(xy 117.700552 -401.08632) (xy 117.700552 -400.92884) (xy 117.701117 -400.91874) (xy 117.708832 -400.900072)
			(xy 117.723105 -400.885777) (xy 117.741761 -400.878033) (xy 117.75186 -400.877532) (xy 118.46814 -400.877532)
			(xy 118.478255 -400.877953) (xy 118.49694 -400.88571) (xy 118.511235 -400.900027) (xy 118.518963 -400.918724)
			(xy 118.519448 -400.92884) (xy 118.519448 -401.08632) (xy 118.51986 -401.095507) (xy 118.526374 -401.11269)
			(xy 118.532148 -401.119848) (xy 118.553994 -401.145529) (xy 118.592087 -401.20116) (xy 118.623241 -401.260953)
			(xy 118.647009 -401.324048) (xy 118.663047 -401.389536) (xy 118.671126 -401.456473) (xy 118.671127 -401.523897)
			(xy 118.663053 -401.590834) (xy 118.647018 -401.656323) (xy 118.623254 -401.719419) (xy 118.620974 -401.723796)
			(xy 119.749006 -401.723796) (xy 119.749008 -401.656371) (xy 119.757086 -401.589431) (xy 119.773123 -401.523941)
			(xy 119.79689 -401.460843) (xy 119.828043 -401.401046) (xy 119.866135 -401.345411) (xy 119.888 -401.319746)
			(xy 119.893802 -401.312605) (xy 119.900313 -401.295411) (xy 119.9007 -401.286218) (xy 119.9007 -400.793966)
			(xy 119.900306 -400.784777) (xy 119.893781 -400.767593) (xy 119.888 -400.760438) (xy 119.866142 -400.734768)
			(xy 119.828053 -400.679134) (xy 119.796902 -400.619339) (xy 119.773138 -400.556242) (xy 119.757102 -400.490754)
			(xy 119.749025 -400.423816) (xy 119.749025 -400.356393) (xy 119.7571 -400.289455) (xy 119.773135 -400.223966)
			(xy 119.796898 -400.16087) (xy 119.828048 -400.101074) (xy 119.866136 -400.045439) (xy 119.888 -400.019774)
			(xy 119.89379 -400.012624) (xy 119.900309 -399.995437) (xy 119.9007 -399.986246) (xy 119.9007 -399.828766)
			(xy 119.901197 -399.818642) (xy 119.908929 -399.799928) (xy 119.923211 -399.785574) (xy 119.941887 -399.777749)
			(xy 119.952008 -399.777204) (xy 120.668288 -399.777204) (xy 120.67841 -399.777626) (xy 120.697114 -399.785371)
			(xy 120.711429 -399.799686) (xy 120.719174 -399.81839) (xy 120.719596 -399.828512) (xy 120.719596 -399.986246)
			(xy 120.720033 -399.99543) (xy 120.726528 -400.012615) (xy 120.732296 -400.019774) (xy 120.754166 -400.045434)
			(xy 120.792255 -400.101069) (xy 120.823405 -400.160866) (xy 120.847169 -400.223964) (xy 120.863205 -400.289454)
			(xy 120.87128 -400.356392) (xy 120.87128 -400.423817) (xy 120.863203 -400.490755) (xy 120.847167 -400.556245)
			(xy 120.823402 -400.619342) (xy 120.79225 -400.679138) (xy 120.75416 -400.734773) (xy 120.732296 -400.760438)
			(xy 120.7265 -400.767584) (xy 120.719985 -400.784774) (xy 120.719596 -400.793966) (xy 120.719596 -401.286218)
			(xy 120.719998 -401.295406) (xy 120.726517 -401.31259) (xy 120.732296 -401.319746) (xy 120.754138 -401.345429)
			(xy 120.792228 -401.401061) (xy 120.82338 -401.460855) (xy 120.847146 -401.523949) (xy 120.863183 -401.589436)
			(xy 120.87126 -401.656372) (xy 120.871262 -401.723794) (xy 120.863189 -401.790731) (xy 120.847155 -401.856219)
			(xy 120.823394 -401.919315) (xy 120.792245 -401.979111) (xy 120.754159 -402.034745) (xy 120.732296 -402.06041)
			(xy 120.726512 -402.067564) (xy 120.71999 -402.084748) (xy 120.719596 -402.093938) (xy 120.719596 -402.251418)
			(xy 120.719089 -402.261541) (xy 120.711362 -402.280256) (xy 120.697083 -402.294611) (xy 120.678409 -402.302436)
			(xy 120.668288 -402.30298) (xy 119.952008 -402.30298) (xy 119.941884 -402.302577) (xy 119.923176 -402.294828)
			(xy 119.908861 -402.280507) (xy 119.901119 -402.261797) (xy 119.9007 -402.251672) (xy 119.9007 -402.093938)
			(xy 119.900272 -402.084753) (xy 119.893771 -402.067568) (xy 119.888 -402.06041) (xy 119.866114 -402.034763)
			(xy 119.828026 -401.979126) (xy 119.796877 -401.919327) (xy 119.773114 -401.856228) (xy 119.75708 -401.790736)
			(xy 119.749006 -401.723796) (xy 118.620974 -401.723796) (xy 118.592102 -401.779215) (xy 118.554013 -401.834848)
			(xy 118.532148 -401.860512) (xy 118.526357 -401.867661) (xy 118.519841 -401.884849) (xy 118.519448 -401.89404)
			(xy 118.519448 -402.386292) (xy 118.519874 -402.395477) (xy 118.526378 -402.412661) (xy 118.532148 -402.41982)
			(xy 118.553967 -402.445523) (xy 118.59206 -402.501151) (xy 118.623216 -402.560942) (xy 118.646985 -402.624034)
			(xy 118.663025 -402.689519) (xy 118.671106 -402.756454) (xy 118.67111 -402.823818) (xy 121.949146 -402.823818)
			(xy 121.94915 -402.756509) (xy 121.957199 -402.689684) (xy 121.973177 -402.624299) (xy 121.996856 -402.561292)
			(xy 122.027895 -402.501567) (xy 122.065849 -402.44598) (xy 122.08764 -402.420328) (xy 122.093455 -402.413196)
			(xy 122.099958 -402.395995) (xy 122.10034 -402.3868) (xy 122.10034 -401.893532) (xy 122.099905 -401.884348)
			(xy 122.093408 -401.867164) (xy 122.08764 -401.860004) (xy 122.065832 -401.834368) (xy 122.027884 -401.778779)
			(xy 121.996852 -401.719054) (xy 121.97318 -401.656047) (xy 121.957208 -401.590663) (xy 121.949166 -401.523838)
			(xy 121.949168 -401.456532) (xy 121.957214 -401.389708) (xy 121.973189 -401.324324) (xy 121.996864 -401.261319)
			(xy 122.0279 -401.201595) (xy 122.065851 -401.146008) (xy 122.08764 -401.120356) (xy 122.093443 -401.113215)
			(xy 122.099953 -401.096021) (xy 122.10034 -401.086828) (xy 122.10034 -400.92884) (xy 122.10075 -400.918715)
			(xy 122.108492 -400.900005) (xy 122.122812 -400.885688) (xy 122.141523 -400.877948) (xy 122.151648 -400.877532)
			(xy 122.868182 -400.877532) (xy 122.878307 -400.878041) (xy 122.897026 -400.885761) (xy 122.911383 -400.900041)
			(xy 122.919204 -400.918718) (xy 122.919744 -400.92884) (xy 122.919744 -401.086828) (xy 122.920153 -401.096015)
			(xy 122.926669 -401.113199) (xy 122.932444 -401.120356) (xy 122.954212 -401.146024) (xy 122.992163 -401.201608)
			(xy 123.023198 -401.261329) (xy 123.046873 -401.324332) (xy 123.062848 -401.389712) (xy 123.070894 -401.456533)
			(xy 123.070895 -401.523837) (xy 123.062853 -401.590658) (xy 123.046882 -401.65604) (xy 123.02321 -401.719043)
			(xy 123.020771 -401.723737) (xy 124.149301 -401.723737) (xy 124.149303 -401.65643) (xy 124.15735 -401.589605)
			(xy 124.173327 -401.524221) (xy 124.197004 -401.461215) (xy 124.228043 -401.401491) (xy 124.265997 -401.345906)
			(xy 124.287788 -401.320254) (xy 124.293585 -401.313109) (xy 124.3001 -401.295918) (xy 124.300488 -401.286726)
			(xy 124.300488 -400.793458) (xy 124.300101 -400.784268) (xy 124.293572 -400.767084) (xy 124.287788 -400.75993)
			(xy 124.266005 -400.734274) (xy 124.228052 -400.678689) (xy 124.197016 -400.618966) (xy 124.173341 -400.555962)
			(xy 124.157366 -400.49058) (xy 124.149321 -400.423757) (xy 124.14932 -400.356452) (xy 124.157365 -400.289629)
			(xy 124.173338 -400.224246) (xy 124.197013 -400.161242) (xy 124.228048 -400.101519) (xy 124.265999 -400.045933)
			(xy 124.287788 -400.020282) (xy 124.293573 -400.013129) (xy 124.300095 -399.995944) (xy 124.300488 -399.986754)
			(xy 124.300488 -399.828766) (xy 124.300837 -399.818586) (xy 124.308643 -399.799781) (xy 124.323052 -399.785395)
			(xy 124.341869 -399.777621) (xy 124.35205 -399.777204) (xy 125.06833 -399.777204) (xy 125.078486 -399.777708)
			(xy 125.097249 -399.785486) (xy 125.111612 -399.799848) (xy 125.119391 -399.818611) (xy 125.119892 -399.828766)
			(xy 125.119892 -399.986754) (xy 125.120326 -399.995939) (xy 125.126823 -400.013123) (xy 125.132592 -400.020282)
			(xy 125.154385 -400.04593) (xy 125.192331 -400.101518) (xy 125.223363 -400.161242) (xy 125.247034 -400.224247)
			(xy 125.263005 -400.289629) (xy 125.271049 -400.356452) (xy 125.271048 -400.423757) (xy 125.263004 -400.490579)
			(xy 125.247031 -400.555962) (xy 125.223359 -400.618966) (xy 125.192327 -400.67869) (xy 125.154379 -400.734277)
			(xy 125.132592 -400.75993) (xy 125.126799 -400.767078) (xy 125.120283 -400.784266) (xy 125.119892 -400.793458)
			(xy 125.119892 -401.286726) (xy 125.120291 -401.295914) (xy 125.126813 -401.313099) (xy 125.132592 -401.320254)
			(xy 125.154357 -401.345924) (xy 125.192305 -401.401509) (xy 125.223337 -401.46123) (xy 125.24701 -401.524232)
			(xy 125.262983 -401.589612) (xy 125.271029 -401.656432) (xy 125.271031 -401.723735) (xy 125.262989 -401.790555)
			(xy 125.24702 -401.855936) (xy 125.223351 -401.918939) (xy 125.192322 -401.978663) (xy 125.154377 -402.034249)
			(xy 125.132592 -402.059902) (xy 125.126811 -402.067058) (xy 125.120287 -402.08424) (xy 125.119892 -402.09343)
			(xy 125.119892 -402.251418) (xy 125.119382 -402.261573) (xy 125.111608 -402.280337) (xy 125.097247 -402.294701)
			(xy 125.078485 -402.30248) (xy 125.06833 -402.30298) (xy 124.35205 -402.30298) (xy 124.341884 -402.302496)
			(xy 124.323094 -402.29473) (xy 124.308708 -402.280363) (xy 124.300918 -402.261584) (xy 124.300488 -402.251418)
			(xy 124.300488 -402.09343) (xy 124.300066 -402.084244) (xy 124.293561 -402.067059) (xy 124.287788 -402.059902)
			(xy 124.265977 -402.034268) (xy 124.228026 -401.97868) (xy 124.196991 -401.918955) (xy 124.173317 -401.855948)
			(xy 124.157344 -401.790563) (xy 124.149301 -401.723737) (xy 123.020771 -401.723737) (xy 122.992178 -401.778766)
			(xy 122.954231 -401.834352) (xy 122.932444 -401.860004) (xy 122.926656 -401.867155) (xy 122.920138 -401.884341)
			(xy 122.919744 -401.893532) (xy 122.919744 -402.3868) (xy 122.920167 -402.395986) (xy 122.926673 -402.413169)
			(xy 122.932444 -402.420328) (xy 122.954185 -402.446019) (xy 122.992136 -402.501599) (xy 123.023173 -402.561317)
			(xy 123.046849 -402.624317) (xy 123.062826 -402.689695) (xy 123.070874 -402.756513) (xy 123.070878 -402.823815)
			(xy 123.07087 -402.823878) (xy 126.348914 -402.823878) (xy 126.348919 -402.75645) (xy 126.357 -402.689508)
			(xy 126.373042 -402.624016) (xy 126.396813 -402.560916) (xy 126.427971 -402.501119) (xy 126.466068 -402.445485)
			(xy 126.487936 -402.41982) (xy 126.493754 -402.41269) (xy 126.500255 -402.395488) (xy 126.500636 -402.386292)
			(xy 126.500636 -401.89404) (xy 126.500198 -401.884856) (xy 126.493703 -401.867672) (xy 126.487936 -401.860512)
			(xy 126.466051 -401.834864) (xy 126.427961 -401.779227) (xy 126.396809 -401.719429) (xy 126.373044 -401.65633)
			(xy 126.357009 -401.590839) (xy 126.348934 -401.523898) (xy 126.348936 -401.456472) (xy 126.357014 -401.389532)
			(xy 126.373053 -401.324041) (xy 126.396821 -401.260943) (xy 126.427976 -401.201147) (xy 126.46607 -401.145513)
			(xy 126.487936 -401.119848) (xy 126.493742 -401.112709) (xy 126.50025 -401.095514) (xy 126.500636 -401.08632)
			(xy 126.500636 -400.92884) (xy 126.50105 -400.918716) (xy 126.508791 -400.900006) (xy 126.523109 -400.885689)
			(xy 126.54182 -400.877949) (xy 126.551944 -400.877532) (xy 127.268224 -400.877532) (xy 127.278352 -400.877897)
			(xy 127.297062 -400.885659) (xy 127.311377 -400.899991) (xy 127.319116 -400.918711) (xy 127.319532 -400.92884)
			(xy 127.319532 -401.08632) (xy 127.319948 -401.095506) (xy 127.326459 -401.11269) (xy 127.332232 -401.119848)
			(xy 127.354075 -401.14553) (xy 127.392162 -401.201163) (xy 127.423312 -401.260957) (xy 127.447076 -401.324052)
			(xy 127.463112 -401.389538) (xy 127.471189 -401.456474) (xy 127.471191 -401.523896) (xy 127.463117 -401.590832)
			(xy 127.447085 -401.65632) (xy 127.423324 -401.719415) (xy 127.421073 -401.723737) (xy 128.549092 -401.723737)
			(xy 128.549094 -401.65643) (xy 128.557141 -401.589605) (xy 128.573117 -401.524221) (xy 128.596794 -401.461216)
			(xy 128.627832 -401.401492) (xy 128.665786 -401.345906) (xy 128.687576 -401.320254) (xy 128.693372 -401.313108)
			(xy 128.699888 -401.295918) (xy 128.700276 -401.286726) (xy 128.700276 -400.793458) (xy 128.699891 -400.784268)
			(xy 128.69336 -400.767084) (xy 128.687576 -400.75993) (xy 128.665793 -400.734273) (xy 128.627842 -400.678688)
			(xy 128.596806 -400.618966) (xy 128.573131 -400.555962) (xy 128.557157 -400.49058) (xy 128.549112 -400.423757)
			(xy 128.549111 -400.356452) (xy 128.557155 -400.289629) (xy 128.573129 -400.224247) (xy 128.596802 -400.161242)
			(xy 128.627837 -400.101519) (xy 128.665788 -400.045934) (xy 128.687576 -400.020282) (xy 128.69336 -400.013128)
			(xy 128.699883 -399.995944) (xy 128.700276 -399.986754) (xy 128.700276 -399.828766) (xy 128.700637 -399.818587)
			(xy 128.70844 -399.799785) (xy 128.722845 -399.7854) (xy 128.741659 -399.777623) (xy 128.751838 -399.777204)
			(xy 129.468118 -399.777204) (xy 129.478273 -399.777718) (xy 129.497036 -399.785492) (xy 129.511399 -399.799851)
			(xy 129.519179 -399.818611) (xy 129.51968 -399.828766) (xy 129.51968 -399.986754) (xy 129.520117 -399.995938)
			(xy 129.526612 -400.013123) (xy 129.53238 -400.020282) (xy 129.554173 -400.045929) (xy 129.592121 -400.101517)
			(xy 129.623152 -400.161241) (xy 129.646824 -400.224247) (xy 129.662796 -400.289629) (xy 129.670839 -400.356452)
			(xy 129.670839 -400.423757) (xy 129.662794 -400.49058) (xy 129.646821 -400.555962) (xy 129.623149 -400.618967)
			(xy 129.592116 -400.678691) (xy 129.554168 -400.734278) (xy 129.53238 -400.75993) (xy 129.526586 -400.767077)
			(xy 129.52007 -400.784266) (xy 129.51968 -400.793458) (xy 129.51968 -401.286726) (xy 129.520082 -401.295914)
			(xy 129.526602 -401.313098) (xy 129.53238 -401.320254) (xy 129.554146 -401.345924) (xy 129.592094 -401.401508)
			(xy 129.623127 -401.46123) (xy 129.6468 -401.524232) (xy 129.662774 -401.589612) (xy 129.67082 -401.656432)
			(xy 129.670822 -401.723735) (xy 129.66278 -401.790556) (xy 129.64681 -401.855937) (xy 129.623141 -401.91894)
			(xy 129.592111 -401.978663) (xy 129.554166 -402.03425) (xy 129.53238 -402.059902) (xy 129.526598 -402.067057)
			(xy 129.520075 -402.08424) (xy 129.51968 -402.09343) (xy 129.51968 -402.251418) (xy 129.519182 -402.261575)
			(xy 129.511405 -402.280341) (xy 129.497041 -402.294705) (xy 129.478275 -402.302482) (xy 129.468118 -402.30298)
			(xy 128.751838 -402.30298) (xy 128.741671 -402.302505) (xy 128.722881 -402.294736) (xy 128.708495 -402.280366)
			(xy 128.700706 -402.261584) (xy 128.700276 -402.251418) (xy 128.700276 -402.09343) (xy 128.699857 -402.084244)
			(xy 128.69335 -402.067059) (xy 128.687576 -402.059902) (xy 128.665766 -402.034268) (xy 128.627815 -401.97868)
			(xy 128.596781 -401.918954) (xy 128.573108 -401.855947) (xy 128.557135 -401.790562) (xy 128.549092 -401.723737)
			(xy 127.421073 -401.723737) (xy 127.392178 -401.779211) (xy 127.354094 -401.834846) (xy 127.332232 -401.860512)
			(xy 127.32644 -401.86766) (xy 127.319924 -401.884849) (xy 127.319532 -401.89404) (xy 127.319532 -402.386292)
			(xy 127.319961 -402.395477) (xy 127.326463 -402.412661) (xy 127.332232 -402.41982) (xy 127.354048 -402.445525)
			(xy 127.392136 -402.501154) (xy 127.423287 -402.560945) (xy 127.447052 -402.624037) (xy 127.46309 -402.689521)
			(xy 127.471169 -402.756454) (xy 127.471174 -402.823818) (xy 130.749234 -402.823818) (xy 130.749238 -402.75651)
			(xy 130.757287 -402.689684) (xy 130.773265 -402.624299) (xy 130.796942 -402.561293) (xy 130.82798 -402.501568)
			(xy 130.865934 -402.44598) (xy 130.887724 -402.420328) (xy 130.893536 -402.413194) (xy 130.900041 -402.395995)
			(xy 130.900424 -402.3868) (xy 130.900424 -401.893532) (xy 130.899993 -401.884347) (xy 130.893493 -401.867163)
			(xy 130.887724 -401.860004) (xy 130.865917 -401.834368) (xy 130.82797 -401.778779) (xy 130.796938 -401.719053)
			(xy 130.773267 -401.656046) (xy 130.757296 -401.590662) (xy 130.749254 -401.523838) (xy 130.749256 -401.456532)
			(xy 130.757301 -401.389708) (xy 130.773276 -401.324325) (xy 130.79695 -401.26132) (xy 130.827985 -401.201595)
			(xy 130.865935 -401.146008) (xy 130.887724 -401.120356) (xy 130.893525 -401.113214) (xy 130.900036 -401.096021)
			(xy 130.900424 -401.086828) (xy 130.900424 -400.92884) (xy 130.900855 -400.918686) (xy 130.908642 -400.899929)
			(xy 130.923036 -400.885604) (xy 130.94183 -400.877907) (xy 130.951986 -400.877532) (xy 131.668266 -400.877532)
			(xy 131.67839 -400.878054) (xy 131.697108 -400.88577) (xy 131.711465 -400.900045) (xy 131.719287 -400.918719)
			(xy 131.719828 -400.92884) (xy 131.719828 -401.086828) (xy 131.720218 -401.096017) (xy 131.726745 -401.113202)
			(xy 131.732528 -401.120356) (xy 131.754297 -401.146024) (xy 131.792249 -401.201607) (xy 131.823285 -401.261328)
			(xy 131.84696 -401.324331) (xy 131.862935 -401.389712) (xy 131.870981 -401.456533) (xy 131.870983 -401.523837)
			(xy 131.862941 -401.590659) (xy 131.846969 -401.65604) (xy 131.823297 -401.719044) (xy 131.792264 -401.778767)
			(xy 131.754315 -401.834352) (xy 131.732528 -401.860004) (xy 131.726738 -401.867154) (xy 131.720222 -401.884341)
			(xy 131.719828 -401.893532) (xy 131.719828 -402.3868) (xy 131.720232 -402.395988) (xy 131.726749 -402.413173)
			(xy 131.732528 -402.420328) (xy 131.75427 -402.446019) (xy 131.792222 -402.501599) (xy 131.823259 -402.561317)
			(xy 131.846936 -402.624316) (xy 131.862913 -402.689694) (xy 131.870962 -402.756513) (xy 131.870966 -402.823815)
			(xy 131.862926 -402.890635) (xy 131.846957 -402.956015) (xy 131.823289 -403.019017) (xy 131.792259 -403.078739)
			(xy 131.754314 -403.134324) (xy 131.732528 -403.159976) (xy 131.726708 -403.167104) (xy 131.720209 -403.184308)
			(xy 131.719828 -403.193504) (xy 131.719828 -403.351492) (xy 131.719372 -403.361642) (xy 131.711585 -403.380389)
			(xy 131.697199 -403.394712) (xy 131.678418 -403.402417) (xy 131.668266 -403.4028) (xy 130.951986 -403.4028)
			(xy 130.941863 -403.402286) (xy 130.92315 -403.394561) (xy 130.908795 -403.380284) (xy 130.90097 -403.361612)
			(xy 130.900424 -403.351492) (xy 130.900424 -403.193504) (xy 130.900007 -403.184318) (xy 130.893498 -403.167133)
			(xy 130.887724 -403.159976) (xy 130.86589 -403.134362) (xy 130.827943 -403.07877) (xy 130.796913 -403.019041)
			(xy 130.773243 -402.956032) (xy 130.757274 -402.890645) (xy 130.749234 -402.823818) (xy 127.471174 -402.823818)
			(xy 127.471174 -402.823874) (xy 127.463103 -402.890808) (xy 127.447074 -402.956294) (xy 127.423316 -403.019389)
			(xy 127.392173 -403.079184) (xy 127.354092 -403.134818) (xy 127.332232 -403.160484) (xy 127.326409 -403.16761)
			(xy 127.319912 -403.184816) (xy 127.319532 -403.194012) (xy 127.319532 -403.351492) (xy 127.319009 -403.361596)
			(xy 127.31128 -403.380268) (xy 127.296995 -403.394562) (xy 127.278328 -403.402303) (xy 127.268224 -403.4028)
			(xy 126.551944 -403.4028) (xy 126.541824 -403.402348) (xy 126.523122 -403.394614) (xy 126.508806 -403.380308)
			(xy 126.501059 -403.361611) (xy 126.500636 -403.351492) (xy 126.500636 -403.194012) (xy 126.500212 -403.184826)
			(xy 126.493707 -403.167642) (xy 126.487936 -403.160484) (xy 126.466024 -403.134858) (xy 126.427934 -403.079219)
			(xy 126.396783 -403.019418) (xy 126.37302 -402.956315) (xy 126.356987 -402.890821) (xy 126.348914 -402.823878)
			(xy 123.07087 -402.823878) (xy 123.062839 -402.890634) (xy 123.04687 -402.956014) (xy 123.023202 -403.019017)
			(xy 122.992173 -403.078739) (xy 122.954229 -403.134324) (xy 122.932444 -403.159976) (xy 122.926626 -403.167106)
			(xy 122.920126 -403.184308) (xy 122.919744 -403.193504) (xy 122.919744 -403.351492) (xy 122.919209 -403.361595)
			(xy 122.911483 -403.380264) (xy 122.897201 -403.394558) (xy 122.878538 -403.402301) (xy 122.868436 -403.4028)
			(xy 122.151902 -403.4028) (xy 122.14178 -403.402273) (xy 122.123067 -403.394553) (xy 122.108712 -403.38028)
			(xy 122.100886 -403.361611) (xy 122.10034 -403.351492) (xy 122.10034 -403.193504) (xy 122.099919 -403.184318)
			(xy 122.093412 -403.167134) (xy 122.08764 -403.159976) (xy 122.065805 -403.134363) (xy 122.027857 -403.078771)
			(xy 121.996826 -403.019042) (xy 121.973156 -402.956032) (xy 121.957186 -402.890645) (xy 121.949146 -402.823818)
			(xy 118.67111 -402.823818) (xy 118.67111 -402.823874) (xy 118.663038 -402.89081) (xy 118.647006 -402.956297)
			(xy 118.623245 -403.019392) (xy 118.592097 -403.079187) (xy 118.554011 -403.13482) (xy 118.532148 -403.160484)
			(xy 118.526327 -403.167612) (xy 118.519828 -403.184816) (xy 118.519448 -403.194012) (xy 118.519448 -403.351492)
			(xy 118.51891 -403.361594) (xy 118.511183 -403.380263) (xy 118.496903 -403.394557) (xy 118.478242 -403.4023)
			(xy 118.46814 -403.4028) (xy 117.75186 -403.4028) (xy 117.741749 -403.402348) (xy 117.72307 -403.394597)
			(xy 117.708776 -403.38029) (xy 117.701043 -403.361604) (xy 117.700552 -403.351492) (xy 117.700552 -403.194012)
			(xy 117.700125 -403.184827) (xy 117.693622 -403.167643) (xy 117.687852 -403.160484) (xy 117.665939 -403.134859)
			(xy 117.627848 -403.07922) (xy 117.596697 -403.019418) (xy 117.572933 -402.956316) (xy 117.556899 -402.890822)
			(xy 117.548826 -402.823878) (xy 87.871055 -402.823878) (xy 87.862984 -402.890809) (xy 87.846954 -402.956295)
			(xy 87.823196 -403.01939) (xy 87.792051 -403.079185) (xy 87.753969 -403.134819) (xy 87.732108 -403.160484)
			(xy 87.726294 -403.167617) (xy 87.71979 -403.184817) (xy 87.719408 -403.194012) (xy 87.719408 -403.351492)
			(xy 87.718978 -403.361613) (xy 87.711234 -403.380315) (xy 87.696922 -403.394629) (xy 87.678221 -403.402376)
			(xy 87.6681 -403.4028) (xy 86.95182 -403.4028) (xy 86.941699 -403.402368) (xy 86.922996 -403.394626)
			(xy 86.908681 -403.380315) (xy 86.900935 -403.361613) (xy 86.900512 -403.351492) (xy 86.900512 -403.194012)
			(xy 86.900093 -403.184826) (xy 86.893585 -403.167642) (xy 86.887812 -403.160484) (xy 86.8659 -403.134858)
			(xy 86.827812 -403.079218) (xy 86.796663 -403.019417) (xy 86.772901 -402.956315) (xy 86.756869 -402.890821)
			(xy 86.748796 -402.823878) (xy 83.470752 -402.823878) (xy 83.46272 -402.890635) (xy 83.446751 -402.956015)
			(xy 83.423082 -403.019018) (xy 83.392052 -403.07874) (xy 83.354106 -403.134324) (xy 83.33232 -403.159976)
			(xy 83.326511 -403.167113) (xy 83.320003 -403.18431) (xy 83.31962 -403.193504) (xy 83.31962 -403.351492)
			(xy 83.319172 -403.361643) (xy 83.311383 -403.380391) (xy 83.296995 -403.394714) (xy 83.278211 -403.402418)
			(xy 83.268058 -403.4028) (xy 82.551778 -403.4028) (xy 82.541655 -403.402293) (xy 82.522941 -403.394565)
			(xy 82.508586 -403.380286) (xy 82.500761 -403.361613) (xy 82.500216 -403.351492) (xy 82.500216 -403.193504)
			(xy 82.4998 -403.184318) (xy 82.49329 -403.167133) (xy 82.487516 -403.159976) (xy 82.465682 -403.134362)
			(xy 82.427736 -403.07877) (xy 82.396706 -403.019041) (xy 82.373037 -402.956031) (xy 82.357068 -402.890645)
			(xy 82.349028 -402.823818) (xy 79.070968 -402.823818) (xy 79.070968 -402.823874) (xy 79.062897 -402.890808)
			(xy 79.046867 -402.956294) (xy 79.023109 -403.019389) (xy 78.991966 -403.079184) (xy 78.953884 -403.134818)
			(xy 78.932024 -403.160484) (xy 78.926212 -403.167618) (xy 78.919706 -403.184817) (xy 78.919324 -403.194012)
			(xy 78.919324 -403.351492) (xy 78.918809 -403.361597) (xy 78.911078 -403.380271) (xy 78.896791 -403.394565)
			(xy 78.878121 -403.402304) (xy 78.868016 -403.4028) (xy 78.151736 -403.4028) (xy 78.141616 -403.402354)
			(xy 78.122913 -403.394618) (xy 78.108598 -403.38031) (xy 78.100851 -403.361612) (xy 78.100428 -403.351492)
			(xy 78.100428 -403.194012) (xy 78.100006 -403.184826) (xy 78.0935 -403.167642) (xy 78.087728 -403.160484)
			(xy 78.065816 -403.134858) (xy 78.027727 -403.079219) (xy 77.996577 -403.019417) (xy 77.972814 -402.956315)
			(xy 77.956781 -402.890821) (xy 77.948708 -402.823878) (xy 74.670664 -402.823878) (xy 74.662632 -402.890635)
			(xy 74.646664 -402.956014) (xy 74.622995 -403.019017) (xy 74.591966 -403.078739) (xy 74.554022 -403.134324)
			(xy 74.532236 -403.159976) (xy 74.526417 -403.167105) (xy 74.519917 -403.184308) (xy 74.519536 -403.193504)
			(xy 74.519536 -403.351492) (xy 74.519073 -403.361641) (xy 74.511286 -403.380386) (xy 74.496903 -403.394709)
			(xy 74.478125 -403.402415) (xy 74.467974 -403.4028) (xy 73.751694 -403.4028) (xy 73.741572 -403.402279)
			(xy 73.722858 -403.394557) (xy 73.708504 -403.380282) (xy 73.700678 -403.361611) (xy 73.700132 -403.351492)
			(xy 73.700132 -403.193504) (xy 73.699713 -403.184318) (xy 73.693205 -403.167134) (xy 73.687432 -403.159976)
			(xy 73.665597 -403.134363) (xy 73.62765 -403.07877) (xy 73.59662 -403.019041) (xy 73.57295 -402.956032)
			(xy 73.55698 -402.890645) (xy 73.54894 -402.823818) (xy 66.525648 -402.823818) (xy 66.525648 -405.623707)
			(xy 71.348811 -405.623707) (xy 71.348811 -405.556283) (xy 71.356888 -405.489345) (xy 71.372924 -405.423856)
			(xy 71.396688 -405.360759) (xy 71.427839 -405.300962) (xy 71.465928 -405.245327) (xy 71.487792 -405.219662)
			(xy 71.493586 -405.212515) (xy 71.500103 -405.195326) (xy 71.500492 -405.186134) (xy 71.500492 -404.693882)
			(xy 71.500092 -404.684694) (xy 71.493571 -404.667509) (xy 71.487792 -404.660354) (xy 71.46595 -404.634671)
			(xy 71.427861 -404.579039) (xy 71.39671 -404.519245) (xy 71.372945 -404.45615) (xy 71.356908 -404.390664)
			(xy 71.348831 -404.323727) (xy 71.348829 -404.256306) (xy 71.356902 -404.189369) (xy 71.372935 -404.123881)
			(xy 71.396696 -404.060785) (xy 71.427844 -404.00099) (xy 71.46593 -403.945355) (xy 71.487792 -403.91969)
			(xy 71.493574 -403.912535) (xy 71.500098 -403.895352) (xy 71.500492 -403.886162) (xy 71.500492 -403.728682)
			(xy 71.50101 -403.71856) (xy 71.508735 -403.699847) (xy 71.523011 -403.685493) (xy 71.541681 -403.677666)
			(xy 71.5518 -403.67712) (xy 72.26808 -403.67712) (xy 72.278235 -403.677538) (xy 72.296991 -403.685331)
			(xy 72.311316 -403.699729) (xy 72.319013 -403.718525) (xy 72.319388 -403.728682) (xy 72.319388 -403.886162)
			(xy 72.319819 -403.895347) (xy 72.326319 -403.912531) (xy 72.332088 -403.91969) (xy 72.353974 -403.945337)
			(xy 72.392063 -404.000974) (xy 72.423213 -404.060773) (xy 72.446977 -404.123872) (xy 72.463011 -404.189363)
			(xy 72.471085 -404.256304) (xy 72.471083 -404.323729) (xy 72.463005 -404.390669) (xy 72.446967 -404.45616)
			(xy 72.4232 -404.519258) (xy 72.392046 -404.579054) (xy 72.353954 -404.634689) (xy 72.332088 -404.660354)
			(xy 72.326285 -404.667494) (xy 72.319774 -404.684689) (xy 72.319388 -404.693882) (xy 72.319388 -405.186134)
			(xy 72.319784 -405.195323) (xy 72.326308 -405.212507) (xy 72.332088 -405.219662) (xy 72.353946 -405.245332)
			(xy 72.392036 -405.300965) (xy 72.423188 -405.360761) (xy 72.446953 -405.423857) (xy 72.462989 -405.489346)
			(xy 72.471066 -405.556284) (xy 72.471066 -405.623707) (xy 72.462991 -405.690645) (xy 72.446956 -405.756134)
			(xy 72.423191 -405.819231) (xy 72.392041 -405.879027) (xy 72.353952 -405.934661) (xy 72.332088 -405.960326)
			(xy 72.326297 -405.967475) (xy 72.319779 -405.984663) (xy 72.319388 -405.993854) (xy 72.319388 -406.151334)
			(xy 72.318902 -406.161459) (xy 72.311168 -406.180176) (xy 72.296883 -406.19453) (xy 72.278203 -406.202353)
			(xy 72.26808 -406.202896) (xy 71.5518 -406.202896) (xy 71.541645 -406.202478) (xy 71.522892 -406.194682)
			(xy 71.508569 -406.180284) (xy 71.50087 -406.161491) (xy 71.500492 -406.151334) (xy 71.500492 -405.993854)
			(xy 71.500058 -405.984669) (xy 71.493561 -405.967485) (xy 71.487792 -405.960326) (xy 71.465922 -405.934665)
			(xy 71.427834 -405.87903) (xy 71.396684 -405.819233) (xy 71.372921 -405.756136) (xy 71.356886 -405.690646)
			(xy 71.348811 -405.623707) (xy 66.525648 -405.623707) (xy 66.525648 -406.72373) (xy 73.548951 -406.72373)
			(xy 73.548954 -406.656422) (xy 73.557001 -406.589598) (xy 73.572978 -406.524214) (xy 73.596654 -406.461208)
			(xy 73.62769 -406.401483) (xy 73.665642 -406.345896) (xy 73.687432 -406.320244) (xy 73.693239 -406.313106)
			(xy 73.699747 -406.29591) (xy 73.700132 -406.286716) (xy 73.700132 -405.793448) (xy 73.699691 -405.784264)
			(xy 73.693198 -405.76708) (xy 73.687432 -405.75992) (xy 73.66564 -405.734271) (xy 73.627692 -405.678684)
			(xy 73.596659 -405.61896) (xy 73.572987 -405.555955) (xy 73.557015 -405.490572) (xy 73.548971 -405.42375)
			(xy 73.548971 -405.356444) (xy 73.557016 -405.289622) (xy 73.572989 -405.224239) (xy 73.596662 -405.161235)
			(xy 73.627695 -405.101511) (xy 73.665644 -405.045924) (xy 73.687432 -405.020272) (xy 73.693227 -405.013126)
			(xy 73.699742 -404.995936) (xy 73.700132 -404.986744) (xy 73.700132 -404.828756) (xy 73.700486 -404.818595)
			(xy 73.708302 -404.799836) (xy 73.72272 -404.785513) (xy 73.74153 -404.77782) (xy 73.751694 -404.777448)
			(xy 74.467974 -404.777448) (xy 74.4781 -404.777948) (xy 74.496822 -404.785669) (xy 74.51118 -404.799951)
			(xy 74.518998 -404.818633) (xy 74.519536 -404.828756) (xy 74.519536 -404.986744) (xy 74.519939 -404.995932)
			(xy 74.526459 -405.013115) (xy 74.532236 -405.020272) (xy 74.55402 -405.045927) (xy 74.591971 -405.101513)
			(xy 74.623006 -405.161235) (xy 74.64668 -405.22424) (xy 74.662654 -405.289622) (xy 74.670699 -405.356444)
			(xy 74.670699 -405.42375) (xy 74.662655 -405.490572) (xy 74.646682 -405.555955) (xy 74.623008 -405.618959)
			(xy 74.620571 -405.623649) (xy 75.749106 -405.623649) (xy 75.749107 -405.556342) (xy 75.757152 -405.489519)
			(xy 75.773127 -405.424136) (xy 75.796802 -405.361131) (xy 75.827839 -405.301407) (xy 75.865791 -405.245822)
			(xy 75.88758 -405.22017) (xy 75.893369 -405.21302) (xy 75.899889 -405.195833) (xy 75.90028 -405.186642)
			(xy 75.90028 -404.693374) (xy 75.899887 -404.684185) (xy 75.893362 -404.667001) (xy 75.88758 -404.659846)
			(xy 75.865813 -404.634177) (xy 75.827861 -404.578594) (xy 75.796824 -404.518873) (xy 75.773148 -404.45587)
			(xy 75.757173 -404.39049) (xy 75.749126 -404.323669) (xy 75.749124 -404.256365) (xy 75.757167 -404.189543)
			(xy 75.773138 -404.124161) (xy 75.796811 -404.061157) (xy 75.827844 -404.001435) (xy 75.865792 -403.94585)
			(xy 75.88758 -403.920198) (xy 75.893358 -403.913039) (xy 75.899884 -403.895859) (xy 75.90028 -403.88667)
			(xy 75.90028 -403.728682) (xy 75.90065 -403.718504) (xy 75.908449 -403.699701) (xy 75.922851 -403.685315)
			(xy 75.941664 -403.677538) (xy 75.951842 -403.67712) (xy 76.668122 -403.67712) (xy 76.678279 -403.677615)
			(xy 76.697045 -403.685393) (xy 76.711409 -403.699758) (xy 76.719186 -403.718525) (xy 76.719684 -403.728682)
			(xy 76.719684 -403.88667) (xy 76.720112 -403.895855) (xy 76.726614 -403.91304) (xy 76.732384 -403.920198)
			(xy 76.754193 -403.945833) (xy 76.792139 -404.001422) (xy 76.82317 -404.061148) (xy 76.846841 -404.124155)
			(xy 76.862812 -404.189539) (xy 76.870854 -404.256363) (xy 76.870852 -404.32367) (xy 76.862806 -404.390493)
			(xy 76.846831 -404.455877) (xy 76.823157 -404.518882) (xy 76.792122 -404.578606) (xy 76.754172 -404.634194)
			(xy 76.732384 -404.659846) (xy 76.726584 -404.666988) (xy 76.720072 -404.684181) (xy 76.719684 -404.693374)
			(xy 76.719684 -405.186642) (xy 76.720077 -405.195831) (xy 76.726603 -405.213015) (xy 76.732384 -405.22017)
			(xy 76.754165 -405.245827) (xy 76.792113 -405.301414) (xy 76.823145 -405.361137) (xy 76.846817 -405.42414)
			(xy 76.86279 -405.489522) (xy 76.870834 -405.556343) (xy 76.870835 -405.623648) (xy 76.862791 -405.690469)
			(xy 76.84682 -405.755851) (xy 76.823149 -405.818855) (xy 76.792117 -405.878579) (xy 76.754171 -405.934166)
			(xy 76.732384 -405.959818) (xy 76.726595 -405.966969) (xy 76.720077 -405.984155) (xy 76.719684 -405.993346)
			(xy 76.719684 -406.151334) (xy 76.719195 -406.161491) (xy 76.711414 -406.180257) (xy 76.697047 -406.19462)
			(xy 76.678279 -406.202397) (xy 76.668122 -406.202896) (xy 75.951842 -406.202896) (xy 75.941677 -406.202403)
			(xy 75.92289 -406.194638) (xy 75.908505 -406.180274) (xy 75.900712 -406.161498) (xy 75.90028 -406.151334)
			(xy 75.90028 -405.993346) (xy 75.899852 -405.984161) (xy 75.893351 -405.966976) (xy 75.88758 -405.959818)
			(xy 75.865785 -405.934171) (xy 75.827834 -405.878585) (xy 75.796799 -405.818861) (xy 75.773124 -405.755856)
			(xy 75.757151 -405.690472) (xy 75.749106 -405.623649) (xy 74.620571 -405.623649) (xy 74.591974 -405.678682)
			(xy 74.554024 -405.734268) (xy 74.532236 -405.75992) (xy 74.526441 -405.767066) (xy 74.519927 -405.784256)
			(xy 74.519536 -405.793448) (xy 74.519536 -406.286716) (xy 74.519953 -406.295902) (xy 74.526464 -406.313086)
			(xy 74.532236 -406.320244) (xy 74.553993 -406.345922) (xy 74.591944 -406.401504) (xy 74.62298 -406.461224)
			(xy 74.646656 -406.524225) (xy 74.662632 -406.589604) (xy 74.670679 -406.656424) (xy 74.670682 -406.723727)
			(xy 74.670675 -406.723789) (xy 77.94872 -406.723789) (xy 77.948723 -406.656363) (xy 77.956802 -406.589422)
			(xy 77.972842 -406.52393) (xy 77.996611 -406.460832) (xy 78.027767 -406.401035) (xy 78.065861 -406.345401)
			(xy 78.087728 -406.319736) (xy 78.093538 -406.3126) (xy 78.100044 -406.295402) (xy 78.100428 -406.286208)
			(xy 78.100428 -405.793956) (xy 78.100033 -405.784767) (xy 78.093508 -405.767584) (xy 78.087728 -405.760428)
			(xy 78.065859 -405.734766) (xy 78.027769 -405.679132) (xy 77.996617 -405.619336) (xy 77.972851 -405.556238)
			(xy 77.956815 -405.490748) (xy 77.948739 -405.423809) (xy 77.94874 -405.356385) (xy 77.956816 -405.289446)
			(xy 77.972853 -405.223956) (xy 77.996619 -405.160859) (xy 78.027772 -405.101063) (xy 78.065863 -405.045429)
			(xy 78.087728 -405.019764) (xy 78.093526 -405.01262) (xy 78.100039 -404.995428) (xy 78.100428 -404.986236)
			(xy 78.100428 -404.828756) (xy 78.10085 -404.818641) (xy 78.108607 -404.799956) (xy 78.122924 -404.785662)
			(xy 78.14162 -404.777934) (xy 78.151736 -404.777448) (xy 78.868016 -404.777448) (xy 78.878119 -404.777971)
			(xy 78.896788 -404.785704) (xy 78.91108 -404.799989) (xy 78.918823 -404.818653) (xy 78.919324 -404.828756)
			(xy 78.919324 -404.986236) (xy 78.919712 -404.995426) (xy 78.92624 -405.01261) (xy 78.932024 -405.019764)
			(xy 78.953883 -405.045433) (xy 78.99197 -405.101067) (xy 79.02312 -405.160863) (xy 79.046883 -405.22396)
			(xy 79.062918 -405.289448) (xy 79.070994 -405.356386) (xy 79.070995 -405.423808) (xy 79.062919 -405.490746)
			(xy 79.046885 -405.556235) (xy 79.023122 -405.619331) (xy 79.020843 -405.623707) (xy 80.148899 -405.623707)
			(xy 80.148899 -405.556284) (xy 80.156975 -405.489345) (xy 80.173011 -405.423856) (xy 80.196775 -405.360759)
			(xy 80.227925 -405.300963) (xy 80.266013 -405.245328) (xy 80.287876 -405.219662) (xy 80.293668 -405.212514)
			(xy 80.300186 -405.195326) (xy 80.300576 -405.186134) (xy 80.300576 -404.693882) (xy 80.30018 -404.684693)
			(xy 80.293657 -404.667509) (xy 80.287876 -404.660354) (xy 80.266034 -404.634671) (xy 80.227947 -404.579038)
			(xy 80.196796 -404.519244) (xy 80.173032 -404.45615) (xy 80.156996 -404.390663) (xy 80.148918 -404.323727)
			(xy 80.148917 -404.256306) (xy 80.15699 -404.189369) (xy 80.173022 -404.123882) (xy 80.196783 -404.060786)
			(xy 80.22793 -404.00099) (xy 80.266014 -403.945356) (xy 80.287876 -403.91969) (xy 80.293657 -403.912533)
			(xy 80.300182 -403.895352) (xy 80.300576 -403.886162) (xy 80.300576 -403.728682) (xy 80.301013 -403.71855)
			(xy 80.308753 -403.699821) (xy 80.323055 -403.685464) (xy 80.341754 -403.677652) (xy 80.351884 -403.67712)
			(xy 81.068164 -403.67712) (xy 81.078318 -403.677552) (xy 81.097074 -403.685339) (xy 81.111399 -403.699733)
			(xy 81.119096 -403.718526) (xy 81.119472 -403.728682) (xy 81.119472 -403.886162) (xy 81.119907 -403.895346)
			(xy 81.126404 -403.912531) (xy 81.132172 -403.91969) (xy 81.154059 -403.945337) (xy 81.192148 -404.000973)
			(xy 81.2233 -404.060772) (xy 81.247064 -404.123871) (xy 81.263099 -404.189363) (xy 81.271173 -404.256304)
			(xy 81.271171 -404.32373) (xy 81.263093 -404.39067) (xy 81.247054 -404.45616) (xy 81.223286 -404.519258)
			(xy 81.192131 -404.579055) (xy 81.154038 -404.634689) (xy 81.132172 -404.660354) (xy 81.126366 -404.667493)
			(xy 81.119858 -404.684688) (xy 81.119472 -404.693882) (xy 81.119472 -405.186134) (xy 81.119872 -405.195322)
			(xy 81.126393 -405.212506) (xy 81.132172 -405.219662) (xy 81.154031 -405.245332) (xy 81.192122 -405.300965)
			(xy 81.223274 -405.36076) (xy 81.24704 -405.423857) (xy 81.263077 -405.489345) (xy 81.271154 -405.556284)
			(xy 81.271154 -405.623707) (xy 81.263078 -405.690646) (xy 81.247043 -405.756135) (xy 81.223278 -405.819232)
			(xy 81.192126 -405.879027) (xy 81.154037 -405.934661) (xy 81.132172 -405.960326) (xy 81.126378 -405.967473)
			(xy 81.119862 -405.984662) (xy 81.119472 -405.993854) (xy 81.119472 -406.151334) (xy 81.119002 -406.161461)
			(xy 81.111265 -406.180181) (xy 81.096974 -406.194536) (xy 81.078289 -406.202356) (xy 81.068164 -406.202896)
			(xy 80.351884 -406.202896) (xy 80.341728 -406.202492) (xy 80.322975 -406.19469) (xy 80.308652 -406.180288)
			(xy 80.300953 -406.161492) (xy 80.300576 -406.151334) (xy 80.300576 -405.993854) (xy 80.300145 -405.984669)
			(xy 80.293646 -405.967484) (xy 80.287876 -405.960326) (xy 80.266007 -405.934665) (xy 80.22792 -405.879029)
			(xy 80.196771 -405.819232) (xy 80.173008 -405.756135) (xy 80.156974 -405.690646) (xy 80.148899 -405.623707)
			(xy 79.020843 -405.623707) (xy 78.991974 -405.679127) (xy 78.953887 -405.734762) (xy 78.932024 -405.760428)
			(xy 78.926236 -405.767579) (xy 78.919715 -405.784765) (xy 78.919324 -405.793956) (xy 78.919324 -406.286208)
			(xy 78.919725 -406.295396) (xy 78.926244 -406.312581) (xy 78.932024 -406.319736) (xy 78.953856 -406.345428)
			(xy 78.991944 -406.401059) (xy 79.023095 -406.460852) (xy 79.046859 -406.523945) (xy 79.062896 -406.589431)
			(xy 79.070974 -406.656366) (xy 79.070977 -406.72373) (xy 82.349039 -406.72373) (xy 82.349042 -406.656422)
			(xy 82.357089 -406.589598) (xy 82.373065 -406.524214) (xy 82.39674 -406.461209) (xy 82.427776 -406.401484)
			(xy 82.465727 -406.345896) (xy 82.487516 -406.320244) (xy 82.493321 -406.313105) (xy 82.49983 -406.29591)
			(xy 82.500216 -406.286716) (xy 82.500216 -405.793448) (xy 82.499779 -405.784264) (xy 82.493284 -405.767079)
			(xy 82.487516 -405.75992) (xy 82.465725 -405.734271) (xy 82.427778 -405.678683) (xy 82.396746 -405.618959)
			(xy 82.373074 -405.555954) (xy 82.357102 -405.490572) (xy 82.349059 -405.423749) (xy 82.349059 -405.356445)
			(xy 82.357103 -405.289622) (xy 82.373076 -405.22424) (xy 82.396748 -405.161235) (xy 82.427781 -405.101511)
			(xy 82.465729 -405.045924) (xy 82.487516 -405.020272) (xy 82.493309 -405.013124) (xy 82.499825 -404.995936)
			(xy 82.500216 -404.986744) (xy 82.500216 -404.828756) (xy 82.500586 -404.818597) (xy 82.508399 -404.799841)
			(xy 82.522811 -404.785518) (xy 82.541617 -404.777823) (xy 82.551778 -404.777448) (xy 83.268058 -404.777448)
			(xy 83.278183 -404.777961) (xy 83.296905 -404.785677) (xy 83.311263 -404.799955) (xy 83.319082 -404.818634)
			(xy 83.31962 -404.828756) (xy 83.31962 -404.986744) (xy 83.320004 -404.995934) (xy 83.326535 -405.013118)
			(xy 83.33232 -405.020272) (xy 83.354105 -405.045927) (xy 83.392057 -405.101512) (xy 83.423092 -405.161235)
			(xy 83.446767 -405.224239) (xy 83.462742 -405.289621) (xy 83.470787 -405.356444) (xy 83.470787 -405.42375)
			(xy 83.462743 -405.490573) (xy 83.446769 -405.555955) (xy 83.423095 -405.61896) (xy 83.420628 -405.623707)
			(xy 84.54869 -405.623707) (xy 84.54869 -405.556284) (xy 84.556766 -405.489346) (xy 84.572801 -405.423857)
			(xy 84.596564 -405.36076) (xy 84.627714 -405.300963) (xy 84.665801 -405.245328) (xy 84.687664 -405.219662)
			(xy 84.693467 -405.212522) (xy 84.699976 -405.195327) (xy 84.700364 -405.186134) (xy 84.700364 -404.693882)
			(xy 84.699948 -404.684696) (xy 84.693437 -404.667512) (xy 84.687664 -404.660354) (xy 84.665823 -404.63467)
			(xy 84.627736 -404.579038) (xy 84.596586 -404.519244) (xy 84.572822 -404.456149) (xy 84.556787 -404.390663)
			(xy 84.548709 -404.323727) (xy 84.548707 -404.256306) (xy 84.556781 -404.18937) (xy 84.572813 -404.123882)
			(xy 84.596573 -404.060787) (xy 84.627719 -404.000991) (xy 84.665803 -403.945356) (xy 84.687664 -403.91969)
			(xy 84.693455 -403.912541) (xy 84.699971 -403.895353) (xy 84.700364 -403.886162) (xy 84.700364 -403.728682)
			(xy 84.700812 -403.718551) (xy 84.70855 -403.699825) (xy 84.722849 -403.685468) (xy 84.741543 -403.677654)
			(xy 84.751672 -403.67712) (xy 85.467952 -403.67712) (xy 85.478105 -403.677561) (xy 85.496861 -403.685345)
			(xy 85.511186 -403.699736) (xy 85.518884 -403.718527) (xy 85.51926 -403.728682) (xy 85.51926 -403.886162)
			(xy 85.519698 -403.895346) (xy 85.526193 -403.91253) (xy 85.53196 -403.91969) (xy 85.553847 -403.945337)
			(xy 85.591938 -404.000973) (xy 85.62309 -404.060771) (xy 85.646854 -404.123871) (xy 85.66289 -404.189362)
			(xy 85.670964 -404.256303) (xy 85.670962 -404.32373) (xy 85.662884 -404.39067) (xy 85.646845 -404.456161)
			(xy 85.623076 -404.519259) (xy 85.591921 -404.579055) (xy 85.553827 -404.634689) (xy 85.53196 -404.660354)
			(xy 85.526153 -404.667492) (xy 85.519646 -404.684688) (xy 85.51926 -404.693882) (xy 85.51926 -405.186134)
			(xy 85.519663 -405.195322) (xy 85.526183 -405.212506) (xy 85.53196 -405.219662) (xy 85.553819 -405.245331)
			(xy 85.591911 -405.300964) (xy 85.623064 -405.36076) (xy 85.64683 -405.423856) (xy 85.662868 -405.489345)
			(xy 85.670945 -405.556284) (xy 85.670945 -405.623707) (xy 85.662869 -405.690646) (xy 85.646833 -405.756135)
			(xy 85.623068 -405.819232) (xy 85.591916 -405.879028) (xy 85.553825 -405.934661) (xy 85.53196 -405.960326)
			(xy 85.526165 -405.967472) (xy 85.51965 -405.984662) (xy 85.51926 -405.993854) (xy 85.51926 -406.151334)
			(xy 85.518801 -406.161463) (xy 85.511062 -406.180185) (xy 85.496768 -406.19454) (xy 85.478079 -406.202358)
			(xy 85.467952 -406.202896) (xy 84.751672 -406.202896) (xy 84.741516 -406.202501) (xy 84.722762 -406.194696)
			(xy 84.708439 -406.180291) (xy 84.700741 -406.161493) (xy 84.700364 -406.151334) (xy 84.700364 -405.993854)
			(xy 84.699914 -405.984671) (xy 84.693426 -405.967487) (xy 84.687664 -405.960326) (xy 84.665795 -405.934665)
			(xy 84.627709 -405.879029) (xy 84.596561 -405.819232) (xy 84.572799 -405.756135) (xy 84.556765 -405.690645)
			(xy 84.54869 -405.623707) (xy 83.420628 -405.623707) (xy 83.39206 -405.678683) (xy 83.354109 -405.734268)
			(xy 83.33232 -405.75992) (xy 83.326535 -405.767073) (xy 83.320013 -405.784258) (xy 83.31962 -405.793448)
			(xy 83.31962 -406.286716) (xy 83.320018 -406.295905) (xy 83.32654 -406.313089) (xy 83.33232 -406.320244)
			(xy 83.354077 -406.345921) (xy 83.39203 -406.401503) (xy 83.423067 -406.461223) (xy 83.446743 -406.524224)
			(xy 83.46272 -406.589604) (xy 83.470767 -406.656424) (xy 83.47077 -406.723728) (xy 83.470763 -406.723789)
			(xy 86.748808 -406.723789) (xy 86.748811 -406.656363) (xy 86.75689 -406.589422) (xy 86.772929 -406.523931)
			(xy 86.796697 -406.460833) (xy 86.827852 -406.401036) (xy 86.865946 -406.345401) (xy 86.887812 -406.319736)
			(xy 86.89362 -406.312599) (xy 86.900127 -406.295402) (xy 86.900512 -406.286208) (xy 86.900512 -405.793956)
			(xy 86.90012 -405.784767) (xy 86.893594 -405.767583) (xy 86.887812 -405.760428) (xy 86.865944 -405.734766)
			(xy 86.827854 -405.679131) (xy 86.796703 -405.619335) (xy 86.772939 -405.556238) (xy 86.756903 -405.490748)
			(xy 86.748827 -405.423809) (xy 86.748828 -405.356385) (xy 86.756904 -405.289446) (xy 86.77294 -405.223957)
			(xy 86.796706 -405.16086) (xy 86.827857 -405.101063) (xy 86.865947 -405.045429) (xy 86.887812 -405.019764)
			(xy 86.893608 -405.012618) (xy 86.900123 -404.995428) (xy 86.900512 -404.986236) (xy 86.900512 -404.828756)
			(xy 86.900949 -404.818643) (xy 86.908704 -404.799961) (xy 86.923015 -404.785668) (xy 86.941706 -404.777937)
			(xy 86.95182 -404.777448) (xy 87.6681 -404.777448) (xy 87.678202 -404.777984) (xy 87.696871 -404.785712)
			(xy 87.711163 -404.799993) (xy 87.718907 -404.818654) (xy 87.719408 -404.828756) (xy 87.719408 -404.986236)
			(xy 87.719799 -404.995425) (xy 87.726326 -405.01261) (xy 87.732108 -405.019764) (xy 87.753968 -405.045433)
			(xy 87.792056 -405.101067) (xy 87.823206 -405.160863) (xy 87.846971 -405.223959) (xy 87.863006 -405.289448)
			(xy 87.871082 -405.356385) (xy 87.871082 -405.423809) (xy 87.863007 -405.490746) (xy 87.846972 -405.556235)
			(xy 87.823209 -405.619332) (xy 87.792059 -405.679128) (xy 87.753971 -405.734763) (xy 87.732108 -405.760428)
			(xy 87.726318 -405.767578) (xy 87.719799 -405.784765) (xy 87.719408 -405.793956) (xy 87.719408 -406.286208)
			(xy 87.719813 -406.295396) (xy 87.72633 -406.31258) (xy 87.732108 -406.319736) (xy 87.75394 -406.345427)
			(xy 87.792029 -406.401058) (xy 87.823181 -406.460851) (xy 87.846947 -406.523944) (xy 87.862984 -406.58943)
			(xy 87.871062 -406.656365) (xy 87.871065 -406.723729) (xy 91.149127 -406.723729) (xy 91.14913 -406.656423)
			(xy 91.157177 -406.589598) (xy 91.173152 -406.524215) (xy 91.196827 -406.461209) (xy 91.227861 -406.401484)
			(xy 91.265812 -406.345897) (xy 91.2876 -406.320244) (xy 91.293403 -406.313103) (xy 91.299914 -406.295909)
			(xy 91.3003 -406.286716) (xy 91.3003 -405.793448) (xy 91.299867 -405.784263) (xy 91.293369 -405.767079)
			(xy 91.2876 -405.75992) (xy 91.26581 -405.734271) (xy 91.227863 -405.678683) (xy 91.196832 -405.618958)
			(xy 91.173162 -405.555954) (xy 91.15719 -405.490572) (xy 91.149147 -405.423749) (xy 91.149147 -405.356445)
			(xy 91.157191 -405.289622) (xy 91.173163 -405.224241) (xy 91.196835 -405.161236) (xy 91.227866 -405.101512)
			(xy 91.265813 -405.045925) (xy 91.2876 -405.020272) (xy 91.293391 -405.013123) (xy 91.299909 -404.995935)
			(xy 91.3003 -404.986744) (xy 91.3003 -404.828756) (xy 91.300686 -404.818599) (xy 91.308496 -404.799846)
			(xy 91.322903 -404.785524) (xy 91.341703 -404.777826) (xy 91.351862 -404.777448) (xy 92.068142 -404.777448)
			(xy 92.078272 -404.777892) (xy 92.096996 -404.785635) (xy 92.111351 -404.799934) (xy 92.119167 -404.818628)
			(xy 92.119704 -404.828756) (xy 92.119704 -404.986744) (xy 92.120092 -404.995934) (xy 92.126621 -405.013118)
			(xy 92.132404 -405.020272) (xy 92.154186 -405.045928) (xy 92.192133 -405.101515) (xy 92.223164 -405.161238)
			(xy 92.246835 -405.224242) (xy 92.262807 -405.289624) (xy 92.270851 -405.356445) (xy 92.270851 -405.423749)
			(xy 92.262808 -405.490571) (xy 92.246837 -405.555952) (xy 92.223166 -405.618956) (xy 92.220728 -405.623648)
			(xy 115.349248 -405.623648) (xy 115.349249 -405.556343) (xy 115.357293 -405.489521) (xy 115.373266 -405.424139)
			(xy 115.396938 -405.361134) (xy 115.42797 -405.30141) (xy 115.465917 -405.245823) (xy 115.487704 -405.22017)
			(xy 115.493496 -405.213022) (xy 115.500013 -405.195834) (xy 115.500404 -405.186642) (xy 115.500404 -404.693374)
			(xy 115.500006 -404.684186) (xy 115.493484 -404.667001) (xy 115.487704 -404.659846) (xy 115.465939 -404.634176)
			(xy 115.427992 -404.578591) (xy 115.396959 -404.51887) (xy 115.373287 -404.455868) (xy 115.357314 -404.390488)
			(xy 115.349268 -404.323668) (xy 115.349266 -404.256365) (xy 115.357308 -404.189545) (xy 115.373277 -404.124164)
			(xy 115.396946 -404.061161) (xy 115.427975 -404.001437) (xy 115.465919 -403.945851) (xy 115.487704 -403.920198)
			(xy 115.493484 -403.913041) (xy 115.500009 -403.89586) (xy 115.500404 -403.88667) (xy 115.500404 -403.728682)
			(xy 115.500918 -403.718527) (xy 115.508692 -403.699764) (xy 115.523051 -403.685401) (xy 115.541811 -403.677621)
			(xy 115.551966 -403.67712) (xy 116.268246 -403.67712) (xy 116.278404 -403.677595) (xy 116.297171 -403.685382)
			(xy 116.311534 -403.699752) (xy 116.31931 -403.718523) (xy 116.319808 -403.728682) (xy 116.319808 -403.88667)
			(xy 116.320231 -403.895856) (xy 116.326735 -403.91304) (xy 116.332508 -403.920198) (xy 116.354319 -403.945832)
			(xy 116.392271 -404.00142) (xy 116.423306 -404.061145) (xy 116.44698 -404.124152) (xy 116.462953 -404.189537)
			(xy 116.470996 -404.256363) (xy 116.470994 -404.32367) (xy 116.462947 -404.390495) (xy 116.44697 -404.455879)
			(xy 116.423292 -404.518885) (xy 116.392254 -404.578609) (xy 116.354299 -404.634195) (xy 116.332508 -404.659846)
			(xy 116.32671 -404.66699) (xy 116.320196 -404.684181) (xy 116.319808 -404.693374) (xy 116.319808 -405.186642)
			(xy 116.320196 -405.195832) (xy 116.326725 -405.213016) (xy 116.332508 -405.22017) (xy 116.354291 -405.245826)
			(xy 116.392244 -405.301411) (xy 116.42328 -405.361133) (xy 116.446956 -405.424137) (xy 116.462931 -405.48952)
			(xy 116.470976 -405.556343) (xy 116.470977 -405.623648) (xy 116.462932 -405.690471) (xy 116.446958 -405.755854)
			(xy 116.423284 -405.818858) (xy 116.392249 -405.878581) (xy 116.354297 -405.934167) (xy 116.332508 -405.959818)
			(xy 116.326722 -405.966971) (xy 116.320201 -405.984155) (xy 116.319808 -405.993346) (xy 116.319808 -406.151334)
			(xy 116.319296 -406.161488) (xy 116.311519 -406.180249) (xy 116.297159 -406.194612) (xy 116.2784 -406.202393)
			(xy 116.268246 -406.202896) (xy 115.551966 -406.202896) (xy 115.54181 -406.202395) (xy 115.523047 -406.194616)
			(xy 115.508684 -406.180253) (xy 115.500905 -406.16149) (xy 115.500404 -406.151334) (xy 115.500404 -405.993346)
			(xy 115.499971 -405.984161) (xy 115.493473 -405.966977) (xy 115.487704 -405.959818) (xy 115.465911 -405.93417)
			(xy 115.427965 -405.878582) (xy 115.396934 -405.818858) (xy 115.373263 -405.755853) (xy 115.357292 -405.69047)
			(xy 115.349248 -405.623648) (xy 92.220728 -405.623648) (xy 92.192136 -405.67868) (xy 92.15419 -405.734267)
			(xy 92.132404 -405.75992) (xy 92.126617 -405.767072) (xy 92.120096 -405.784257) (xy 92.119704 -405.793448)
			(xy 92.119704 -406.286716) (xy 92.120106 -406.295904) (xy 92.126625 -406.313088) (xy 92.132404 -406.320244)
			(xy 92.154159 -406.345923) (xy 92.192106 -406.401506) (xy 92.223138 -406.461227) (xy 92.246811 -406.524228)
			(xy 92.262785 -406.589606) (xy 92.270831 -406.656425) (xy 92.270834 -406.723727) (xy 92.270826 -406.72379)
			(xy 117.548838 -406.72379) (xy 117.548841 -406.656362) (xy 117.55692 -406.589421) (xy 117.572961 -406.523929)
			(xy 117.596731 -406.460831) (xy 117.627888 -406.401034) (xy 117.665984 -406.3454) (xy 117.687852 -406.319736)
			(xy 117.693665 -406.312602) (xy 117.700168 -406.295403) (xy 117.700552 -406.286208) (xy 117.700552 -405.793956)
			(xy 117.700151 -405.784768) (xy 117.69363 -405.767585) (xy 117.687852 -405.760428) (xy 117.665982 -405.734767)
			(xy 117.62789 -405.679133) (xy 117.596737 -405.619337) (xy 117.572971 -405.556239) (xy 117.556934 -405.490749)
			(xy 117.548857 -405.42381) (xy 117.548858 -405.356384) (xy 117.556935 -405.289445) (xy 117.572972 -405.223955)
			(xy 117.596739 -405.160858) (xy 117.627893 -405.101062) (xy 117.665986 -405.045428) (xy 117.687852 -405.019764)
			(xy 117.693653 -405.012622) (xy 117.700164 -404.995429) (xy 117.700552 -404.986236) (xy 117.700552 -404.828756)
			(xy 117.701048 -404.81865) (xy 117.708791 -404.79998) (xy 117.723084 -404.785689) (xy 117.741754 -404.777947)
			(xy 117.75186 -404.777448) (xy 118.46814 -404.777448) (xy 118.478245 -404.777951) (xy 118.496914 -404.785692)
			(xy 118.511206 -404.799983) (xy 118.518948 -404.818651) (xy 118.519448 -404.828756) (xy 118.519448 -404.986236)
			(xy 118.519853 -404.995424) (xy 118.526372 -405.012607) (xy 118.532148 -405.019764) (xy 118.55401 -405.045432)
			(xy 118.592102 -405.101065) (xy 118.623256 -405.16086) (xy 118.647023 -405.223957) (xy 118.66306 -405.289446)
			(xy 118.671137 -405.356385) (xy 118.671137 -405.423809) (xy 118.663061 -405.490748) (xy 118.647024 -405.556238)
			(xy 118.623258 -405.619335) (xy 118.62098 -405.623708) (xy 119.749017 -405.623708) (xy 119.749017 -405.556283)
			(xy 119.757094 -405.489345) (xy 119.77313 -405.423855) (xy 119.796895 -405.360758) (xy 119.828046 -405.300962)
			(xy 119.866136 -405.245327) (xy 119.888 -405.219662) (xy 119.893795 -405.212516) (xy 119.900311 -405.195326)
			(xy 119.9007 -405.186134) (xy 119.9007 -404.693882) (xy 119.900298 -404.684694) (xy 119.893779 -404.66751)
			(xy 119.888 -404.660354) (xy 119.866158 -404.634671) (xy 119.828068 -404.579039) (xy 119.796917 -404.519245)
			(xy 119.773151 -404.456151) (xy 119.757114 -404.390664) (xy 119.749037 -404.323727) (xy 119.749035 -404.256306)
			(xy 119.757108 -404.189369) (xy 119.773141 -404.123881) (xy 119.796903 -404.060785) (xy 119.828051 -404.000989)
			(xy 119.866137 -403.945355) (xy 119.888 -403.91969) (xy 119.893783 -403.912535) (xy 119.900306 -403.895352)
			(xy 119.9007 -403.886162) (xy 119.9007 -403.728682) (xy 119.90121 -403.718559) (xy 119.908937 -403.699845)
			(xy 119.923215 -403.685491) (xy 119.941888 -403.677665) (xy 119.952008 -403.67712) (xy 120.668288 -403.67712)
			(xy 120.678412 -403.677526) (xy 120.697119 -403.685274) (xy 120.711435 -403.699594) (xy 120.719177 -403.718304)
			(xy 120.719596 -403.728428) (xy 120.719596 -403.886162) (xy 120.720025 -403.895347) (xy 120.726526 -403.912532)
			(xy 120.732296 -403.91969) (xy 120.754182 -403.945337) (xy 120.79227 -404.000974) (xy 120.82342 -404.060773)
			(xy 120.847183 -404.123872) (xy 120.863217 -404.189363) (xy 120.871291 -404.256304) (xy 120.871289 -404.323729)
			(xy 120.863211 -404.390669) (xy 120.847173 -404.456159) (xy 120.823407 -404.519257) (xy 120.792253 -404.579054)
			(xy 120.754161 -404.634689) (xy 120.732296 -404.660354) (xy 120.726494 -404.667495) (xy 120.719983 -404.684689)
			(xy 120.719596 -404.693882) (xy 120.719596 -405.186134) (xy 120.719991 -405.195323) (xy 120.726515 -405.212507)
			(xy 120.732296 -405.219662) (xy 120.754154 -405.245332) (xy 120.792243 -405.300966) (xy 120.823395 -405.360761)
			(xy 120.847159 -405.423858) (xy 120.863195 -405.489346) (xy 120.871272 -405.556284) (xy 120.871272 -405.623707)
			(xy 120.863197 -405.690645) (xy 120.847162 -405.756134) (xy 120.823398 -405.81923) (xy 120.792248 -405.879026)
			(xy 120.75416 -405.934661) (xy 120.732296 -405.960326) (xy 120.726505 -405.967475) (xy 120.719987 -405.984663)
			(xy 120.719596 -405.993854) (xy 120.719596 -406.151334) (xy 120.719102 -406.161458) (xy 120.71137 -406.180174)
			(xy 120.697087 -406.194527) (xy 120.67841 -406.202352) (xy 120.668288 -406.202896) (xy 119.952008 -406.202896)
			(xy 119.941886 -406.202477) (xy 119.923181 -406.194731) (xy 119.908867 -406.180415) (xy 119.901122 -406.16171)
			(xy 119.9007 -406.151588) (xy 119.9007 -405.993854) (xy 119.900264 -405.98467) (xy 119.893768 -405.967485)
			(xy 119.888 -405.960326) (xy 119.86613 -405.934666) (xy 119.828042 -405.87903) (xy 119.796891 -405.819234)
			(xy 119.773127 -405.756136) (xy 119.757092 -405.690646) (xy 119.749017 -405.623708) (xy 118.62098 -405.623708)
			(xy 118.592105 -405.67913) (xy 118.554014 -405.734764) (xy 118.532148 -405.760428) (xy 118.526351 -405.767572)
			(xy 118.519838 -405.784764) (xy 118.519448 -405.793956) (xy 118.519448 -406.286208) (xy 118.519866 -406.295394)
			(xy 118.526375 -406.312578) (xy 118.532148 -406.319736) (xy 118.553982 -406.345426) (xy 118.592075 -406.401056)
			(xy 118.62323 -406.460848) (xy 118.646999 -406.523942) (xy 118.663038 -406.589429) (xy 118.671117 -406.656365)
			(xy 118.67112 -406.72373) (xy 121.949157 -406.72373) (xy 121.94916 -406.656422) (xy 121.957208 -406.589597)
			(xy 121.973184 -406.524213) (xy 121.99686 -406.461207) (xy 122.027897 -406.401483) (xy 122.06585 -406.345896)
			(xy 122.08764 -406.320244) (xy 122.093448 -406.313107) (xy 122.099955 -406.29591) (xy 122.10034 -406.286716)
			(xy 122.10034 -405.793448) (xy 122.099898 -405.784264) (xy 122.093405 -405.76708) (xy 122.08764 -405.75992)
			(xy 122.065848 -405.734271) (xy 122.027899 -405.678684) (xy 121.996866 -405.61896) (xy 121.973194 -405.555955)
			(xy 121.957221 -405.490573) (xy 121.949177 -405.42375) (xy 121.949177 -405.356444) (xy 121.957222 -405.289621)
			(xy 121.973195 -405.224239) (xy 121.996869 -405.161234) (xy 122.027902 -405.101511) (xy 122.065852 -405.045924)
			(xy 122.08764 -405.020272) (xy 122.093436 -405.013127) (xy 122.09995 -404.995936) (xy 122.10034 -404.986744)
			(xy 122.10034 -404.828756) (xy 122.100681 -404.818626) (xy 122.108451 -404.799913) (xy 122.122791 -404.785599)
			(xy 122.141517 -404.777863) (xy 122.151648 -404.777448) (xy 122.868182 -404.777448) (xy 122.878309 -404.777941)
			(xy 122.897031 -404.785665) (xy 122.911388 -404.799949) (xy 122.919207 -404.818632) (xy 122.919744 -404.828756)
			(xy 122.919744 -404.986744) (xy 122.920145 -404.995932) (xy 122.926666 -405.013116) (xy 122.932444 -405.020272)
			(xy 122.954228 -405.045927) (xy 122.992178 -405.101513) (xy 123.023213 -405.161236) (xy 123.046886 -405.22424)
			(xy 123.06286 -405.289622) (xy 123.070905 -405.356444) (xy 123.070905 -405.42375) (xy 123.062861 -405.490572)
			(xy 123.046888 -405.555954) (xy 123.023215 -405.618959) (xy 123.020778 -405.623649) (xy 124.149312 -405.623649)
			(xy 124.149313 -405.556342) (xy 124.157358 -405.489518) (xy 124.173333 -405.424135) (xy 124.197009 -405.36113)
			(xy 124.228046 -405.301407) (xy 124.265998 -405.245822) (xy 124.287788 -405.22017) (xy 124.293578 -405.21302)
			(xy 124.300097 -405.195833) (xy 124.300488 -405.186642) (xy 124.300488 -404.693374) (xy 124.300093 -404.684185)
			(xy 124.293569 -404.667001) (xy 124.287788 -404.659846) (xy 124.26602 -404.634177) (xy 124.228068 -404.578594)
			(xy 124.197031 -404.518873) (xy 124.173355 -404.455871) (xy 124.157379 -404.39049) (xy 124.149332 -404.323669)
			(xy 124.14933 -404.256364) (xy 124.157373 -404.189542) (xy 124.173345 -404.124161) (xy 124.197017 -404.061157)
			(xy 124.228051 -404.001435) (xy 124.266 -403.945849) (xy 124.287788 -403.920198) (xy 124.293567 -403.91304)
			(xy 124.300092 -403.895859) (xy 124.300488 -403.88667) (xy 124.300488 -403.728682) (xy 124.30085 -403.718503)
			(xy 124.308651 -403.699698) (xy 124.323056 -403.685313) (xy 124.34187 -403.677537) (xy 124.35205 -403.67712)
			(xy 125.06833 -403.67712) (xy 125.078487 -403.677608) (xy 125.097254 -403.685389) (xy 125.111617 -403.699756)
			(xy 125.119394 -403.718524) (xy 125.119892 -403.728682) (xy 125.119892 -403.88667) (xy 125.120318 -403.895855)
			(xy 125.126821 -403.91304) (xy 125.132592 -403.920198) (xy 125.1544 -403.945833) (xy 125.192347 -404.001422)
			(xy 125.223377 -404.061149) (xy 125.247047 -404.124155) (xy 125.263018 -404.189539) (xy 125.27106 -404.256363)
			(xy 125.271058 -404.32367) (xy 125.263012 -404.390493) (xy 125.247038 -404.455876) (xy 125.223364 -404.518882)
			(xy 125.19233 -404.578606) (xy 125.15438 -404.634193) (xy 125.132592 -404.659846) (xy 125.126792 -404.666989)
			(xy 125.12028 -404.684181) (xy 125.119892 -404.693374) (xy 125.119892 -405.186642) (xy 125.120284 -405.195831)
			(xy 125.12681 -405.213015) (xy 125.132592 -405.22017) (xy 125.154373 -405.245827) (xy 125.19232 -405.301414)
			(xy 125.223352 -405.361137) (xy 125.247023 -405.424141) (xy 125.262996 -405.489522) (xy 125.27104 -405.556343)
			(xy 125.271041 -405.623647) (xy 125.262998 -405.690469) (xy 125.247026 -405.755851) (xy 125.223355 -405.818855)
			(xy 125.192325 -405.878578) (xy 125.154378 -405.934165) (xy 125.132592 -405.959818) (xy 125.126804 -405.96697)
			(xy 125.120285 -405.984155) (xy 125.119892 -405.993346) (xy 125.119892 -406.151334) (xy 125.119395 -406.16149)
			(xy 125.111615 -406.180254) (xy 125.097251 -406.194617) (xy 125.078486 -406.202396) (xy 125.06833 -406.202896)
			(xy 124.35205 -406.202896) (xy 124.341886 -406.202396) (xy 124.323099 -406.194634) (xy 124.308713 -406.180272)
			(xy 124.30092 -406.161497) (xy 124.300488 -406.151334) (xy 124.300488 -405.993346) (xy 124.300059 -405.984161)
			(xy 124.293559 -405.966976) (xy 124.287788 -405.959818) (xy 124.265993 -405.934171) (xy 124.228041 -405.878585)
			(xy 124.197005 -405.818861) (xy 124.173331 -405.755856) (xy 124.157357 -405.690473) (xy 124.149312 -405.623649)
			(xy 123.020778 -405.623649) (xy 122.992181 -405.678682) (xy 122.954232 -405.734268) (xy 122.932444 -405.75992)
			(xy 122.92665 -405.767066) (xy 122.920135 -405.784256) (xy 122.919744 -405.793448) (xy 122.919744 -406.286716)
			(xy 122.920159 -406.295902) (xy 122.926671 -406.313086) (xy 122.932444 -406.320244) (xy 122.954201 -406.345922)
			(xy 122.992152 -406.401504) (xy 123.023187 -406.461224) (xy 123.046862 -406.524225) (xy 123.062838 -406.589605)
			(xy 123.070885 -406.656425) (xy 123.070888 -406.723727) (xy 123.070881 -406.723789) (xy 126.348926 -406.723789)
			(xy 126.348929 -406.656363) (xy 126.357008 -406.589421) (xy 126.373048 -406.52393) (xy 126.396818 -406.460832)
			(xy 126.427974 -406.401035) (xy 126.466069 -406.345401) (xy 126.487936 -406.319736) (xy 126.493747 -406.312601)
			(xy 126.500252 -406.295403) (xy 126.500636 -406.286208) (xy 126.500636 -405.793956) (xy 126.500239 -405.784768)
			(xy 126.493715 -405.767584) (xy 126.487936 -405.760428) (xy 126.466067 -405.734767) (xy 126.427976 -405.679132)
			(xy 126.396823 -405.619336) (xy 126.373058 -405.556239) (xy 126.357022 -405.490749) (xy 126.348945 -405.423809)
			(xy 126.348946 -405.356385) (xy 126.357023 -405.289445) (xy 126.37306 -405.223956) (xy 126.396826 -405.160859)
			(xy 126.427979 -405.101062) (xy 126.466071 -405.045429) (xy 126.487936 -405.019764) (xy 126.493735 -405.012621)
			(xy 126.500247 -404.995429) (xy 126.500636 -404.986236) (xy 126.500636 -404.828756) (xy 126.50105 -404.81864)
			(xy 126.508809 -404.799954) (xy 126.523128 -404.785659) (xy 126.541827 -404.777933) (xy 126.551944 -404.777448)
			(xy 127.268224 -404.777448) (xy 127.278328 -404.777964) (xy 127.296997 -404.7857) (xy 127.311289 -404.799986)
			(xy 127.319032 -404.818652) (xy 127.319532 -404.828756) (xy 127.319532 -404.986236) (xy 127.31994 -404.995423)
			(xy 127.326457 -405.012607) (xy 127.332232 -405.019764) (xy 127.354091 -405.045433) (xy 127.392178 -405.101068)
			(xy 127.423327 -405.160864) (xy 127.44709 -405.22396) (xy 127.463125 -405.289448) (xy 127.4712 -405.356386)
			(xy 127.471201 -405.423808) (xy 127.463126 -405.490746) (xy 127.447092 -405.556234) (xy 127.423329 -405.619331)
			(xy 127.42108 -405.623649) (xy 128.549103 -405.623649) (xy 128.549104 -405.556342) (xy 128.557149 -405.489519)
			(xy 128.573124 -405.424136) (xy 128.596799 -405.361131) (xy 128.627835 -405.301407) (xy 128.665787 -405.245822)
			(xy 128.687576 -405.22017) (xy 128.693365 -405.213019) (xy 128.699885 -405.195833) (xy 128.700276 -405.186642)
			(xy 128.700276 -404.693374) (xy 128.699884 -404.684185) (xy 128.693358 -404.667) (xy 128.687576 -404.659846)
			(xy 128.665809 -404.634177) (xy 128.627857 -404.578593) (xy 128.596821 -404.518873) (xy 128.573145 -404.45587)
			(xy 128.557169 -404.39049) (xy 128.549123 -404.323669) (xy 128.549121 -404.256365) (xy 128.557164 -404.189543)
			(xy 128.573135 -404.124161) (xy 128.596807 -404.061158) (xy 128.62784 -404.001435) (xy 128.665789 -403.94585)
			(xy 128.687576 -403.920198) (xy 128.693353 -403.913039) (xy 128.69988 -403.895859) (xy 128.700276 -403.88667)
			(xy 128.700276 -403.728682) (xy 128.70065 -403.718505) (xy 128.708448 -403.699702) (xy 128.722849 -403.685317)
			(xy 128.74166 -403.677539) (xy 128.751838 -403.67712) (xy 129.468118 -403.67712) (xy 129.478275 -403.677618)
			(xy 129.497041 -403.685395) (xy 129.511405 -403.699759) (xy 129.519182 -403.718525) (xy 129.51968 -403.728682)
			(xy 129.51968 -403.88667) (xy 129.520109 -403.895855) (xy 129.52661 -403.913039) (xy 129.53238 -403.920198)
			(xy 129.554189 -403.945833) (xy 129.592136 -404.001422) (xy 129.623167 -404.061148) (xy 129.646838 -404.124155)
			(xy 129.662809 -404.189539) (xy 129.670851 -404.256363) (xy 129.670849 -404.32367) (xy 129.662803 -404.390494)
			(xy 129.646828 -404.455877) (xy 129.623154 -404.518882) (xy 129.592119 -404.578606) (xy 129.554169 -404.634194)
			(xy 129.53238 -404.659846) (xy 129.526579 -404.666988) (xy 129.520068 -404.684181) (xy 129.51968 -404.693374)
			(xy 129.51968 -405.186642) (xy 129.520074 -405.195831) (xy 129.5266 -405.213015) (xy 129.53238 -405.22017)
			(xy 129.554161 -405.245827) (xy 129.592109 -405.301413) (xy 129.623142 -405.361136) (xy 129.646814 -405.42414)
			(xy 129.662787 -405.489522) (xy 129.670831 -405.556343) (xy 129.670832 -405.623648) (xy 129.662788 -405.690469)
			(xy 129.646817 -405.755851) (xy 129.623145 -405.818855) (xy 129.592114 -405.878579) (xy 129.554167 -405.934166)
			(xy 129.53238 -405.959818) (xy 129.526591 -405.966968) (xy 129.520072 -405.984155) (xy 129.51968 -405.993346)
			(xy 129.51968 -406.151334) (xy 129.519195 -406.161492) (xy 129.511413 -406.180258) (xy 129.497045 -406.194622)
			(xy 129.478276 -406.202398) (xy 129.468118 -406.202896) (xy 128.751838 -406.202896) (xy 128.741673 -406.202406)
			(xy 128.722886 -406.19464) (xy 128.708501 -406.180275) (xy 128.700708 -406.161498) (xy 128.700276 -406.151334)
			(xy 128.700276 -405.993346) (xy 128.699849 -405.984161) (xy 128.693347 -405.966976) (xy 128.687576 -405.959818)
			(xy 128.665781 -405.934171) (xy 128.62783 -405.878585) (xy 128.596795 -405.818861) (xy 128.573121 -405.755856)
			(xy 128.557148 -405.690472) (xy 128.549103 -405.623649) (xy 127.42108 -405.623649) (xy 127.392181 -405.679127)
			(xy 127.354095 -405.734762) (xy 127.332232 -405.760428) (xy 127.326433 -405.767571) (xy 127.319922 -405.784763)
			(xy 127.319532 -405.793956) (xy 127.319532 -406.286208) (xy 127.319954 -406.295394) (xy 127.326461 -406.312577)
			(xy 127.332232 -406.319736) (xy 127.354063 -406.345428) (xy 127.392151 -406.401059) (xy 127.423301 -406.460852)
			(xy 127.447066 -406.523945) (xy 127.463103 -406.589431) (xy 127.471181 -406.656366) (xy 127.471183 -406.72373)
			(xy 130.749245 -406.72373) (xy 130.749248 -406.656422) (xy 130.757295 -406.589598) (xy 130.773271 -406.524214)
			(xy 130.796947 -406.461208) (xy 130.827983 -406.401484) (xy 130.865935 -406.345896) (xy 130.887724 -406.320244)
			(xy 130.89353 -406.313105) (xy 130.900038 -406.29591) (xy 130.900424 -406.286716) (xy 130.900424 -405.793448)
			(xy 130.899985 -405.784264) (xy 130.893491 -405.76708) (xy 130.887724 -405.75992) (xy 130.865933 -405.734271)
			(xy 130.827985 -405.678684) (xy 130.796953 -405.61896) (xy 130.773281 -405.555955) (xy 130.757309 -405.490572)
			(xy 130.749265 -405.42375) (xy 130.749265 -405.356444) (xy 130.75731 -405.289622) (xy 130.773283 -405.22424)
			(xy 130.796955 -405.161235) (xy 130.827988 -405.101511) (xy 130.865936 -405.045924) (xy 130.887724 -405.020272)
			(xy 130.893518 -405.013125) (xy 130.900033 -404.995936) (xy 130.900424 -404.986744) (xy 130.900424 -404.828756)
			(xy 130.900786 -404.818596) (xy 130.908601 -404.799838) (xy 130.923016 -404.785515) (xy 130.941823 -404.777822)
			(xy 130.951986 -404.777448) (xy 131.668266 -404.777448) (xy 131.678391 -404.777955) (xy 131.697113 -404.785673)
			(xy 131.711471 -404.799953) (xy 131.71929 -404.818633) (xy 131.719828 -404.828756) (xy 131.719828 -404.986744)
			(xy 131.720211 -404.995934) (xy 131.726743 -405.013119) (xy 131.732528 -405.020272) (xy 131.754313 -405.045927)
			(xy 131.792264 -405.101512) (xy 131.823299 -405.161235) (xy 131.846974 -405.224239) (xy 131.862948 -405.289622)
			(xy 131.870993 -405.356444) (xy 131.870993 -405.42375) (xy 131.862949 -405.490573) (xy 131.846975 -405.555955)
			(xy 131.823302 -405.618959) (xy 131.792267 -405.678683) (xy 131.754316 -405.734268) (xy 131.732528 -405.75992)
			(xy 131.726732 -405.767065) (xy 131.720219 -405.784256) (xy 131.719828 -405.793448) (xy 131.719828 -406.286716)
			(xy 131.720224 -406.295905) (xy 131.726747 -406.313089) (xy 131.732528 -406.320244) (xy 131.754285 -406.345922)
			(xy 131.792237 -406.401504) (xy 131.823274 -406.461223) (xy 131.84695 -406.524225) (xy 131.862926 -406.589604)
			(xy 131.870973 -406.656424) (xy 131.870976 -406.723728) (xy 131.862934 -406.790548) (xy 131.846964 -406.855929)
			(xy 131.823293 -406.918933) (xy 131.792262 -406.978655) (xy 131.754315 -407.03424) (xy 131.732528 -407.059892)
			(xy 131.726744 -407.067045) (xy 131.720224 -407.08423) (xy 131.719828 -407.09342) (xy 131.719828 -407.251408)
			(xy 131.719385 -407.261559) (xy 131.711592 -407.280306) (xy 131.697203 -407.294628) (xy 131.678419 -407.302333)
			(xy 131.668266 -407.302716) (xy 130.951986 -407.302716) (xy 130.941853 -407.302283) (xy 130.923123 -407.294543)
			(xy 130.908766 -407.28024) (xy 130.900955 -407.261539) (xy 130.900424 -407.251408) (xy 130.900424 -407.09342)
			(xy 130.899999 -407.084235) (xy 130.893495 -407.06705) (xy 130.887724 -407.059892) (xy 130.865905 -407.034266)
			(xy 130.827958 -406.978675) (xy 130.796927 -406.918948) (xy 130.773257 -406.85594) (xy 130.757287 -406.790555)
			(xy 130.749245 -406.72373) (xy 127.471183 -406.72373) (xy 127.471183 -406.723786) (xy 127.463111 -406.790722)
			(xy 127.44708 -406.856209) (xy 127.423321 -406.919304) (xy 127.392176 -406.9791) (xy 127.354093 -407.034734)
			(xy 127.332232 -407.0604) (xy 127.326445 -407.067551) (xy 127.319926 -407.084737) (xy 127.319532 -407.093928)
			(xy 127.319532 -407.251408) (xy 127.319022 -407.261513) (xy 127.311288 -407.280185) (xy 127.296999 -407.294479)
			(xy 127.278329 -407.302219) (xy 127.268224 -407.302716) (xy 126.551944 -407.302716) (xy 126.541826 -407.302248)
			(xy 126.523127 -407.294518) (xy 126.508812 -407.280217) (xy 126.501062 -407.261525) (xy 126.500636 -407.251408)
			(xy 126.500636 -407.093928) (xy 126.500204 -407.084743) (xy 126.493705 -407.067559) (xy 126.487936 -407.0604)
			(xy 126.466039 -407.034761) (xy 126.427949 -406.979124) (xy 126.396798 -406.919324) (xy 126.373034 -406.856224)
			(xy 126.357 -406.790731) (xy 126.348926 -406.723789) (xy 123.070881 -406.723789) (xy 123.062847 -406.790548)
			(xy 123.046877 -406.855929) (xy 123.023207 -406.918932) (xy 122.992176 -406.978654) (xy 122.95423 -407.03424)
			(xy 122.932444 -407.059892) (xy 122.926661 -407.067047) (xy 122.92014 -407.08423) (xy 122.919744 -407.09342)
			(xy 122.919744 -407.251408) (xy 122.919222 -407.261512) (xy 122.91149 -407.280182) (xy 122.897205 -407.294475)
			(xy 122.878539 -407.302217) (xy 122.868436 -407.302716) (xy 122.151902 -407.302716) (xy 122.14177 -407.30227)
			(xy 122.123041 -407.294535) (xy 122.108683 -407.280236) (xy 122.100871 -407.261538) (xy 122.10034 -407.251408)
			(xy 122.10034 -407.09342) (xy 122.099911 -407.084235) (xy 122.09341 -407.067051) (xy 122.08764 -407.059892)
			(xy 122.065821 -407.034266) (xy 122.027873 -406.978676) (xy 121.996841 -406.918949) (xy 121.97317 -406.855941)
			(xy 121.957199 -406.790555) (xy 121.949157 -406.72373) (xy 118.67112 -406.72373) (xy 118.67112 -406.723787)
			(xy 118.663047 -406.790724) (xy 118.647013 -406.856212) (xy 118.62325 -406.919308) (xy 118.5921 -406.979103)
			(xy 118.554012 -407.034736) (xy 118.532148 -407.0604) (xy 118.526362 -407.067553) (xy 118.519843 -407.084738)
			(xy 118.519448 -407.093928) (xy 118.519448 -407.251408) (xy 118.518922 -407.261511) (xy 118.511191 -407.28018)
			(xy 118.496907 -407.294473) (xy 118.478243 -407.302216) (xy 118.46814 -407.302716) (xy 117.75186 -407.302716)
			(xy 117.741751 -407.302248) (xy 117.723075 -407.2945) (xy 117.708782 -407.280198) (xy 117.701046 -407.261518)
			(xy 117.700552 -407.251408) (xy 117.700552 -407.093928) (xy 117.700117 -407.084744) (xy 117.693619 -407.06756)
			(xy 117.687852 -407.0604) (xy 117.665955 -407.034762) (xy 117.627864 -406.979124) (xy 117.596711 -406.919325)
			(xy 117.572947 -406.856225) (xy 117.556912 -406.790732) (xy 117.548838 -406.72379) (xy 92.270826 -406.72379)
			(xy 92.262793 -406.790546) (xy 92.246825 -406.855926) (xy 92.223158 -406.918929) (xy 92.192131 -406.978652)
			(xy 92.154188 -407.034239) (xy 92.132404 -407.059892) (xy 92.126629 -407.067052) (xy 92.120101 -407.084231)
			(xy 92.119704 -407.09342) (xy 92.119704 -407.251408) (xy 92.119285 -407.261562) (xy 92.111487 -407.280314)
			(xy 92.09709 -407.294637) (xy 92.078298 -407.302337) (xy 92.068142 -407.302716) (xy 91.351862 -407.302716)
			(xy 91.341727 -407.302303) (xy 91.322997 -407.294555) (xy 91.308641 -407.280246) (xy 91.30083 -407.261541)
			(xy 91.3003 -407.251408) (xy 91.3003 -407.09342) (xy 91.29988 -407.084234) (xy 91.293373 -407.067049)
			(xy 91.2876 -407.059892) (xy 91.265782 -407.034265) (xy 91.227837 -406.978674) (xy 91.196807 -406.918947)
			(xy 91.173138 -406.855939) (xy 91.157168 -406.790554) (xy 91.149127 -406.723729) (xy 87.871065 -406.723729)
			(xy 87.871065 -406.723786) (xy 87.862993 -406.790722) (xy 87.846961 -406.85621) (xy 87.823201 -406.919305)
			(xy 87.792054 -406.9791) (xy 87.75397 -407.034735) (xy 87.732108 -407.0604) (xy 87.72633 -407.067558)
			(xy 87.719804 -407.084739) (xy 87.719408 -407.093928) (xy 87.719408 -407.251408) (xy 87.718921 -407.261516)
			(xy 87.711183 -407.280193) (xy 87.696886 -407.294487) (xy 87.678208 -407.302223) (xy 87.6681 -407.302716)
			(xy 86.95182 -407.302716) (xy 86.941701 -407.302268) (xy 86.923001 -407.29453) (xy 86.908686 -407.280223)
			(xy 86.900937 -407.261527) (xy 86.900512 -407.251408) (xy 86.900512 -407.093928) (xy 86.900086 -407.084743)
			(xy 86.893583 -407.067558) (xy 86.887812 -407.0604) (xy 86.865916 -407.034761) (xy 86.827828 -406.979123)
			(xy 86.796678 -406.919323) (xy 86.772915 -406.856223) (xy 86.756881 -406.790731) (xy 86.748808 -406.723789)
			(xy 83.470763 -406.723789) (xy 83.462728 -406.790549) (xy 83.446757 -406.85593) (xy 83.423086 -406.918933)
			(xy 83.392055 -406.978655) (xy 83.354107 -407.03424) (xy 83.33232 -407.059892) (xy 83.326547 -407.067054)
			(xy 83.320017 -407.084231) (xy 83.31962 -407.09342) (xy 83.31962 -407.251408) (xy 83.319185 -407.26156)
			(xy 83.311391 -407.280309) (xy 83.296998 -407.294631) (xy 83.278212 -407.302334) (xy 83.268058 -407.302716)
			(xy 82.551778 -407.302716) (xy 82.541644 -407.30229) (xy 82.522914 -407.294547) (xy 82.508557 -407.280242)
			(xy 82.500747 -407.26154) (xy 82.500216 -407.251408) (xy 82.500216 -407.09342) (xy 82.499792 -407.084234)
			(xy 82.493288 -407.06705) (xy 82.487516 -407.059892) (xy 82.465698 -407.034265) (xy 82.427751 -406.978675)
			(xy 82.396721 -406.918947) (xy 82.373051 -406.85594) (xy 82.35708 -406.790555) (xy 82.349039 -406.72373)
			(xy 79.070977 -406.72373) (xy 79.070977 -406.723786) (xy 79.062905 -406.790722) (xy 79.046874 -406.856209)
			(xy 79.023114 -406.919304) (xy 78.991969 -406.9791) (xy 78.953885 -407.034734) (xy 78.932024 -407.0604)
			(xy 78.926248 -407.06756) (xy 78.91972 -407.084739) (xy 78.919324 -407.093928) (xy 78.919324 -407.251408)
			(xy 78.918822 -407.261514) (xy 78.911086 -407.280188) (xy 78.896795 -407.294482) (xy 78.878122 -407.30222)
			(xy 78.868016 -407.302716) (xy 78.151736 -407.302716) (xy 78.141618 -407.302255) (xy 78.122918 -407.294521)
			(xy 78.108603 -407.280219) (xy 78.100854 -407.261526) (xy 78.100428 -407.251408) (xy 78.100428 -407.093928)
			(xy 78.099998 -407.084743) (xy 78.093497 -407.067559) (xy 78.087728 -407.0604) (xy 78.065832 -407.034761)
			(xy 78.027742 -406.979124) (xy 77.996591 -406.919324) (xy 77.972828 -406.856224) (xy 77.956793 -406.790731)
			(xy 77.94872 -406.723789) (xy 74.670675 -406.723789) (xy 74.662641 -406.790548) (xy 74.64667 -406.855929)
			(xy 74.623 -406.918932) (xy 74.591969 -406.978655) (xy 74.554022 -407.03424) (xy 74.532236 -407.059892)
			(xy 74.526453 -407.067046) (xy 74.519932 -407.08423) (xy 74.519536 -407.09342) (xy 74.519536 -407.251408)
			(xy 74.519085 -407.261558) (xy 74.511294 -407.280304) (xy 74.496907 -407.294625) (xy 74.478126 -407.302331)
			(xy 74.467974 -407.302716) (xy 73.751694 -407.302716) (xy 73.741562 -407.302277) (xy 73.722832 -407.294539)
			(xy 73.708474 -407.280238) (xy 73.700663 -407.261538) (xy 73.700132 -407.251408) (xy 73.700132 -407.09342)
			(xy 73.699705 -407.084235) (xy 73.693202 -407.067051) (xy 73.687432 -407.059892) (xy 73.665613 -407.034266)
			(xy 73.627666 -406.978675) (xy 73.596634 -406.918948) (xy 73.572963 -406.85594) (xy 73.556993 -406.790555)
			(xy 73.548951 -406.72373) (xy 66.525648 -406.72373) (xy 66.525648 -409.523886) (xy 71.34879 -409.523886)
			(xy 71.348793 -409.45646) (xy 71.356872 -409.389519) (xy 71.372911 -409.324028) (xy 71.396679 -409.26093)
			(xy 71.427834 -409.201133) (xy 71.465926 -409.145497) (xy 71.487792 -409.119832) (xy 71.493599 -409.112694)
			(xy 71.500108 -409.095498) (xy 71.500492 -409.086304) (xy 71.500492 -408.594052) (xy 71.500059 -408.584867)
			(xy 71.493561 -408.567682) (xy 71.487792 -408.560524) (xy 71.46592 -408.534865) (xy 71.427833 -408.479229)
			(xy 71.396683 -408.419432) (xy 71.372919 -408.356335) (xy 71.356885 -408.290845) (xy 71.348809 -408.223906)
			(xy 71.34881 -408.156482) (xy 71.356887 -408.089543) (xy 71.372923 -408.024054) (xy 71.396688 -407.960957)
			(xy 71.427839 -407.90116) (xy 71.465928 -407.845525) (xy 71.487792 -407.81986) (xy 71.493587 -407.812714)
			(xy 71.500103 -407.795524) (xy 71.500492 -407.786332) (xy 71.500492 -407.628852) (xy 71.500946 -407.618741)
			(xy 71.508698 -407.600063) (xy 71.523004 -407.585771) (xy 71.541689 -407.578036) (xy 71.5518 -407.577544)
			(xy 72.26808 -407.577544) (xy 72.278181 -407.5781) (xy 72.296848 -407.585821) (xy 72.311141 -407.600095)
			(xy 72.318887 -407.618752) (xy 72.319388 -407.628852) (xy 72.319388 -407.786332) (xy 72.319785 -407.795521)
			(xy 72.326308 -407.812705) (xy 72.332088 -407.81986) (xy 72.353945 -407.845532) (xy 72.392034 -407.901165)
			(xy 72.423186 -407.96096) (xy 72.446951 -408.024056) (xy 72.462988 -408.089545) (xy 72.471064 -408.156482)
			(xy 72.471065 -408.223906) (xy 72.46299 -408.290844) (xy 72.446955 -408.356332) (xy 72.423191 -408.419429)
			(xy 72.39204 -408.479225) (xy 72.353952 -408.534859) (xy 72.332088 -408.560524) (xy 72.326297 -408.567673)
			(xy 72.31978 -408.584861) (xy 72.319388 -408.594052) (xy 72.319388 -409.086304) (xy 72.319799 -409.095491)
			(xy 72.326313 -409.112675) (xy 72.332088 -409.119832) (xy 72.353917 -409.145526) (xy 72.392008 -409.201156)
			(xy 72.423161 -409.260948) (xy 72.446927 -409.324042) (xy 72.462966 -409.389527) (xy 72.471045 -409.456462)
			(xy 72.471048 -409.523884) (xy 72.462975 -409.59082) (xy 72.446943 -409.656307) (xy 72.423183 -409.719402)
			(xy 72.392035 -409.779197) (xy 72.35395 -409.834831) (xy 72.332088 -409.860496) (xy 72.326309 -409.867654)
			(xy 72.319784 -409.884835) (xy 72.319388 -409.894024) (xy 72.319388 -410.051504) (xy 72.318987 -410.061628)
			(xy 72.311235 -410.080334) (xy 72.296914 -410.094649) (xy 72.278204 -410.102392) (xy 72.26808 -410.102812)
			(xy 71.5518 -410.102812) (xy 71.541693 -410.102315) (xy 71.523017 -410.09458) (xy 71.508723 -410.080286)
			(xy 71.500986 -410.061611) (xy 71.500492 -410.051504) (xy 71.500492 -409.894024) (xy 71.500072 -409.884838)
			(xy 71.493565 -409.867653) (xy 71.487792 -409.860496) (xy 71.465893 -409.83486) (xy 71.427806 -409.779221)
			(xy 71.396657 -409.719421) (xy 71.372895 -409.65632) (xy 71.356863 -409.590827) (xy 71.34879 -409.523886)
			(xy 66.525648 -409.523886) (xy 66.525648 -410.623641) (xy 73.548963 -410.623641) (xy 73.548964 -410.556335)
			(xy 73.55701 -410.489511) (xy 73.572984 -410.424128) (xy 73.596658 -410.361123) (xy 73.627693 -410.301399)
			(xy 73.665643 -410.245812) (xy 73.687432 -410.22016) (xy 73.693232 -410.213017) (xy 73.699744 -410.195825)
			(xy 73.700132 -410.186632) (xy 73.700132 -409.693364) (xy 73.699732 -409.684176) (xy 73.69321 -409.666992)
			(xy 73.687432 -409.659836) (xy 73.665656 -409.634174) (xy 73.627707 -409.578589) (xy 73.596674 -409.518867)
			(xy 73.573001 -409.455863) (xy 73.557027 -409.390482) (xy 73.548982 -409.323661) (xy 73.548981 -409.256357)
			(xy 73.557024 -409.189535) (xy 73.572995 -409.124154) (xy 73.596667 -409.06115) (xy 73.627698 -409.001427)
			(xy 73.665645 -408.94584) (xy 73.687432 -408.920188) (xy 73.69322 -408.913037) (xy 73.699739 -408.895851)
			(xy 73.700132 -408.88666) (xy 73.700132 -408.728672) (xy 73.700499 -408.718512) (xy 73.70831 -408.699753)
			(xy 73.722724 -408.685429) (xy 73.741532 -408.677736) (xy 73.751694 -408.677364) (xy 74.467974 -408.677364)
			(xy 74.478102 -408.677848) (xy 74.496827 -408.685572) (xy 74.511185 -408.69986) (xy 74.519001 -408.718546)
			(xy 74.519536 -408.728672) (xy 74.519536 -408.88666) (xy 74.51998 -408.895843) (xy 74.526472 -408.913027)
			(xy 74.532236 -408.920188) (xy 74.554036 -408.94583) (xy 74.591986 -409.001418) (xy 74.62302 -409.061142)
			(xy 74.646694 -409.124148) (xy 74.662666 -409.189532) (xy 74.67071 -409.256356) (xy 74.670709 -409.323662)
			(xy 74.662663 -409.390486) (xy 74.646688 -409.455869) (xy 74.623013 -409.518874) (xy 74.620439 -409.523827)
			(xy 75.749085 -409.523827) (xy 75.749088 -409.456519) (xy 75.757137 -409.389693) (xy 75.773115 -409.324308)
			(xy 75.796793 -409.261302) (xy 75.827833 -409.201578) (xy 75.865789 -409.145992) (xy 75.88758 -409.12034)
			(xy 75.893382 -409.113199) (xy 75.899894 -409.096005) (xy 75.90028 -409.086812) (xy 75.90028 -408.593544)
			(xy 75.899853 -408.584358) (xy 75.893352 -408.567174) (xy 75.88758 -408.560016) (xy 75.865783 -408.534371)
			(xy 75.827832 -408.478784) (xy 75.796797 -408.41906) (xy 75.773123 -408.356055) (xy 75.757149 -408.290671)
			(xy 75.749105 -408.223847) (xy 75.749106 -408.156541) (xy 75.757151 -408.089717) (xy 75.773126 -408.024334)
			(xy 75.796802 -407.961329) (xy 75.827838 -407.901605) (xy 75.865791 -407.84602) (xy 75.88758 -407.820368)
			(xy 75.89337 -407.813218) (xy 75.899889 -407.796031) (xy 75.90028 -407.78684) (xy 75.90028 -407.628852)
			(xy 75.900682 -407.618697) (xy 75.90849 -407.599948) (xy 75.922892 -407.585627) (xy 75.941685 -407.577925)
			(xy 75.951842 -407.577544) (xy 76.668122 -407.577544) (xy 76.678251 -407.578008) (xy 76.696973 -407.585744)
			(xy 76.711329 -407.600037) (xy 76.719147 -407.618726) (xy 76.719684 -407.628852) (xy 76.719684 -407.78684)
			(xy 76.720078 -407.796029) (xy 76.726603 -407.813213) (xy 76.732384 -407.820368) (xy 76.754163 -407.846027)
			(xy 76.792111 -407.901613) (xy 76.823143 -407.961336) (xy 76.846815 -408.024339) (xy 76.862788 -408.08972)
			(xy 76.870833 -408.156542) (xy 76.870833 -408.223846) (xy 76.86279 -408.290668) (xy 76.846819 -408.356049)
			(xy 76.823148 -408.419053) (xy 76.792117 -408.478777) (xy 76.754171 -408.534364) (xy 76.732384 -408.560016)
			(xy 76.726596 -408.567167) (xy 76.720077 -408.584353) (xy 76.719684 -408.593544) (xy 76.719684 -409.086812)
			(xy 76.720092 -409.095999) (xy 76.726607 -409.113184) (xy 76.732384 -409.12034) (xy 76.754135 -409.146022)
			(xy 76.792084 -409.201605) (xy 76.823117 -409.261324) (xy 76.846791 -409.324325) (xy 76.862766 -409.389703)
			(xy 76.870812 -409.456522) (xy 76.870816 -409.523824) (xy 76.862775 -409.590644) (xy 76.846807 -409.656023)
			(xy 76.823139 -409.719026) (xy 76.792112 -409.778749) (xy 76.754169 -409.834335) (xy 76.732384 -409.859988)
			(xy 76.726566 -409.867118) (xy 76.720065 -409.88432) (xy 76.719684 -409.893516) (xy 76.719684 -410.051504)
			(xy 76.719281 -410.06166) (xy 76.711481 -410.080416) (xy 76.697079 -410.09474) (xy 76.678281 -410.102436)
			(xy 76.668122 -410.102812) (xy 75.951842 -410.102812) (xy 75.941724 -410.10224) (xy 75.923014 -410.094536)
			(xy 75.908658 -410.080276) (xy 75.900828 -410.061618) (xy 75.90028 -410.051504) (xy 75.90028 -409.893516)
			(xy 75.899867 -409.884329) (xy 75.893356 -409.867144) (xy 75.88758 -409.859988) (xy 75.865756 -409.834365)
			(xy 75.827805 -409.778776) (xy 75.796771 -409.719048) (xy 75.773099 -409.65604) (xy 75.757127 -409.590654)
			(xy 75.749085 -409.523827) (xy 74.620439 -409.523827) (xy 74.591977 -409.578598) (xy 74.554025 -409.634184)
			(xy 74.532236 -409.659836) (xy 74.526434 -409.666977) (xy 74.519924 -409.684171) (xy 74.519536 -409.693364)
			(xy 74.519536 -410.186632) (xy 74.519945 -410.195819) (xy 74.526461 -410.213002) (xy 74.532236 -410.22016)
			(xy 74.554009 -410.245825) (xy 74.59196 -410.301409) (xy 74.622995 -410.36113) (xy 74.64667 -410.424133)
			(xy 74.662644 -410.489514) (xy 74.67069 -410.556336) (xy 74.670692 -410.62364) (xy 74.670685 -410.623701)
			(xy 77.948731 -410.623701) (xy 77.948732 -410.556275) (xy 77.95681 -410.489335) (xy 77.972848 -410.423845)
			(xy 77.996615 -410.360747) (xy 78.02777 -410.300951) (xy 78.065862 -410.245317) (xy 78.087728 -410.219652)
			(xy 78.093531 -410.212512) (xy 78.100041 -410.195317) (xy 78.100428 -410.186124) (xy 78.100428 -409.693872)
			(xy 78.100025 -409.684684) (xy 78.093506 -409.6675) (xy 78.087728 -409.660344) (xy 78.065875 -409.63467)
			(xy 78.027784 -409.579037) (xy 77.996631 -409.519242) (xy 77.972865 -409.456147) (xy 77.956828 -409.390658)
			(xy 77.948751 -409.323721) (xy 77.94875 -409.256297) (xy 77.956825 -409.189359) (xy 77.97286 -409.123871)
			(xy 77.996624 -409.060774) (xy 78.027775 -409.000979) (xy 78.065864 -408.945345) (xy 78.087728 -408.91968)
			(xy 78.093519 -408.912531) (xy 78.100036 -408.895343) (xy 78.100428 -408.886152) (xy 78.100428 -408.728672)
			(xy 78.100794 -408.718544) (xy 78.108556 -408.699835) (xy 78.122888 -408.68552) (xy 78.141608 -408.677781)
			(xy 78.151736 -408.677364) (xy 78.868016 -408.677364) (xy 78.878121 -408.677871) (xy 78.896793 -408.685608)
			(xy 78.911086 -408.699897) (xy 78.918826 -408.718567) (xy 78.919324 -408.728672) (xy 78.919324 -408.886152)
			(xy 78.919752 -408.895337) (xy 78.926253 -408.912522) (xy 78.932024 -408.91968) (xy 78.953899 -408.945336)
			(xy 78.991986 -409.000972) (xy 79.023135 -409.06077) (xy 79.046897 -409.123868) (xy 79.062931 -409.189358)
			(xy 79.071005 -409.256297) (xy 79.071004 -409.323721) (xy 79.062928 -409.39066) (xy 79.046892 -409.456149)
			(xy 79.023127 -409.519246) (xy 79.02071 -409.523886) (xy 80.148878 -409.523886) (xy 80.148881 -409.45646)
			(xy 80.15696 -409.38952) (xy 80.172999 -409.324029) (xy 80.196766 -409.260931) (xy 80.227919 -409.201133)
			(xy 80.266011 -409.145498) (xy 80.287876 -409.119832) (xy 80.293681 -409.112693) (xy 80.300191 -409.095498)
			(xy 80.300576 -409.086304) (xy 80.300576 -408.594052) (xy 80.300146 -408.584867) (xy 80.293647 -408.567682)
			(xy 80.287876 -408.560524) (xy 80.266005 -408.534865) (xy 80.227918 -408.479229) (xy 80.196769 -408.419432)
			(xy 80.173006 -408.356334) (xy 80.156972 -408.290844) (xy 80.148897 -408.223906) (xy 80.148898 -408.156482)
			(xy 80.156974 -408.089544) (xy 80.17301 -408.024055) (xy 80.196774 -407.960957) (xy 80.227924 -407.901161)
			(xy 80.266012 -407.845526) (xy 80.287876 -407.81986) (xy 80.293669 -407.812712) (xy 80.300187 -407.795524)
			(xy 80.300576 -407.786332) (xy 80.300576 -407.628852) (xy 80.301045 -407.618743) (xy 80.308794 -407.600069)
			(xy 80.323095 -407.585776) (xy 80.341775 -407.578039) (xy 80.351884 -407.577544) (xy 81.068164 -407.577544)
			(xy 81.078264 -407.578113) (xy 81.09693 -407.585829) (xy 81.111224 -407.600099) (xy 81.11897 -407.618753)
			(xy 81.119472 -407.628852) (xy 81.119472 -407.786332) (xy 81.119873 -407.79552) (xy 81.126394 -407.812704)
			(xy 81.132172 -407.81986) (xy 81.154029 -407.845531) (xy 81.19212 -407.901164) (xy 81.223273 -407.960959)
			(xy 81.247038 -408.024056) (xy 81.263075 -408.089544) (xy 81.271152 -408.156482) (xy 81.271153 -408.223906)
			(xy 81.263077 -408.290844) (xy 81.247042 -408.356333) (xy 81.223277 -408.41943) (xy 81.192126 -408.479225)
			(xy 81.154036 -408.534859) (xy 81.132172 -408.560524) (xy 81.126379 -408.567672) (xy 81.119863 -408.58486)
			(xy 81.119472 -408.594052) (xy 81.119472 -409.086304) (xy 81.119886 -409.095491) (xy 81.126398 -409.112675)
			(xy 81.132172 -409.119832) (xy 81.154002 -409.145526) (xy 81.192093 -409.201156) (xy 81.223247 -409.260948)
			(xy 81.247014 -409.324041) (xy 81.263053 -409.389527) (xy 81.271132 -409.456462) (xy 81.271136 -409.523884)
			(xy 81.263063 -409.59082) (xy 81.247031 -409.656307) (xy 81.223269 -409.719403) (xy 81.192121 -409.779198)
			(xy 81.154035 -409.834831) (xy 81.132172 -409.860496) (xy 81.126391 -409.867652) (xy 81.119868 -409.884834)
			(xy 81.119472 -409.894024) (xy 81.119472 -410.051504) (xy 81.119086 -410.06163) (xy 81.111332 -410.080339)
			(xy 81.097006 -410.094654) (xy 81.078291 -410.102394) (xy 81.068164 -410.102812) (xy 80.351884 -410.102812)
			(xy 80.341776 -410.102328) (xy 80.3231 -410.094587) (xy 80.308806 -410.08029) (xy 80.30107 -410.061612)
			(xy 80.300576 -410.051504) (xy 80.300576 -409.894024) (xy 80.30016 -409.884837) (xy 80.293651 -409.867653)
			(xy 80.287876 -409.860496) (xy 80.265978 -409.83486) (xy 80.227891 -409.77922) (xy 80.196744 -409.71942)
			(xy 80.172983 -409.656319) (xy 80.15695 -409.590827) (xy 80.148878 -409.523886) (xy 79.02071 -409.523886)
			(xy 78.991976 -409.579043) (xy 78.953888 -409.634678) (xy 78.932024 -409.660344) (xy 78.926229 -409.667491)
			(xy 78.919713 -409.68468) (xy 78.919324 -409.693872) (xy 78.919324 -410.186124) (xy 78.919717 -410.195313)
			(xy 78.926242 -410.212497) (xy 78.932024 -410.219652) (xy 78.953871 -410.245331) (xy 78.991959 -410.300964)
			(xy 79.023109 -410.360758) (xy 79.046873 -410.423853) (xy 79.062909 -410.489341) (xy 79.070986 -410.556277)
			(xy 79.070987 -410.623641) (xy 82.349051 -410.623641) (xy 82.349052 -410.556335) (xy 82.357097 -410.489512)
			(xy 82.373071 -410.424129) (xy 82.396745 -410.361124) (xy 82.427779 -410.3014) (xy 82.465728 -410.245812)
			(xy 82.487516 -410.22016) (xy 82.493314 -410.213016) (xy 82.499827 -410.195824) (xy 82.500216 -410.186632)
			(xy 82.500216 -409.693364) (xy 82.49982 -409.684175) (xy 82.493296 -409.666991) (xy 82.487516 -409.659836)
			(xy 82.465741 -409.634174) (xy 82.427793 -409.578588) (xy 82.39676 -409.518866) (xy 82.373088 -409.455863)
			(xy 82.357115 -409.390482) (xy 82.34907 -409.323661) (xy 82.349069 -409.256357) (xy 82.357112 -409.189536)
			(xy 82.373083 -409.124155) (xy 82.396753 -409.061151) (xy 82.427784 -409.001427) (xy 82.46573 -408.94584)
			(xy 82.487516 -408.920188) (xy 82.493302 -408.913035) (xy 82.499822 -408.89585) (xy 82.500216 -408.88666)
			(xy 82.500216 -408.728672) (xy 82.500599 -408.718514) (xy 82.508407 -408.699758) (xy 82.522815 -408.685435)
			(xy 82.541618 -408.677739) (xy 82.551778 -408.677364) (xy 83.268058 -408.677364) (xy 83.278185 -408.677862)
			(xy 83.29691 -408.68558) (xy 83.311268 -408.699864) (xy 83.319085 -408.718548) (xy 83.31962 -408.728672)
			(xy 83.31962 -408.88666) (xy 83.320045 -408.895846) (xy 83.326548 -408.913031) (xy 83.33232 -408.920188)
			(xy 83.354121 -408.94583) (xy 83.392072 -409.001417) (xy 83.423107 -409.061141) (xy 83.446781 -409.124147)
			(xy 83.462754 -409.189531) (xy 83.470798 -409.256356) (xy 83.470797 -409.323662) (xy 83.462751 -409.390487)
			(xy 83.446775 -409.45587) (xy 83.423099 -409.518875) (xy 83.420495 -409.523886) (xy 84.548669 -409.523886)
			(xy 84.548672 -409.45646) (xy 84.556751 -409.38952) (xy 84.572789 -409.324029) (xy 84.596556 -409.260931)
			(xy 84.627709 -409.201134) (xy 84.665799 -409.145498) (xy 84.687664 -409.119832) (xy 84.69348 -409.112701)
			(xy 84.699981 -409.095499) (xy 84.700364 -409.086304) (xy 84.700364 -408.594052) (xy 84.699915 -408.584869)
			(xy 84.693427 -408.567685) (xy 84.687664 -408.560524) (xy 84.665793 -408.534865) (xy 84.627707 -408.479228)
			(xy 84.596559 -408.419431) (xy 84.572797 -408.356334) (xy 84.556763 -408.290844) (xy 84.548688 -408.223906)
			(xy 84.548689 -408.156482) (xy 84.556765 -408.089544) (xy 84.5728 -408.024055) (xy 84.596564 -407.960958)
			(xy 84.627714 -407.901161) (xy 84.665801 -407.845526) (xy 84.687664 -407.81986) (xy 84.693468 -407.81272)
			(xy 84.699976 -407.795525) (xy 84.700364 -407.786332) (xy 84.700364 -407.628852) (xy 84.700845 -407.618745)
			(xy 84.708592 -407.600072) (xy 84.722889 -407.585781) (xy 84.741564 -407.578041) (xy 84.751672 -407.577544)
			(xy 85.467952 -407.577544) (xy 85.478051 -407.578123) (xy 85.496717 -407.585835) (xy 85.511012 -407.600102)
			(xy 85.518758 -407.618754) (xy 85.51926 -407.628852) (xy 85.51926 -407.786332) (xy 85.519664 -407.79552)
			(xy 85.526183 -407.812703) (xy 85.53196 -407.81986) (xy 85.553818 -407.845531) (xy 85.591909 -407.901164)
			(xy 85.623062 -407.960959) (xy 85.646829 -408.024055) (xy 85.662866 -408.089544) (xy 85.670943 -408.156482)
			(xy 85.670944 -408.223906) (xy 85.662868 -408.290844) (xy 85.646832 -408.356333) (xy 85.623067 -408.41943)
			(xy 85.591915 -408.479226) (xy 85.553825 -408.534859) (xy 85.53196 -408.560524) (xy 85.526166 -408.567671)
			(xy 85.519651 -408.58486) (xy 85.51926 -408.594052) (xy 85.51926 -409.086304) (xy 85.519677 -409.09549)
			(xy 85.526187 -409.112674) (xy 85.53196 -409.119832) (xy 85.55379 -409.145526) (xy 85.591882 -409.201155)
			(xy 85.623037 -409.260947) (xy 85.646805 -409.32404) (xy 85.662844 -409.389526) (xy 85.670923 -409.456462)
			(xy 85.670927 -409.523884) (xy 85.662854 -409.59082) (xy 85.646821 -409.656308) (xy 85.623059 -409.719403)
			(xy 85.59191 -409.779198) (xy 85.553823 -409.834831) (xy 85.53196 -409.860496) (xy 85.526178 -409.867651)
			(xy 85.519655 -409.884834) (xy 85.51926 -409.894024) (xy 85.51926 -410.051504) (xy 85.518886 -410.061632)
			(xy 85.511129 -410.080343) (xy 85.496799 -410.094659) (xy 85.47808 -410.102396) (xy 85.467952 -410.102812)
			(xy 84.751672 -410.102812) (xy 84.741563 -410.102338) (xy 84.722886 -410.094594) (xy 84.708593 -410.080293)
			(xy 84.700857 -410.061613) (xy 84.700364 -410.051504) (xy 84.700364 -409.894024) (xy 84.699928 -409.88484)
			(xy 84.693431 -409.867656) (xy 84.687664 -409.860496) (xy 84.665766 -409.834859) (xy 84.627681 -409.77922)
			(xy 84.596534 -409.719419) (xy 84.572773 -409.656319) (xy 84.556741 -409.590827) (xy 84.548669 -409.523886)
			(xy 83.420495 -409.523886) (xy 83.392063 -409.578599) (xy 83.35411 -409.634184) (xy 83.33232 -409.659836)
			(xy 83.326528 -409.666985) (xy 83.32001 -409.684172) (xy 83.31962 -409.693364) (xy 83.31962 -410.186632)
			(xy 83.32001 -410.195821) (xy 83.326537 -410.213006) (xy 83.33232 -410.22016) (xy 83.354093 -410.245825)
			(xy 83.392045 -410.301408) (xy 83.423081 -410.36113) (xy 83.446757 -410.424133) (xy 83.462732 -410.489514)
			(xy 83.470778 -410.556336) (xy 83.47078 -410.62364) (xy 83.470773 -410.623701) (xy 86.748819 -410.623701)
			(xy 86.74882 -410.556275) (xy 86.756898 -410.489336) (xy 86.772936 -410.423846) (xy 86.796702 -410.360748)
			(xy 86.827855 -410.300952) (xy 86.865947 -410.245317) (xy 86.887812 -410.219652) (xy 86.893613 -410.21251)
			(xy 86.900125 -410.195317) (xy 86.900512 -410.186124) (xy 86.900512 -409.693872) (xy 86.900113 -409.684684)
			(xy 86.893591 -409.6675) (xy 86.887812 -409.660344) (xy 86.865959 -409.634669) (xy 86.82787 -409.579036)
			(xy 86.796718 -409.519242) (xy 86.772952 -409.456146) (xy 86.756916 -409.390658) (xy 86.748839 -409.32372)
			(xy 86.748837 -409.256298) (xy 86.756912 -409.18936) (xy 86.772947 -409.123871) (xy 86.79671 -409.060775)
			(xy 86.82786 -409.000979) (xy 86.865948 -408.945345) (xy 86.887812 -408.91968) (xy 86.893601 -408.912529)
			(xy 86.90012 -408.895343) (xy 86.900512 -408.886152) (xy 86.900512 -408.728672) (xy 86.900962 -408.71856)
			(xy 86.908711 -408.699879) (xy 86.923019 -408.685585) (xy 86.941708 -408.677853) (xy 86.95182 -408.677364)
			(xy 87.6681 -408.677364) (xy 87.678204 -408.677884) (xy 87.696876 -408.685615) (xy 87.711169 -408.699901)
			(xy 87.71891 -408.718568) (xy 87.719408 -408.728672) (xy 87.719408 -408.886152) (xy 87.719839 -408.895337)
			(xy 87.726338 -408.912522) (xy 87.732108 -408.91968) (xy 87.753983 -408.945336) (xy 87.792071 -409.000972)
			(xy 87.823221 -409.060769) (xy 87.846984 -409.123867) (xy 87.863019 -409.189358) (xy 87.871093 -409.256297)
			(xy 87.871092 -409.323721) (xy 87.863015 -409.39066) (xy 87.846979 -409.45615) (xy 87.823214 -409.519247)
			(xy 87.792062 -409.579044) (xy 87.753972 -409.634679) (xy 87.732108 -409.660344) (xy 87.726311 -409.667489)
			(xy 87.719796 -409.68468) (xy 87.719408 -409.693872) (xy 87.719408 -410.186124) (xy 87.719805 -410.195313)
			(xy 87.726328 -410.212497) (xy 87.732108 -410.219652) (xy 87.753956 -410.24533) (xy 87.792045 -410.300963)
			(xy 87.823196 -410.360758) (xy 87.84696 -410.423853) (xy 87.862997 -410.48934) (xy 87.871074 -410.556277)
			(xy 87.871075 -410.623641) (xy 91.149138 -410.623641) (xy 91.14914 -410.556335) (xy 91.157185 -410.489512)
			(xy 91.173158 -410.42413) (xy 91.196831 -410.361125) (xy 91.227864 -410.3014) (xy 91.265813 -410.245813)
			(xy 91.2876 -410.22016) (xy 91.293396 -410.213014) (xy 91.299911 -410.195824) (xy 91.3003 -410.186632)
			(xy 91.3003 -409.693364) (xy 91.299907 -409.684175) (xy 91.293382 -409.666991) (xy 91.2876 -409.659836)
			(xy 91.265825 -409.634174) (xy 91.227879 -409.578588) (xy 91.196847 -409.518865) (xy 91.173175 -409.455862)
			(xy 91.157203 -409.390482) (xy 91.149158 -409.323661) (xy 91.149157 -409.256357) (xy 91.157199 -409.189536)
			(xy 91.17317 -409.124155) (xy 91.19684 -409.061151) (xy 91.227869 -409.001428) (xy 91.265814 -408.945841)
			(xy 91.2876 -408.920188) (xy 91.293384 -408.913034) (xy 91.299906 -408.89585) (xy 91.3003 -408.88666)
			(xy 91.3003 -408.728672) (xy 91.300699 -408.718516) (xy 91.308503 -408.699763) (xy 91.322907 -408.685441)
			(xy 91.341704 -408.677742) (xy 91.351862 -408.677364) (xy 92.068142 -408.677364) (xy 92.078274 -408.677793)
			(xy 92.097001 -408.685539) (xy 92.111357 -408.699843) (xy 92.11917 -408.718542) (xy 92.119704 -408.728672)
			(xy 92.119704 -408.88666) (xy 92.120132 -408.895845) (xy 92.126633 -408.91303) (xy 92.132404 -408.920188)
			(xy 92.154202 -408.945831) (xy 92.192148 -409.00142) (xy 92.223178 -409.061145) (xy 92.246848 -409.124151)
			(xy 92.262819 -409.189534) (xy 92.270862 -409.256356) (xy 92.270861 -409.323662) (xy 92.262816 -409.390484)
			(xy 92.246843 -409.455867) (xy 92.223171 -409.518871) (xy 92.220596 -409.523827) (xy 115.349227 -409.523827)
			(xy 115.349231 -409.456519) (xy 115.357278 -409.389695) (xy 115.373254 -409.324311) (xy 115.396929 -409.261305)
			(xy 115.427964 -409.20158) (xy 115.465915 -409.145993) (xy 115.487704 -409.12034) (xy 115.493509 -409.113201)
			(xy 115.500019 -409.096006) (xy 115.500404 -409.086812) (xy 115.500404 -408.593544) (xy 115.499972 -408.584359)
			(xy 115.493473 -408.567175) (xy 115.487704 -408.560016) (xy 115.465909 -408.53437) (xy 115.427963 -408.478782)
			(xy 115.396932 -408.419057) (xy 115.373261 -408.356052) (xy 115.35729 -408.290669) (xy 115.349247 -408.223846)
			(xy 115.349248 -408.156541) (xy 115.357292 -408.089719) (xy 115.373265 -408.024337) (xy 115.396937 -407.961332)
			(xy 115.427969 -407.901608) (xy 115.465917 -407.846021) (xy 115.487704 -407.820368) (xy 115.493497 -407.81322)
			(xy 115.500014 -407.796032) (xy 115.500404 -407.78684) (xy 115.500404 -407.628852) (xy 115.500846 -407.61874)
			(xy 115.5086 -407.60006) (xy 115.52291 -407.585767) (xy 115.541599 -407.578034) (xy 115.551712 -407.577544)
			(xy 116.268246 -407.577544) (xy 116.278376 -407.577989) (xy 116.297099 -407.585733) (xy 116.311454 -407.600031)
			(xy 116.319271 -407.618724) (xy 116.319808 -407.628852) (xy 116.319808 -407.78684) (xy 116.320197 -407.79603)
			(xy 116.326725 -407.813214) (xy 116.332508 -407.820368) (xy 116.354289 -407.846026) (xy 116.392242 -407.90161)
			(xy 116.423279 -407.961333) (xy 116.446954 -408.024336) (xy 116.462929 -408.089718) (xy 116.470975 -408.156541)
			(xy 116.470976 -408.223847) (xy 116.462931 -408.29067) (xy 116.446958 -408.356052) (xy 116.423283 -408.419056)
			(xy 116.392248 -408.478779) (xy 116.354297 -408.534365) (xy 116.332508 -408.560016) (xy 116.326723 -408.56717)
			(xy 116.320201 -408.584354) (xy 116.319808 -408.593544) (xy 116.319808 -409.086812) (xy 116.320211 -409.096)
			(xy 116.326729 -409.113184) (xy 116.332508 -409.12034) (xy 116.354262 -409.146021) (xy 116.392215 -409.201602)
			(xy 116.423253 -409.261321) (xy 116.44693 -409.324322) (xy 116.462907 -409.389701) (xy 116.470955 -409.456521)
			(xy 116.470958 -409.523825) (xy 116.462917 -409.590646) (xy 116.446946 -409.656026) (xy 116.423275 -409.71903)
			(xy 116.392243 -409.778752) (xy 116.354295 -409.834337) (xy 116.332508 -409.859988) (xy 116.326692 -409.86712)
			(xy 116.320189 -409.884321) (xy 116.319808 -409.893516) (xy 116.319808 -410.051504) (xy 116.319318 -410.061612)
			(xy 116.311581 -410.080289) (xy 116.297285 -410.094583) (xy 116.278608 -410.102319) (xy 116.2685 -410.102812)
			(xy 115.551966 -410.102812) (xy 115.541844 -410.102303) (xy 115.523131 -410.094574) (xy 115.508778 -410.080295)
			(xy 115.500951 -410.061624) (xy 115.500404 -410.051504) (xy 115.500404 -409.893516) (xy 115.499985 -409.88433)
			(xy 115.493477 -409.867145) (xy 115.487704 -409.859988) (xy 115.465882 -409.834364) (xy 115.427937 -409.778773)
			(xy 115.396907 -409.719045) (xy 115.373238 -409.656037) (xy 115.357268 -409.590652) (xy 115.349227 -409.523827)
			(xy 92.220596 -409.523827) (xy 92.192139 -409.578596) (xy 92.154191 -409.634183) (xy 92.132404 -409.659836)
			(xy 92.12661 -409.666983) (xy 92.120094 -409.684172) (xy 92.119704 -409.693364) (xy 92.119704 -410.186632)
			(xy 92.120098 -410.195821) (xy 92.126623 -410.213005) (xy 92.132404 -410.22016) (xy 92.154175 -410.245826)
			(xy 92.192121 -410.301411) (xy 92.223153 -410.361133) (xy 92.246825 -410.424136) (xy 92.262797 -410.489516)
			(xy 92.270842 -410.556336) (xy 92.270844 -410.623639) (xy 92.270837 -410.623701) (xy 117.548849 -410.623701)
			(xy 117.54885 -410.556275) (xy 117.556929 -410.489335) (xy 117.572967 -410.423844) (xy 117.596736 -410.360746)
			(xy 117.627891 -410.30095) (xy 117.665985 -410.245316) (xy 117.687852 -410.219652) (xy 117.693658 -410.212514)
			(xy 117.700166 -410.195318) (xy 117.700552 -410.186124) (xy 117.700552 -409.693872) (xy 117.700144 -409.684685)
			(xy 117.693627 -409.667501) (xy 117.687852 -409.660344) (xy 117.665998 -409.63467) (xy 117.627906 -409.579038)
			(xy 117.596751 -409.519243) (xy 117.572984 -409.456148) (xy 117.556946 -409.390659) (xy 117.548869 -409.323721)
			(xy 117.548868 -409.256297) (xy 117.556943 -409.189359) (xy 117.572979 -409.12387) (xy 117.596744 -409.060773)
			(xy 117.627896 -409.000978) (xy 117.665987 -408.945344) (xy 117.687852 -408.91968) (xy 117.693646 -408.912533)
			(xy 117.700161 -408.895344) (xy 117.700552 -408.886152) (xy 117.700552 -408.728672) (xy 117.701061 -408.718567)
			(xy 117.708799 -408.699898) (xy 117.723088 -408.685606) (xy 117.741756 -408.677863) (xy 117.75186 -408.677364)
			(xy 118.46814 -408.677364) (xy 118.478247 -408.677852) (xy 118.496919 -408.685596) (xy 118.511211 -408.699891)
			(xy 118.518951 -408.718565) (xy 118.519448 -408.728672) (xy 118.519448 -408.886152) (xy 118.519893 -408.895335)
			(xy 118.526384 -408.912519) (xy 118.532148 -408.91968) (xy 118.554026 -408.945335) (xy 118.592117 -409.000969)
			(xy 118.62327 -409.060767) (xy 118.647036 -409.123865) (xy 118.663072 -409.189356) (xy 118.671148 -409.256296)
			(xy 118.671147 -409.323722) (xy 118.663069 -409.390662) (xy 118.647031 -409.456152) (xy 118.623263 -409.51925)
			(xy 118.620848 -409.523886) (xy 119.748996 -409.523886) (xy 119.748999 -409.45646) (xy 119.757078 -409.389519)
			(xy 119.773118 -409.324028) (xy 119.796886 -409.26093) (xy 119.828041 -409.201132) (xy 119.866134 -409.145497)
			(xy 119.888 -409.119832) (xy 119.893808 -409.112695) (xy 119.900316 -409.095498) (xy 119.9007 -409.086304)
			(xy 119.9007 -408.594052) (xy 119.900265 -408.584867) (xy 119.893769 -408.567683) (xy 119.888 -408.560524)
			(xy 119.866128 -408.534865) (xy 119.82804 -408.47923) (xy 119.796889 -408.419433) (xy 119.773126 -408.356335)
			(xy 119.757091 -408.290845) (xy 119.749015 -408.223906) (xy 119.749016 -408.156482) (xy 119.757093 -408.089543)
			(xy 119.773129 -408.024054) (xy 119.796894 -407.960956) (xy 119.828046 -407.90116) (xy 119.866136 -407.845525)
			(xy 119.888 -407.81986) (xy 119.893796 -407.812714) (xy 119.900311 -407.795524) (xy 119.9007 -407.786332)
			(xy 119.9007 -407.628852) (xy 119.901146 -407.61874) (xy 119.908899 -407.600061) (xy 119.923208 -407.585768)
			(xy 119.941896 -407.578035) (xy 119.952008 -407.577544) (xy 120.668288 -407.577544) (xy 120.678389 -407.578094)
			(xy 120.697056 -407.585817) (xy 120.71135 -407.600093) (xy 120.719095 -407.618752) (xy 120.719596 -407.628852)
			(xy 120.719596 -407.786332) (xy 120.719991 -407.795521) (xy 120.726515 -407.812705) (xy 120.732296 -407.81986)
			(xy 120.754152 -407.845532) (xy 120.792241 -407.901165) (xy 120.823393 -407.96096) (xy 120.847158 -408.024056)
			(xy 120.863194 -408.089545) (xy 120.87127 -408.156482) (xy 120.871271 -408.223906) (xy 120.863196 -408.290843)
			(xy 120.847161 -408.356332) (xy 120.823398 -408.419429) (xy 120.792248 -408.479225) (xy 120.75416 -408.534859)
			(xy 120.732296 -408.560524) (xy 120.726506 -408.567674) (xy 120.719988 -408.584861) (xy 120.719596 -408.594052)
			(xy 120.719596 -409.086304) (xy 120.720005 -409.095491) (xy 120.72652 -409.112675) (xy 120.732296 -409.119832)
			(xy 120.754125 -409.145526) (xy 120.792215 -409.201157) (xy 120.823367 -409.260949) (xy 120.847134 -409.324042)
			(xy 120.863172 -409.389527) (xy 120.871251 -409.456463) (xy 120.871254 -409.523883) (xy 120.863181 -409.590819)
			(xy 120.84715 -409.656306) (xy 120.823389 -409.719402) (xy 120.792243 -409.779197) (xy 120.754158 -409.834831)
			(xy 120.732296 -409.860496) (xy 120.726518 -409.867654) (xy 120.719992 -409.884835) (xy 120.719596 -409.894024)
			(xy 120.719596 -410.051504) (xy 120.719187 -410.061627) (xy 120.711437 -410.080332) (xy 120.697118 -410.094646)
			(xy 120.678411 -410.10239) (xy 120.668288 -410.102812) (xy 119.952008 -410.102812) (xy 119.941888 -410.102378)
			(xy 119.923186 -410.094634) (xy 119.908872 -410.080324) (xy 119.901125 -410.061624) (xy 119.9007 -410.051504)
			(xy 119.9007 -409.894024) (xy 119.900278 -409.884838) (xy 119.893773 -409.867654) (xy 119.888 -409.860496)
			(xy 119.866101 -409.83486) (xy 119.828013 -409.779221) (xy 119.796864 -409.719421) (xy 119.773102 -409.65632)
			(xy 119.757069 -409.590828) (xy 119.748996 -409.523886) (xy 118.620848 -409.523886) (xy 118.592108 -409.579046)
			(xy 118.554015 -409.63468) (xy 118.532148 -409.660344) (xy 118.526344 -409.667484) (xy 118.519835 -409.684679)
			(xy 118.519448 -409.693872) (xy 118.519448 -410.186124) (xy 118.519858 -410.195311) (xy 118.526373 -410.212495)
			(xy 118.532148 -410.219652) (xy 118.553998 -410.245329) (xy 118.592091 -410.300961) (xy 118.623245 -410.360755)
			(xy 118.647012 -410.42385) (xy 118.663051 -410.489338) (xy 118.671128 -410.556276) (xy 118.67113 -410.623641)
			(xy 121.949169 -410.623641) (xy 121.94917 -410.556335) (xy 121.957216 -410.489511) (xy 121.97319 -410.424128)
			(xy 121.996865 -410.361123) (xy 122.0279 -410.301399) (xy 122.065851 -410.245812) (xy 122.08764 -410.22016)
			(xy 122.093441 -410.213018) (xy 122.099952 -410.195825) (xy 122.10034 -410.186632) (xy 122.10034 -409.693364)
			(xy 122.099938 -409.684176) (xy 122.093418 -409.666992) (xy 122.08764 -409.659836) (xy 122.065864 -409.634174)
			(xy 122.027915 -409.578589) (xy 121.996881 -409.518867) (xy 121.973208 -409.455864) (xy 121.957234 -409.390483)
			(xy 121.949189 -409.323661) (xy 121.949188 -409.256357) (xy 121.957231 -409.189535) (xy 121.973202 -409.124154)
			(xy 121.996874 -409.06115) (xy 122.027906 -409.001427) (xy 122.065853 -408.94584) (xy 122.08764 -408.920188)
			(xy 122.093429 -408.913038) (xy 122.099947 -408.895851) (xy 122.10034 -408.88666) (xy 122.10034 -408.728672)
			(xy 122.100694 -408.718543) (xy 122.108459 -408.699831) (xy 122.122795 -408.685516) (xy 122.141518 -408.677779)
			(xy 122.151648 -408.677364) (xy 122.868182 -408.677364) (xy 122.878311 -408.677842) (xy 122.897036 -408.685568)
			(xy 122.911394 -408.699858) (xy 122.919209 -408.718546) (xy 122.919744 -408.728672) (xy 122.919744 -408.88666)
			(xy 122.920186 -408.895844) (xy 122.926679 -408.913028) (xy 122.932444 -408.920188) (xy 122.954244 -408.94583)
			(xy 122.992193 -409.001418) (xy 123.023227 -409.061143) (xy 123.0469 -409.124148) (xy 123.062873 -409.189532)
			(xy 123.070916 -409.256356) (xy 123.070915 -409.323662) (xy 123.062869 -409.390486) (xy 123.046895 -409.455869)
			(xy 123.02322 -409.518874) (xy 123.020646 -409.523827) (xy 124.149291 -409.523827) (xy 124.149295 -409.456519)
			(xy 124.157343 -409.389693) (xy 124.173321 -409.324308) (xy 124.197 -409.261302) (xy 124.22804 -409.201577)
			(xy 124.265997 -409.145992) (xy 124.287788 -409.12034) (xy 124.293591 -409.113199) (xy 124.300102 -409.096005)
			(xy 124.300488 -409.086812) (xy 124.300488 -408.593544) (xy 124.300059 -408.584359) (xy 124.293559 -408.567174)
			(xy 124.287788 -408.560016) (xy 124.265991 -408.534371) (xy 124.228039 -408.478785) (xy 124.197004 -408.419061)
			(xy 124.173329 -408.356055) (xy 124.157355 -408.290671) (xy 124.149311 -408.223847) (xy 124.149312 -408.156541)
			(xy 124.157357 -408.089717) (xy 124.173333 -408.024333) (xy 124.197008 -407.961328) (xy 124.228045 -407.901605)
			(xy 124.265998 -407.84602) (xy 124.287788 -407.820368) (xy 124.293579 -407.813219) (xy 124.300097 -407.796031)
			(xy 124.300488 -407.78684) (xy 124.300488 -407.628852) (xy 124.300946 -407.618742) (xy 124.308697 -407.600065)
			(xy 124.323002 -407.585772) (xy 124.341685 -407.578037) (xy 124.351796 -407.577544) (xy 125.06833 -407.577544)
			(xy 125.078459 -407.578002) (xy 125.097182 -407.58574) (xy 125.111537 -407.600035) (xy 125.119355 -407.618725)
			(xy 125.119892 -407.628852) (xy 125.119892 -407.78684) (xy 125.120285 -407.796029) (xy 125.126811 -407.813213)
			(xy 125.132592 -407.820368) (xy 125.154371 -407.846027) (xy 125.192318 -407.901613) (xy 125.22335 -407.961336)
			(xy 125.247022 -408.02434) (xy 125.262994 -408.089721) (xy 125.271039 -408.156542) (xy 125.271039 -408.223846)
			(xy 125.262997 -408.290667) (xy 125.247025 -408.356049) (xy 125.223355 -408.419053) (xy 125.192324 -408.478776)
			(xy 125.154378 -408.534363) (xy 125.132592 -408.560016) (xy 125.126805 -408.567168) (xy 125.120285 -408.584353)
			(xy 125.119892 -408.593544) (xy 125.119892 -409.086812) (xy 125.120298 -409.096) (xy 125.126815 -409.113184)
			(xy 125.132592 -409.12034) (xy 125.154343 -409.146022) (xy 125.192291 -409.201605) (xy 125.223324 -409.261324)
			(xy 125.246998 -409.324325) (xy 125.262972 -409.389703) (xy 125.271019 -409.456522) (xy 125.271022 -409.523824)
			(xy 125.262982 -409.590643) (xy 125.247014 -409.656023) (xy 125.223347 -409.719026) (xy 125.192319 -409.778749)
			(xy 125.154377 -409.834336) (xy 125.132592 -409.859988) (xy 125.126775 -409.867118) (xy 125.120273 -409.88432)
			(xy 125.119892 -409.893516) (xy 125.119892 -410.051504) (xy 125.119487 -410.061628) (xy 125.111736 -410.080333)
			(xy 125.097416 -410.094647) (xy 125.078708 -410.102391) (xy 125.068584 -410.102812) (xy 124.35205 -410.102812)
			(xy 124.341933 -410.102234) (xy 124.323223 -410.094532) (xy 124.308867 -410.080274) (xy 124.301036 -410.061618)
			(xy 124.300488 -410.051504) (xy 124.300488 -409.893516) (xy 124.300073 -409.884329) (xy 124.293563 -409.867145)
			(xy 124.287788 -409.859988) (xy 124.265963 -409.834366) (xy 124.228013 -409.778776) (xy 124.196978 -409.719049)
			(xy 124.173305 -409.65604) (xy 124.157333 -409.590654) (xy 124.149291 -409.523827) (xy 123.020646 -409.523827)
			(xy 122.992184 -409.578598) (xy 122.954233 -409.634184) (xy 122.932444 -409.659836) (xy 122.926643 -409.666978)
			(xy 122.920132 -409.684171) (xy 122.919744 -409.693364) (xy 122.919744 -410.186632) (xy 122.920151 -410.195819)
			(xy 122.926668 -410.213003) (xy 122.932444 -410.22016) (xy 122.954216 -410.245825) (xy 122.992167 -410.301409)
			(xy 123.023202 -410.361131) (xy 123.046876 -410.424134) (xy 123.062851 -410.489514) (xy 123.070896 -410.556336)
			(xy 123.070898 -410.62364) (xy 123.070891 -410.623701) (xy 126.348937 -410.623701) (xy 126.348938 -410.556275)
			(xy 126.357016 -410.489335) (xy 126.373055 -410.423845) (xy 126.396822 -410.360747) (xy 126.427977 -410.300951)
			(xy 126.46607 -410.245317) (xy 126.487936 -410.219652) (xy 126.49374 -410.212512) (xy 126.500249 -410.195317)
			(xy 126.500636 -410.186124) (xy 126.500636 -409.693872) (xy 126.500231 -409.684684) (xy 126.493713 -409.667501)
			(xy 126.487936 -409.660344) (xy 126.466083 -409.63467) (xy 126.427991 -409.579037) (xy 126.396838 -409.519243)
			(xy 126.373071 -409.456147) (xy 126.357034 -409.390659) (xy 126.348957 -409.323721) (xy 126.348956 -409.256297)
			(xy 126.357031 -409.189359) (xy 126.373066 -409.12387) (xy 126.396831 -409.060774) (xy 126.427982 -409.000978)
			(xy 126.466071 -408.945345) (xy 126.487936 -408.91968) (xy 126.493728 -408.912532) (xy 126.500245 -408.895343)
			(xy 126.500636 -408.886152) (xy 126.500636 -408.728672) (xy 126.500994 -408.718543) (xy 126.508758 -408.699832)
			(xy 126.523093 -408.685517) (xy 126.541815 -408.67778) (xy 126.551944 -408.677364) (xy 127.268224 -408.677364)
			(xy 127.27833 -408.677864) (xy 127.297002 -408.685603) (xy 127.311294 -408.699895) (xy 127.319035 -408.718566)
			(xy 127.319532 -408.728672) (xy 127.319532 -408.886152) (xy 127.31998 -408.895335) (xy 127.326469 -408.912519)
			(xy 127.332232 -408.91968) (xy 127.354107 -408.945336) (xy 127.392193 -409.000973) (xy 127.423341 -409.06077)
			(xy 127.447103 -409.123868) (xy 127.463137 -409.189358) (xy 127.471211 -409.256297) (xy 127.47121 -409.323721)
			(xy 127.463134 -409.39066) (xy 127.447098 -409.456149) (xy 127.423334 -409.519246) (xy 127.420948 -409.523827)
			(xy 128.549082 -409.523827) (xy 128.549085 -409.456519) (xy 128.557133 -409.389693) (xy 128.573111 -409.324308)
			(xy 128.59679 -409.261302) (xy 128.627829 -409.201578) (xy 128.665785 -409.145991) (xy 128.687576 -409.12034)
			(xy 128.693378 -409.113198) (xy 128.69989 -409.096005) (xy 128.700276 -409.086812) (xy 128.700276 -408.593544)
			(xy 128.69985 -408.584358) (xy 128.693348 -408.567174) (xy 128.687576 -408.560016) (xy 128.665779 -408.534371)
			(xy 128.627828 -408.478784) (xy 128.596793 -408.41906) (xy 128.573119 -408.356055) (xy 128.557146 -408.290671)
			(xy 128.549102 -408.223847) (xy 128.549103 -408.156541) (xy 128.557148 -408.089717) (xy 128.573123 -408.024334)
			(xy 128.596798 -407.961329) (xy 128.627835 -407.901605) (xy 128.665787 -407.84602) (xy 128.687576 -407.820368)
			(xy 128.693366 -407.813218) (xy 128.699885 -407.796031) (xy 128.700276 -407.78684) (xy 128.700276 -407.628852)
			(xy 128.700745 -407.618743) (xy 128.708494 -407.600069) (xy 128.722795 -407.585776) (xy 128.741475 -407.578039)
			(xy 128.751584 -407.577544) (xy 129.468118 -407.577544) (xy 129.478246 -407.578012) (xy 129.496969 -407.585746)
			(xy 129.511325 -407.600038) (xy 129.519143 -407.618726) (xy 129.51968 -407.628852) (xy 129.51968 -407.78684)
			(xy 129.520075 -407.796029) (xy 129.5266 -407.813213) (xy 129.53238 -407.820368) (xy 129.554159 -407.846027)
			(xy 129.592107 -407.901613) (xy 129.62314 -407.961336) (xy 129.646812 -408.024339) (xy 129.662785 -408.08972)
			(xy 129.67083 -408.156542) (xy 129.67083 -408.223846) (xy 129.662787 -408.290668) (xy 129.646816 -408.356049)
			(xy 129.623145 -408.419053) (xy 129.592113 -408.478777) (xy 129.554167 -408.534364) (xy 129.53238 -408.560016)
			(xy 129.526592 -408.567167) (xy 129.520073 -408.584353) (xy 129.51968 -408.593544) (xy 129.51968 -409.086812)
			(xy 129.520089 -409.095999) (xy 129.526604 -409.113183) (xy 129.53238 -409.12034) (xy 129.554131 -409.146022)
			(xy 129.59208 -409.201604) (xy 129.623114 -409.261324) (xy 129.646788 -409.324325) (xy 129.662763 -409.389703)
			(xy 129.670809 -409.456522) (xy 129.670813 -409.523824) (xy 129.662772 -409.590644) (xy 129.646804 -409.656024)
			(xy 129.623136 -409.719026) (xy 129.592108 -409.778749) (xy 129.554165 -409.834335) (xy 129.53238 -409.859988)
			(xy 129.526561 -409.867117) (xy 129.52006 -409.88432) (xy 129.51968 -409.893516) (xy 129.51968 -410.051504)
			(xy 129.519287 -410.061629) (xy 129.511534 -410.080337) (xy 129.49721 -410.094651) (xy 129.478497 -410.102393)
			(xy 129.468372 -410.102812) (xy 128.751838 -410.102812) (xy 128.74172 -410.102244) (xy 128.72301 -410.094538)
			(xy 128.708654 -410.080277) (xy 128.700824 -410.061618) (xy 128.700276 -410.051504) (xy 128.700276 -409.893516)
			(xy 128.699864 -409.884329) (xy 128.693352 -409.867144) (xy 128.687576 -409.859988) (xy 128.665751 -409.834366)
			(xy 128.627801 -409.778776) (xy 128.596768 -409.719048) (xy 128.573095 -409.65604) (xy 128.557124 -409.590654)
			(xy 128.549082 -409.523827) (xy 127.420948 -409.523827) (xy 127.392184 -409.579043) (xy 127.354096 -409.634678)
			(xy 127.332232 -409.660344) (xy 127.326426 -409.667482) (xy 127.319919 -409.684678) (xy 127.319532 -409.693872)
			(xy 127.319532 -410.186124) (xy 127.319946 -410.19531) (xy 127.326459 -410.212494) (xy 127.332232 -410.219652)
			(xy 127.354079 -410.245331) (xy 127.392166 -410.300964) (xy 127.423316 -410.360759) (xy 127.44708 -410.423854)
			(xy 127.463115 -410.489341) (xy 127.471192 -410.556277) (xy 127.471193 -410.623641) (xy 130.749257 -410.623641)
			(xy 130.749258 -410.556335) (xy 130.757303 -410.489512) (xy 130.773278 -410.424129) (xy 130.796952 -410.361123)
			(xy 130.827986 -410.301399) (xy 130.865936 -410.245812) (xy 130.887724 -410.22016) (xy 130.893523 -410.213017)
			(xy 130.900035 -410.195825) (xy 130.900424 -410.186632) (xy 130.900424 -409.693364) (xy 130.900026 -409.684176)
			(xy 130.893503 -409.666992) (xy 130.887724 -409.659836) (xy 130.865948 -409.634174) (xy 130.828 -409.578589)
			(xy 130.796967 -409.518866) (xy 130.773294 -409.455863) (xy 130.757321 -409.390482) (xy 130.749276 -409.323661)
			(xy 130.749275 -409.256357) (xy 130.757318 -409.189536) (xy 130.773289 -409.124154) (xy 130.79696 -409.06115)
			(xy 130.827991 -409.001427) (xy 130.865937 -408.94584) (xy 130.887724 -408.920188) (xy 130.893511 -408.913036)
			(xy 130.900031 -408.895851) (xy 130.900424 -408.88666) (xy 130.900424 -408.728672) (xy 130.900799 -408.718513)
			(xy 130.908608 -408.699755) (xy 130.92302 -408.685432) (xy 130.941825 -408.677738) (xy 130.951986 -408.677364)
			(xy 131.668266 -408.677364) (xy 131.678393 -408.677855) (xy 131.697118 -408.685576) (xy 131.711477 -408.699862)
			(xy 131.719293 -408.718547) (xy 131.719828 -408.728672) (xy 131.719828 -408.88666) (xy 131.720251 -408.895846)
			(xy 131.726755 -408.913031) (xy 131.732528 -408.920188) (xy 131.754328 -408.94583) (xy 131.792279 -409.001417)
			(xy 131.823314 -409.061142) (xy 131.846987 -409.124148) (xy 131.86296 -409.189532) (xy 131.871004 -409.256356)
			(xy 131.871003 -409.323662) (xy 131.862957 -409.390486) (xy 131.846982 -409.45587) (xy 131.823306 -409.518875)
			(xy 131.79227 -409.578598) (xy 131.754317 -409.634184) (xy 131.732528 -409.659836) (xy 131.726725 -409.666976)
			(xy 131.720216 -409.684171) (xy 131.719828 -409.693364) (xy 131.719828 -410.186632) (xy 131.720217 -410.195822)
			(xy 131.726745 -410.213006) (xy 131.732528 -410.22016) (xy 131.754301 -410.245825) (xy 131.792252 -410.301409)
			(xy 131.823288 -410.36113) (xy 131.846963 -410.424133) (xy 131.862938 -410.489514) (xy 131.870984 -410.556336)
			(xy 131.870986 -410.62364) (xy 131.862943 -410.690462) (xy 131.84697 -410.755844) (xy 131.823298 -410.818848)
			(xy 131.792265 -410.878571) (xy 131.754316 -410.934156) (xy 131.732528 -410.959808) (xy 131.726737 -410.966957)
			(xy 131.720221 -410.984145) (xy 131.719828 -410.993336) (xy 131.719828 -411.151324) (xy 131.719399 -411.161476)
			(xy 131.7116 -411.180224) (xy 131.697207 -411.194545) (xy 131.67842 -411.202249) (xy 131.668266 -411.202632)
			(xy 130.951986 -411.202632) (xy 130.941855 -411.202184) (xy 130.923128 -411.194446) (xy 130.908772 -411.180148)
			(xy 130.900958 -411.161453) (xy 130.900424 -411.151324) (xy 130.900424 -410.993336) (xy 130.899991 -410.984151)
			(xy 130.893493 -410.966967) (xy 130.887724 -410.959808) (xy 130.865921 -410.934169) (xy 130.827974 -410.87858)
			(xy 130.796942 -410.818855) (xy 130.773271 -410.755848) (xy 130.757299 -410.690465) (xy 130.749257 -410.623641)
			(xy 127.471193 -410.623641) (xy 127.471193 -410.623699) (xy 127.463119 -410.690635) (xy 127.447087 -410.756123)
			(xy 127.423326 -410.819219) (xy 127.392179 -410.879015) (xy 127.354094 -410.93465) (xy 127.332232 -410.960316)
			(xy 127.326438 -410.967463) (xy 127.319924 -410.984652) (xy 127.319532 -410.993844) (xy 127.319532 -411.151324)
			(xy 127.319035 -411.16143) (xy 127.311296 -411.180103) (xy 127.297003 -411.194396) (xy 127.27833 -411.202135)
			(xy 127.268224 -411.202632) (xy 126.551944 -411.202632) (xy 126.541828 -411.202149) (xy 126.523132 -411.194421)
			(xy 126.508817 -411.180125) (xy 126.501065 -411.161439) (xy 126.500636 -411.151324) (xy 126.500636 -410.993844)
			(xy 126.500196 -410.98466) (xy 126.493702 -410.967476) (xy 126.487936 -410.960316) (xy 126.466055 -410.934664)
			(xy 126.427964 -410.879029) (xy 126.396812 -410.819231) (xy 126.373048 -410.756132) (xy 126.357012 -410.690641)
			(xy 126.348937 -410.623701) (xy 123.070891 -410.623701) (xy 123.062855 -410.690462) (xy 123.046883 -410.755843)
			(xy 123.023211 -410.818847) (xy 122.992179 -410.87857) (xy 122.954231 -410.934156) (xy 122.932444 -410.959808)
			(xy 122.926655 -410.966958) (xy 122.920137 -410.984145) (xy 122.919744 -410.993336) (xy 122.919744 -411.151324)
			(xy 122.919236 -411.161429) (xy 122.911498 -411.180099) (xy 122.897209 -411.194392) (xy 122.878541 -411.202133)
			(xy 122.868436 -411.202632) (xy 122.151902 -411.202632) (xy 122.141772 -411.202171) (xy 122.123046 -411.194439)
			(xy 122.108688 -411.180144) (xy 122.100874 -411.161452) (xy 122.10034 -411.151324) (xy 122.10034 -410.993336)
			(xy 122.099903 -410.984152) (xy 122.093407 -410.966968) (xy 122.08764 -410.959808) (xy 122.065836 -410.934169)
			(xy 122.027888 -410.878581) (xy 121.996855 -410.818855) (xy 121.973183 -410.755849) (xy 121.957211 -410.690465)
			(xy 121.949169 -410.623641) (xy 118.67113 -410.623641) (xy 118.67113 -410.6237) (xy 118.663055 -410.690638)
			(xy 118.647019 -410.756127) (xy 118.623255 -410.819223) (xy 118.592103 -410.879018) (xy 118.554013 -410.934652)
			(xy 118.532148 -410.960316) (xy 118.526356 -410.967464) (xy 118.51984 -410.984653) (xy 118.519448 -410.993844)
			(xy 118.519448 -411.151324) (xy 118.518936 -411.161428) (xy 118.511199 -411.180098) (xy 118.496911 -411.19439)
			(xy 118.478244 -411.202133) (xy 118.46814 -411.202632) (xy 117.75186 -411.202632) (xy 117.741753 -411.202148)
			(xy 117.72308 -411.194404) (xy 117.708787 -411.180107) (xy 117.701048 -411.161431) (xy 117.700552 -411.151324)
			(xy 117.700552 -410.993844) (xy 117.700109 -410.984661) (xy 117.693617 -410.967477) (xy 117.687852 -410.960316)
			(xy 117.66597 -410.934665) (xy 117.627879 -410.879029) (xy 117.596726 -410.819232) (xy 117.57296 -410.756133)
			(xy 117.556924 -410.690642) (xy 117.548849 -410.623701) (xy 92.270837 -410.623701) (xy 92.262802 -410.69046)
			(xy 92.246832 -410.755841) (xy 92.223163 -410.818845) (xy 92.192134 -410.878568) (xy 92.154189 -410.934155)
			(xy 92.132404 -410.959808) (xy 92.126622 -410.966964) (xy 92.120098 -410.984146) (xy 92.119704 -410.993336)
			(xy 92.119704 -411.151324) (xy 92.119298 -411.161479) (xy 92.111495 -411.180231) (xy 92.097094 -411.194554)
			(xy 92.078299 -411.202253) (xy 92.068142 -411.202632) (xy 91.351862 -411.202632) (xy 91.341729 -411.202204)
			(xy 91.323002 -411.194458) (xy 91.308646 -411.180154) (xy 91.300833 -411.161455) (xy 91.3003 -411.151324)
			(xy 91.3003 -410.993336) (xy 91.299873 -410.984151) (xy 91.293371 -410.966966) (xy 91.2876 -410.959808)
			(xy 91.265798 -410.934168) (xy 91.227852 -410.878579) (xy 91.196822 -410.818853) (xy 91.173151 -410.755847)
			(xy 91.157181 -410.690464) (xy 91.149138 -410.623641) (xy 87.871075 -410.623641) (xy 87.871075 -410.623699)
			(xy 87.863001 -410.690636) (xy 87.846967 -410.756124) (xy 87.823205 -410.81922) (xy 87.792057 -410.879016)
			(xy 87.753971 -410.934651) (xy 87.732108 -410.960316) (xy 87.726323 -410.96747) (xy 87.719801 -410.984654)
			(xy 87.719408 -410.993844) (xy 87.719408 -411.151324) (xy 87.718935 -411.161433) (xy 87.711191 -411.180111)
			(xy 87.69689 -411.194404) (xy 87.67821 -411.20214) (xy 87.6681 -411.202632) (xy 86.95182 -411.202632)
			(xy 86.941716 -411.202099) (xy 86.923045 -411.194374) (xy 86.90875 -411.180092) (xy 86.901009 -411.161427)
			(xy 86.900512 -411.151324) (xy 86.900512 -410.993844) (xy 86.900078 -410.984659) (xy 86.893581 -410.967475)
			(xy 86.887812 -410.960316) (xy 86.865932 -410.934664) (xy 86.827843 -410.879028) (xy 86.796692 -410.81923)
			(xy 86.772928 -410.756131) (xy 86.756894 -410.69064) (xy 86.748819 -410.623701) (xy 83.470773 -410.623701)
			(xy 83.462736 -410.690462) (xy 83.446764 -410.755844) (xy 83.423091 -410.818848) (xy 83.392058 -410.878571)
			(xy 83.354108 -410.934156) (xy 83.33232 -410.959808) (xy 83.32654 -410.966965) (xy 83.320015 -410.984146)
			(xy 83.31962 -410.993336) (xy 83.31962 -411.151324) (xy 83.319199 -411.161477) (xy 83.311399 -411.180226)
			(xy 83.297003 -411.194548) (xy 83.278213 -411.202251) (xy 83.268058 -411.202632) (xy 82.551778 -411.202632)
			(xy 82.541646 -411.202191) (xy 82.522919 -411.194451) (xy 82.508563 -411.18015) (xy 82.500749 -411.161454)
			(xy 82.500216 -411.151324) (xy 82.500216 -410.993336) (xy 82.499785 -410.984151) (xy 82.493285 -410.966967)
			(xy 82.487516 -410.959808) (xy 82.465713 -410.934169) (xy 82.427766 -410.87858) (xy 82.396735 -410.818854)
			(xy 82.373064 -410.755848) (xy 82.357093 -410.690465) (xy 82.349051 -410.623641) (xy 79.070987 -410.623641)
			(xy 79.070987 -410.623699) (xy 79.062913 -410.690636) (xy 79.04688 -410.756124) (xy 79.023119 -410.81922)
			(xy 78.991971 -410.879016) (xy 78.953886 -410.93465) (xy 78.932024 -410.960316) (xy 78.926241 -410.967471)
			(xy 78.919717 -410.984654) (xy 78.919324 -410.993844) (xy 78.919324 -411.151324) (xy 78.918835 -411.161431)
			(xy 78.911094 -411.180106) (xy 78.896799 -411.194399) (xy 78.878123 -411.202137) (xy 78.868016 -411.202632)
			(xy 78.151736 -411.202632) (xy 78.14162 -411.202155) (xy 78.122923 -411.194425) (xy 78.108609 -411.180127)
			(xy 78.100857 -411.16144) (xy 78.100428 -411.151324) (xy 78.100428 -410.993844) (xy 78.09999 -410.98466)
			(xy 78.093495 -410.967476) (xy 78.087728 -410.960316) (xy 78.065847 -410.934664) (xy 78.027757 -410.879028)
			(xy 77.996606 -410.819231) (xy 77.972841 -410.756132) (xy 77.956806 -410.690641) (xy 77.948731 -410.623701)
			(xy 74.670685 -410.623701) (xy 74.662649 -410.690462) (xy 74.646677 -410.755844) (xy 74.623005 -410.818848)
			(xy 74.591972 -410.87857) (xy 74.554023 -410.934156) (xy 74.532236 -410.959808) (xy 74.526446 -410.966957)
			(xy 74.519929 -410.984145) (xy 74.519536 -410.993336) (xy 74.519536 -411.151324) (xy 74.519099 -411.161475)
			(xy 74.511302 -411.180221) (xy 74.496911 -411.194542) (xy 74.478127 -411.202248) (xy 74.467974 -411.202632)
			(xy 73.751694 -411.202632) (xy 73.741563 -411.202177) (xy 73.722837 -411.194442) (xy 73.70848 -411.180146)
			(xy 73.700666 -411.161452) (xy 73.700132 -411.151324) (xy 73.700132 -410.993336) (xy 73.699697 -410.984152)
			(xy 73.6932 -410.966967) (xy 73.687432 -410.959808) (xy 73.665629 -410.934169) (xy 73.627681 -410.87858)
			(xy 73.596649 -410.818855) (xy 73.572977 -410.755849) (xy 73.557005 -410.690465) (xy 73.548963 -410.623641)
			(xy 66.525648 -410.623641) (xy 66.525648 -417.289488) (xy 66.525648 -417.371276) (xy 141.02334 -417.371276)
			(xy 141.02334 -394.305282) (xy 141.023796 -394.293166) (xy 141.031289 -394.270122) (xy 141.045535 -394.25052)
			(xy 141.06514 -394.23628) (xy 141.088186 -394.228793) (xy 141.100302 -394.22832) (xy 154.426158 -394.22832)
			(xy 154.57678 -394.378688) (xy 154.57678 -397.823825) (xy 159.349135 -397.823825) (xy 159.349138 -397.756518)
			(xy 159.357186 -397.689693) (xy 159.373162 -397.624309) (xy 159.396838 -397.561303) (xy 159.427875 -397.501578)
			(xy 159.465827 -397.44599) (xy 159.487616 -397.420338) (xy 159.493423 -397.4132) (xy 159.499931 -397.396004)
			(xy 159.500316 -397.38681) (xy 159.500316 -396.893542) (xy 159.499882 -396.884357) (xy 159.493384 -396.867173)
			(xy 159.487616 -396.860014) (xy 159.465819 -396.83437) (xy 159.427872 -396.778782) (xy 159.396841 -396.719057)
			(xy 159.373169 -396.656051) (xy 159.357198 -396.590668) (xy 159.349155 -396.523845) (xy 159.349156 -396.45654)
			(xy 159.3572 -396.389717) (xy 159.373174 -396.324334) (xy 159.396847 -396.26133) (xy 159.42788 -396.201606)
			(xy 159.465828 -396.146018) (xy 159.487616 -396.120366) (xy 159.493411 -396.11322) (xy 159.499926 -396.09603)
			(xy 159.500316 -396.086838) (xy 159.500316 -395.92885) (xy 159.500804 -395.918684) (xy 159.508569 -395.899895)
			(xy 159.522934 -395.885509) (xy 159.541713 -395.877718) (xy 159.551878 -395.877288) (xy 160.268158 -395.877288)
			(xy 160.278333 -395.877699) (xy 160.297136 -395.88548) (xy 160.311525 -395.89987) (xy 160.319302 -395.918675)
			(xy 160.31972 -395.92885) (xy 160.31972 -396.086838) (xy 160.320108 -396.096028) (xy 160.326637 -396.113212)
			(xy 160.33242 -396.120366) (xy 160.354199 -396.146026) (xy 160.392151 -396.20161) (xy 160.423187 -396.261332)
			(xy 160.446862 -396.324336) (xy 160.462837 -396.389718) (xy 160.470882 -396.45654) (xy 160.470883 -396.523845)
			(xy 160.46284 -396.590668) (xy 160.446866 -396.65605) (xy 160.423193 -396.719054) (xy 160.392159 -396.778777)
			(xy 160.354208 -396.834362) (xy 160.33242 -396.860014) (xy 160.326637 -396.867169) (xy 160.320114 -396.884352)
			(xy 160.31972 -396.893542) (xy 160.31972 -397.38681) (xy 160.320121 -397.395998) (xy 160.326641 -397.413183)
			(xy 160.33242 -397.420338) (xy 160.354172 -397.44602) (xy 160.392124 -397.501601) (xy 160.420549 -397.556296)
			(xy 161.5488 -397.556296) (xy 161.556874 -397.489359) (xy 161.572908 -397.423871) (xy 161.596669 -397.360775)
			(xy 161.627817 -397.300979) (xy 161.665902 -397.245344) (xy 161.687764 -397.219678) (xy 161.69356 -397.212533)
			(xy 161.700073 -397.195342) (xy 161.700464 -397.18615) (xy 161.700464 -397.028924) (xy 161.701004 -397.018821)
			(xy 161.708727 -397.00015) (xy 161.723007 -396.985856) (xy 161.74167 -396.978114) (xy 161.751772 -396.977616)
			(xy 162.468052 -396.977616) (xy 162.478173 -396.978056) (xy 162.496879 -396.985791) (xy 162.511195 -397.000101)
			(xy 162.51894 -397.018803) (xy 162.51936 -397.028924) (xy 162.51936 -397.18615) (xy 162.519803 -397.195333)
			(xy 162.526295 -397.212518) (xy 162.53206 -397.219678) (xy 162.553935 -397.245334) (xy 162.592026 -397.300969)
			(xy 162.623179 -397.360766) (xy 162.646944 -397.423864) (xy 162.66298 -397.489355) (xy 162.671056 -397.556295)
			(xy 162.671055 -397.62372) (xy 162.662977 -397.69066) (xy 162.64694 -397.75615) (xy 162.623173 -397.819247)
			(xy 162.620757 -397.823885) (xy 163.748903 -397.823885) (xy 163.748907 -397.756458) (xy 163.756987 -397.689517)
			(xy 163.773027 -397.624026) (xy 163.796796 -397.560927) (xy 163.827951 -397.50113) (xy 163.866045 -397.445495)
			(xy 163.887912 -397.41983) (xy 163.893722 -397.412694) (xy 163.900228 -397.395497) (xy 163.900612 -397.386302)
			(xy 163.900612 -396.89405) (xy 163.900175 -396.884866) (xy 163.89368 -396.867681) (xy 163.887912 -396.860522)
			(xy 163.866038 -396.834865) (xy 163.827949 -396.77923) (xy 163.796798 -396.719432) (xy 163.773034 -396.656334)
			(xy 163.756998 -396.590844) (xy 163.748923 -396.523905) (xy 163.748924 -396.45648) (xy 163.757001 -396.389541)
			(xy 163.773038 -396.324051) (xy 163.796804 -396.260954) (xy 163.827956 -396.201157) (xy 163.866047 -396.145523)
			(xy 163.887912 -396.119858) (xy 163.89371 -396.112714) (xy 163.900224 -396.095523) (xy 163.900612 -396.08633)
			(xy 163.900612 -395.92885) (xy 163.901167 -395.91873) (xy 163.908873 -395.900015) (xy 163.923138 -395.885658)
			(xy 163.941803 -395.877832) (xy 163.95192 -395.877288) (xy 164.6682 -395.877288) (xy 164.678353 -395.877721)
			(xy 164.697103 -395.885515) (xy 164.711426 -395.899908) (xy 164.719127 -395.918695) (xy 164.719508 -395.92885)
			(xy 164.719508 -396.08633) (xy 164.719902 -396.095519) (xy 164.726426 -396.112703) (xy 164.732208 -396.119858)
			(xy 164.754062 -396.145531) (xy 164.79215 -396.201165) (xy 164.823301 -396.26096) (xy 164.847065 -396.324056)
			(xy 164.863101 -396.389544) (xy 164.871178 -396.456481) (xy 164.871179 -396.523904) (xy 164.863104 -396.590841)
			(xy 164.84707 -396.65633) (xy 164.823307 -396.719426) (xy 164.792158 -396.779222) (xy 164.754071 -396.834857)
			(xy 164.732208 -396.860522) (xy 164.726421 -396.867674) (xy 164.7199 -396.884859) (xy 164.719508 -396.89405)
			(xy 164.719508 -397.386302) (xy 164.719915 -397.395489) (xy 164.726431 -397.412674) (xy 164.732208 -397.41983)
			(xy 164.754034 -397.445526) (xy 164.792124 -397.501156) (xy 164.823276 -397.560948) (xy 164.846898 -397.62366)
			(xy 165.949096 -397.62366) (xy 165.949096 -397.556355) (xy 165.957139 -397.489533) (xy 165.973111 -397.424151)
			(xy 165.996783 -397.361147) (xy 166.027816 -397.301424) (xy 166.065765 -397.245838) (xy 166.087552 -397.220186)
			(xy 166.093343 -397.213037) (xy 166.09986 -397.195849) (xy 166.100252 -397.186658) (xy 166.100252 -397.028924)
			(xy 166.10074 -397.018777) (xy 166.108519 -397.000035) (xy 166.122895 -396.985712) (xy 166.141666 -396.978003)
			(xy 166.151814 -396.977616) (xy 166.868094 -396.977616) (xy 166.878217 -396.978131) (xy 166.896934 -396.985852)
			(xy 166.911289 -397.000129) (xy 166.919113 -397.018803) (xy 166.919656 -397.028924) (xy 166.919656 -397.186658)
			(xy 166.920096 -397.195842) (xy 166.92659 -397.213026) (xy 166.932356 -397.220186) (xy 166.954154 -397.24583)
			(xy 166.992103 -397.301417) (xy 167.023136 -397.361142) (xy 167.046808 -397.424148) (xy 167.062781 -397.489531)
			(xy 167.070824 -397.556355) (xy 167.070823 -397.62366) (xy 167.062778 -397.690484) (xy 167.046804 -397.755867)
			(xy 167.02313 -397.818872) (xy 167.020556 -397.823825) (xy 168.149223 -397.823825) (xy 168.149226 -397.756518)
			(xy 168.157274 -397.689693) (xy 168.17325 -397.624309) (xy 168.196925 -397.561304) (xy 168.22796 -397.501579)
			(xy 168.265911 -397.445991) (xy 168.2877 -397.420338) (xy 168.293505 -397.413199) (xy 168.300015 -397.396004)
			(xy 168.3004 -397.38681) (xy 168.3004 -396.893542) (xy 168.29997 -396.884357) (xy 168.29347 -396.867172)
			(xy 168.2877 -396.860014) (xy 168.265904 -396.834369) (xy 168.227958 -396.778781) (xy 168.196927 -396.719056)
			(xy 168.173256 -396.656051) (xy 168.157285 -396.590668) (xy 168.149243 -396.523845) (xy 168.149244 -396.45654)
			(xy 168.157288 -396.389717) (xy 168.173261 -396.324335) (xy 168.196933 -396.26133) (xy 168.227965 -396.201606)
			(xy 168.265913 -396.146019) (xy 168.2877 -396.120366) (xy 168.293494 -396.113219) (xy 168.30001 -396.09603)
			(xy 168.3004 -396.086838) (xy 168.3004 -395.92885) (xy 168.300904 -395.918686) (xy 168.308665 -395.8999)
			(xy 168.323026 -395.885515) (xy 168.341799 -395.877721) (xy 168.351962 -395.877288) (xy 169.068242 -395.877288)
			(xy 169.078423 -395.877631) (xy 169.097228 -395.885439) (xy 169.111613 -395.89985) (xy 169.119388 -395.918669)
			(xy 169.119804 -395.92885) (xy 169.119804 -396.086838) (xy 169.120195 -396.096027) (xy 169.126722 -396.113212)
			(xy 169.132504 -396.120366) (xy 169.154281 -396.146027) (xy 169.192227 -396.201613) (xy 169.223258 -396.261336)
			(xy 169.24693 -396.324339) (xy 169.262902 -396.38972) (xy 169.270946 -396.456541) (xy 169.270947 -396.523844)
			(xy 169.262905 -396.590665) (xy 169.246934 -396.656047) (xy 169.223264 -396.71905) (xy 169.192235 -396.778774)
			(xy 169.15429 -396.834361) (xy 169.132504 -396.860014) (xy 169.126719 -396.867168) (xy 169.120197 -396.884352)
			(xy 169.119804 -396.893542) (xy 169.119804 -397.38681) (xy 169.120209 -397.395998) (xy 169.126726 -397.413182)
			(xy 169.132504 -397.420338) (xy 169.154253 -397.446021) (xy 169.1922 -397.501604) (xy 169.22062 -397.556296)
			(xy 170.348863 -397.556296) (xy 170.356939 -397.489357) (xy 170.372975 -397.423868) (xy 170.39674 -397.360771)
			(xy 170.427892 -397.300976) (xy 170.465983 -397.245342) (xy 170.487848 -397.219678) (xy 170.493642 -397.212531)
			(xy 170.500157 -397.195342) (xy 170.500548 -397.18615) (xy 170.500548 -397.028924) (xy 170.501103 -397.018823)
			(xy 170.508823 -397.000155) (xy 170.523098 -396.985862) (xy 170.541756 -396.978117) (xy 170.551856 -396.977616)
			(xy 171.268136 -396.977616) (xy 171.278249 -396.978056) (xy 171.296931 -396.985808) (xy 171.311225 -397.000119)
			(xy 171.318956 -397.01881) (xy 171.319444 -397.028924) (xy 171.319444 -397.18615) (xy 171.319891 -397.195333)
			(xy 171.326381 -397.212517) (xy 171.332144 -397.219678) (xy 171.35402 -397.245334) (xy 171.392112 -397.300969)
			(xy 171.423265 -397.360766) (xy 171.447031 -397.423864) (xy 171.463068 -397.489355) (xy 171.471144 -397.556295)
			(xy 171.471143 -397.62372) (xy 171.463065 -397.69066) (xy 171.447027 -397.756151) (xy 171.423259 -397.819248)
			(xy 171.420874 -397.823826) (xy 172.54899 -397.823826) (xy 172.548993 -397.756517) (xy 172.557042 -397.689691)
			(xy 172.57302 -397.624306) (xy 172.5967 -397.5613) (xy 172.62774 -397.501575) (xy 172.665697 -397.44599)
			(xy 172.687488 -397.420338) (xy 172.693292 -397.413198) (xy 172.699803 -397.396004) (xy 172.700188 -397.38681)
			(xy 172.700188 -396.893542) (xy 172.69976 -396.884357) (xy 172.693259 -396.867172) (xy 172.687488 -396.860014)
			(xy 172.665689 -396.834371) (xy 172.627737 -396.778784) (xy 172.596702 -396.71906) (xy 172.573027 -396.656054)
			(xy 172.557054 -396.59067) (xy 172.54901 -396.523846) (xy 172.54901 -396.456539) (xy 172.557056 -396.389715)
			(xy 172.573032 -396.324332) (xy 172.596708 -396.261327) (xy 172.627745 -396.201603) (xy 172.665698 -396.146018)
			(xy 172.687488 -396.120366) (xy 172.69328 -396.113218) (xy 172.699798 -396.09603) (xy 172.700188 -396.086838)
			(xy 172.700188 -395.92885) (xy 172.700606 -395.918675) (xy 172.708384 -395.899872) (xy 172.722772 -395.885484)
			(xy 172.741575 -395.877706) (xy 172.75175 -395.877288) (xy 173.46803 -395.877288) (xy 173.47821 -395.87764)
			(xy 173.497015 -395.885445) (xy 173.5114 -395.899852) (xy 173.519175 -395.91867) (xy 173.519592 -395.92885)
			(xy 173.519592 -396.086838) (xy 173.519986 -396.096027) (xy 173.526511 -396.113211) (xy 173.532292 -396.120366)
			(xy 173.554069 -396.146027) (xy 173.592016 -396.201613) (xy 173.623048 -396.261335) (xy 173.64672 -396.324339)
			(xy 173.662693 -396.389719) (xy 173.670737 -396.456541) (xy 173.670738 -396.523844) (xy 173.662695 -396.590666)
			(xy 173.646725 -396.656047) (xy 173.623054 -396.719051) (xy 173.592024 -396.778774) (xy 173.554078 -396.834361)
			(xy 173.532292 -396.860014) (xy 173.526506 -396.867167) (xy 173.519985 -396.884351) (xy 173.519592 -396.893542)
			(xy 173.519592 -397.38681) (xy 173.519999 -397.395998) (xy 173.526515 -397.413182) (xy 173.532292 -397.420338)
			(xy 173.554041 -397.446021) (xy 173.591989 -397.501604) (xy 173.620441 -397.556355) (xy 174.749183 -397.556355)
			(xy 174.757226 -397.489534) (xy 174.773198 -397.424152) (xy 174.796869 -397.361148) (xy 174.827901 -397.301424)
			(xy 174.865849 -397.245838) (xy 174.887636 -397.220186) (xy 174.893426 -397.213036) (xy 174.899944 -397.195849)
			(xy 174.900336 -397.186658) (xy 174.900336 -397.028924) (xy 174.900742 -397.018767) (xy 174.908536 -397.000008)
			(xy 174.922939 -396.985682) (xy 174.941739 -396.977988) (xy 174.951898 -396.977616) (xy 175.668178 -396.977616)
			(xy 175.6783 -396.978144) (xy 175.697017 -396.98586) (xy 175.711373 -397.000133) (xy 175.719197 -397.018805)
			(xy 175.71974 -397.028924) (xy 175.71974 -397.186658) (xy 175.720184 -397.195841) (xy 175.726675 -397.213025)
			(xy 175.73244 -397.220186) (xy 175.754238 -397.24583) (xy 175.792188 -397.301417) (xy 175.823222 -397.361142)
			(xy 175.846895 -397.424147) (xy 175.862868 -397.489531) (xy 175.870912 -397.556354) (xy 175.870911 -397.623661)
			(xy 175.862865 -397.690484) (xy 175.846891 -397.755867) (xy 175.823216 -397.818872) (xy 175.79218 -397.878596)
			(xy 175.754229 -397.934182) (xy 175.73244 -397.959834) (xy 175.726639 -397.966976) (xy 175.720129 -397.984169)
			(xy 175.71974 -397.993362) (xy 175.71974 -398.486884) (xy 175.720171 -398.496069) (xy 175.726672 -398.513253)
			(xy 175.73244 -398.520412) (xy 175.754264 -398.546035) (xy 175.792213 -398.601625) (xy 175.823246 -398.661352)
			(xy 175.846918 -398.724361) (xy 175.862889 -398.789747) (xy 175.87093 -398.856573) (xy 175.870927 -398.923881)
			(xy 175.862879 -398.990707) (xy 175.846902 -399.056091) (xy 175.823224 -399.119097) (xy 175.792185 -399.178822)
			(xy 175.754231 -399.234408) (xy 175.73244 -399.26006) (xy 175.726628 -399.267194) (xy 175.720124 -399.284393)
			(xy 175.71974 -399.293588) (xy 175.71974 -399.451576) (xy 175.71926 -399.461724) (xy 175.71148 -399.480468)
			(xy 175.697101 -399.494791) (xy 175.678327 -399.502498) (xy 175.668178 -399.502884) (xy 174.951898 -399.502884)
			(xy 174.941774 -399.502376) (xy 174.923058 -399.494652) (xy 174.908702 -399.480372) (xy 174.900879 -399.461697)
			(xy 174.900336 -399.451576) (xy 174.900336 -399.293588) (xy 174.899924 -399.284401) (xy 174.893411 -399.267217)
			(xy 174.887636 -399.26006) (xy 174.865884 -399.234379) (xy 174.827934 -399.178796) (xy 174.7969 -399.119077)
			(xy 174.773225 -399.056076) (xy 174.75725 -398.990697) (xy 174.749203 -398.923878) (xy 174.749199 -398.856576)
			(xy 174.75724 -398.789756) (xy 174.773209 -398.724376) (xy 174.796878 -398.661373) (xy 174.827906 -398.60165)
			(xy 174.865851 -398.546064) (xy 174.887636 -398.520412) (xy 174.893457 -398.513284) (xy 174.899956 -398.49608)
			(xy 174.900336 -398.486884) (xy 174.900336 -397.993362) (xy 174.899936 -397.984174) (xy 174.893414 -397.96699)
			(xy 174.887636 -397.959834) (xy 174.865858 -397.934174) (xy 174.827909 -397.878588) (xy 174.796876 -397.818866)
			(xy 174.773202 -397.755863) (xy 174.757229 -397.690481) (xy 174.749184 -397.62366) (xy 174.749183 -397.556355)
			(xy 173.620441 -397.556355) (xy 173.623023 -397.561324) (xy 173.646696 -397.624324) (xy 173.662671 -397.689702)
			(xy 173.670718 -397.756521) (xy 173.670721 -397.823822) (xy 173.662681 -397.890642) (xy 173.646713 -397.956021)
			(xy 173.623046 -398.019024) (xy 173.592019 -398.078747) (xy 173.554077 -398.134334) (xy 173.532292 -398.159986)
			(xy 173.526475 -398.167117) (xy 173.519973 -398.184318) (xy 173.519592 -398.193514) (xy 173.519592 -398.351502)
			(xy 173.519069 -398.361656) (xy 173.511299 -398.38042) (xy 173.496943 -398.394784) (xy 173.478184 -398.402563)
			(xy 173.46803 -398.403064) (xy 172.75175 -398.403064) (xy 172.741582 -398.402595) (xy 172.722789 -398.394827)
			(xy 172.708402 -398.380455) (xy 172.700615 -398.36167) (xy 172.700188 -398.351502) (xy 172.700188 -398.193514)
			(xy 172.699774 -398.184327) (xy 172.693263 -398.167143) (xy 172.687488 -398.159986) (xy 172.665661 -398.134365)
			(xy 172.627711 -398.078775) (xy 172.596676 -398.019048) (xy 172.573004 -397.956039) (xy 172.557032 -397.890653)
			(xy 172.54899 -397.823826) (xy 171.420874 -397.823826) (xy 171.392104 -397.879044) (xy 171.354011 -397.934678)
			(xy 171.332144 -397.960342) (xy 171.32634 -397.967482) (xy 171.319831 -397.984677) (xy 171.319444 -397.99387)
			(xy 171.319444 -398.486376) (xy 171.319878 -398.49556) (xy 171.326376 -398.512744) (xy 171.332144 -398.519904)
			(xy 171.354045 -398.545539) (xy 171.392137 -398.601177) (xy 171.423289 -398.660976) (xy 171.447054 -398.724077)
			(xy 171.463088 -398.789571) (xy 171.471162 -398.856513) (xy 171.471159 -398.923941) (xy 171.463078 -398.990883)
			(xy 171.447037 -399.056374) (xy 171.423267 -399.119473) (xy 171.392109 -399.17927) (xy 171.354012 -399.234904)
			(xy 171.332144 -399.260568) (xy 171.326329 -399.2677) (xy 171.319827 -399.284901) (xy 171.319444 -399.294096)
			(xy 171.319444 -399.451576) (xy 171.318896 -399.461678) (xy 171.311175 -399.480347) (xy 171.296897 -399.494641)
			(xy 171.278237 -399.502385) (xy 171.268136 -399.502884) (xy 170.551856 -399.502884) (xy 170.541742 -399.50245)
			(xy 170.52306 -399.494695) (xy 170.508766 -399.480383) (xy 170.501036 -399.46169) (xy 170.500548 -399.451576)
			(xy 170.500548 -399.294096) (xy 170.500129 -399.28491) (xy 170.49362 -399.267726) (xy 170.487848 -399.260568)
			(xy 170.466018 -399.234874) (xy 170.427925 -399.179245) (xy 170.39677 -399.119453) (xy 170.373001 -399.05636)
			(xy 170.356962 -398.990874) (xy 170.348883 -398.923938) (xy 170.348879 -398.856516) (xy 170.356952 -398.789579)
			(xy 170.372985 -398.724092) (xy 170.396748 -398.660996) (xy 170.427897 -398.601201) (xy 170.465984 -398.545568)
			(xy 170.487848 -398.519904) (xy 170.493631 -398.51275) (xy 170.500153 -398.495566) (xy 170.500548 -398.486376)
			(xy 170.500548 -397.99387) (xy 170.500141 -397.984683) (xy 170.493624 -397.967499) (xy 170.487848 -397.960342)
			(xy 170.465992 -397.934669) (xy 170.4279 -397.879037) (xy 170.396746 -397.819242) (xy 170.372979 -397.756146)
			(xy 170.356942 -397.690658) (xy 170.348864 -397.623719) (xy 170.348863 -397.556296) (xy 169.22062 -397.556296)
			(xy 169.223233 -397.561324) (xy 169.246906 -397.624324) (xy 169.26288 -397.689702) (xy 169.270927 -397.756521)
			(xy 169.27093 -397.823822) (xy 169.26289 -397.890641) (xy 169.246923 -397.956021) (xy 169.223256 -398.019024)
			(xy 169.19223 -398.078746) (xy 169.154288 -398.134333) (xy 169.132504 -398.159986) (xy 169.126689 -398.167118)
			(xy 169.120185 -398.184319) (xy 169.119804 -398.193514) (xy 169.119804 -398.351502) (xy 169.119269 -398.361655)
			(xy 169.111502 -398.380416) (xy 169.097149 -398.394779) (xy 169.078394 -398.402561) (xy 169.068242 -398.403064)
			(xy 168.351962 -398.403064) (xy 168.341802 -398.402598) (xy 168.323032 -398.394811) (xy 168.308669 -398.380437)
			(xy 168.300895 -398.361662) (xy 168.3004 -398.351502) (xy 168.3004 -398.193514) (xy 168.299983 -398.184328)
			(xy 168.293474 -398.167143) (xy 168.2877 -398.159986) (xy 168.265876 -398.134364) (xy 168.227931 -398.078772)
			(xy 168.196902 -398.019044) (xy 168.173233 -397.956036) (xy 168.157263 -397.89065) (xy 168.149223 -397.823825)
			(xy 167.020556 -397.823825) (xy 166.992095 -397.878596) (xy 166.954145 -397.934182) (xy 166.932356 -397.959834)
			(xy 166.926557 -397.966977) (xy 166.920045 -397.984169) (xy 166.919656 -397.993362) (xy 166.919656 -398.486884)
			(xy 166.920084 -398.496069) (xy 166.926586 -398.513253) (xy 166.932356 -398.520412) (xy 166.954179 -398.546035)
			(xy 166.992127 -398.601625) (xy 167.023159 -398.661353) (xy 167.04683 -398.724361) (xy 167.062801 -398.789747)
			(xy 167.070842 -398.856573) (xy 167.070839 -398.923881) (xy 167.062791 -398.990706) (xy 167.046814 -399.05609)
			(xy 167.023137 -399.119097) (xy 166.9921 -399.178821) (xy 166.954146 -399.234408) (xy 166.932356 -399.26006)
			(xy 166.926546 -399.267195) (xy 166.92004 -399.284394) (xy 166.919656 -399.293588) (xy 166.919656 -399.451576)
			(xy 166.91916 -399.461722) (xy 166.911383 -399.480463) (xy 166.89701 -399.494785) (xy 166.878241 -399.502496)
			(xy 166.868094 -399.502884) (xy 166.151814 -399.502884) (xy 166.141691 -399.502363) (xy 166.122975 -399.494644)
			(xy 166.108619 -399.480369) (xy 166.100795 -399.461696) (xy 166.100252 -399.451576) (xy 166.100252 -399.293588)
			(xy 166.099836 -399.284402) (xy 166.093325 -399.267218) (xy 166.087552 -399.26006) (xy 166.065799 -399.234379)
			(xy 166.027849 -399.178797) (xy 165.996813 -399.119077) (xy 165.973138 -399.056077) (xy 165.957162 -398.990698)
			(xy 165.949115 -398.923878) (xy 165.949111 -398.856576) (xy 165.957152 -398.789755) (xy 165.973122 -398.724375)
			(xy 165.996791 -398.661372) (xy 166.027821 -398.60165) (xy 166.065766 -398.546064) (xy 166.087552 -398.520412)
			(xy 166.093375 -398.513286) (xy 166.099872 -398.49608) (xy 166.100252 -398.486884) (xy 166.100252 -397.993362)
			(xy 166.099848 -397.984174) (xy 166.093329 -397.966991) (xy 166.087552 -397.959834) (xy 166.065774 -397.934174)
			(xy 166.027824 -397.878589) (xy 165.99679 -397.818866) (xy 165.973116 -397.755863) (xy 165.957142 -397.690482)
			(xy 165.949096 -397.62366) (xy 164.846898 -397.62366) (xy 164.847042 -397.624041) (xy 164.863079 -397.689526)
			(xy 164.871158 -397.756461) (xy 164.871162 -397.823882) (xy 164.86309 -397.890817) (xy 164.847058 -397.956304)
			(xy 164.823299 -398.019399) (xy 164.792153 -398.079195) (xy 164.754069 -398.134829) (xy 164.732208 -398.160494)
			(xy 164.726432 -398.167654) (xy 164.719905 -398.184833) (xy 164.719508 -398.194022) (xy 164.719508 -398.351502)
			(xy 164.718976 -398.361623) (xy 164.711257 -398.380335) (xy 164.696985 -398.394689) (xy 164.678318 -398.402517)
			(xy 164.6682 -398.403064) (xy 163.95192 -398.403064) (xy 163.941763 -398.402661) (xy 163.923004 -398.394866)
			(xy 163.908678 -398.380462) (xy 163.900984 -398.361662) (xy 163.900612 -398.351502) (xy 163.900612 -398.194022)
			(xy 163.900188 -398.184836) (xy 163.893684 -398.167652) (xy 163.887912 -398.160494) (xy 163.86601 -398.13486)
			(xy 163.827922 -398.079221) (xy 163.796772 -398.019421) (xy 163.77301 -397.95632) (xy 163.756976 -397.890827)
			(xy 163.748903 -397.823885) (xy 162.620757 -397.823885) (xy 162.592019 -397.879044) (xy 162.553926 -397.934677)
			(xy 162.53206 -397.960342) (xy 162.526258 -397.967483) (xy 162.519748 -397.984677) (xy 162.51936 -397.99387)
			(xy 162.51936 -398.486376) (xy 162.51979 -398.495561) (xy 162.526291 -398.512745) (xy 162.53206 -398.519904)
			(xy 162.553961 -398.545539) (xy 162.592051 -398.601177) (xy 162.623202 -398.660977) (xy 162.646966 -398.724078)
			(xy 162.663 -398.789571) (xy 162.671074 -398.856513) (xy 162.671071 -398.923941) (xy 162.662991 -398.990882)
			(xy 162.64695 -399.056374) (xy 162.62318 -399.119472) (xy 162.592023 -399.179269) (xy 162.553928 -399.234903)
			(xy 162.53206 -399.260568) (xy 162.526247 -399.267701) (xy 162.519743 -399.284901) (xy 162.51936 -399.294096)
			(xy 162.51936 -399.451576) (xy 162.518964 -399.461702) (xy 162.511216 -399.480413) (xy 162.496893 -399.494729)
			(xy 162.478178 -399.502468) (xy 162.468052 -399.502884) (xy 161.751772 -399.502884) (xy 161.741659 -399.502438)
			(xy 161.722978 -399.494688) (xy 161.708683 -399.480379) (xy 161.700952 -399.461689) (xy 161.700464 -399.451576)
			(xy 161.700464 -399.294096) (xy 161.700041 -399.28491) (xy 161.693535 -399.267727) (xy 161.687764 -399.260568)
			(xy 161.665937 -399.234873) (xy 161.627849 -399.179242) (xy 161.596699 -399.119449) (xy 161.572934 -399.056357)
			(xy 161.556897 -398.990871) (xy 161.548819 -398.923937) (xy 161.548816 -398.856517) (xy 161.556888 -398.789582)
			(xy 161.572918 -398.724095) (xy 161.596677 -398.661) (xy 161.627821 -398.601205) (xy 161.665903 -398.54557)
			(xy 161.687764 -398.519904) (xy 161.693549 -398.512751) (xy 161.700069 -398.495566) (xy 161.700464 -398.486376)
			(xy 161.700464 -397.99387) (xy 161.700054 -397.984683) (xy 161.693538 -397.9675) (xy 161.687764 -397.960342)
			(xy 161.665911 -397.934668) (xy 161.627824 -397.879034) (xy 161.596675 -397.819239) (xy 161.572912 -397.756143)
			(xy 161.556877 -397.690655) (xy 161.548801 -397.623719) (xy 161.5488 -397.556296) (xy 160.420549 -397.556296)
			(xy 160.423161 -397.561321) (xy 160.446838 -397.624321) (xy 160.462815 -397.6897) (xy 160.470863 -397.75652)
			(xy 160.470866 -397.823823) (xy 160.462825 -397.890644) (xy 160.446855 -397.956024) (xy 160.423185 -398.019027)
			(xy 160.392154 -398.078749) (xy 160.354207 -398.134334) (xy 160.33242 -398.159986) (xy 160.326607 -398.16712)
			(xy 160.320101 -398.184319) (xy 160.31972 -398.193514) (xy 160.31972 -398.351502) (xy 160.319337 -398.361679)
			(xy 160.311543 -398.380482) (xy 160.297145 -398.394868) (xy 160.278335 -398.402645) (xy 160.268158 -398.403064)
			(xy 159.551878 -398.403064) (xy 159.541719 -398.402585) (xy 159.52295 -398.394804) (xy 159.508585 -398.380433)
			(xy 159.500811 -398.361661) (xy 159.500316 -398.351502) (xy 159.500316 -398.193514) (xy 159.499895 -398.184328)
			(xy 159.493388 -398.167144) (xy 159.487616 -398.159986) (xy 159.465792 -398.134364) (xy 159.427845 -398.078773)
			(xy 159.396815 -398.019045) (xy 159.373145 -397.956036) (xy 159.357176 -397.890651) (xy 159.349135 -397.823825)
			(xy 154.57678 -397.823825) (xy 154.57678 -401.723737) (xy 159.349146 -401.723737) (xy 159.349148 -401.65643)
			(xy 159.357194 -401.589607) (xy 159.373169 -401.524223) (xy 159.396843 -401.461218) (xy 159.427878 -401.401494)
			(xy 159.465828 -401.345906) (xy 159.487616 -401.320254) (xy 159.493416 -401.313112) (xy 159.499928 -401.295919)
			(xy 159.500316 -401.286726) (xy 159.500316 -400.793458) (xy 159.499923 -400.784269) (xy 159.493397 -400.767085)
			(xy 159.487616 -400.75993) (xy 159.465835 -400.734273) (xy 159.427887 -400.678686) (xy 159.396855 -400.618963)
			(xy 159.373183 -400.55596) (xy 159.35721 -400.490578) (xy 159.349166 -400.423757) (xy 159.349165 -400.356452)
			(xy 159.357209 -400.289631) (xy 159.37318 -400.224249) (xy 159.396851 -400.161245) (xy 159.427883 -400.101521)
			(xy 159.465829 -400.045934) (xy 159.487616 -400.020282) (xy 159.493405 -400.013131) (xy 159.499923 -399.995945)
			(xy 159.500316 -399.986754) (xy 159.500316 -399.828766) (xy 159.500805 -399.818609) (xy 159.508586 -399.799843)
			(xy 159.522953 -399.78548) (xy 159.541721 -399.777703) (xy 159.551878 -399.777204) (xy 160.268158 -399.777204)
			(xy 160.278323 -399.777697) (xy 160.29711 -399.785462) (xy 160.311495 -399.799826) (xy 160.319288 -399.818602)
			(xy 160.31972 -399.828766) (xy 160.31972 -399.986754) (xy 160.320148 -399.995939) (xy 160.326649 -400.013124)
			(xy 160.33242 -400.020282) (xy 160.354215 -400.045929) (xy 160.392166 -400.101515) (xy 160.423201 -400.161239)
			(xy 160.446876 -400.224244) (xy 160.462849 -400.289628) (xy 160.470894 -400.356451) (xy 160.470893 -400.423758)
			(xy 160.462848 -400.490581) (xy 160.446873 -400.555964) (xy 160.423198 -400.618969) (xy 160.392161 -400.678693)
			(xy 160.354209 -400.734278) (xy 160.33242 -400.75993) (xy 160.326631 -400.76708) (xy 160.320111 -400.784267)
			(xy 160.31972 -400.793458) (xy 160.31972 -401.286726) (xy 160.320113 -401.295915) (xy 160.326638 -401.313099)
			(xy 160.33242 -401.320254) (xy 160.354187 -401.345923) (xy 160.392139 -401.401506) (xy 160.423176 -401.461227)
			(xy 160.446852 -401.52423) (xy 160.462827 -401.58961) (xy 160.470874 -401.656431) (xy 160.470876 -401.723735)
			(xy 160.462833 -401.790557) (xy 160.446862 -401.855939) (xy 160.423189 -401.918943) (xy 160.392156 -401.978665)
			(xy 160.354208 -402.03425) (xy 160.33242 -402.059902) (xy 160.326642 -402.067061) (xy 160.320116 -402.084241)
			(xy 160.31972 -402.09343) (xy 160.31972 -402.251418) (xy 160.31935 -402.261596) (xy 160.311551 -402.280399)
			(xy 160.297149 -402.294785) (xy 160.278336 -402.302562) (xy 160.268158 -402.30298) (xy 159.551878 -402.30298)
			(xy 159.541721 -402.302485) (xy 159.522955 -402.294707) (xy 159.508591 -402.280342) (xy 159.500814 -402.261575)
			(xy 159.500316 -402.251418) (xy 159.500316 -402.09343) (xy 159.499888 -402.084245) (xy 159.493386 -402.06706)
			(xy 159.487616 -402.059902) (xy 159.465807 -402.034267) (xy 159.427861 -401.978678) (xy 159.39683 -401.918952)
			(xy 159.373159 -401.855945) (xy 159.357188 -401.790561) (xy 159.349146 -401.723737) (xy 154.57678 -401.723737)
			(xy 154.57678 -402.823877) (xy 161.54876 -402.823877) (xy 161.548765 -402.756451) (xy 161.556845 -402.68951)
			(xy 161.572884 -402.624018) (xy 161.596652 -402.56092) (xy 161.627806 -402.501122) (xy 161.665898 -402.445486)
			(xy 161.687764 -402.41982) (xy 161.693585 -402.412692) (xy 161.700083 -402.395488) (xy 161.700464 -402.386292)
			(xy 161.700464 -401.89404) (xy 161.70002 -401.884857) (xy 161.693528 -401.867673) (xy 161.687764 -401.860512)
			(xy 161.665882 -401.834862) (xy 161.627796 -401.779225) (xy 161.596648 -401.719426) (xy 161.572887 -401.656327)
			(xy 161.556854 -401.590837) (xy 161.54878 -401.523897) (xy 161.548782 -401.456473) (xy 161.556859 -401.389534)
			(xy 161.572896 -401.324044) (xy 161.59666 -401.260946) (xy 161.627811 -401.201149) (xy 161.6659 -401.145514)
			(xy 161.687764 -401.119848) (xy 161.693573 -401.112712) (xy 161.700078 -401.095514) (xy 161.700464 -401.08632)
			(xy 161.700464 -400.92884) (xy 161.700948 -400.918725) (xy 161.708676 -400.900029) (xy 161.722972 -400.885714)
			(xy 161.741657 -400.877961) (xy 161.751772 -400.877532) (xy 162.468052 -400.877532) (xy 162.478175 -400.877956)
			(xy 162.496884 -400.885694) (xy 162.511201 -400.900009) (xy 162.518942 -400.918717) (xy 162.51936 -400.92884)
			(xy 162.51936 -401.08632) (xy 162.519769 -401.095507) (xy 162.526285 -401.112691) (xy 162.53206 -401.119848)
			(xy 162.553906 -401.145529) (xy 162.591998 -401.20116) (xy 162.623151 -401.260954) (xy 162.646919 -401.324049)
			(xy 162.662957 -401.389536) (xy 162.671035 -401.456474) (xy 162.671037 -401.523896) (xy 162.662962 -401.590834)
			(xy 162.646927 -401.656323) (xy 162.623164 -401.719419) (xy 162.620884 -401.723796) (xy 163.748915 -401.723796)
			(xy 163.748917 -401.656371) (xy 163.756995 -401.589431) (xy 163.773033 -401.52394) (xy 163.7968 -401.460842)
			(xy 163.827954 -401.401046) (xy 163.866046 -401.345411) (xy 163.887912 -401.319746) (xy 163.893715 -401.312606)
			(xy 163.900226 -401.295411) (xy 163.900612 -401.286218) (xy 163.900612 -400.793966) (xy 163.900216 -400.784777)
			(xy 163.893692 -400.767593) (xy 163.887912 -400.760438) (xy 163.866054 -400.734768) (xy 163.827964 -400.679135)
			(xy 163.796812 -400.619339) (xy 163.773047 -400.556243) (xy 163.757011 -400.490754) (xy 163.748934 -400.423816)
			(xy 163.748934 -400.356393) (xy 163.757009 -400.289455) (xy 163.773044 -400.223966) (xy 163.796809 -400.160869)
			(xy 163.827959 -400.101073) (xy 163.866048 -400.045439) (xy 163.887912 -400.019774) (xy 163.893703 -400.012625)
			(xy 163.900221 -399.995437) (xy 163.900612 -399.986246) (xy 163.900612 -399.828766) (xy 163.901098 -399.818641)
			(xy 163.908832 -399.799924) (xy 163.923117 -399.78557) (xy 163.941797 -399.777747) (xy 163.95192 -399.777204)
			(xy 164.6682 -399.777204) (xy 164.678355 -399.777622) (xy 164.697108 -399.785418) (xy 164.711431 -399.799816)
			(xy 164.71913 -399.818609) (xy 164.719508 -399.828766) (xy 164.719508 -399.986246) (xy 164.719942 -399.995431)
			(xy 164.726439 -400.012615) (xy 164.732208 -400.019774) (xy 164.754078 -400.045435) (xy 164.792166 -400.10107)
			(xy 164.823316 -400.160867) (xy 164.847079 -400.223964) (xy 164.863114 -400.289454) (xy 164.871189 -400.356393)
			(xy 164.871189 -400.423817) (xy 164.863112 -400.490755) (xy 164.847076 -400.556244) (xy 164.823312 -400.619341)
			(xy 164.792161 -400.679138) (xy 164.754072 -400.734773) (xy 164.732208 -400.760438) (xy 164.726414 -400.767585)
			(xy 164.719897 -400.784774) (xy 164.719508 -400.793966) (xy 164.719508 -401.286218) (xy 164.719908 -401.295406)
			(xy 164.726429 -401.312591) (xy 164.732208 -401.319746) (xy 164.75405 -401.345429) (xy 164.792139 -401.401061)
			(xy 164.82329 -401.460855) (xy 164.847055 -401.52395) (xy 164.863092 -401.589436) (xy 164.871169 -401.656373)
			(xy 164.871171 -401.723794) (xy 164.863098 -401.790731) (xy 164.847065 -401.856219) (xy 164.823304 -401.919315)
			(xy 164.792156 -401.97911) (xy 164.75407 -402.034745) (xy 164.732208 -402.06041) (xy 164.726426 -402.067565)
			(xy 164.719902 -402.084748) (xy 164.719508 -402.093938) (xy 164.719508 -402.251418) (xy 164.71899 -402.26154)
			(xy 164.711265 -402.280253) (xy 164.696989 -402.294607) (xy 164.678319 -402.302434) (xy 164.6682 -402.30298)
			(xy 163.95192 -402.30298) (xy 163.941765 -402.302562) (xy 163.923009 -402.294769) (xy 163.908684 -402.280371)
			(xy 163.900987 -402.261575) (xy 163.900612 -402.251418) (xy 163.900612 -402.093938) (xy 163.900181 -402.084753)
			(xy 163.893681 -402.067569) (xy 163.887912 -402.06041) (xy 163.866026 -402.034763) (xy 163.827937 -401.979126)
			(xy 163.796787 -401.919327) (xy 163.773023 -401.856228) (xy 163.756989 -401.790737) (xy 163.748915 -401.723796)
			(xy 162.620884 -401.723796) (xy 162.592013 -401.779214) (xy 162.553924 -401.834847) (xy 162.53206 -401.860512)
			(xy 162.526271 -401.867662) (xy 162.519753 -401.884849) (xy 162.51936 -401.89404) (xy 162.51936 -402.386292)
			(xy 162.519783 -402.395478) (xy 162.526289 -402.412662) (xy 162.53206 -402.41982) (xy 162.553878 -402.445523)
			(xy 162.591971 -402.501152) (xy 162.623126 -402.560942) (xy 162.646895 -402.624034) (xy 162.662935 -402.689519)
			(xy 162.671015 -402.756454) (xy 162.671019 -402.823818) (xy 165.949055 -402.823818) (xy 165.94906 -402.756509)
			(xy 165.957109 -402.689683) (xy 165.973087 -402.624298) (xy 165.996766 -402.561292) (xy 166.027805 -402.501567)
			(xy 166.065761 -402.44598) (xy 166.087552 -402.420328) (xy 166.093368 -402.413197) (xy 166.09987 -402.395995)
			(xy 166.100252 -402.3868) (xy 166.100252 -401.893532) (xy 166.099815 -401.884348) (xy 166.093319 -401.867164)
			(xy 166.087552 -401.860004) (xy 166.065744 -401.834368) (xy 166.027795 -401.77878) (xy 165.996762 -401.719054)
			(xy 165.97309 -401.656047) (xy 165.957118 -401.590663) (xy 165.949075 -401.523838) (xy 165.949077 -401.456532)
			(xy 165.957123 -401.389707) (xy 165.973098 -401.324324) (xy 165.996774 -401.261318) (xy 166.02781 -401.201594)
			(xy 166.065762 -401.146008) (xy 166.087552 -401.120356) (xy 166.093356 -401.113216) (xy 166.099865 -401.096021)
			(xy 166.100252 -401.086828) (xy 166.100252 -400.92884) (xy 166.100754 -400.918694) (xy 166.108527 -400.899952)
			(xy 166.122899 -400.885629) (xy 166.141667 -400.87792) (xy 166.151814 -400.877532) (xy 166.868094 -400.877532)
			(xy 166.878219 -400.878031) (xy 166.896939 -400.885756) (xy 166.911295 -400.900038) (xy 166.919116 -400.918717)
			(xy 166.919656 -400.92884) (xy 166.919656 -401.086828) (xy 166.920063 -401.096015) (xy 166.92658 -401.113199)
			(xy 166.932356 -401.120356) (xy 166.954124 -401.146024) (xy 166.992074 -401.201608) (xy 167.023108 -401.26133)
			(xy 167.046782 -401.324332) (xy 167.062757 -401.389712) (xy 167.070803 -401.456533) (xy 167.070804 -401.523837)
			(xy 167.062762 -401.590658) (xy 167.046791 -401.656039) (xy 167.02312 -401.719043) (xy 167.020682 -401.723736)
			(xy 168.149234 -401.723736) (xy 168.149236 -401.65643) (xy 168.157282 -401.589607) (xy 168.173256 -401.524224)
			(xy 168.19693 -401.461219) (xy 168.227963 -401.401494) (xy 168.265912 -401.345907) (xy 168.2877 -401.320254)
			(xy 168.293499 -401.31311) (xy 168.300012 -401.295919) (xy 168.3004 -401.286726) (xy 168.3004 -400.793458)
			(xy 168.30001 -400.784269) (xy 168.293482 -400.767084) (xy 168.2877 -400.75993) (xy 168.265919 -400.734272)
			(xy 168.227973 -400.678686) (xy 168.196942 -400.618963) (xy 168.17327 -400.555959) (xy 168.157298 -400.490578)
			(xy 168.149254 -400.423756) (xy 168.149253 -400.356453) (xy 168.157296 -400.289631) (xy 168.173267 -400.22425)
			(xy 168.196938 -400.161246) (xy 168.227968 -400.101522) (xy 168.265914 -400.045935) (xy 168.2877 -400.020282)
			(xy 168.293487 -400.01313) (xy 168.300007 -399.995945) (xy 168.3004 -399.986754) (xy 168.3004 -399.828766)
			(xy 168.300905 -399.818611) (xy 168.308683 -399.799848) (xy 168.323045 -399.785485) (xy 168.341807 -399.777705)
			(xy 168.351962 -399.777204) (xy 169.068242 -399.777204) (xy 169.078398 -399.777698) (xy 169.097162 -399.78548)
			(xy 169.111524 -399.799845) (xy 169.119303 -399.81861) (xy 169.119804 -399.828766) (xy 169.119804 -399.986754)
			(xy 169.120235 -399.995939) (xy 169.126734 -400.013124) (xy 169.132504 -400.020282) (xy 169.154296 -400.04593)
			(xy 169.192242 -400.101518) (xy 169.223273 -400.161243) (xy 169.246943 -400.224248) (xy 169.262915 -400.28963)
			(xy 169.270958 -400.356452) (xy 169.270957 -400.423757) (xy 169.262913 -400.490579) (xy 169.246941 -400.555961)
			(xy 169.223269 -400.618966) (xy 169.192237 -400.67869) (xy 169.154291 -400.734277) (xy 169.132504 -400.75993)
			(xy 169.126713 -400.767079) (xy 169.120195 -400.784267) (xy 169.119804 -400.793458) (xy 169.119804 -401.286726)
			(xy 169.1202 -401.295915) (xy 169.126723 -401.313099) (xy 169.132504 -401.320254) (xy 169.154269 -401.345925)
			(xy 169.192215 -401.401509) (xy 169.223247 -401.461231) (xy 169.246919 -401.524233) (xy 169.262893 -401.589612)
			(xy 169.270938 -401.656432) (xy 169.27094 -401.723735) (xy 169.262899 -401.790555) (xy 169.246929 -401.855936)
			(xy 169.223261 -401.918939) (xy 169.192232 -401.978662) (xy 169.154289 -402.034249) (xy 169.132504 -402.059902)
			(xy 169.126725 -402.067059) (xy 169.1202 -402.084241) (xy 169.119804 -402.09343) (xy 169.119804 -402.251418)
			(xy 169.119283 -402.261572) (xy 169.11151 -402.280333) (xy 169.097154 -402.294697) (xy 169.078396 -402.302478)
			(xy 169.068242 -402.30298) (xy 168.351962 -402.30298) (xy 168.341804 -402.302498) (xy 168.323037 -402.294715)
			(xy 168.308674 -402.280346) (xy 168.300898 -402.261576) (xy 168.3004 -402.251418) (xy 168.3004 -402.09343)
			(xy 168.299975 -402.084244) (xy 168.293472 -402.06706) (xy 168.2877 -402.059902) (xy 168.265892 -402.034267)
			(xy 168.227946 -401.978677) (xy 168.196916 -401.918951) (xy 168.173246 -401.855944) (xy 168.157276 -401.79056)
			(xy 168.149234 -401.723736) (xy 167.020682 -401.723736) (xy 166.992089 -401.778766) (xy 166.954142 -401.834352)
			(xy 166.932356 -401.860004) (xy 166.92657 -401.867156) (xy 166.92005 -401.884342) (xy 166.919656 -401.893532)
			(xy 166.919656 -402.3868) (xy 166.920076 -402.395986) (xy 166.926584 -402.41317) (xy 166.932356 -402.420328)
			(xy 166.954097 -402.446019) (xy 166.992047 -402.5016) (xy 167.023083 -402.561318) (xy 167.046758 -402.624317)
			(xy 167.062735 -402.689695) (xy 167.070783 -402.756513) (xy 167.070787 -402.823815) (xy 167.070779 -402.823878)
			(xy 170.348823 -402.823878) (xy 170.348828 -402.75645) (xy 170.356909 -402.689507) (xy 170.372951 -402.624015)
			(xy 170.396723 -402.560916) (xy 170.427882 -402.501119) (xy 170.465979 -402.445484) (xy 170.487848 -402.41982)
			(xy 170.493667 -402.412691) (xy 170.500167 -402.395488) (xy 170.500548 -402.386292) (xy 170.500548 -401.89404)
			(xy 170.500108 -401.884856) (xy 170.493614 -401.867672) (xy 170.487848 -401.860512) (xy 170.465963 -401.834864)
			(xy 170.427871 -401.779228) (xy 170.396719 -401.71943) (xy 170.372954 -401.656331) (xy 170.356918 -401.590839)
			(xy 170.348843 -401.523898) (xy 170.348845 -401.456472) (xy 170.356924 -401.389531) (xy 170.372963 -401.324041)
			(xy 170.396731 -401.260943) (xy 170.427887 -401.201146) (xy 170.465981 -401.145512) (xy 170.487848 -401.119848)
			(xy 170.493655 -401.112711) (xy 170.500162 -401.095514) (xy 170.500548 -401.08632) (xy 170.500548 -400.92884)
			(xy 170.501117 -400.91874) (xy 170.508832 -400.900073) (xy 170.523102 -400.885779) (xy 170.541757 -400.878033)
			(xy 170.551856 -400.877532) (xy 171.268136 -400.877532) (xy 171.278265 -400.877887) (xy 171.296975 -400.885653)
			(xy 171.311289 -400.899989) (xy 171.319028 -400.918711) (xy 171.319444 -400.92884) (xy 171.319444 -401.08632)
			(xy 171.319857 -401.095507) (xy 171.32637 -401.11269) (xy 171.332144 -401.119848) (xy 171.35399 -401.145528)
			(xy 171.392083 -401.20116) (xy 171.423238 -401.260953) (xy 171.447006 -401.324048) (xy 171.463044 -401.389536)
			(xy 171.471123 -401.456473) (xy 171.471124 -401.523897) (xy 171.46305 -401.590834) (xy 171.447015 -401.656323)
			(xy 171.42325 -401.719419) (xy 171.421001 -401.723737) (xy 172.549001 -401.723737) (xy 172.549003 -401.65643)
			(xy 172.55705 -401.589605) (xy 172.573027 -401.524221) (xy 172.596704 -401.461215) (xy 172.627743 -401.401491)
			(xy 172.665697 -401.345906) (xy 172.687488 -401.320254) (xy 172.693285 -401.313109) (xy 172.6998 -401.295918)
			(xy 172.700188 -401.286726) (xy 172.700188 -400.793458) (xy 172.699801 -400.784268) (xy 172.693272 -400.767084)
			(xy 172.687488 -400.75993) (xy 172.665705 -400.734274) (xy 172.627752 -400.678689) (xy 172.596716 -400.618966)
			(xy 172.573041 -400.555962) (xy 172.557066 -400.49058) (xy 172.549021 -400.423757) (xy 172.54902 -400.356452)
			(xy 172.557065 -400.289629) (xy 172.573038 -400.224246) (xy 172.596713 -400.161242) (xy 172.627748 -400.101519)
			(xy 172.665699 -400.045933) (xy 172.687488 -400.020282) (xy 172.693273 -400.013129) (xy 172.699795 -399.995944)
			(xy 172.700188 -399.986754) (xy 172.700188 -399.828766) (xy 172.700537 -399.818586) (xy 172.708343 -399.799781)
			(xy 172.722752 -399.785395) (xy 172.741569 -399.777621) (xy 172.75175 -399.777204) (xy 173.46803 -399.777204)
			(xy 173.478186 -399.777708) (xy 173.496949 -399.785486) (xy 173.511312 -399.799848) (xy 173.519091 -399.818611)
			(xy 173.519592 -399.828766) (xy 173.519592 -399.986754) (xy 173.520026 -399.995939) (xy 173.526523 -400.013123)
			(xy 173.532292 -400.020282) (xy 173.554085 -400.04593) (xy 173.592031 -400.101518) (xy 173.623063 -400.161242)
			(xy 173.646734 -400.224247) (xy 173.662705 -400.289629) (xy 173.670749 -400.356452) (xy 173.670748 -400.423757)
			(xy 173.662704 -400.490579) (xy 173.646731 -400.555962) (xy 173.623059 -400.618966) (xy 173.592027 -400.67869)
			(xy 173.554079 -400.734277) (xy 173.532292 -400.75993) (xy 173.526499 -400.767078) (xy 173.519983 -400.784266)
			(xy 173.519592 -400.793458) (xy 173.519592 -401.286726) (xy 173.519991 -401.295914) (xy 173.526513 -401.313099)
			(xy 173.532292 -401.320254) (xy 173.554057 -401.345924) (xy 173.592005 -401.401509) (xy 173.623037 -401.46123)
			(xy 173.64671 -401.524232) (xy 173.662683 -401.589612) (xy 173.670729 -401.656432) (xy 173.670731 -401.723735)
			(xy 173.662689 -401.790555) (xy 173.64672 -401.855936) (xy 173.623051 -401.918939) (xy 173.592022 -401.978663)
			(xy 173.554077 -402.034249) (xy 173.532292 -402.059902) (xy 173.526511 -402.067058) (xy 173.519987 -402.08424)
			(xy 173.519592 -402.09343) (xy 173.519592 -402.251418) (xy 173.519082 -402.261573) (xy 173.511308 -402.280337)
			(xy 173.496947 -402.294701) (xy 173.478185 -402.30248) (xy 173.46803 -402.30298) (xy 172.75175 -402.30298)
			(xy 172.741584 -402.302496) (xy 172.722794 -402.29473) (xy 172.708408 -402.280363) (xy 172.700618 -402.261584)
			(xy 172.700188 -402.251418) (xy 172.700188 -402.09343) (xy 172.699766 -402.084244) (xy 172.693261 -402.067059)
			(xy 172.687488 -402.059902) (xy 172.665677 -402.034268) (xy 172.627726 -401.97868) (xy 172.596691 -401.918955)
			(xy 172.573017 -401.855948) (xy 172.557044 -401.790563) (xy 172.549001 -401.723737) (xy 171.421001 -401.723737)
			(xy 171.392099 -401.779215) (xy 171.354009 -401.834848) (xy 171.332144 -401.860512) (xy 171.326353 -401.867661)
			(xy 171.319836 -401.884849) (xy 171.319444 -401.89404) (xy 171.319444 -402.386292) (xy 171.31987 -402.395477)
			(xy 171.326374 -402.412661) (xy 171.332144 -402.41982) (xy 171.353963 -402.445523) (xy 171.392057 -402.501151)
			(xy 171.423213 -402.560941) (xy 171.446982 -402.624033) (xy 171.463022 -402.689518) (xy 171.471103 -402.756453)
			(xy 171.471107 -402.823818) (xy 174.749143 -402.823818) (xy 174.749147 -402.75651) (xy 174.757196 -402.689684)
			(xy 174.773174 -402.624299) (xy 174.796852 -402.561292) (xy 174.827891 -402.501567) (xy 174.865845 -402.44598)
			(xy 174.887636 -402.420328) (xy 174.89345 -402.413195) (xy 174.899953 -402.395995) (xy 174.900336 -402.3868)
			(xy 174.900336 -401.893532) (xy 174.899902 -401.884348) (xy 174.893404 -401.867163) (xy 174.887636 -401.860004)
			(xy 174.865829 -401.834368) (xy 174.827881 -401.778779) (xy 174.796848 -401.719053) (xy 174.773177 -401.656047)
			(xy 174.757205 -401.590663) (xy 174.749163 -401.523838) (xy 174.749165 -401.456532) (xy 174.757211 -401.389708)
			(xy 174.773186 -401.324324) (xy 174.796861 -401.261319) (xy 174.827896 -401.201595) (xy 174.865847 -401.146008)
			(xy 174.887636 -401.120356) (xy 174.893438 -401.113215) (xy 174.899949 -401.096021) (xy 174.900336 -401.086828)
			(xy 174.900336 -400.92884) (xy 174.900755 -400.918684) (xy 174.908544 -400.899926) (xy 174.922943 -400.8856)
			(xy 174.94174 -400.877905) (xy 174.951898 -400.877532) (xy 175.668178 -400.877532) (xy 175.678302 -400.878044)
			(xy 175.697022 -400.885763) (xy 175.711378 -400.900042) (xy 175.7192 -400.918718) (xy 175.71974 -400.92884)
			(xy 175.71974 -401.086828) (xy 175.72015 -401.096015) (xy 175.726665 -401.113198) (xy 175.73244 -401.120356)
			(xy 175.754209 -401.146024) (xy 175.792159 -401.201608) (xy 175.823195 -401.261329) (xy 175.846869 -401.324331)
			(xy 175.862844 -401.389712) (xy 175.870891 -401.456533) (xy 175.870892 -401.523837) (xy 175.86285 -401.590658)
			(xy 175.846878 -401.65604) (xy 175.823207 -401.719044) (xy 175.792175 -401.778766) (xy 175.754227 -401.834352)
			(xy 175.73244 -401.860004) (xy 175.726652 -401.867155) (xy 175.720134 -401.884341) (xy 175.71974 -401.893532)
			(xy 175.71974 -402.3868) (xy 175.720164 -402.395985) (xy 175.726669 -402.413169) (xy 175.73244 -402.420328)
			(xy 175.754181 -402.446019) (xy 175.792133 -402.501599) (xy 175.823169 -402.561317) (xy 175.846846 -402.624317)
			(xy 175.862823 -402.689694) (xy 175.870871 -402.756513) (xy 175.870875 -402.823815) (xy 175.862835 -402.890634)
			(xy 175.846867 -402.956014) (xy 175.823199 -403.019017) (xy 175.79217 -403.078739) (xy 175.754225 -403.134324)
			(xy 175.73244 -403.159976) (xy 175.726621 -403.167105) (xy 175.720122 -403.184308) (xy 175.71974 -403.193504)
			(xy 175.71974 -403.351492) (xy 175.719273 -403.361641) (xy 175.711487 -403.380385) (xy 175.697105 -403.394707)
			(xy 175.678328 -403.402415) (xy 175.668178 -403.4028) (xy 174.951898 -403.4028) (xy 174.941776 -403.402276)
			(xy 174.923063 -403.394555) (xy 174.908708 -403.380281) (xy 174.900882 -403.361611) (xy 174.900336 -403.351492)
			(xy 174.900336 -403.193504) (xy 174.899916 -403.184318) (xy 174.893408 -403.167134) (xy 174.887636 -403.159976)
			(xy 174.865801 -403.134363) (xy 174.827854 -403.078771) (xy 174.796823 -403.019042) (xy 174.773153 -402.956032)
			(xy 174.757183 -402.890645) (xy 174.749143 -402.823818) (xy 171.471107 -402.823818) (xy 171.471107 -402.823874)
			(xy 171.463035 -402.89081) (xy 171.447003 -402.956298) (xy 171.423242 -403.019393) (xy 171.392094 -403.079187)
			(xy 171.354007 -403.13482) (xy 171.332144 -403.160484) (xy 171.326322 -403.167611) (xy 171.319824 -403.184816)
			(xy 171.319444 -403.194012) (xy 171.319444 -403.351492) (xy 171.318909 -403.361595) (xy 171.311183 -403.380264)
			(xy 171.296901 -403.394558) (xy 171.278238 -403.402301) (xy 171.268136 -403.4028) (xy 170.551856 -403.4028)
			(xy 170.541744 -403.402351) (xy 170.523065 -403.394599) (xy 170.508772 -403.380291) (xy 170.501039 -403.361604)
			(xy 170.500548 -403.351492) (xy 170.500548 -403.194012) (xy 170.500121 -403.184827) (xy 170.493618 -403.167643)
			(xy 170.487848 -403.160484) (xy 170.465935 -403.134858) (xy 170.427845 -403.079219) (xy 170.396693 -403.019418)
			(xy 170.37293 -402.956316) (xy 170.356896 -402.890822) (xy 170.348823 -402.823878) (xy 167.070779 -402.823878)
			(xy 167.062748 -402.890634) (xy 167.04678 -402.956014) (xy 167.023112 -403.019016) (xy 166.992084 -403.078738)
			(xy 166.954141 -403.134324) (xy 166.932356 -403.159976) (xy 166.926539 -403.167107) (xy 166.920038 -403.184308)
			(xy 166.919656 -403.193504) (xy 166.919656 -403.351492) (xy 166.919173 -403.361639) (xy 166.911391 -403.38038)
			(xy 166.897014 -403.394702) (xy 166.878242 -403.402412) (xy 166.868094 -403.4028) (xy 166.151814 -403.4028)
			(xy 166.141693 -403.402263) (xy 166.12298 -403.394547) (xy 166.108624 -403.380277) (xy 166.100798 -403.36161)
			(xy 166.100252 -403.351492) (xy 166.100252 -403.193504) (xy 166.099828 -403.184318) (xy 166.093323 -403.167135)
			(xy 166.087552 -403.159976) (xy 166.065717 -403.134363) (xy 166.027768 -403.078771) (xy 165.996736 -403.019042)
			(xy 165.973066 -402.956033) (xy 165.957096 -402.890646) (xy 165.949055 -402.823818) (xy 162.671019 -402.823818)
			(xy 162.671019 -402.823874) (xy 162.662948 -402.89081) (xy 162.646916 -402.956297) (xy 162.623155 -403.019392)
			(xy 162.592008 -403.079187) (xy 162.553923 -403.13482) (xy 162.53206 -403.160484) (xy 162.52624 -403.167613)
			(xy 162.51974 -403.184816) (xy 162.51936 -403.194012) (xy 162.51936 -403.351492) (xy 162.518976 -403.361619)
			(xy 162.511224 -403.38033) (xy 162.496896 -403.394646) (xy 162.478179 -403.402384) (xy 162.468052 -403.4028)
			(xy 161.751772 -403.4028) (xy 161.741661 -403.402338) (xy 161.722983 -403.394591) (xy 161.708689 -403.380287)
			(xy 161.700955 -403.361603) (xy 161.700464 -403.351492) (xy 161.700464 -403.194012) (xy 161.700034 -403.184827)
			(xy 161.693532 -403.167643) (xy 161.687764 -403.160484) (xy 161.665854 -403.134857) (xy 161.627769 -403.079216)
			(xy 161.596623 -403.019414) (xy 161.572863 -402.956313) (xy 161.556832 -402.890819) (xy 161.54876 -402.823877)
			(xy 154.57678 -402.823877) (xy 154.57678 -405.623648) (xy 159.349158 -405.623648) (xy 159.349158 -405.556343)
			(xy 159.357202 -405.48952) (xy 159.373175 -405.424138) (xy 159.396848 -405.361133) (xy 159.427881 -405.301409)
			(xy 159.465829 -405.245822) (xy 159.487616 -405.22017) (xy 159.49341 -405.213023) (xy 159.499926 -405.195834)
			(xy 159.500316 -405.186642) (xy 159.500316 -404.693374) (xy 159.499915 -404.684186) (xy 159.493395 -404.667002)
			(xy 159.487616 -404.659846) (xy 159.465851 -404.634176) (xy 159.427903 -404.578591) (xy 159.39687 -404.51887)
			(xy 159.373197 -404.455868) (xy 159.357223 -404.390488) (xy 159.349177 -404.323668) (xy 159.349175 -404.256365)
			(xy 159.357217 -404.189544) (xy 159.373187 -404.124164) (xy 159.396856 -404.06116) (xy 159.427886 -404.001437)
			(xy 159.46583 -403.94585) (xy 159.487616 -403.920198) (xy 159.493398 -403.913042) (xy 159.499921 -403.89586)
			(xy 159.500316 -403.88667) (xy 159.500316 -403.728682) (xy 159.500818 -403.718526) (xy 159.508594 -403.69976)
			(xy 159.522957 -403.685396) (xy 159.541722 -403.677619) (xy 159.551878 -403.67712) (xy 160.268158 -403.67712)
			(xy 160.278325 -403.677598) (xy 160.297115 -403.685366) (xy 160.311501 -403.699735) (xy 160.31929 -403.718516)
			(xy 160.31972 -403.728682) (xy 160.31972 -403.88667) (xy 160.32014 -403.895856) (xy 160.326646 -403.913041)
			(xy 160.33242 -403.920198) (xy 160.354231 -403.945832) (xy 160.392181 -404.00142) (xy 160.423216 -404.061146)
			(xy 160.446889 -404.124153) (xy 160.462862 -404.189538) (xy 160.470905 -404.256363) (xy 160.470903 -404.32367)
			(xy 160.462856 -404.390495) (xy 160.446879 -404.455879) (xy 160.423202 -404.518885) (xy 160.392164 -404.578608)
			(xy 160.35421 -404.634194) (xy 160.33242 -404.659846) (xy 160.326624 -404.666992) (xy 160.320108 -404.684182)
			(xy 160.31972 -404.693374) (xy 160.31972 -405.186642) (xy 160.320105 -405.195832) (xy 160.326636 -405.213016)
			(xy 160.33242 -405.22017) (xy 160.354203 -405.245826) (xy 160.392155 -405.301411) (xy 160.42319 -405.361134)
			(xy 160.446865 -405.424138) (xy 160.46284 -405.48952) (xy 160.470885 -405.556343) (xy 160.470886 -405.623648)
			(xy 160.462842 -405.690471) (xy 160.446868 -405.755853) (xy 160.423194 -405.818858) (xy 160.392159 -405.878581)
			(xy 160.354209 -405.934166) (xy 160.33242 -405.959818) (xy 160.326636 -405.966972) (xy 160.320113 -405.984156)
			(xy 160.31972 -405.993346) (xy 160.31972 -406.151334) (xy 160.319363 -406.161513) (xy 160.311559 -406.180317)
			(xy 160.297153 -406.194702) (xy 160.278338 -406.202478) (xy 160.268158 -406.202896) (xy 159.551878 -406.202896)
			(xy 159.541723 -406.202386) (xy 159.52296 -406.19461) (xy 159.508596 -406.18025) (xy 159.500817 -406.161489)
			(xy 159.500316 -406.151334) (xy 159.500316 -405.993346) (xy 159.49988 -405.984162) (xy 159.493384 -405.966977)
			(xy 159.487616 -405.959818) (xy 159.465823 -405.93417) (xy 159.427876 -405.878583) (xy 159.396844 -405.818858)
			(xy 159.373173 -405.755853) (xy 159.357201 -405.690471) (xy 159.349158 -405.623648) (xy 154.57678 -405.623648)
			(xy 154.57678 -406.723789) (xy 161.548771 -406.723789) (xy 161.548774 -406.656363) (xy 161.556853 -406.589423)
			(xy 161.572891 -406.523933) (xy 161.596657 -406.460835) (xy 161.627809 -406.401038) (xy 161.665899 -406.345402)
			(xy 161.687764 -406.319736) (xy 161.693578 -406.312604) (xy 161.70008 -406.295403) (xy 161.700464 -406.286208)
			(xy 161.700464 -405.793956) (xy 161.700061 -405.784768) (xy 161.693541 -405.767585) (xy 161.687764 -405.760428)
			(xy 161.665897 -405.734765) (xy 161.627811 -405.67913) (xy 161.596663 -405.619333) (xy 161.5729 -405.556236)
			(xy 161.556866 -405.490747) (xy 161.548791 -405.423809) (xy 161.548792 -405.356385) (xy 161.556867 -405.289447)
			(xy 161.572902 -405.223959) (xy 161.596665 -405.160862) (xy 161.627814 -405.101065) (xy 161.665901 -405.04543)
			(xy 161.687764 -405.019764) (xy 161.693566 -405.012623) (xy 161.700076 -404.995429) (xy 161.700464 -404.986236)
			(xy 161.700464 -404.828756) (xy 161.700948 -404.818649) (xy 161.708694 -404.799977) (xy 161.72299 -404.785685)
			(xy 161.741665 -404.777945) (xy 161.751772 -404.777448) (xy 162.468052 -404.777448) (xy 162.478165 -404.777954)
			(xy 162.496858 -404.785677) (xy 162.511172 -404.799965) (xy 162.518928 -404.818644) (xy 162.51936 -404.828756)
			(xy 162.51936 -404.986236) (xy 162.519762 -404.995424) (xy 162.526282 -405.012608) (xy 162.53206 -405.019764)
			(xy 162.553921 -405.045432) (xy 162.592013 -405.101065) (xy 162.623166 -405.16086) (xy 162.646932 -405.223957)
			(xy 162.662969 -405.289446) (xy 162.671046 -405.356385) (xy 162.671046 -405.423809) (xy 162.66297 -405.490748)
			(xy 162.646934 -405.556237) (xy 162.623168 -405.619334) (xy 162.620889 -405.623708) (xy 163.748926 -405.623708)
			(xy 163.748926 -405.556283) (xy 163.757003 -405.489344) (xy 163.77304 -405.423855) (xy 163.796805 -405.360758)
			(xy 163.827957 -405.300961) (xy 163.866047 -405.245327) (xy 163.887912 -405.219662) (xy 163.893709 -405.212517)
			(xy 163.900223 -405.195326) (xy 163.900612 -405.186134) (xy 163.900612 -404.693882) (xy 163.900208 -404.684694)
			(xy 163.89369 -404.66751) (xy 163.887912 -404.660354) (xy 163.866069 -404.634671) (xy 163.827979 -404.579039)
			(xy 163.796827 -404.519246) (xy 163.773061 -404.456151) (xy 163.757023 -404.390664) (xy 163.748946 -404.323728)
			(xy 163.748944 -404.256305) (xy 163.757018 -404.189368) (xy 163.773051 -404.12388) (xy 163.796813 -404.060784)
			(xy 163.827962 -404.000989) (xy 163.866049 -403.945355) (xy 163.887912 -403.91969) (xy 163.893697 -403.912536)
			(xy 163.900218 -403.895352) (xy 163.900612 -403.886162) (xy 163.900612 -403.728682) (xy 163.901111 -403.718558)
			(xy 163.908839 -403.699841) (xy 163.923121 -403.685486) (xy 163.941798 -403.677663) (xy 163.95192 -403.67712)
			(xy 164.6682 -403.67712) (xy 164.678357 -403.677522) (xy 164.697113 -403.685321) (xy 164.711437 -403.699724)
			(xy 164.719133 -403.718523) (xy 164.719508 -403.728682) (xy 164.719508 -403.886162) (xy 164.719935 -403.895347)
			(xy 164.726437 -403.912532) (xy 164.732208 -403.91969) (xy 164.754093 -403.945338) (xy 164.792181 -404.000975)
			(xy 164.82333 -404.060774) (xy 164.847093 -404.123873) (xy 164.863126 -404.189364) (xy 164.8712 -404.256304)
			(xy 164.871198 -404.323729) (xy 164.86312 -404.390669) (xy 164.847083 -404.456159) (xy 164.823317 -404.519257)
			(xy 164.792164 -404.579054) (xy 164.754073 -404.634689) (xy 164.732208 -404.660354) (xy 164.726407 -404.667496)
			(xy 164.719895 -404.684689) (xy 164.719508 -404.693882) (xy 164.719508 -405.186134) (xy 164.7199 -405.195323)
			(xy 164.726426 -405.212508) (xy 164.732208 -405.219662) (xy 164.754066 -405.245332) (xy 164.792154 -405.300966)
			(xy 164.823305 -405.360762) (xy 164.847069 -405.423858) (xy 164.863104 -405.489346) (xy 164.871181 -405.556284)
			(xy 164.871181 -405.623707) (xy 164.863106 -405.690645) (xy 164.847072 -405.756133) (xy 164.823308 -405.81923)
			(xy 164.792159 -405.879026) (xy 164.754071 -405.934661) (xy 164.732208 -405.960326) (xy 164.726419 -405.967477)
			(xy 164.719899 -405.984663) (xy 164.719508 -405.993854) (xy 164.719508 -406.151334) (xy 164.719003 -406.161457)
			(xy 164.711273 -406.18017) (xy 164.696993 -406.194523) (xy 164.67832 -406.20235) (xy 164.6682 -406.202896)
			(xy 163.95192 -406.202896) (xy 163.941767 -406.202462) (xy 163.923014 -406.194672) (xy 163.90869 -406.180279)
			(xy 163.90099 -406.161489) (xy 163.900612 -406.151334) (xy 163.900612 -405.993854) (xy 163.900173 -405.98467)
			(xy 163.893679 -405.967485) (xy 163.887912 -405.960326) (xy 163.866042 -405.934666) (xy 163.827952 -405.879031)
			(xy 163.796801 -405.819234) (xy 163.773037 -405.756137) (xy 163.757001 -405.690647) (xy 163.748926 -405.623708)
			(xy 162.620889 -405.623708) (xy 162.592016 -405.67913) (xy 162.553925 -405.734763) (xy 162.53206 -405.760428)
			(xy 162.526264 -405.767573) (xy 162.51975 -405.784764) (xy 162.51936 -405.793956) (xy 162.51936 -406.286208)
			(xy 162.519775 -406.295394) (xy 162.526286 -406.312578) (xy 162.53206 -406.319736) (xy 162.553894 -406.345426)
			(xy 162.591986 -406.401056) (xy 162.623141 -406.460849) (xy 162.646908 -406.523942) (xy 162.662947 -406.589429)
			(xy 162.671026 -406.656365) (xy 162.671029 -406.72373) (xy 165.949066 -406.72373) (xy 165.949069 -406.656422)
			(xy 165.957117 -406.589597) (xy 165.973094 -406.524213) (xy 165.996771 -406.461207) (xy 166.027808 -406.401483)
			(xy 166.065762 -406.345896) (xy 166.087552 -406.320244) (xy 166.093361 -406.313108) (xy 166.099867 -406.29591)
			(xy 166.100252 -406.286716) (xy 166.100252 -405.793448) (xy 166.099807 -405.784265) (xy 166.093316 -405.767081)
			(xy 166.087552 -405.75992) (xy 166.06576 -405.734271) (xy 166.027811 -405.678685) (xy 165.996777 -405.618961)
			(xy 165.973104 -405.555956) (xy 165.957131 -405.490573) (xy 165.949087 -405.42375) (xy 165.949087 -405.356444)
			(xy 165.957132 -405.289621) (xy 165.973105 -405.224239) (xy 165.996779 -405.161234) (xy 166.027814 -405.10151)
			(xy 166.065764 -405.045924) (xy 166.087552 -405.020272) (xy 166.093349 -405.013128) (xy 166.099862 -404.995936)
			(xy 166.100252 -404.986744) (xy 166.100252 -404.828756) (xy 166.100685 -404.818605) (xy 166.108486 -404.799861)
			(xy 166.122878 -404.785541) (xy 166.141661 -404.777834) (xy 166.151814 -404.777448) (xy 166.868094 -404.777448)
			(xy 166.878221 -404.777932) (xy 166.896944 -404.785659) (xy 166.911301 -404.799946) (xy 166.919119 -404.818631)
			(xy 166.919656 -404.828756) (xy 166.919656 -404.986744) (xy 166.920055 -404.995932) (xy 166.926578 -405.013116)
			(xy 166.932356 -405.020272) (xy 166.95414 -405.045927) (xy 166.992089 -405.101513) (xy 167.023123 -405.161236)
			(xy 167.046796 -405.22424) (xy 167.062769 -405.289622) (xy 167.070814 -405.356445) (xy 167.070814 -405.423749)
			(xy 167.06277 -405.490572) (xy 167.046798 -405.555954) (xy 167.023125 -405.618958) (xy 167.020688 -405.623648)
			(xy 168.149245 -405.623648) (xy 168.149246 -405.556343) (xy 168.15729 -405.489521) (xy 168.173263 -405.424139)
			(xy 168.196934 -405.361134) (xy 168.227966 -405.30141) (xy 168.265913 -405.245823) (xy 168.2877 -405.22017)
			(xy 168.293492 -405.213021) (xy 168.300009 -405.195834) (xy 168.3004 -405.186642) (xy 168.3004 -404.693374)
			(xy 168.300003 -404.684185) (xy 168.29348 -404.667001) (xy 168.2877 -404.659846) (xy 168.265935 -404.634176)
			(xy 168.227988 -404.578591) (xy 168.196956 -404.518869) (xy 168.173284 -404.455867) (xy 168.15731 -404.390488)
			(xy 168.149265 -404.323668) (xy 168.149263 -404.256365) (xy 168.157305 -404.189545) (xy 168.173274 -404.124164)
			(xy 168.196943 -404.061161) (xy 168.227971 -404.001438) (xy 168.265915 -403.945851) (xy 168.2877 -403.920198)
			(xy 168.29348 -403.913041) (xy 168.300005 -403.89586) (xy 168.3004 -403.88667) (xy 168.3004 -403.728682)
			(xy 168.300917 -403.718528) (xy 168.308691 -403.699765) (xy 168.323049 -403.685402) (xy 168.341808 -403.677621)
			(xy 168.351962 -403.67712) (xy 169.068242 -403.67712) (xy 169.0784 -403.677599) (xy 169.097167 -403.685383)
			(xy 169.11153 -403.699753) (xy 169.119306 -403.718524) (xy 169.119804 -403.728682) (xy 169.119804 -403.88667)
			(xy 169.120228 -403.895856) (xy 169.126732 -403.91304) (xy 169.132504 -403.920198) (xy 169.154312 -403.945833)
			(xy 169.192257 -404.001423) (xy 169.223287 -404.061149) (xy 169.246957 -404.124156) (xy 169.262927 -404.18954)
			(xy 169.270969 -404.256364) (xy 169.270967 -404.32367) (xy 169.262921 -404.390493) (xy 169.246947 -404.455876)
			(xy 169.223274 -404.518881) (xy 169.19224 -404.578606) (xy 169.154292 -404.634193) (xy 169.132504 -404.659846)
			(xy 169.126706 -404.66699) (xy 169.120192 -404.684181) (xy 169.119804 -404.693374) (xy 169.119804 -405.186642)
			(xy 169.120193 -405.195832) (xy 169.126721 -405.213016) (xy 169.132504 -405.22017) (xy 169.154284 -405.245828)
			(xy 169.192231 -405.301414) (xy 169.223262 -405.361137) (xy 169.246933 -405.424141) (xy 169.262905 -405.489522)
			(xy 169.270949 -405.556344) (xy 169.27095 -405.623647) (xy 169.262907 -405.690469) (xy 169.246936 -405.75585)
			(xy 169.223266 -405.818854) (xy 169.192235 -405.878578) (xy 169.15429 -405.934165) (xy 169.132504 -405.959818)
			(xy 169.126718 -405.966971) (xy 169.120197 -405.984155) (xy 169.119804 -405.993346) (xy 169.119804 -406.151334)
			(xy 169.119296 -406.161489) (xy 169.111518 -406.180251) (xy 169.097157 -406.194613) (xy 169.078397 -406.202394)
			(xy 169.068242 -406.202896) (xy 168.351962 -406.202896) (xy 168.341806 -406.202399) (xy 168.323042 -406.194618)
			(xy 168.30868 -406.180254) (xy 168.300901 -406.16149) (xy 168.3004 -406.151334) (xy 168.3004 -405.993346)
			(xy 168.299968 -405.984161) (xy 168.293469 -405.966977) (xy 168.2877 -405.959818) (xy 168.265908 -405.93417)
			(xy 168.227961 -405.878582) (xy 168.196931 -405.818858) (xy 168.17326 -405.755853) (xy 168.157289 -405.69047)
			(xy 168.149245 -405.623648) (xy 167.020688 -405.623648) (xy 166.992092 -405.678681) (xy 166.954143 -405.734268)
			(xy 166.932356 -405.75992) (xy 166.926563 -405.767067) (xy 166.920047 -405.784256) (xy 166.919656 -405.793448)
			(xy 166.919656 -406.286716) (xy 166.920068 -406.295903) (xy 166.926582 -406.313087) (xy 166.932356 -406.320244)
			(xy 166.954112 -406.345922) (xy 166.992062 -406.401505) (xy 167.023097 -406.461225) (xy 167.046772 -406.524226)
			(xy 167.062747 -406.589605) (xy 167.070794 -406.656425) (xy 167.070797 -406.723727) (xy 167.070789 -406.72379)
			(xy 170.348835 -406.72379) (xy 170.348838 -406.656362) (xy 170.356917 -406.589421) (xy 170.372958 -406.52393)
			(xy 170.396728 -406.460831) (xy 170.427885 -406.401034) (xy 170.46598 -406.3454) (xy 170.487848 -406.319736)
			(xy 170.49366 -406.312602) (xy 170.500164 -406.295403) (xy 170.500548 -406.286208) (xy 170.500548 -405.793956)
			(xy 170.500148 -405.784768) (xy 170.493626 -405.767584) (xy 170.487848 -405.760428) (xy 170.465978 -405.734767)
			(xy 170.427887 -405.679133) (xy 170.396733 -405.619337) (xy 170.372967 -405.556239) (xy 170.356931 -405.490749)
			(xy 170.348854 -405.423809) (xy 170.348855 -405.356385) (xy 170.356932 -405.289445) (xy 170.372969 -405.223955)
			(xy 170.396736 -405.160858) (xy 170.42789 -405.101062) (xy 170.465982 -405.045428) (xy 170.487848 -405.019764)
			(xy 170.493648 -405.012622) (xy 170.500159 -404.995429) (xy 170.500548 -404.986236) (xy 170.500548 -404.828756)
			(xy 170.501048 -404.818651) (xy 170.50879 -404.799982) (xy 170.523082 -404.78569) (xy 170.541751 -404.777948)
			(xy 170.551856 -404.777448) (xy 171.268136 -404.777448) (xy 171.278241 -404.777954) (xy 171.29691 -404.785694)
			(xy 171.311201 -404.799984) (xy 171.318944 -404.818651) (xy 171.319444 -404.828756) (xy 171.319444 -404.986236)
			(xy 171.31985 -404.995423) (xy 171.326368 -405.012607) (xy 171.332144 -405.019764) (xy 171.354006 -405.045432)
			(xy 171.392099 -405.101064) (xy 171.423253 -405.16086) (xy 171.447019 -405.223956) (xy 171.463057 -405.289446)
			(xy 171.471134 -405.356385) (xy 171.471134 -405.423809) (xy 171.463058 -405.490748) (xy 171.447021 -405.556238)
			(xy 171.423255 -405.619335) (xy 171.421007 -405.623649) (xy 172.549012 -405.623649) (xy 172.549013 -405.556342)
			(xy 172.557058 -405.489518) (xy 172.573033 -405.424135) (xy 172.596709 -405.36113) (xy 172.627746 -405.301407)
			(xy 172.665698 -405.245822) (xy 172.687488 -405.22017) (xy 172.693278 -405.21302) (xy 172.699797 -405.195833)
			(xy 172.700188 -405.186642) (xy 172.700188 -404.693374) (xy 172.699793 -404.684185) (xy 172.693269 -404.667001)
			(xy 172.687488 -404.659846) (xy 172.66572 -404.634177) (xy 172.627768 -404.578594) (xy 172.596731 -404.518873)
			(xy 172.573055 -404.455871) (xy 172.557079 -404.39049) (xy 172.549032 -404.323669) (xy 172.54903 -404.256364)
			(xy 172.557073 -404.189542) (xy 172.573045 -404.124161) (xy 172.596717 -404.061157) (xy 172.627751 -404.001435)
			(xy 172.6657 -403.945849) (xy 172.687488 -403.920198) (xy 172.693267 -403.91304) (xy 172.699792 -403.895859)
			(xy 172.700188 -403.88667) (xy 172.700188 -403.728682) (xy 172.70055 -403.718503) (xy 172.708351 -403.699698)
			(xy 172.722756 -403.685313) (xy 172.74157 -403.677537) (xy 172.75175 -403.67712) (xy 173.46803 -403.67712)
			(xy 173.478187 -403.677608) (xy 173.496954 -403.685389) (xy 173.511317 -403.699756) (xy 173.519094 -403.718524)
			(xy 173.519592 -403.728682) (xy 173.519592 -403.88667) (xy 173.520018 -403.895855) (xy 173.526521 -403.91304)
			(xy 173.532292 -403.920198) (xy 173.5541 -403.945833) (xy 173.592047 -404.001422) (xy 173.623077 -404.061149)
			(xy 173.646747 -404.124155) (xy 173.662718 -404.189539) (xy 173.67076 -404.256363) (xy 173.670758 -404.32367)
			(xy 173.662712 -404.390493) (xy 173.646738 -404.455876) (xy 173.623064 -404.518882) (xy 173.59203 -404.578606)
			(xy 173.55408 -404.634193) (xy 173.532292 -404.659846) (xy 173.526492 -404.666989) (xy 173.51998 -404.684181)
			(xy 173.519592 -404.693374) (xy 173.519592 -405.186642) (xy 173.519984 -405.195831) (xy 173.52651 -405.213015)
			(xy 173.532292 -405.22017) (xy 173.554073 -405.245827) (xy 173.59202 -405.301414) (xy 173.623052 -405.361137)
			(xy 173.646723 -405.424141) (xy 173.662696 -405.489522) (xy 173.67074 -405.556343) (xy 173.670741 -405.623647)
			(xy 173.662698 -405.690469) (xy 173.646726 -405.755851) (xy 173.623055 -405.818855) (xy 173.592025 -405.878578)
			(xy 173.554078 -405.934165) (xy 173.532292 -405.959818) (xy 173.526504 -405.96697) (xy 173.519985 -405.984155)
			(xy 173.519592 -405.993346) (xy 173.519592 -406.151334) (xy 173.519095 -406.16149) (xy 173.511315 -406.180254)
			(xy 173.496951 -406.194617) (xy 173.478186 -406.202396) (xy 173.46803 -406.202896) (xy 172.75175 -406.202896)
			(xy 172.741586 -406.202396) (xy 172.722799 -406.194634) (xy 172.708413 -406.180272) (xy 172.70062 -406.161497)
			(xy 172.700188 -406.151334) (xy 172.700188 -405.993346) (xy 172.699759 -405.984161) (xy 172.693259 -405.966976)
			(xy 172.687488 -405.959818) (xy 172.665693 -405.934171) (xy 172.627741 -405.878585) (xy 172.596705 -405.818861)
			(xy 172.573031 -405.755856) (xy 172.557057 -405.690473) (xy 172.549012 -405.623649) (xy 171.421007 -405.623649)
			(xy 171.392102 -405.67913) (xy 171.35401 -405.734764) (xy 171.332144 -405.760428) (xy 171.326346 -405.767572)
			(xy 171.319834 -405.784764) (xy 171.319444 -405.793956) (xy 171.319444 -406.286208) (xy 171.319863 -406.295394)
			(xy 171.326372 -406.312578) (xy 171.332144 -406.319736) (xy 171.353978 -406.345426) (xy 171.392072 -406.401056)
			(xy 171.423227 -406.460848) (xy 171.446996 -406.523942) (xy 171.463035 -406.589428) (xy 171.471114 -406.656365)
			(xy 171.471117 -406.72373) (xy 174.749154 -406.72373) (xy 174.749157 -406.656422) (xy 174.757205 -406.589597)
			(xy 174.773181 -406.524213) (xy 174.796857 -406.461208) (xy 174.827894 -406.401483) (xy 174.865846 -406.345896)
			(xy 174.887636 -406.320244) (xy 174.893443 -406.313107) (xy 174.899951 -406.29591) (xy 174.900336 -406.286716)
			(xy 174.900336 -405.793448) (xy 174.899895 -405.784264) (xy 174.893402 -405.76708) (xy 174.887636 -405.75992)
			(xy 174.865844 -405.734271) (xy 174.827896 -405.678684) (xy 174.796863 -405.61896) (xy 174.77319 -405.555955)
			(xy 174.757218 -405.490573) (xy 174.749174 -405.42375) (xy 174.749174 -405.356444) (xy 174.757219 -405.289621)
			(xy 174.773192 -405.224239) (xy 174.796865 -405.161234) (xy 174.827899 -405.101511) (xy 174.865848 -405.045924)
			(xy 174.887636 -405.020272) (xy 174.893432 -405.013126) (xy 174.899946 -404.995936) (xy 174.900336 -404.986744)
			(xy 174.900336 -404.828756) (xy 174.900686 -404.818594) (xy 174.908503 -404.799834) (xy 174.922922 -404.785511)
			(xy 174.941734 -404.77782) (xy 174.951898 -404.777448) (xy 175.668178 -404.777448) (xy 175.678304 -404.777945)
			(xy 175.697027 -404.785667) (xy 175.711384 -404.79995) (xy 175.719202 -404.818632) (xy 175.71974 -404.828756)
			(xy 175.71974 -404.986744) (xy 175.720142 -404.995932) (xy 175.726663 -405.013115) (xy 175.73244 -405.020272)
			(xy 175.754224 -405.045927) (xy 175.792175 -405.101513) (xy 175.823209 -405.161236) (xy 175.846883 -405.22424)
			(xy 175.862857 -405.289622) (xy 175.870902 -405.356444) (xy 175.870902 -405.42375) (xy 175.862858 -405.490572)
			(xy 175.846885 -405.555954) (xy 175.823212 -405.618959) (xy 175.792178 -405.678682) (xy 175.754228 -405.734268)
			(xy 175.73244 -405.75992) (xy 175.726645 -405.767066) (xy 175.720131 -405.784256) (xy 175.71974 -405.793448)
			(xy 175.71974 -406.286716) (xy 175.720156 -406.295902) (xy 175.726667 -406.313086) (xy 175.73244 -406.320244)
			(xy 175.754197 -406.345922) (xy 175.792148 -406.401504) (xy 175.823184 -406.461224) (xy 175.846859 -406.524225)
			(xy 175.862835 -406.589604) (xy 175.870882 -406.656424) (xy 175.870885 -406.723727) (xy 175.862844 -406.790548)
			(xy 175.846873 -406.855929) (xy 175.823203 -406.918932) (xy 175.792173 -406.978655) (xy 175.754226 -407.03424)
			(xy 175.73244 -407.059892) (xy 175.726657 -407.067046) (xy 175.720136 -407.08423) (xy 175.71974 -407.09342)
			(xy 175.71974 -407.251408) (xy 175.719286 -407.261558) (xy 175.711495 -407.280302) (xy 175.697109 -407.294624)
			(xy 175.678329 -407.302331) (xy 175.668178 -407.302716) (xy 174.951898 -407.302716) (xy 174.941766 -407.302274)
			(xy 174.923036 -407.294537) (xy 174.908679 -407.280237) (xy 174.900867 -407.261538) (xy 174.900336 -407.251408)
			(xy 174.900336 -407.09342) (xy 174.899908 -407.084235) (xy 174.893406 -407.067051) (xy 174.887636 -407.059892)
			(xy 174.865817 -407.034266) (xy 174.827869 -406.978676) (xy 174.796837 -406.918948) (xy 174.773167 -406.85594)
			(xy 174.757196 -406.790555) (xy 174.749154 -406.72373) (xy 171.471117 -406.72373) (xy 171.471117 -406.723787)
			(xy 171.463044 -406.790724) (xy 171.44701 -406.856212) (xy 171.423247 -406.919308) (xy 171.392097 -406.979103)
			(xy 171.354008 -407.034736) (xy 171.332144 -407.0604) (xy 171.326358 -407.067552) (xy 171.319839 -407.084738)
			(xy 171.319444 -407.093928) (xy 171.319444 -407.251408) (xy 171.318922 -407.261512) (xy 171.31119 -407.280182)
			(xy 171.296905 -407.294475) (xy 171.278239 -407.302217) (xy 171.268136 -407.302716) (xy 170.551856 -407.302716)
			(xy 170.541746 -407.302251) (xy 170.52307 -407.294502) (xy 170.508778 -407.280199) (xy 170.501042 -407.261518)
			(xy 170.500548 -407.251408) (xy 170.500548 -407.093928) (xy 170.500114 -407.084744) (xy 170.493616 -407.067559)
			(xy 170.487848 -407.0604) (xy 170.465951 -407.034762) (xy 170.42786 -406.979124) (xy 170.396708 -406.919325)
			(xy 170.372944 -406.856224) (xy 170.356909 -406.790732) (xy 170.348835 -406.72379) (xy 167.070789 -406.72379)
			(xy 167.062756 -406.790548) (xy 167.046786 -406.855928) (xy 167.023117 -406.918931) (xy 166.992087 -406.978654)
			(xy 166.954142 -407.03424) (xy 166.932356 -407.059892) (xy 166.926575 -407.067048) (xy 166.920052 -407.08423)
			(xy 166.919656 -407.09342) (xy 166.919656 -407.251408) (xy 166.919186 -407.261556) (xy 166.911398 -407.280297)
			(xy 166.897017 -407.294618) (xy 166.878243 -407.302328) (xy 166.868094 -407.302716) (xy 166.151814 -407.302716)
			(xy 166.141683 -407.302261) (xy 166.122954 -407.294529) (xy 166.108595 -407.280233) (xy 166.100783 -407.261537)
			(xy 166.100252 -407.251408) (xy 166.100252 -407.09342) (xy 166.099821 -407.084235) (xy 166.093321 -407.067051)
			(xy 166.087552 -407.059892) (xy 166.065732 -407.034266) (xy 166.027784 -406.978676) (xy 165.996751 -406.918949)
			(xy 165.973079 -406.855941) (xy 165.957108 -406.790556) (xy 165.949066 -406.72373) (xy 162.671029 -406.72373)
			(xy 162.671029 -406.723787) (xy 162.662956 -406.790724) (xy 162.646923 -406.856212) (xy 162.62316 -406.919307)
			(xy 162.592011 -406.979102) (xy 162.553923 -407.034735) (xy 162.53206 -407.0604) (xy 162.526276 -407.067554)
			(xy 162.519755 -407.084738) (xy 162.51936 -407.093928) (xy 162.51936 -407.251408) (xy 162.518989 -407.261536)
			(xy 162.511231 -407.280247) (xy 162.4969 -407.294563) (xy 162.47818 -407.3023) (xy 162.468052 -407.302716)
			(xy 161.751772 -407.302716) (xy 161.741663 -407.302238) (xy 161.722988 -407.294494) (xy 161.708694 -407.280196)
			(xy 161.700958 -407.261517) (xy 161.700464 -407.251408) (xy 161.700464 -407.093928) (xy 161.700026 -407.084744)
			(xy 161.69353 -407.06756) (xy 161.687764 -407.0604) (xy 161.66587 -407.03476) (xy 161.627784 -406.979121)
			(xy 161.596637 -406.919321) (xy 161.572876 -406.856221) (xy 161.556844 -406.790729) (xy 161.548771 -406.723789)
			(xy 154.57678 -406.723789) (xy 154.57678 -409.523827) (xy 159.349136 -409.523827) (xy 159.34914 -409.456519)
			(xy 159.357187 -409.389695) (xy 159.373163 -409.324311) (xy 159.396839 -409.261305) (xy 159.427875 -409.20158)
			(xy 159.465827 -409.145992) (xy 159.487616 -409.12034) (xy 159.493422 -409.113202) (xy 159.499931 -409.096006)
			(xy 159.500316 -409.086812) (xy 159.500316 -408.593544) (xy 159.499881 -408.58436) (xy 159.493384 -408.567175)
			(xy 159.487616 -408.560016) (xy 159.465821 -408.53437) (xy 159.427874 -408.478782) (xy 159.396842 -408.419058)
			(xy 159.373171 -408.356052) (xy 159.357199 -408.29067) (xy 159.349156 -408.223847) (xy 159.349157 -408.156541)
			(xy 159.357201 -408.089719) (xy 159.373175 -408.024336) (xy 159.396847 -407.961331) (xy 159.42788 -407.901607)
			(xy 159.465828 -407.84602) (xy 159.487616 -407.820368) (xy 159.49341 -407.813221) (xy 159.499926 -407.796032)
			(xy 159.500316 -407.78684) (xy 159.500316 -407.628852) (xy 159.500683 -407.618693) (xy 159.508497 -407.599936)
			(xy 159.522911 -407.585614) (xy 159.541716 -407.577919) (xy 159.551878 -407.577544) (xy 160.268158 -407.577544)
			(xy 160.278283 -407.578061) (xy 160.297003 -407.585776) (xy 160.311361 -407.600053) (xy 160.319181 -407.61873)
			(xy 160.31972 -407.628852) (xy 160.31972 -407.78684) (xy 160.320107 -407.79603) (xy 160.326636 -407.813214)
			(xy 160.33242 -407.820368) (xy 160.354201 -407.846026) (xy 160.392153 -407.901611) (xy 160.423189 -407.961333)
			(xy 160.446864 -408.024337) (xy 160.462838 -408.089719) (xy 160.470884 -408.156541) (xy 160.470885 -408.223847)
			(xy 160.462841 -408.290669) (xy 160.446867 -408.356052) (xy 160.423194 -408.419056) (xy 160.392159 -408.478779)
			(xy 160.354208 -408.534364) (xy 160.33242 -408.560016) (xy 160.326636 -408.567171) (xy 160.320113 -408.584354)
			(xy 160.31972 -408.593544) (xy 160.31972 -409.086812) (xy 160.32012 -409.096) (xy 160.32664 -409.113185)
			(xy 160.33242 -409.12034) (xy 160.354174 -409.146021) (xy 160.392126 -409.201602) (xy 160.423163 -409.261321)
			(xy 160.44684 -409.324322) (xy 160.462817 -409.389701) (xy 160.470864 -409.456521) (xy 160.470867 -409.523824)
			(xy 160.462826 -409.590645) (xy 160.446856 -409.656026) (xy 160.423185 -409.719029) (xy 160.392154 -409.778751)
			(xy 160.354207 -409.834336) (xy 160.33242 -409.859988) (xy 160.326606 -409.867121) (xy 160.320101 -409.884321)
			(xy 160.31972 -409.893516) (xy 160.31972 -410.051504) (xy 160.319282 -410.061656) (xy 160.311489 -410.080404)
			(xy 160.297098 -410.094727) (xy 160.278312 -410.10243) (xy 160.268158 -410.102812) (xy 159.551878 -410.102812)
			(xy 159.541756 -410.102293) (xy 159.523044 -410.094568) (xy 159.508691 -410.080292) (xy 159.500863 -410.061623)
			(xy 159.500316 -410.051504) (xy 159.500316 -409.893516) (xy 159.499894 -409.88433) (xy 159.493388 -409.867146)
			(xy 159.487616 -409.859988) (xy 159.465794 -409.834365) (xy 159.427847 -409.778774) (xy 159.396817 -409.719046)
			(xy 159.373147 -409.656038) (xy 159.357177 -409.590652) (xy 159.349136 -409.523827) (xy 154.57678 -409.523827)
			(xy 154.57678 -410.6237) (xy 161.548783 -410.6237) (xy 161.548784 -410.556276) (xy 161.556861 -410.489337)
			(xy 161.572897 -410.423848) (xy 161.596662 -410.36075) (xy 161.627812 -410.300953) (xy 161.6659 -410.245318)
			(xy 161.687764 -410.219652) (xy 161.693571 -410.212515) (xy 161.700078 -410.195318) (xy 161.700464 -410.186124)
			(xy 161.700464 -409.693872) (xy 161.700053 -409.684685) (xy 161.693538 -409.667502) (xy 161.687764 -409.660344)
			(xy 161.665913 -409.634668) (xy 161.627826 -409.579035) (xy 161.596677 -409.519239) (xy 161.572914 -409.456144)
			(xy 161.556879 -409.390657) (xy 161.548802 -409.32372) (xy 161.548801 -409.256298) (xy 161.556875 -409.189361)
			(xy 161.572909 -409.123873) (xy 161.59667 -409.060777) (xy 161.627817 -409.000981) (xy 161.665902 -408.945346)
			(xy 161.687764 -408.91968) (xy 161.693559 -408.912534) (xy 161.700073 -408.895344) (xy 161.700464 -408.886152)
			(xy 161.700464 -408.728672) (xy 161.700961 -408.718566) (xy 161.708701 -408.699894) (xy 161.722994 -408.685601)
			(xy 161.741666 -408.677861) (xy 161.751772 -408.677364) (xy 162.468052 -408.677364) (xy 162.478167 -408.677854)
			(xy 162.496863 -408.68558) (xy 162.511177 -408.699874) (xy 162.518931 -408.718558) (xy 162.51936 -408.728672)
			(xy 162.51936 -408.886152) (xy 162.519802 -408.895336) (xy 162.526295 -408.91252) (xy 162.53206 -408.91968)
			(xy 162.553937 -408.945335) (xy 162.592028 -409.00097) (xy 162.623181 -409.060767) (xy 162.646946 -409.123866)
			(xy 162.662982 -409.189356) (xy 162.671057 -409.256296) (xy 162.671056 -409.323722) (xy 162.662978 -409.390662)
			(xy 162.64694 -409.456152) (xy 162.623173 -409.519249) (xy 162.620757 -409.523886) (xy 163.748905 -409.523886)
			(xy 163.748908 -409.45646) (xy 163.756988 -409.389519) (xy 163.773027 -409.324027) (xy 163.796796 -409.260929)
			(xy 163.827952 -409.201132) (xy 163.866045 -409.145497) (xy 163.887912 -409.119832) (xy 163.893721 -409.112696)
			(xy 163.900228 -409.095498) (xy 163.900612 -409.086304) (xy 163.900612 -408.594052) (xy 163.900174 -408.584868)
			(xy 163.893679 -408.567683) (xy 163.887912 -408.560524) (xy 163.86604 -408.534865) (xy 163.82795 -408.47923)
			(xy 163.796799 -408.419433) (xy 163.773035 -408.356335) (xy 163.757 -408.290845) (xy 163.748925 -408.223906)
			(xy 163.748925 -408.156482) (xy 163.757002 -408.089543) (xy 163.773039 -408.024053) (xy 163.796804 -407.960956)
			(xy 163.827957 -407.901159) (xy 163.866047 -407.845525) (xy 163.887912 -407.81986) (xy 163.893709 -407.812715)
			(xy 163.900223 -407.795524) (xy 163.900612 -407.786332) (xy 163.900612 -407.628852) (xy 163.901046 -407.618739)
			(xy 163.908802 -407.600057) (xy 163.923114 -407.585764) (xy 163.941806 -407.578033) (xy 163.95192 -407.577544)
			(xy 164.6682 -407.577544) (xy 164.678302 -407.578084) (xy 164.696969 -407.585811) (xy 164.711262 -407.60009)
			(xy 164.719007 -407.618751) (xy 164.719508 -407.628852) (xy 164.719508 -407.786332) (xy 164.719901 -407.795521)
			(xy 164.726426 -407.812705) (xy 164.732208 -407.81986) (xy 164.754064 -407.845532) (xy 164.792152 -407.901166)
			(xy 164.823303 -407.960961) (xy 164.847067 -408.024057) (xy 164.863103 -408.089545) (xy 164.871179 -408.156483)
			(xy 164.87118 -408.223905) (xy 164.863105 -408.290843) (xy 164.847071 -408.356332) (xy 164.823308 -408.419428)
			(xy 164.792158 -408.479224) (xy 164.754071 -408.534859) (xy 164.732208 -408.560524) (xy 164.72642 -408.567675)
			(xy 164.7199 -408.584861) (xy 164.719508 -408.594052) (xy 164.719508 -409.086304) (xy 164.719915 -409.095492)
			(xy 164.726431 -409.112676) (xy 164.732208 -409.119832) (xy 164.754036 -409.145527) (xy 164.792126 -409.201157)
			(xy 164.823277 -409.260949) (xy 164.847043 -409.324042) (xy 164.863081 -409.389528) (xy 164.87116 -409.456463)
			(xy 164.871163 -409.523883) (xy 164.863091 -409.590819) (xy 164.847059 -409.656306) (xy 164.8233 -409.719401)
			(xy 164.792153 -409.779196) (xy 164.75407 -409.834831) (xy 164.732208 -409.860496) (xy 164.726432 -409.867656)
			(xy 164.719905 -409.884835) (xy 164.719508 -409.894024) (xy 164.719508 -410.051504) (xy 164.719018 -410.061612)
			(xy 164.711281 -410.080289) (xy 164.696985 -410.094583) (xy 164.678308 -410.102319) (xy 164.6682 -410.102812)
			(xy 163.95192 -410.102812) (xy 163.9418 -410.102368) (xy 163.923099 -410.094629) (xy 163.908785 -410.080321)
			(xy 163.901037 -410.061624) (xy 163.900612 -410.051504) (xy 163.900612 -409.894024) (xy 163.900188 -409.884838)
			(xy 163.893683 -409.867654) (xy 163.887912 -409.860496) (xy 163.866012 -409.83486) (xy 163.827924 -409.779222)
			(xy 163.796774 -409.719422) (xy 163.773011 -409.656321) (xy 163.756978 -409.590828) (xy 163.748905 -409.523886)
			(xy 162.620757 -409.523886) (xy 162.592019 -409.579046) (xy 162.553926 -409.634679) (xy 162.53206 -409.660344)
			(xy 162.526257 -409.667485) (xy 162.519747 -409.684679) (xy 162.51936 -409.693872) (xy 162.51936 -410.186124)
			(xy 162.519768 -410.195311) (xy 162.526284 -410.212495) (xy 162.53206 -410.219652) (xy 162.55391 -410.24533)
			(xy 162.592001 -410.300961) (xy 162.623155 -410.360755) (xy 162.646922 -410.423851) (xy 162.66296 -410.489339)
			(xy 162.671038 -410.556276) (xy 162.671039 -410.623641) (xy 165.949078 -410.623641) (xy 165.949079 -410.556335)
			(xy 165.957125 -410.489511) (xy 165.9731 -410.424127) (xy 165.996775 -410.361122) (xy 166.027811 -410.301398)
			(xy 166.065763 -410.245812) (xy 166.087552 -410.22016) (xy 166.093354 -410.213019) (xy 166.099864 -410.195825)
			(xy 166.100252 -410.186632) (xy 166.100252 -409.693364) (xy 166.099847 -409.684176) (xy 166.093328 -409.666993)
			(xy 166.087552 -409.659836) (xy 166.065776 -409.634174) (xy 166.027826 -409.578589) (xy 165.996791 -409.518867)
			(xy 165.973117 -409.455864) (xy 165.957143 -409.390483) (xy 165.949098 -409.323661) (xy 165.949097 -409.256357)
			(xy 165.95714 -409.189535) (xy 165.973112 -409.124153) (xy 165.996784 -409.061149) (xy 166.027817 -409.001426)
			(xy 166.065765 -408.94584) (xy 166.087552 -408.920188) (xy 166.093343 -408.913039) (xy 166.099859 -408.895851)
			(xy 166.100252 -408.88666) (xy 166.100252 -408.728672) (xy 166.100698 -408.718522) (xy 166.108493 -408.699778)
			(xy 166.122882 -408.685458) (xy 166.141662 -408.67775) (xy 166.151814 -408.677364) (xy 166.868094 -408.677364)
			(xy 166.878223 -408.677832) (xy 166.896949 -408.685562) (xy 166.911306 -408.699855) (xy 166.919121 -408.718545)
			(xy 166.919656 -408.728672) (xy 166.919656 -408.88666) (xy 166.920095 -408.895844) (xy 166.92659 -408.913028)
			(xy 166.932356 -408.920188) (xy 166.954156 -408.94583) (xy 166.992105 -409.001418) (xy 167.023138 -409.061143)
			(xy 167.04681 -409.124149) (xy 167.062782 -409.189532) (xy 167.070826 -409.256356) (xy 167.070824 -409.323662)
			(xy 167.062779 -409.390486) (xy 167.046805 -409.455869) (xy 167.02313 -409.518874) (xy 167.020557 -409.523826)
			(xy 168.149224 -409.523826) (xy 168.149228 -409.456519) (xy 168.157275 -409.389695) (xy 168.17325 -409.324311)
			(xy 168.196925 -409.261305) (xy 168.227961 -409.201581) (xy 168.265911 -409.145993) (xy 168.2877 -409.12034)
			(xy 168.293505 -409.1132) (xy 168.300014 -409.096006) (xy 168.3004 -409.086812) (xy 168.3004 -408.593544)
			(xy 168.299969 -408.584359) (xy 168.29347 -408.567174) (xy 168.2877 -408.560016) (xy 168.265906 -408.53437)
			(xy 168.22796 -408.478782) (xy 168.196929 -408.419057) (xy 168.173258 -408.356052) (xy 168.157287 -408.290669)
			(xy 168.149244 -408.223846) (xy 168.149245 -408.156542) (xy 168.157289 -408.089719) (xy 168.173262 -408.024337)
			(xy 168.196934 -407.961332) (xy 168.227966 -407.901608) (xy 168.265913 -407.846021) (xy 168.2877 -407.820368)
			(xy 168.293493 -407.81322) (xy 168.30001 -407.796032) (xy 168.3004 -407.78684) (xy 168.3004 -407.628852)
			(xy 168.300782 -407.618695) (xy 168.308594 -407.599941) (xy 168.323002 -407.58562) (xy 168.341802 -407.577922)
			(xy 168.351962 -407.577544) (xy 169.068242 -407.577544) (xy 169.078372 -407.577992) (xy 169.097095 -407.585735)
			(xy 169.11145 -407.600032) (xy 169.119267 -407.618724) (xy 169.119804 -407.628852) (xy 169.119804 -407.78684)
			(xy 169.120194 -407.796029) (xy 169.126721 -407.813214) (xy 169.132504 -407.820368) (xy 169.154283 -407.846027)
			(xy 169.192229 -407.901614) (xy 169.22326 -407.961337) (xy 169.246931 -408.02434) (xy 169.262904 -408.089721)
			(xy 169.270948 -408.156542) (xy 169.270948 -408.223846) (xy 169.262906 -408.290667) (xy 169.246935 -408.356048)
			(xy 169.223265 -408.419052) (xy 169.192235 -408.478776) (xy 169.15429 -408.534363) (xy 169.132504 -408.560016)
			(xy 169.126719 -408.567169) (xy 169.120197 -408.584354) (xy 169.119804 -408.593544) (xy 169.119804 -409.086812)
			(xy 169.120208 -409.096) (xy 169.126726 -409.113184) (xy 169.132504 -409.12034) (xy 169.154255 -409.146022)
			(xy 169.192202 -409.201605) (xy 169.223235 -409.261325) (xy 169.246908 -409.324325) (xy 169.262882 -409.389704)
			(xy 169.270928 -409.456522) (xy 169.270931 -409.523824) (xy 169.262891 -409.590643) (xy 169.246924 -409.656023)
			(xy 169.223257 -409.719026) (xy 169.19223 -409.778748) (xy 169.154288 -409.834335) (xy 169.132504 -409.859988)
			(xy 169.126688 -409.86712) (xy 169.120185 -409.88432) (xy 169.119804 -409.893516) (xy 169.119804 -410.051504)
			(xy 169.119382 -410.061658) (xy 169.111586 -410.08041) (xy 169.097189 -410.094733) (xy 169.078398 -410.102433)
			(xy 169.068242 -410.102812) (xy 168.351962 -410.102812) (xy 168.341839 -410.102306) (xy 168.323127 -410.094575)
			(xy 168.308774 -410.080296) (xy 168.300947 -410.061624) (xy 168.3004 -410.051504) (xy 168.3004 -409.893516)
			(xy 168.299982 -409.88433) (xy 168.293474 -409.867145) (xy 168.2877 -409.859988) (xy 168.265878 -409.834364)
			(xy 168.227933 -409.778773) (xy 168.196903 -409.719045) (xy 168.173234 -409.656037) (xy 168.157265 -409.590652)
			(xy 168.149224 -409.523826) (xy 167.020557 -409.523826) (xy 166.992095 -409.578598) (xy 166.954145 -409.634184)
			(xy 166.932356 -409.659836) (xy 166.926556 -409.666979) (xy 166.920045 -409.684171) (xy 166.919656 -409.693364)
			(xy 166.919656 -410.186632) (xy 166.920061 -410.19582) (xy 166.926579 -410.213003) (xy 166.932356 -410.22016)
			(xy 166.954128 -410.245825) (xy 166.992078 -410.30141) (xy 167.023112 -410.361131) (xy 167.046786 -410.424134)
			(xy 167.06276 -410.489515) (xy 167.070805 -410.556336) (xy 167.070807 -410.62364) (xy 167.0708 -410.623701)
			(xy 170.348846 -410.623701) (xy 170.348847 -410.556275) (xy 170.356926 -410.489335) (xy 170.372964 -410.423844)
			(xy 170.396732 -410.360747) (xy 170.427888 -410.30095) (xy 170.465981 -410.245316) (xy 170.487848 -410.219652)
			(xy 170.493653 -410.212513) (xy 170.500162 -410.195318) (xy 170.500548 -410.186124) (xy 170.500548 -409.693872)
			(xy 170.50014 -409.684685) (xy 170.493624 -409.667501) (xy 170.487848 -409.660344) (xy 170.465994 -409.63467)
			(xy 170.427902 -409.579038) (xy 170.396748 -409.519243) (xy 170.372981 -409.456147) (xy 170.356943 -409.390659)
			(xy 170.348866 -409.323721) (xy 170.348865 -409.256297) (xy 170.35694 -409.189359) (xy 170.372976 -409.12387)
			(xy 170.396741 -409.060773) (xy 170.427893 -409.000978) (xy 170.465983 -408.945344) (xy 170.487848 -408.91968)
			(xy 170.493642 -408.912533) (xy 170.500157 -408.895344) (xy 170.500548 -408.886152) (xy 170.500548 -408.728672)
			(xy 170.501061 -408.718568) (xy 170.508798 -408.699899) (xy 170.523086 -408.685607) (xy 170.541752 -408.677864)
			(xy 170.551856 -408.677364) (xy 171.268136 -408.677364) (xy 171.278243 -408.677855) (xy 171.296915 -408.685598)
			(xy 171.311207 -408.699892) (xy 171.318947 -408.718565) (xy 171.319444 -408.728672) (xy 171.319444 -408.886152)
			(xy 171.31989 -408.895335) (xy 171.32638 -408.912519) (xy 171.332144 -408.91968) (xy 171.354022 -408.945335)
			(xy 171.392114 -409.000969) (xy 171.423267 -409.060766) (xy 171.447033 -409.123865) (xy 171.463069 -409.189356)
			(xy 171.471145 -409.256296) (xy 171.471144 -409.323722) (xy 171.463066 -409.390662) (xy 171.447028 -409.456152)
			(xy 171.42326 -409.51925) (xy 171.420875 -409.523827) (xy 172.548991 -409.523827) (xy 172.548995 -409.456519)
			(xy 172.557043 -409.389693) (xy 172.573021 -409.324308) (xy 172.5967 -409.261302) (xy 172.62774 -409.201577)
			(xy 172.665697 -409.145992) (xy 172.687488 -409.12034) (xy 172.693291 -409.113199) (xy 172.699802 -409.096005)
			(xy 172.700188 -409.086812) (xy 172.700188 -408.593544) (xy 172.699759 -408.584359) (xy 172.693259 -408.567174)
			(xy 172.687488 -408.560016) (xy 172.665691 -408.534371) (xy 172.627739 -408.478785) (xy 172.596704 -408.419061)
			(xy 172.573029 -408.356055) (xy 172.557055 -408.290671) (xy 172.549011 -408.223847) (xy 172.549012 -408.156541)
			(xy 172.557057 -408.089717) (xy 172.573033 -408.024333) (xy 172.596708 -407.961328) (xy 172.627745 -407.901605)
			(xy 172.665698 -407.84602) (xy 172.687488 -407.820368) (xy 172.693279 -407.813219) (xy 172.699797 -407.796031)
			(xy 172.700188 -407.78684) (xy 172.700188 -407.628852) (xy 172.700582 -407.618696) (xy 172.708391 -407.599945)
			(xy 172.722796 -407.585624) (xy 172.741592 -407.577924) (xy 172.75175 -407.577544) (xy 173.46803 -407.577544)
			(xy 173.478159 -407.578002) (xy 173.496882 -407.58574) (xy 173.511237 -407.600035) (xy 173.519055 -407.618725)
			(xy 173.519592 -407.628852) (xy 173.519592 -407.78684) (xy 173.519985 -407.796029) (xy 173.526511 -407.813213)
			(xy 173.532292 -407.820368) (xy 173.554071 -407.846027) (xy 173.592018 -407.901613) (xy 173.62305 -407.961336)
			(xy 173.646722 -408.02434) (xy 173.662694 -408.089721) (xy 173.670739 -408.156542) (xy 173.670739 -408.223846)
			(xy 173.662697 -408.290667) (xy 173.646725 -408.356049) (xy 173.623055 -408.419053) (xy 173.592024 -408.478776)
			(xy 173.554078 -408.534363) (xy 173.532292 -408.560016) (xy 173.526505 -408.567168) (xy 173.519985 -408.584353)
			(xy 173.519592 -408.593544) (xy 173.519592 -409.086812) (xy 173.519998 -409.096) (xy 173.526515 -409.113184)
			(xy 173.532292 -409.12034) (xy 173.554043 -409.146022) (xy 173.591991 -409.201605) (xy 173.623024 -409.261324)
			(xy 173.646698 -409.324325) (xy 173.662672 -409.389703) (xy 173.670719 -409.456522) (xy 173.670722 -409.523824)
			(xy 173.662682 -409.590643) (xy 173.646714 -409.656023) (xy 173.623047 -409.719026) (xy 173.592019 -409.778749)
			(xy 173.554077 -409.834336) (xy 173.532292 -409.859988) (xy 173.526475 -409.867118) (xy 173.519973 -409.88432)
			(xy 173.519592 -409.893516) (xy 173.519592 -410.051504) (xy 173.519181 -410.061659) (xy 173.511383 -410.080413)
			(xy 173.496983 -410.094737) (xy 173.478187 -410.102435) (xy 173.46803 -410.102812) (xy 172.75175 -410.102812)
			(xy 172.741633 -410.102234) (xy 172.722923 -410.094532) (xy 172.708567 -410.080274) (xy 172.700736 -410.061618)
			(xy 172.700188 -410.051504) (xy 172.700188 -409.893516) (xy 172.699773 -409.884329) (xy 172.693263 -409.867145)
			(xy 172.687488 -409.859988) (xy 172.665663 -409.834366) (xy 172.627713 -409.778776) (xy 172.596678 -409.719049)
			(xy 172.573005 -409.65604) (xy 172.557033 -409.590654) (xy 172.548991 -409.523827) (xy 171.420875 -409.523827)
			(xy 171.392104 -409.579046) (xy 171.354011 -409.63468) (xy 171.332144 -409.660344) (xy 171.326339 -409.667483)
			(xy 171.319831 -409.684679) (xy 171.319444 -409.693872) (xy 171.319444 -410.186124) (xy 171.319855 -410.195311)
			(xy 171.32637 -410.212494) (xy 171.332144 -410.219652) (xy 171.353994 -410.245329) (xy 171.392087 -410.300961)
			(xy 171.423242 -410.360755) (xy 171.447009 -410.42385) (xy 171.463047 -410.489338) (xy 171.471125 -410.556276)
			(xy 171.471127 -410.623641) (xy 174.749166 -410.623641) (xy 174.749167 -410.556335) (xy 174.757213 -410.489511)
			(xy 174.773187 -410.424128) (xy 174.796862 -410.361123) (xy 174.827897 -410.301399) (xy 174.865847 -410.245812)
			(xy 174.887636 -410.22016) (xy 174.893437 -410.213018) (xy 174.899948 -410.195825) (xy 174.900336 -410.186632)
			(xy 174.900336 -409.693364) (xy 174.899935 -409.684176) (xy 174.893414 -409.666992) (xy 174.887636 -409.659836)
			(xy 174.86586 -409.634174) (xy 174.827911 -409.578589) (xy 174.796878 -409.518867) (xy 174.773205 -409.455863)
			(xy 174.757231 -409.390482) (xy 174.749186 -409.323661) (xy 174.749185 -409.256357) (xy 174.757228 -409.189535)
			(xy 174.773199 -409.124154) (xy 174.79687 -409.06115) (xy 174.827902 -409.001427) (xy 174.865849 -408.94584)
			(xy 174.887636 -408.920188) (xy 174.893425 -408.913037) (xy 174.899943 -408.895851) (xy 174.900336 -408.88666)
			(xy 174.900336 -408.728672) (xy 174.900699 -408.718512) (xy 174.908511 -408.699752) (xy 174.922926 -408.685428)
			(xy 174.941735 -408.677736) (xy 174.951898 -408.677364) (xy 175.668178 -408.677364) (xy 175.678306 -408.677845)
			(xy 175.697032 -408.68557) (xy 175.711389 -408.699859) (xy 175.719205 -408.718546) (xy 175.71974 -408.728672)
			(xy 175.71974 -408.88666) (xy 175.720183 -408.895843) (xy 175.726675 -408.913028) (xy 175.73244 -408.920188)
			(xy 175.75424 -408.94583) (xy 175.79219 -409.001418) (xy 175.823224 -409.061142) (xy 175.846897 -409.124148)
			(xy 175.862869 -409.189532) (xy 175.870913 -409.256356) (xy 175.870912 -409.323662) (xy 175.862866 -409.390486)
			(xy 175.846891 -409.455869) (xy 175.823216 -409.518874) (xy 175.792181 -409.578598) (xy 175.754229 -409.634184)
			(xy 175.73244 -409.659836) (xy 175.726638 -409.666977) (xy 175.720128 -409.684171) (xy 175.71974 -409.693364)
			(xy 175.71974 -410.186632) (xy 175.720148 -410.195819) (xy 175.726665 -410.213003) (xy 175.73244 -410.22016)
			(xy 175.754213 -410.245825) (xy 175.792163 -410.301409) (xy 175.823198 -410.361131) (xy 175.846873 -410.424134)
			(xy 175.862848 -410.489514) (xy 175.870893 -410.556336) (xy 175.870895 -410.62364) (xy 175.862852 -410.690462)
			(xy 175.84688 -410.755843) (xy 175.823208 -410.818847) (xy 175.792176 -410.87857) (xy 175.754227 -410.934156)
			(xy 175.73244 -410.959808) (xy 175.72665 -410.966958) (xy 175.720133 -410.984145) (xy 175.71974 -410.993336)
			(xy 175.71974 -411.151324) (xy 175.719299 -411.161475) (xy 175.711503 -411.18022) (xy 175.697113 -411.194541)
			(xy 175.678331 -411.202247) (xy 175.668178 -411.202632) (xy 174.951898 -411.202632) (xy 174.941768 -411.202174)
			(xy 174.923041 -411.194441) (xy 174.908684 -411.180145) (xy 174.90087 -411.161452) (xy 174.900336 -411.151324)
			(xy 174.900336 -410.993336) (xy 174.8999 -410.984152) (xy 174.893403 -410.966968) (xy 174.887636 -410.959808)
			(xy 174.865833 -410.934169) (xy 174.827884 -410.87858) (xy 174.796852 -410.818855) (xy 174.77318 -410.755849)
			(xy 174.757208 -410.690465) (xy 174.749166 -410.623641) (xy 171.471127 -410.623641) (xy 171.471127 -410.6237)
			(xy 171.463052 -410.690638) (xy 171.447016 -410.756127) (xy 171.423251 -410.819223) (xy 171.392099 -410.879019)
			(xy 171.354009 -410.934652) (xy 171.332144 -410.960316) (xy 171.326351 -410.967464) (xy 171.319836 -410.984653)
			(xy 171.319444 -410.993844) (xy 171.319444 -411.151324) (xy 171.318936 -411.161429) (xy 171.311198 -411.180099)
			(xy 171.296909 -411.194392) (xy 171.278241 -411.202133) (xy 171.268136 -411.202632) (xy 170.551856 -411.202632)
			(xy 170.541748 -411.202152) (xy 170.523075 -411.194405) (xy 170.508783 -411.180108) (xy 170.501044 -411.161432)
			(xy 170.500548 -411.151324) (xy 170.500548 -410.993844) (xy 170.500106 -410.98466) (xy 170.493613 -410.967476)
			(xy 170.487848 -410.960316) (xy 170.465967 -410.934665) (xy 170.427875 -410.879029) (xy 170.396723 -410.819232)
			(xy 170.372957 -410.756133) (xy 170.356921 -410.690641) (xy 170.348846 -410.623701) (xy 167.0708 -410.623701)
			(xy 167.062764 -410.690461) (xy 167.046793 -410.755843) (xy 167.023122 -410.818847) (xy 166.99209 -410.87857)
			(xy 166.954143 -410.934156) (xy 166.932356 -410.959808) (xy 166.926568 -410.966959) (xy 166.920049 -410.984145)
			(xy 166.919656 -410.993336) (xy 166.919656 -411.151324) (xy 166.919199 -411.161473) (xy 166.911406 -411.180215)
			(xy 166.897021 -411.194535) (xy 166.878245 -411.202244) (xy 166.868094 -411.202632) (xy 166.151814 -411.202632)
			(xy 166.141685 -411.202161) (xy 166.122959 -411.194433) (xy 166.108601 -411.180141) (xy 166.100786 -411.161451)
			(xy 166.100252 -411.151324) (xy 166.100252 -410.993336) (xy 166.099813 -410.984152) (xy 166.093318 -410.966968)
			(xy 166.087552 -410.959808) (xy 166.065748 -410.934169) (xy 166.027799 -410.878581) (xy 165.996765 -410.818856)
			(xy 165.973093 -410.75585) (xy 165.957121 -410.690466) (xy 165.949078 -410.623641) (xy 162.671039 -410.623641)
			(xy 162.671039 -410.6237) (xy 162.662964 -410.690637) (xy 162.646929 -410.756126) (xy 162.623165 -410.819223)
			(xy 162.592014 -410.879018) (xy 162.553924 -410.934651) (xy 162.53206 -410.960316) (xy 162.526269 -410.967465)
			(xy 162.519752 -410.984653) (xy 162.51936 -410.993844) (xy 162.51936 -411.151324) (xy 162.519003 -411.161453)
			(xy 162.511239 -411.180165) (xy 162.496904 -411.19448) (xy 162.478182 -411.202217) (xy 162.468052 -411.202632)
			(xy 161.751772 -411.202632) (xy 161.741665 -411.202139) (xy 161.722993 -411.194398) (xy 161.7087 -411.180104)
			(xy 161.700961 -411.161431) (xy 161.700464 -411.151324) (xy 161.700464 -410.993844) (xy 161.700019 -410.984661)
			(xy 161.693528 -410.967477) (xy 161.687764 -410.960316) (xy 161.665886 -410.934663) (xy 161.6278 -410.879026)
			(xy 161.596652 -410.819228) (xy 161.57289 -410.756129) (xy 161.556857 -410.690639) (xy 161.548783 -410.6237)
			(xy 154.57678 -410.6237) (xy 154.57678 -417.371276) (xy 154.576371 -417.383441) (xy 154.568857 -417.406581)
			(xy 154.554556 -417.426265) (xy 154.53487 -417.440562) (xy 154.511729 -417.448073) (xy 154.499564 -417.448492)
			(xy 141.100302 -417.448492) (xy 141.088157 -417.448035) (xy 141.06506 -417.440516) (xy 141.045426 -417.426216)
			(xy 141.031183 -417.406541) (xy 141.02373 -417.383422) (xy 141.02334 -417.371276) (xy 66.525648 -417.371276)
			(xy 66.525648 -417.533836) (xy 66.525172 -417.545883) (xy 66.517735 -417.568802) (xy 66.503597 -417.588313)
			(xy 66.484133 -417.602517) (xy 66.46124 -417.610031) (xy 66.449194 -417.610544) (xy 53.151024 -417.610544)
			(xy 53.138954 -417.610016) (xy 53.115994 -417.602564) (xy 53.09646 -417.588383) (xy 53.082263 -417.56886)
			(xy 53.074793 -417.545905) (xy 53.074316 -417.533836) (xy 53.074316 -417.289488) (xy 53.073808 -417.289488)
			(xy 0.682829 -417.289488) (xy 0.737106 -417.383499) (xy 0.799937 -417.475656) (xy 0.86948 -417.56286)
			(xy 0.945345 -417.644623) (xy 1.027108 -417.720488) (xy 1.114312 -417.790031) (xy 1.206469 -417.852862)
			(xy 1.303064 -417.908631) (xy 1.403556 -417.957026) (xy 1.507384 -417.997775) (xy 1.613967 -418.030652)
			(xy 1.722709 -418.055471) (xy 1.833001 -418.072095) (xy 1.944227 -418.080431) (xy 1.999996 -418.080952)
			(xy 6.799834 -418.080952) (xy 6.80085 -418.081968) (xy 7.986268 -418.081968)
		)
		(stroke
			(width 0)
			(type solid)
		)
		(fill yes)
		(layer "In1.Cu")
		(net "GND")
	)
	(gr_circle
		(center 36.849812 -316.799722)
		(end 37.103812 -316.799722)
		(stroke
			(width 0.1016)
			(type default)
		)
		(fill no)
		(layer "In1.Cu")
	)
	(gr_circle
		(center 36.849812 -314.899802)
		(end 37.103812 -314.899802)
		(stroke
			(width 0.1016)
			(type default)
		)
		(fill no)
		(layer "In1.Cu")
	)
	(gr_circle
		(center 36.849812 -312.049922)
		(end 37.103812 -312.049922)
		(stroke
			(width 0.1016)
			(type default)
		)
		(fill no)
		(layer "In1.Cu")
	)
	(gr_circle
		(center 36.849812 -310.149748)
		(end 37.103812 -310.149748)
		(stroke
			(width 0.1016)
			(type default)
		)
		(fill no)
		(layer "In1.Cu")
	)
	(gr_circle
		(center 36.849812 -308.249828)
		(end 37.103812 -308.249828)
		(stroke
			(width 0.1016)
			(type default)
		)
		(fill no)
		(layer "In1.Cu")
	)
	(gr_circle
		(center 36.849812 -306.349908)
		(end 37.103812 -306.349908)
		(stroke
			(width 0.1016)
			(type default)
		)
		(fill no)
		(layer "In1.Cu")
	)
	(gr_circle
		(center 36.849812 -304.449734)
		(end 37.103812 -304.449734)
		(stroke
			(width 0.1016)
			(type default)
		)
		(fill no)
		(layer "In1.Cu")
	)
	(gr_circle
		(center 36.849812 -302.549814)
		(end 37.103812 -302.549814)
		(stroke
			(width 0.1016)
			(type default)
		)
		(fill no)
		(layer "In1.Cu")
	)
	(gr_circle
		(center 37.799772 -316.799722)
		(end 38.053772 -316.799722)
		(stroke
			(width 0.1016)
			(type default)
		)
		(fill no)
		(layer "In1.Cu")
	)
	(gr_circle
		(center 37.799772 -314.899802)
		(end 38.053772 -314.899802)
		(stroke
			(width 0.1016)
			(type default)
		)
		(fill no)
		(layer "In1.Cu")
	)
	(gr_circle
		(center 37.799772 -312.049922)
		(end 38.053772 -312.049922)
		(stroke
			(width 0.1016)
			(type default)
		)
		(fill no)
		(layer "In1.Cu")
	)
	(gr_circle
		(center 37.799772 -310.149748)
		(end 38.053772 -310.149748)
		(stroke
			(width 0.1016)
			(type default)
		)
		(fill no)
		(layer "In1.Cu")
	)
	(gr_circle
		(center 37.799772 -308.249828)
		(end 38.053772 -308.249828)
		(stroke
			(width 0.1016)
			(type default)
		)
		(fill no)
		(layer "In1.Cu")
	)
	(gr_circle
		(center 37.799772 -306.349908)
		(end 38.053772 -306.349908)
		(stroke
			(width 0.1016)
			(type default)
		)
		(fill no)
		(layer "In1.Cu")
	)
	(gr_circle
		(center 37.799772 -304.449734)
		(end 38.053772 -304.449734)
		(stroke
			(width 0.1016)
			(type default)
		)
		(fill no)
		(layer "In1.Cu")
	)
	(gr_circle
		(center 37.799772 -302.549814)
		(end 38.053772 -302.549814)
		(stroke
			(width 0.1016)
			(type default)
		)
		(fill no)
		(layer "In1.Cu")
	)
	(gr_circle
		(center 38.749986 -318.699896)
		(end 39.003986 -318.699896)
		(stroke
			(width 0.1016)
			(type default)
		)
		(fill no)
		(layer "In1.Cu")
	)
	(gr_circle
		(center 38.749986 -317.749936)
		(end 39.003986 -317.749936)
		(stroke
			(width 0.1016)
			(type default)
		)
		(fill no)
		(layer "In1.Cu")
	)
	(gr_circle
		(center 38.749986 -313.949842)
		(end 39.003986 -313.949842)
		(stroke
			(width 0.1016)
			(type default)
		)
		(fill no)
		(layer "In1.Cu")
	)
	(gr_circle
		(center 38.749986 -312.999882)
		(end 39.003986 -312.999882)
		(stroke
			(width 0.1016)
			(type default)
		)
		(fill no)
		(layer "In1.Cu")
	)
	(gr_circle
		(center 38.749986 -309.199788)
		(end 39.003986 -309.199788)
		(stroke
			(width 0.1016)
			(type default)
		)
		(fill no)
		(layer "In1.Cu")
	)
	(gr_circle
		(center 38.749986 -307.299868)
		(end 39.003986 -307.299868)
		(stroke
			(width 0.1016)
			(type default)
		)
		(fill no)
		(layer "In1.Cu")
	)
	(gr_circle
		(center 38.749986 -305.399948)
		(end 39.003986 -305.399948)
		(stroke
			(width 0.1016)
			(type default)
		)
		(fill no)
		(layer "In1.Cu")
	)
	(gr_circle
		(center 38.749986 -303.499774)
		(end 39.003986 -303.499774)
		(stroke
			(width 0.1016)
			(type default)
		)
		(fill no)
		(layer "In1.Cu")
	)
	(gr_circle
		(center 38.749986 -301.599854)
		(end 39.003986 -301.599854)
		(stroke
			(width 0.1016)
			(type default)
		)
		(fill no)
		(layer "In1.Cu")
	)
	(gr_circle
		(center 39.699946 -316.799722)
		(end 39.953946 -316.799722)
		(stroke
			(width 0.1016)
			(type default)
		)
		(fill no)
		(layer "In1.Cu")
	)
	(gr_circle
		(center 39.699946 -315.849762)
		(end 39.953946 -315.849762)
		(stroke
			(width 0.1016)
			(type default)
		)
		(fill no)
		(layer "In1.Cu")
	)
	(gr_circle
		(center 39.699946 -312.049922)
		(end 39.953946 -312.049922)
		(stroke
			(width 0.1016)
			(type default)
		)
		(fill no)
		(layer "In1.Cu")
	)
	(gr_circle
		(center 39.699946 -311.099962)
		(end 39.953946 -311.099962)
		(stroke
			(width 0.1016)
			(type default)
		)
		(fill no)
		(layer "In1.Cu")
	)
	(gr_circle
		(center 39.699946 -309.199788)
		(end 39.953946 -309.199788)
		(stroke
			(width 0.1016)
			(type default)
		)
		(fill no)
		(layer "In1.Cu")
	)
	(gr_circle
		(center 39.699946 -307.299868)
		(end 39.953946 -307.299868)
		(stroke
			(width 0.1016)
			(type default)
		)
		(fill no)
		(layer "In1.Cu")
	)
	(gr_circle
		(center 39.699946 -305.399948)
		(end 39.953946 -305.399948)
		(stroke
			(width 0.1016)
			(type default)
		)
		(fill no)
		(layer "In1.Cu")
	)
	(gr_circle
		(center 39.699946 -303.499774)
		(end 39.953946 -303.499774)
		(stroke
			(width 0.1016)
			(type default)
		)
		(fill no)
		(layer "In1.Cu")
	)
	(gr_circle
		(center 39.699946 -301.599854)
		(end 39.953946 -301.599854)
		(stroke
			(width 0.1016)
			(type default)
		)
		(fill no)
		(layer "In1.Cu")
	)
	(gr_circle
		(center 40.649906 -318.699896)
		(end 40.903906 -318.699896)
		(stroke
			(width 0.1016)
			(type default)
		)
		(fill no)
		(layer "In1.Cu")
	)
	(gr_circle
		(center 40.649906 -317.749936)
		(end 40.903906 -317.749936)
		(stroke
			(width 0.1016)
			(type default)
		)
		(fill no)
		(layer "In1.Cu")
	)
	(gr_circle
		(center 40.649906 -313.949842)
		(end 40.903906 -313.949842)
		(stroke
			(width 0.1016)
			(type default)
		)
		(fill no)
		(layer "In1.Cu")
	)
	(gr_circle
		(center 40.649906 -312.999882)
		(end 40.903906 -312.999882)
		(stroke
			(width 0.1016)
			(type default)
		)
		(fill no)
		(layer "In1.Cu")
	)
	(gr_circle
		(center 41.599866 -316.799722)
		(end 41.853866 -316.799722)
		(stroke
			(width 0.1016)
			(type default)
		)
		(fill no)
		(layer "In1.Cu")
	)
	(gr_circle
		(center 41.599866 -315.849762)
		(end 41.853866 -315.849762)
		(stroke
			(width 0.1016)
			(type default)
		)
		(fill no)
		(layer "In1.Cu")
	)
	(gr_circle
		(center 41.599866 -312.049922)
		(end 41.853866 -312.049922)
		(stroke
			(width 0.1016)
			(type default)
		)
		(fill no)
		(layer "In1.Cu")
	)
	(gr_circle
		(center 41.599866 -311.099962)
		(end 41.853866 -311.099962)
		(stroke
			(width 0.1016)
			(type default)
		)
		(fill no)
		(layer "In1.Cu")
	)
	(gr_circle
		(center 41.599866 -309.199788)
		(end 41.853866 -309.199788)
		(stroke
			(width 0.1016)
			(type default)
		)
		(fill no)
		(layer "In1.Cu")
	)
	(gr_circle
		(center 41.599866 -307.299868)
		(end 41.853866 -307.299868)
		(stroke
			(width 0.1016)
			(type default)
		)
		(fill no)
		(layer "In1.Cu")
	)
	(gr_circle
		(center 41.599866 -305.399948)
		(end 41.853866 -305.399948)
		(stroke
			(width 0.1016)
			(type default)
		)
		(fill no)
		(layer "In1.Cu")
	)
	(gr_circle
		(center 41.599866 -303.499774)
		(end 41.853866 -303.499774)
		(stroke
			(width 0.1016)
			(type default)
		)
		(fill no)
		(layer "In1.Cu")
	)
	(gr_circle
		(center 41.599866 -301.599854)
		(end 41.853866 -301.599854)
		(stroke
			(width 0.1016)
			(type default)
		)
		(fill no)
		(layer "In1.Cu")
	)
	(gr_circle
		(center 42.549826 -318.699896)
		(end 42.803826 -318.699896)
		(stroke
			(width 0.1016)
			(type default)
		)
		(fill no)
		(layer "In1.Cu")
	)
	(gr_circle
		(center 42.549826 -317.749936)
		(end 42.803826 -317.749936)
		(stroke
			(width 0.1016)
			(type default)
		)
		(fill no)
		(layer "In1.Cu")
	)
	(gr_circle
		(center 42.549826 -313.949842)
		(end 42.803826 -313.949842)
		(stroke
			(width 0.1016)
			(type default)
		)
		(fill no)
		(layer "In1.Cu")
	)
	(gr_circle
		(center 42.549826 -312.999882)
		(end 42.803826 -312.999882)
		(stroke
			(width 0.1016)
			(type default)
		)
		(fill no)
		(layer "In1.Cu")
	)
	(gr_circle
		(center 42.549826 -309.199788)
		(end 42.803826 -309.199788)
		(stroke
			(width 0.1016)
			(type default)
		)
		(fill no)
		(layer "In1.Cu")
	)
	(gr_circle
		(center 42.549826 -307.299868)
		(end 42.803826 -307.299868)
		(stroke
			(width 0.1016)
			(type default)
		)
		(fill no)
		(layer "In1.Cu")
	)
	(gr_circle
		(center 42.549826 -305.399948)
		(end 42.803826 -305.399948)
		(stroke
			(width 0.1016)
			(type default)
		)
		(fill no)
		(layer "In1.Cu")
	)
	(gr_circle
		(center 42.549826 -303.499774)
		(end 42.803826 -303.499774)
		(stroke
			(width 0.1016)
			(type default)
		)
		(fill no)
		(layer "In1.Cu")
	)
	(gr_circle
		(center 42.549826 -301.599854)
		(end 42.803826 -301.599854)
		(stroke
			(width 0.1016)
			(type default)
		)
		(fill no)
		(layer "In1.Cu")
	)
	(gr_circle
		(center 43.499786 -316.799722)
		(end 43.753786 -316.799722)
		(stroke
			(width 0.1016)
			(type default)
		)
		(fill no)
		(layer "In1.Cu")
	)
	(gr_circle
		(center 43.499786 -315.849762)
		(end 43.753786 -315.849762)
		(stroke
			(width 0.1016)
			(type default)
		)
		(fill no)
		(layer "In1.Cu")
	)
	(gr_circle
		(center 43.499786 -312.049922)
		(end 43.753786 -312.049922)
		(stroke
			(width 0.1016)
			(type default)
		)
		(fill no)
		(layer "In1.Cu")
	)
	(gr_circle
		(center 43.499786 -311.099962)
		(end 43.753786 -311.099962)
		(stroke
			(width 0.1016)
			(type default)
		)
		(fill no)
		(layer "In1.Cu")
	)
	(gr_circle
		(center 43.499786 -308.249828)
		(end 43.753786 -308.249828)
		(stroke
			(width 0.1016)
			(type default)
		)
		(fill no)
		(layer "In1.Cu")
	)
	(gr_circle
		(center 43.499786 -306.349908)
		(end 43.753786 -306.349908)
		(stroke
			(width 0.1016)
			(type default)
		)
		(fill no)
		(layer "In1.Cu")
	)
	(gr_circle
		(center 43.499786 -304.449734)
		(end 43.753786 -304.449734)
		(stroke
			(width 0.1016)
			(type default)
		)
		(fill no)
		(layer "In1.Cu")
	)
	(gr_circle
		(center 43.499786 -302.549814)
		(end 43.753786 -302.549814)
		(stroke
			(width 0.1016)
			(type default)
		)
		(fill no)
		(layer "In1.Cu")
	)
	(gr_circle
		(center 44.449746 -318.699896)
		(end 44.703746 -318.699896)
		(stroke
			(width 0.1016)
			(type default)
		)
		(fill no)
		(layer "In1.Cu")
	)
	(gr_circle
		(center 44.449746 -317.749936)
		(end 44.703746 -317.749936)
		(stroke
			(width 0.1016)
			(type default)
		)
		(fill no)
		(layer "In1.Cu")
	)
	(gr_circle
		(center 44.449746 -313.949842)
		(end 44.703746 -313.949842)
		(stroke
			(width 0.1016)
			(type default)
		)
		(fill no)
		(layer "In1.Cu")
	)
	(gr_circle
		(center 44.449746 -312.999882)
		(end 44.703746 -312.999882)
		(stroke
			(width 0.1016)
			(type default)
		)
		(fill no)
		(layer "In1.Cu")
	)
	(gr_circle
		(center 44.449746 -308.249828)
		(end 44.703746 -308.249828)
		(stroke
			(width 0.1016)
			(type default)
		)
		(fill no)
		(layer "In1.Cu")
	)
	(gr_circle
		(center 44.449746 -306.349908)
		(end 44.703746 -306.349908)
		(stroke
			(width 0.1016)
			(type default)
		)
		(fill no)
		(layer "In1.Cu")
	)
	(gr_circle
		(center 44.449746 -304.449734)
		(end 44.703746 -304.449734)
		(stroke
			(width 0.1016)
			(type default)
		)
		(fill no)
		(layer "In1.Cu")
	)
	(gr_circle
		(center 44.449746 -302.549814)
		(end 44.703746 -302.549814)
		(stroke
			(width 0.1016)
			(type default)
		)
		(fill no)
		(layer "In1.Cu")
	)
	(gr_circle
		(center 44.449746 -278.799798)
		(end 44.703746 -278.799798)
		(stroke
			(width 0.1016)
			(type default)
		)
		(fill no)
		(layer "In1.Cu")
	)
	(gr_circle
		(center 44.449746 -277.849838)
		(end 44.703746 -277.849838)
		(stroke
			(width 0.1016)
			(type default)
		)
		(fill no)
		(layer "In1.Cu")
	)
	(gr_circle
		(center 44.449746 -274.049744)
		(end 44.703746 -274.049744)
		(stroke
			(width 0.1016)
			(type default)
		)
		(fill no)
		(layer "In1.Cu")
	)
	(gr_circle
		(center 44.449746 -273.099784)
		(end 44.703746 -273.099784)
		(stroke
			(width 0.1016)
			(type default)
		)
		(fill no)
		(layer "In1.Cu")
	)
	(gr_circle
		(center 45.39996 -316.799722)
		(end 45.65396 -316.799722)
		(stroke
			(width 0.1016)
			(type default)
		)
		(fill no)
		(layer "In1.Cu")
	)
	(gr_circle
		(center 45.39996 -315.849762)
		(end 45.65396 -315.849762)
		(stroke
			(width 0.1016)
			(type default)
		)
		(fill no)
		(layer "In1.Cu")
	)
	(gr_circle
		(center 45.39996 -312.049922)
		(end 45.65396 -312.049922)
		(stroke
			(width 0.1016)
			(type default)
		)
		(fill no)
		(layer "In1.Cu")
	)
	(gr_circle
		(center 45.39996 -311.099962)
		(end 45.65396 -311.099962)
		(stroke
			(width 0.1016)
			(type default)
		)
		(fill no)
		(layer "In1.Cu")
	)
	(gr_circle
		(center 45.39996 -280.699464)
		(end 45.65396 -280.699464)
		(stroke
			(width 0.1016)
			(type default)
		)
		(fill no)
		(layer "In1.Cu")
	)
	(gr_circle
		(center 45.39996 -279.749504)
		(end 45.65396 -279.749504)
		(stroke
			(width 0.1016)
			(type default)
		)
		(fill no)
		(layer "In1.Cu")
	)
	(gr_circle
		(center 45.39996 -275.949918)
		(end 45.65396 -275.949918)
		(stroke
			(width 0.1016)
			(type default)
		)
		(fill no)
		(layer "In1.Cu")
	)
	(gr_circle
		(center 45.39996 -274.999958)
		(end 45.65396 -274.999958)
		(stroke
			(width 0.1016)
			(type default)
		)
		(fill no)
		(layer "In1.Cu")
	)
	(gr_circle
		(center 46.34992 -318.699896)
		(end 46.60392 -318.699896)
		(stroke
			(width 0.1016)
			(type default)
		)
		(fill no)
		(layer "In1.Cu")
	)
	(gr_circle
		(center 46.34992 -317.749936)
		(end 46.60392 -317.749936)
		(stroke
			(width 0.1016)
			(type default)
		)
		(fill no)
		(layer "In1.Cu")
	)
	(gr_circle
		(center 46.34992 -313.949842)
		(end 46.60392 -313.949842)
		(stroke
			(width 0.1016)
			(type default)
		)
		(fill no)
		(layer "In1.Cu")
	)
	(gr_circle
		(center 46.34992 -312.999882)
		(end 46.60392 -312.999882)
		(stroke
			(width 0.1016)
			(type default)
		)
		(fill no)
		(layer "In1.Cu")
	)
	(gr_circle
		(center 46.34992 -278.799798)
		(end 46.60392 -278.799798)
		(stroke
			(width 0.1016)
			(type default)
		)
		(fill no)
		(layer "In1.Cu")
	)
	(gr_circle
		(center 46.34992 -277.849838)
		(end 46.60392 -277.849838)
		(stroke
			(width 0.1016)
			(type default)
		)
		(fill no)
		(layer "In1.Cu")
	)
	(gr_circle
		(center 46.34992 -274.049744)
		(end 46.60392 -274.049744)
		(stroke
			(width 0.1016)
			(type default)
		)
		(fill no)
		(layer "In1.Cu")
	)
	(gr_circle
		(center 46.34992 -273.099784)
		(end 46.60392 -273.099784)
		(stroke
			(width 0.1016)
			(type default)
		)
		(fill no)
		(layer "In1.Cu")
	)
	(gr_circle
		(center 47.29988 -316.799722)
		(end 47.55388 -316.799722)
		(stroke
			(width 0.1016)
			(type default)
		)
		(fill no)
		(layer "In1.Cu")
	)
	(gr_circle
		(center 47.29988 -315.849762)
		(end 47.55388 -315.849762)
		(stroke
			(width 0.1016)
			(type default)
		)
		(fill no)
		(layer "In1.Cu")
	)
	(gr_circle
		(center 47.29988 -312.049922)
		(end 47.55388 -312.049922)
		(stroke
			(width 0.1016)
			(type default)
		)
		(fill no)
		(layer "In1.Cu")
	)
	(gr_circle
		(center 47.29988 -311.099962)
		(end 47.55388 -311.099962)
		(stroke
			(width 0.1016)
			(type default)
		)
		(fill no)
		(layer "In1.Cu")
	)
	(gr_circle
		(center 47.29988 -280.699464)
		(end 47.55388 -280.699464)
		(stroke
			(width 0.1016)
			(type default)
		)
		(fill no)
		(layer "In1.Cu")
	)
	(gr_circle
		(center 47.29988 -279.749504)
		(end 47.55388 -279.749504)
		(stroke
			(width 0.1016)
			(type default)
		)
		(fill no)
		(layer "In1.Cu")
	)
	(gr_circle
		(center 47.29988 -275.949918)
		(end 47.55388 -275.949918)
		(stroke
			(width 0.1016)
			(type default)
		)
		(fill no)
		(layer "In1.Cu")
	)
	(gr_circle
		(center 47.29988 -274.999958)
		(end 47.55388 -274.999958)
		(stroke
			(width 0.1016)
			(type default)
		)
		(fill no)
		(layer "In1.Cu")
	)
	(gr_circle
		(center 48.24984 -318.699896)
		(end 48.50384 -318.699896)
		(stroke
			(width 0.1016)
			(type default)
		)
		(fill no)
		(layer "In1.Cu")
	)
	(gr_circle
		(center 48.24984 -317.749936)
		(end 48.50384 -317.749936)
		(stroke
			(width 0.1016)
			(type default)
		)
		(fill no)
		(layer "In1.Cu")
	)
	(gr_circle
		(center 48.24984 -313.949842)
		(end 48.50384 -313.949842)
		(stroke
			(width 0.1016)
			(type default)
		)
		(fill no)
		(layer "In1.Cu")
	)
	(gr_circle
		(center 48.24984 -312.999882)
		(end 48.50384 -312.999882)
		(stroke
			(width 0.1016)
			(type default)
		)
		(fill no)
		(layer "In1.Cu")
	)
	(gr_circle
		(center 48.24984 -278.799798)
		(end 48.50384 -278.799798)
		(stroke
			(width 0.1016)
			(type default)
		)
		(fill no)
		(layer "In1.Cu")
	)
	(gr_circle
		(center 48.24984 -277.849838)
		(end 48.50384 -277.849838)
		(stroke
			(width 0.1016)
			(type default)
		)
		(fill no)
		(layer "In1.Cu")
	)
	(gr_circle
		(center 48.24984 -274.049744)
		(end 48.50384 -274.049744)
		(stroke
			(width 0.1016)
			(type default)
		)
		(fill no)
		(layer "In1.Cu")
	)
	(gr_circle
		(center 48.24984 -273.099784)
		(end 48.50384 -273.099784)
		(stroke
			(width 0.1016)
			(type default)
		)
		(fill no)
		(layer "In1.Cu")
	)
	(gr_circle
		(center 49.1998 -316.799722)
		(end 49.4538 -316.799722)
		(stroke
			(width 0.1016)
			(type default)
		)
		(fill no)
		(layer "In1.Cu")
	)
	(gr_circle
		(center 49.1998 -315.849762)
		(end 49.4538 -315.849762)
		(stroke
			(width 0.1016)
			(type default)
		)
		(fill no)
		(layer "In1.Cu")
	)
	(gr_circle
		(center 49.1998 -312.049922)
		(end 49.4538 -312.049922)
		(stroke
			(width 0.1016)
			(type default)
		)
		(fill no)
		(layer "In1.Cu")
	)
	(gr_circle
		(center 49.1998 -311.099962)
		(end 49.4538 -311.099962)
		(stroke
			(width 0.1016)
			(type default)
		)
		(fill no)
		(layer "In1.Cu")
	)
	(gr_circle
		(center 49.1998 -280.699464)
		(end 49.4538 -280.699464)
		(stroke
			(width 0.1016)
			(type default)
		)
		(fill no)
		(layer "In1.Cu")
	)
	(gr_circle
		(center 49.1998 -279.749504)
		(end 49.4538 -279.749504)
		(stroke
			(width 0.1016)
			(type default)
		)
		(fill no)
		(layer "In1.Cu")
	)
	(gr_circle
		(center 49.1998 -275.949918)
		(end 49.4538 -275.949918)
		(stroke
			(width 0.1016)
			(type default)
		)
		(fill no)
		(layer "In1.Cu")
	)
	(gr_circle
		(center 49.1998 -274.999958)
		(end 49.4538 -274.999958)
		(stroke
			(width 0.1016)
			(type default)
		)
		(fill no)
		(layer "In1.Cu")
	)
	(gr_circle
		(center 50.14976 -318.699896)
		(end 50.40376 -318.699896)
		(stroke
			(width 0.1016)
			(type default)
		)
		(fill no)
		(layer "In1.Cu")
	)
	(gr_circle
		(center 50.14976 -317.749936)
		(end 50.40376 -317.749936)
		(stroke
			(width 0.1016)
			(type default)
		)
		(fill no)
		(layer "In1.Cu")
	)
	(gr_circle
		(center 50.14976 -313.949842)
		(end 50.40376 -313.949842)
		(stroke
			(width 0.1016)
			(type default)
		)
		(fill no)
		(layer "In1.Cu")
	)
	(gr_circle
		(center 50.14976 -312.999882)
		(end 50.40376 -312.999882)
		(stroke
			(width 0.1016)
			(type default)
		)
		(fill no)
		(layer "In1.Cu")
	)
	(gr_circle
		(center 50.14976 -278.799798)
		(end 50.40376 -278.799798)
		(stroke
			(width 0.1016)
			(type default)
		)
		(fill no)
		(layer "In1.Cu")
	)
	(gr_circle
		(center 50.14976 -277.849838)
		(end 50.40376 -277.849838)
		(stroke
			(width 0.1016)
			(type default)
		)
		(fill no)
		(layer "In1.Cu")
	)
	(gr_circle
		(center 50.14976 -274.049744)
		(end 50.40376 -274.049744)
		(stroke
			(width 0.1016)
			(type default)
		)
		(fill no)
		(layer "In1.Cu")
	)
	(gr_circle
		(center 50.14976 -273.099784)
		(end 50.40376 -273.099784)
		(stroke
			(width 0.1016)
			(type default)
		)
		(fill no)
		(layer "In1.Cu")
	)
	(gr_circle
		(center 51.099974 -316.799722)
		(end 51.353974 -316.799722)
		(stroke
			(width 0.1016)
			(type default)
		)
		(fill no)
		(layer "In1.Cu")
	)
	(gr_circle
		(center 51.099974 -315.849762)
		(end 51.353974 -315.849762)
		(stroke
			(width 0.1016)
			(type default)
		)
		(fill no)
		(layer "In1.Cu")
	)
	(gr_circle
		(center 51.099974 -312.049922)
		(end 51.353974 -312.049922)
		(stroke
			(width 0.1016)
			(type default)
		)
		(fill no)
		(layer "In1.Cu")
	)
	(gr_circle
		(center 51.099974 -311.099962)
		(end 51.353974 -311.099962)
		(stroke
			(width 0.1016)
			(type default)
		)
		(fill no)
		(layer "In1.Cu")
	)
	(gr_circle
		(center 51.099974 -280.699464)
		(end 51.353974 -280.699464)
		(stroke
			(width 0.1016)
			(type default)
		)
		(fill no)
		(layer "In1.Cu")
	)
	(gr_circle
		(center 51.099974 -279.749504)
		(end 51.353974 -279.749504)
		(stroke
			(width 0.1016)
			(type default)
		)
		(fill no)
		(layer "In1.Cu")
	)
	(gr_circle
		(center 51.099974 -275.949918)
		(end 51.353974 -275.949918)
		(stroke
			(width 0.1016)
			(type default)
		)
		(fill no)
		(layer "In1.Cu")
	)
	(gr_circle
		(center 51.099974 -274.999958)
		(end 51.353974 -274.999958)
		(stroke
			(width 0.1016)
			(type default)
		)
		(fill no)
		(layer "In1.Cu")
	)
	(gr_circle
		(center 52.049934 -318.699896)
		(end 52.303934 -318.699896)
		(stroke
			(width 0.1016)
			(type default)
		)
		(fill no)
		(layer "In1.Cu")
	)
	(gr_circle
		(center 52.049934 -317.749936)
		(end 52.303934 -317.749936)
		(stroke
			(width 0.1016)
			(type default)
		)
		(fill no)
		(layer "In1.Cu")
	)
	(gr_circle
		(center 52.049934 -313.949842)
		(end 52.303934 -313.949842)
		(stroke
			(width 0.1016)
			(type default)
		)
		(fill no)
		(layer "In1.Cu")
	)
	(gr_circle
		(center 52.049934 -312.999882)
		(end 52.303934 -312.999882)
		(stroke
			(width 0.1016)
			(type default)
		)
		(fill no)
		(layer "In1.Cu")
	)
	(gr_circle
		(center 52.049934 -278.799798)
		(end 52.303934 -278.799798)
		(stroke
			(width 0.1016)
			(type default)
		)
		(fill no)
		(layer "In1.Cu")
	)
	(gr_circle
		(center 52.049934 -277.849838)
		(end 52.303934 -277.849838)
		(stroke
			(width 0.1016)
			(type default)
		)
		(fill no)
		(layer "In1.Cu")
	)
	(gr_circle
		(center 52.049934 -274.049744)
		(end 52.303934 -274.049744)
		(stroke
			(width 0.1016)
			(type default)
		)
		(fill no)
		(layer "In1.Cu")
	)
	(gr_circle
		(center 52.049934 -273.099784)
		(end 52.303934 -273.099784)
		(stroke
			(width 0.1016)
			(type default)
		)
		(fill no)
		(layer "In1.Cu")
	)
	(gr_circle
		(center 52.999894 -316.799722)
		(end 53.253894 -316.799722)
		(stroke
			(width 0.1016)
			(type default)
		)
		(fill no)
		(layer "In1.Cu")
	)
	(gr_circle
		(center 52.999894 -315.849762)
		(end 53.253894 -315.849762)
		(stroke
			(width 0.1016)
			(type default)
		)
		(fill no)
		(layer "In1.Cu")
	)
	(gr_circle
		(center 52.999894 -312.049922)
		(end 53.253894 -312.049922)
		(stroke
			(width 0.1016)
			(type default)
		)
		(fill no)
		(layer "In1.Cu")
	)
	(gr_circle
		(center 52.999894 -311.099962)
		(end 53.253894 -311.099962)
		(stroke
			(width 0.1016)
			(type default)
		)
		(fill no)
		(layer "In1.Cu")
	)
	(gr_circle
		(center 52.999894 -280.699464)
		(end 53.253894 -280.699464)
		(stroke
			(width 0.1016)
			(type default)
		)
		(fill no)
		(layer "In1.Cu")
	)
	(gr_circle
		(center 52.999894 -279.749504)
		(end 53.253894 -279.749504)
		(stroke
			(width 0.1016)
			(type default)
		)
		(fill no)
		(layer "In1.Cu")
	)
	(gr_circle
		(center 52.999894 -275.949918)
		(end 53.253894 -275.949918)
		(stroke
			(width 0.1016)
			(type default)
		)
		(fill no)
		(layer "In1.Cu")
	)
	(gr_circle
		(center 52.999894 -274.999958)
		(end 53.253894 -274.999958)
		(stroke
			(width 0.1016)
			(type default)
		)
		(fill no)
		(layer "In1.Cu")
	)
	(gr_circle
		(center 53.949854 -318.699896)
		(end 54.203854 -318.699896)
		(stroke
			(width 0.1016)
			(type default)
		)
		(fill no)
		(layer "In1.Cu")
	)
	(gr_circle
		(center 53.949854 -317.749936)
		(end 54.203854 -317.749936)
		(stroke
			(width 0.1016)
			(type default)
		)
		(fill no)
		(layer "In1.Cu")
	)
	(gr_circle
		(center 53.949854 -313.949842)
		(end 54.203854 -313.949842)
		(stroke
			(width 0.1016)
			(type default)
		)
		(fill no)
		(layer "In1.Cu")
	)
	(gr_circle
		(center 53.949854 -312.999882)
		(end 54.203854 -312.999882)
		(stroke
			(width 0.1016)
			(type default)
		)
		(fill no)
		(layer "In1.Cu")
	)
	(gr_circle
		(center 53.949854 -278.799798)
		(end 54.203854 -278.799798)
		(stroke
			(width 0.1016)
			(type default)
		)
		(fill no)
		(layer "In1.Cu")
	)
	(gr_circle
		(center 53.949854 -277.849838)
		(end 54.203854 -277.849838)
		(stroke
			(width 0.1016)
			(type default)
		)
		(fill no)
		(layer "In1.Cu")
	)
	(gr_circle
		(center 53.949854 -274.049744)
		(end 54.203854 -274.049744)
		(stroke
			(width 0.1016)
			(type default)
		)
		(fill no)
		(layer "In1.Cu")
	)
	(gr_circle
		(center 53.949854 -273.099784)
		(end 54.203854 -273.099784)
		(stroke
			(width 0.1016)
			(type default)
		)
		(fill no)
		(layer "In1.Cu")
	)
	(gr_circle
		(center 54.899814 -316.799722)
		(end 55.153814 -316.799722)
		(stroke
			(width 0.1016)
			(type default)
		)
		(fill no)
		(layer "In1.Cu")
	)
	(gr_circle
		(center 54.899814 -315.849762)
		(end 55.153814 -315.849762)
		(stroke
			(width 0.1016)
			(type default)
		)
		(fill no)
		(layer "In1.Cu")
	)
	(gr_circle
		(center 54.899814 -312.049922)
		(end 55.153814 -312.049922)
		(stroke
			(width 0.1016)
			(type default)
		)
		(fill no)
		(layer "In1.Cu")
	)
	(gr_circle
		(center 54.899814 -311.099962)
		(end 55.153814 -311.099962)
		(stroke
			(width 0.1016)
			(type default)
		)
		(fill no)
		(layer "In1.Cu")
	)
	(gr_circle
		(center 54.899814 -280.699464)
		(end 55.153814 -280.699464)
		(stroke
			(width 0.1016)
			(type default)
		)
		(fill no)
		(layer "In1.Cu")
	)
	(gr_circle
		(center 54.899814 -279.749504)
		(end 55.153814 -279.749504)
		(stroke
			(width 0.1016)
			(type default)
		)
		(fill no)
		(layer "In1.Cu")
	)
	(gr_circle
		(center 54.899814 -275.949918)
		(end 55.153814 -275.949918)
		(stroke
			(width 0.1016)
			(type default)
		)
		(fill no)
		(layer "In1.Cu")
	)
	(gr_circle
		(center 54.899814 -274.999958)
		(end 55.153814 -274.999958)
		(stroke
			(width 0.1016)
			(type default)
		)
		(fill no)
		(layer "In1.Cu")
	)
	(gr_circle
		(center 55.849774 -318.699896)
		(end 56.103774 -318.699896)
		(stroke
			(width 0.1016)
			(type default)
		)
		(fill no)
		(layer "In1.Cu")
	)
	(gr_circle
		(center 55.849774 -317.749936)
		(end 56.103774 -317.749936)
		(stroke
			(width 0.1016)
			(type default)
		)
		(fill no)
		(layer "In1.Cu")
	)
	(gr_circle
		(center 55.849774 -313.949842)
		(end 56.103774 -313.949842)
		(stroke
			(width 0.1016)
			(type default)
		)
		(fill no)
		(layer "In1.Cu")
	)
	(gr_circle
		(center 55.849774 -312.999882)
		(end 56.103774 -312.999882)
		(stroke
			(width 0.1016)
			(type default)
		)
		(fill no)
		(layer "In1.Cu")
	)
	(gr_circle
		(center 55.849774 -278.799798)
		(end 56.103774 -278.799798)
		(stroke
			(width 0.1016)
			(type default)
		)
		(fill no)
		(layer "In1.Cu")
	)
	(gr_circle
		(center 55.849774 -277.849838)
		(end 56.103774 -277.849838)
		(stroke
			(width 0.1016)
			(type default)
		)
		(fill no)
		(layer "In1.Cu")
	)
	(gr_circle
		(center 55.849774 -274.049744)
		(end 56.103774 -274.049744)
		(stroke
			(width 0.1016)
			(type default)
		)
		(fill no)
		(layer "In1.Cu")
	)
	(gr_circle
		(center 55.849774 -273.099784)
		(end 56.103774 -273.099784)
		(stroke
			(width 0.1016)
			(type default)
		)
		(fill no)
		(layer "In1.Cu")
	)
	(gr_circle
		(center 56.799734 -280.699464)
		(end 57.053734 -280.699464)
		(stroke
			(width 0.1016)
			(type default)
		)
		(fill no)
		(layer "In1.Cu")
	)
	(gr_circle
		(center 56.799734 -279.749504)
		(end 57.053734 -279.749504)
		(stroke
			(width 0.1016)
			(type default)
		)
		(fill no)
		(layer "In1.Cu")
	)
	(gr_circle
		(center 56.799988 -316.799722)
		(end 57.053988 -316.799722)
		(stroke
			(width 0.1016)
			(type default)
		)
		(fill no)
		(layer "In1.Cu")
	)
	(gr_circle
		(center 56.799988 -315.849762)
		(end 57.053988 -315.849762)
		(stroke
			(width 0.1016)
			(type default)
		)
		(fill no)
		(layer "In1.Cu")
	)
	(gr_circle
		(center 56.799988 -312.049922)
		(end 57.053988 -312.049922)
		(stroke
			(width 0.1016)
			(type default)
		)
		(fill no)
		(layer "In1.Cu")
	)
	(gr_circle
		(center 56.799988 -311.099962)
		(end 57.053988 -311.099962)
		(stroke
			(width 0.1016)
			(type default)
		)
		(fill no)
		(layer "In1.Cu")
	)
	(gr_circle
		(center 56.799988 -275.949918)
		(end 57.053988 -275.949918)
		(stroke
			(width 0.1016)
			(type default)
		)
		(fill no)
		(layer "In1.Cu")
	)
	(gr_circle
		(center 56.799988 -274.999958)
		(end 57.053988 -274.999958)
		(stroke
			(width 0.1016)
			(type default)
		)
		(fill no)
		(layer "In1.Cu")
	)
	(gr_circle
		(center 57.749948 -318.699896)
		(end 58.003948 -318.699896)
		(stroke
			(width 0.1016)
			(type default)
		)
		(fill no)
		(layer "In1.Cu")
	)
	(gr_circle
		(center 57.749948 -317.749936)
		(end 58.003948 -317.749936)
		(stroke
			(width 0.1016)
			(type default)
		)
		(fill no)
		(layer "In1.Cu")
	)
	(gr_circle
		(center 57.749948 -313.949842)
		(end 58.003948 -313.949842)
		(stroke
			(width 0.1016)
			(type default)
		)
		(fill no)
		(layer "In1.Cu")
	)
	(gr_circle
		(center 57.749948 -312.999882)
		(end 58.003948 -312.999882)
		(stroke
			(width 0.1016)
			(type default)
		)
		(fill no)
		(layer "In1.Cu")
	)
	(gr_circle
		(center 57.749948 -278.799798)
		(end 58.003948 -278.799798)
		(stroke
			(width 0.1016)
			(type default)
		)
		(fill no)
		(layer "In1.Cu")
	)
	(gr_circle
		(center 57.749948 -277.849838)
		(end 58.003948 -277.849838)
		(stroke
			(width 0.1016)
			(type default)
		)
		(fill no)
		(layer "In1.Cu")
	)
	(gr_circle
		(center 57.749948 -274.049744)
		(end 58.003948 -274.049744)
		(stroke
			(width 0.1016)
			(type default)
		)
		(fill no)
		(layer "In1.Cu")
	)
	(gr_circle
		(center 57.749948 -273.099784)
		(end 58.003948 -273.099784)
		(stroke
			(width 0.1016)
			(type default)
		)
		(fill no)
		(layer "In1.Cu")
	)
	(gr_circle
		(center 58.699908 -316.799722)
		(end 58.953908 -316.799722)
		(stroke
			(width 0.1016)
			(type default)
		)
		(fill no)
		(layer "In1.Cu")
	)
	(gr_circle
		(center 58.699908 -315.849762)
		(end 58.953908 -315.849762)
		(stroke
			(width 0.1016)
			(type default)
		)
		(fill no)
		(layer "In1.Cu")
	)
	(gr_circle
		(center 58.699908 -312.049922)
		(end 58.953908 -312.049922)
		(stroke
			(width 0.1016)
			(type default)
		)
		(fill no)
		(layer "In1.Cu")
	)
	(gr_circle
		(center 58.699908 -311.099962)
		(end 58.953908 -311.099962)
		(stroke
			(width 0.1016)
			(type default)
		)
		(fill no)
		(layer "In1.Cu")
	)
	(gr_circle
		(center 58.699908 -280.699464)
		(end 58.953908 -280.699464)
		(stroke
			(width 0.1016)
			(type default)
		)
		(fill no)
		(layer "In1.Cu")
	)
	(gr_circle
		(center 58.699908 -279.749504)
		(end 58.953908 -279.749504)
		(stroke
			(width 0.1016)
			(type default)
		)
		(fill no)
		(layer "In1.Cu")
	)
	(gr_circle
		(center 58.699908 -275.949918)
		(end 58.953908 -275.949918)
		(stroke
			(width 0.1016)
			(type default)
		)
		(fill no)
		(layer "In1.Cu")
	)
	(gr_circle
		(center 58.699908 -274.999958)
		(end 58.953908 -274.999958)
		(stroke
			(width 0.1016)
			(type default)
		)
		(fill no)
		(layer "In1.Cu")
	)
	(gr_circle
		(center 59.649614 -278.799798)
		(end 59.903614 -278.799798)
		(stroke
			(width 0.1016)
			(type default)
		)
		(fill no)
		(layer "In1.Cu")
	)
	(gr_circle
		(center 59.649614 -277.849838)
		(end 59.903614 -277.849838)
		(stroke
			(width 0.1016)
			(type default)
		)
		(fill no)
		(layer "In1.Cu")
	)
	(gr_circle
		(center 59.649614 -274.04949)
		(end 59.903614 -274.04949)
		(stroke
			(width 0.1016)
			(type default)
		)
		(fill no)
		(layer "In1.Cu")
	)
	(gr_circle
		(center 59.649614 -273.09953)
		(end 59.903614 -273.09953)
		(stroke
			(width 0.1016)
			(type default)
		)
		(fill no)
		(layer "In1.Cu")
	)
	(gr_circle
		(center 59.649868 -318.699896)
		(end 59.903868 -318.699896)
		(stroke
			(width 0.1016)
			(type default)
		)
		(fill no)
		(layer "In1.Cu")
	)
	(gr_circle
		(center 59.649868 -317.749936)
		(end 59.903868 -317.749936)
		(stroke
			(width 0.1016)
			(type default)
		)
		(fill no)
		(layer "In1.Cu")
	)
	(gr_circle
		(center 59.649868 -313.949842)
		(end 59.903868 -313.949842)
		(stroke
			(width 0.1016)
			(type default)
		)
		(fill no)
		(layer "In1.Cu")
	)
	(gr_circle
		(center 59.649868 -312.999882)
		(end 59.903868 -312.999882)
		(stroke
			(width 0.1016)
			(type default)
		)
		(fill no)
		(layer "In1.Cu")
	)
	(gr_circle
		(center 60.599574 -275.949664)
		(end 60.853574 -275.949664)
		(stroke
			(width 0.1016)
			(type default)
		)
		(fill no)
		(layer "In1.Cu")
	)
	(gr_circle
		(center 60.599574 -274.999704)
		(end 60.853574 -274.999704)
		(stroke
			(width 0.1016)
			(type default)
		)
		(fill no)
		(layer "In1.Cu")
	)
	(gr_circle
		(center 60.599828 -316.799722)
		(end 60.853828 -316.799722)
		(stroke
			(width 0.1016)
			(type default)
		)
		(fill no)
		(layer "In1.Cu")
	)
	(gr_circle
		(center 60.599828 -315.849762)
		(end 60.853828 -315.849762)
		(stroke
			(width 0.1016)
			(type default)
		)
		(fill no)
		(layer "In1.Cu")
	)
	(gr_circle
		(center 60.599828 -312.049922)
		(end 60.853828 -312.049922)
		(stroke
			(width 0.1016)
			(type default)
		)
		(fill no)
		(layer "In1.Cu")
	)
	(gr_circle
		(center 60.599828 -311.099962)
		(end 60.853828 -311.099962)
		(stroke
			(width 0.1016)
			(type default)
		)
		(fill no)
		(layer "In1.Cu")
	)
	(gr_circle
		(center 60.599828 -280.699464)
		(end 60.853828 -280.699464)
		(stroke
			(width 0.1016)
			(type default)
		)
		(fill no)
		(layer "In1.Cu")
	)
	(gr_circle
		(center 60.599828 -279.749504)
		(end 60.853828 -279.749504)
		(stroke
			(width 0.1016)
			(type default)
		)
		(fill no)
		(layer "In1.Cu")
	)
	(gr_circle
		(center 61.549534 -278.799798)
		(end 61.803534 -278.799798)
		(stroke
			(width 0.1016)
			(type default)
		)
		(fill no)
		(layer "In1.Cu")
	)
	(gr_circle
		(center 61.549534 -277.849838)
		(end 61.803534 -277.849838)
		(stroke
			(width 0.1016)
			(type default)
		)
		(fill no)
		(layer "In1.Cu")
	)
	(gr_circle
		(center 61.549534 -274.049744)
		(end 61.803534 -274.049744)
		(stroke
			(width 0.1016)
			(type default)
		)
		(fill no)
		(layer "In1.Cu")
	)
	(gr_circle
		(center 61.549534 -273.099784)
		(end 61.803534 -273.099784)
		(stroke
			(width 0.1016)
			(type default)
		)
		(fill no)
		(layer "In1.Cu")
	)
	(gr_circle
		(center 61.549788 -318.699896)
		(end 61.803788 -318.699896)
		(stroke
			(width 0.1016)
			(type default)
		)
		(fill no)
		(layer "In1.Cu")
	)
	(gr_circle
		(center 61.549788 -317.749936)
		(end 61.803788 -317.749936)
		(stroke
			(width 0.1016)
			(type default)
		)
		(fill no)
		(layer "In1.Cu")
	)
	(gr_circle
		(center 61.549788 -313.949842)
		(end 61.803788 -313.949842)
		(stroke
			(width 0.1016)
			(type default)
		)
		(fill no)
		(layer "In1.Cu")
	)
	(gr_circle
		(center 61.549788 -312.999882)
		(end 61.803788 -312.999882)
		(stroke
			(width 0.1016)
			(type default)
		)
		(fill no)
		(layer "In1.Cu")
	)
	(gr_circle
		(center 62.499494 -275.949918)
		(end 62.753494 -275.949918)
		(stroke
			(width 0.1016)
			(type default)
		)
		(fill no)
		(layer "In1.Cu")
	)
	(gr_circle
		(center 62.499494 -274.999958)
		(end 62.753494 -274.999958)
		(stroke
			(width 0.1016)
			(type default)
		)
		(fill no)
		(layer "In1.Cu")
	)
	(gr_circle
		(center 62.499748 -316.799722)
		(end 62.753748 -316.799722)
		(stroke
			(width 0.1016)
			(type default)
		)
		(fill no)
		(layer "In1.Cu")
	)
	(gr_circle
		(center 62.499748 -315.849762)
		(end 62.753748 -315.849762)
		(stroke
			(width 0.1016)
			(type default)
		)
		(fill no)
		(layer "In1.Cu")
	)
	(gr_circle
		(center 62.499748 -312.049922)
		(end 62.753748 -312.049922)
		(stroke
			(width 0.1016)
			(type default)
		)
		(fill no)
		(layer "In1.Cu")
	)
	(gr_circle
		(center 62.499748 -311.099962)
		(end 62.753748 -311.099962)
		(stroke
			(width 0.1016)
			(type default)
		)
		(fill no)
		(layer "In1.Cu")
	)
	(gr_circle
		(center 62.499748 -280.699464)
		(end 62.753748 -280.699464)
		(stroke
			(width 0.1016)
			(type default)
		)
		(fill no)
		(layer "In1.Cu")
	)
	(gr_circle
		(center 62.499748 -279.749504)
		(end 62.753748 -279.749504)
		(stroke
			(width 0.1016)
			(type default)
		)
		(fill no)
		(layer "In1.Cu")
	)
	(gr_circle
		(center 63.449708 -278.799798)
		(end 63.703708 -278.799798)
		(stroke
			(width 0.1016)
			(type default)
		)
		(fill no)
		(layer "In1.Cu")
	)
	(gr_circle
		(center 63.449708 -277.849838)
		(end 63.703708 -277.849838)
		(stroke
			(width 0.1016)
			(type default)
		)
		(fill no)
		(layer "In1.Cu")
	)
	(gr_circle
		(center 63.449708 -274.049744)
		(end 63.703708 -274.049744)
		(stroke
			(width 0.1016)
			(type default)
		)
		(fill no)
		(layer "In1.Cu")
	)
	(gr_circle
		(center 63.449708 -273.099784)
		(end 63.703708 -273.099784)
		(stroke
			(width 0.1016)
			(type default)
		)
		(fill no)
		(layer "In1.Cu")
	)
	(gr_circle
		(center 63.449962 -318.699896)
		(end 63.703962 -318.699896)
		(stroke
			(width 0.1016)
			(type default)
		)
		(fill no)
		(layer "In1.Cu")
	)
	(gr_circle
		(center 63.449962 -317.749936)
		(end 63.703962 -317.749936)
		(stroke
			(width 0.1016)
			(type default)
		)
		(fill no)
		(layer "In1.Cu")
	)
	(gr_circle
		(center 63.449962 -313.949842)
		(end 63.703962 -313.949842)
		(stroke
			(width 0.1016)
			(type default)
		)
		(fill no)
		(layer "In1.Cu")
	)
	(gr_circle
		(center 63.449962 -312.999882)
		(end 63.703962 -312.999882)
		(stroke
			(width 0.1016)
			(type default)
		)
		(fill no)
		(layer "In1.Cu")
	)
	(gr_circle
		(center 64.399668 -275.949664)
		(end 64.653668 -275.949664)
		(stroke
			(width 0.1016)
			(type default)
		)
		(fill no)
		(layer "In1.Cu")
	)
	(gr_circle
		(center 64.399668 -274.999704)
		(end 64.653668 -274.999704)
		(stroke
			(width 0.1016)
			(type default)
		)
		(fill no)
		(layer "In1.Cu")
	)
	(gr_circle
		(center 64.399922 -316.799722)
		(end 64.653922 -316.799722)
		(stroke
			(width 0.1016)
			(type default)
		)
		(fill no)
		(layer "In1.Cu")
	)
	(gr_circle
		(center 64.399922 -315.849762)
		(end 64.653922 -315.849762)
		(stroke
			(width 0.1016)
			(type default)
		)
		(fill no)
		(layer "In1.Cu")
	)
	(gr_circle
		(center 64.399922 -312.049922)
		(end 64.653922 -312.049922)
		(stroke
			(width 0.1016)
			(type default)
		)
		(fill no)
		(layer "In1.Cu")
	)
	(gr_circle
		(center 64.399922 -311.099962)
		(end 64.653922 -311.099962)
		(stroke
			(width 0.1016)
			(type default)
		)
		(fill no)
		(layer "In1.Cu")
	)
	(gr_circle
		(center 64.399922 -280.699464)
		(end 64.653922 -280.699464)
		(stroke
			(width 0.1016)
			(type default)
		)
		(fill no)
		(layer "In1.Cu")
	)
	(gr_circle
		(center 64.399922 -279.749504)
		(end 64.653922 -279.749504)
		(stroke
			(width 0.1016)
			(type default)
		)
		(fill no)
		(layer "In1.Cu")
	)
	(gr_circle
		(center 65.349628 -278.799798)
		(end 65.603628 -278.799798)
		(stroke
			(width 0.1016)
			(type default)
		)
		(fill no)
		(layer "In1.Cu")
	)
	(gr_circle
		(center 65.349628 -277.849838)
		(end 65.603628 -277.849838)
		(stroke
			(width 0.1016)
			(type default)
		)
		(fill no)
		(layer "In1.Cu")
	)
	(gr_circle
		(center 65.349628 -274.049744)
		(end 65.603628 -274.049744)
		(stroke
			(width 0.1016)
			(type default)
		)
		(fill no)
		(layer "In1.Cu")
	)
	(gr_circle
		(center 65.349628 -273.099784)
		(end 65.603628 -273.099784)
		(stroke
			(width 0.1016)
			(type default)
		)
		(fill no)
		(layer "In1.Cu")
	)
	(gr_circle
		(center 65.349882 -318.699896)
		(end 65.603882 -318.699896)
		(stroke
			(width 0.1016)
			(type default)
		)
		(fill no)
		(layer "In1.Cu")
	)
	(gr_circle
		(center 65.349882 -317.749936)
		(end 65.603882 -317.749936)
		(stroke
			(width 0.1016)
			(type default)
		)
		(fill no)
		(layer "In1.Cu")
	)
	(gr_circle
		(center 65.349882 -313.949842)
		(end 65.603882 -313.949842)
		(stroke
			(width 0.1016)
			(type default)
		)
		(fill no)
		(layer "In1.Cu")
	)
	(gr_circle
		(center 65.349882 -312.999882)
		(end 65.603882 -312.999882)
		(stroke
			(width 0.1016)
			(type default)
		)
		(fill no)
		(layer "In1.Cu")
	)
	(gr_circle
		(center 66.299588 -275.949918)
		(end 66.553588 -275.949918)
		(stroke
			(width 0.1016)
			(type default)
		)
		(fill no)
		(layer "In1.Cu")
	)
	(gr_circle
		(center 66.299588 -274.999958)
		(end 66.553588 -274.999958)
		(stroke
			(width 0.1016)
			(type default)
		)
		(fill no)
		(layer "In1.Cu")
	)
	(gr_circle
		(center 66.299842 -316.799722)
		(end 66.553842 -316.799722)
		(stroke
			(width 0.1016)
			(type default)
		)
		(fill no)
		(layer "In1.Cu")
	)
	(gr_circle
		(center 66.299842 -315.849762)
		(end 66.553842 -315.849762)
		(stroke
			(width 0.1016)
			(type default)
		)
		(fill no)
		(layer "In1.Cu")
	)
	(gr_circle
		(center 66.299842 -312.049922)
		(end 66.553842 -312.049922)
		(stroke
			(width 0.1016)
			(type default)
		)
		(fill no)
		(layer "In1.Cu")
	)
	(gr_circle
		(center 66.299842 -311.099962)
		(end 66.553842 -311.099962)
		(stroke
			(width 0.1016)
			(type default)
		)
		(fill no)
		(layer "In1.Cu")
	)
	(gr_circle
		(center 66.299842 -280.699464)
		(end 66.553842 -280.699464)
		(stroke
			(width 0.1016)
			(type default)
		)
		(fill no)
		(layer "In1.Cu")
	)
	(gr_circle
		(center 66.299842 -279.749504)
		(end 66.553842 -279.749504)
		(stroke
			(width 0.1016)
			(type default)
		)
		(fill no)
		(layer "In1.Cu")
	)
	(gr_circle
		(center 67.249548 -278.799798)
		(end 67.503548 -278.799798)
		(stroke
			(width 0.1016)
			(type default)
		)
		(fill no)
		(layer "In1.Cu")
	)
	(gr_circle
		(center 67.249548 -277.849838)
		(end 67.503548 -277.849838)
		(stroke
			(width 0.1016)
			(type default)
		)
		(fill no)
		(layer "In1.Cu")
	)
	(gr_circle
		(center 67.249548 -274.049744)
		(end 67.503548 -274.049744)
		(stroke
			(width 0.1016)
			(type default)
		)
		(fill no)
		(layer "In1.Cu")
	)
	(gr_circle
		(center 67.249548 -273.099784)
		(end 67.503548 -273.099784)
		(stroke
			(width 0.1016)
			(type default)
		)
		(fill no)
		(layer "In1.Cu")
	)
	(gr_circle
		(center 67.249802 -318.699896)
		(end 67.503802 -318.699896)
		(stroke
			(width 0.1016)
			(type default)
		)
		(fill no)
		(layer "In1.Cu")
	)
	(gr_circle
		(center 67.249802 -317.749936)
		(end 67.503802 -317.749936)
		(stroke
			(width 0.1016)
			(type default)
		)
		(fill no)
		(layer "In1.Cu")
	)
	(gr_circle
		(center 67.249802 -313.949842)
		(end 67.503802 -313.949842)
		(stroke
			(width 0.1016)
			(type default)
		)
		(fill no)
		(layer "In1.Cu")
	)
	(gr_circle
		(center 67.249802 -312.999882)
		(end 67.503802 -312.999882)
		(stroke
			(width 0.1016)
			(type default)
		)
		(fill no)
		(layer "In1.Cu")
	)
	(gr_circle
		(center 68.199508 -275.949664)
		(end 68.453508 -275.949664)
		(stroke
			(width 0.1016)
			(type default)
		)
		(fill no)
		(layer "In1.Cu")
	)
	(gr_circle
		(center 68.199508 -274.999704)
		(end 68.453508 -274.999704)
		(stroke
			(width 0.1016)
			(type default)
		)
		(fill no)
		(layer "In1.Cu")
	)
	(gr_circle
		(center 68.199762 -316.799722)
		(end 68.453762 -316.799722)
		(stroke
			(width 0.1016)
			(type default)
		)
		(fill no)
		(layer "In1.Cu")
	)
	(gr_circle
		(center 68.199762 -315.849762)
		(end 68.453762 -315.849762)
		(stroke
			(width 0.1016)
			(type default)
		)
		(fill no)
		(layer "In1.Cu")
	)
	(gr_circle
		(center 68.199762 -312.049922)
		(end 68.453762 -312.049922)
		(stroke
			(width 0.1016)
			(type default)
		)
		(fill no)
		(layer "In1.Cu")
	)
	(gr_circle
		(center 68.199762 -311.099962)
		(end 68.453762 -311.099962)
		(stroke
			(width 0.1016)
			(type default)
		)
		(fill no)
		(layer "In1.Cu")
	)
	(gr_circle
		(center 68.199762 -280.699464)
		(end 68.453762 -280.699464)
		(stroke
			(width 0.1016)
			(type default)
		)
		(fill no)
		(layer "In1.Cu")
	)
	(gr_circle
		(center 68.199762 -279.749504)
		(end 68.453762 -279.749504)
		(stroke
			(width 0.1016)
			(type default)
		)
		(fill no)
		(layer "In1.Cu")
	)
	(gr_circle
		(center 69.149722 -278.799798)
		(end 69.403722 -278.799798)
		(stroke
			(width 0.1016)
			(type default)
		)
		(fill no)
		(layer "In1.Cu")
	)
	(gr_circle
		(center 69.149722 -277.849838)
		(end 69.403722 -277.849838)
		(stroke
			(width 0.1016)
			(type default)
		)
		(fill no)
		(layer "In1.Cu")
	)
	(gr_circle
		(center 69.149722 -274.049744)
		(end 69.403722 -274.049744)
		(stroke
			(width 0.1016)
			(type default)
		)
		(fill no)
		(layer "In1.Cu")
	)
	(gr_circle
		(center 69.149722 -273.099784)
		(end 69.403722 -273.099784)
		(stroke
			(width 0.1016)
			(type default)
		)
		(fill no)
		(layer "In1.Cu")
	)
	(gr_circle
		(center 69.149976 -318.699896)
		(end 69.403976 -318.699896)
		(stroke
			(width 0.1016)
			(type default)
		)
		(fill no)
		(layer "In1.Cu")
	)
	(gr_circle
		(center 69.149976 -317.749936)
		(end 69.403976 -317.749936)
		(stroke
			(width 0.1016)
			(type default)
		)
		(fill no)
		(layer "In1.Cu")
	)
	(gr_circle
		(center 69.149976 -313.949842)
		(end 69.403976 -313.949842)
		(stroke
			(width 0.1016)
			(type default)
		)
		(fill no)
		(layer "In1.Cu")
	)
	(gr_circle
		(center 69.149976 -312.999882)
		(end 69.403976 -312.999882)
		(stroke
			(width 0.1016)
			(type default)
		)
		(fill no)
		(layer "In1.Cu")
	)
	(gr_circle
		(center 70.099428 -275.949918)
		(end 70.353428 -275.949918)
		(stroke
			(width 0.1016)
			(type default)
		)
		(fill no)
		(layer "In1.Cu")
	)
	(gr_circle
		(center 70.099428 -274.999958)
		(end 70.353428 -274.999958)
		(stroke
			(width 0.1016)
			(type default)
		)
		(fill no)
		(layer "In1.Cu")
	)
	(gr_circle
		(center 70.099936 -316.799722)
		(end 70.353936 -316.799722)
		(stroke
			(width 0.1016)
			(type default)
		)
		(fill no)
		(layer "In1.Cu")
	)
	(gr_circle
		(center 70.099936 -315.849762)
		(end 70.353936 -315.849762)
		(stroke
			(width 0.1016)
			(type default)
		)
		(fill no)
		(layer "In1.Cu")
	)
	(gr_circle
		(center 70.099936 -312.049922)
		(end 70.353936 -312.049922)
		(stroke
			(width 0.1016)
			(type default)
		)
		(fill no)
		(layer "In1.Cu")
	)
	(gr_circle
		(center 70.099936 -311.099962)
		(end 70.353936 -311.099962)
		(stroke
			(width 0.1016)
			(type default)
		)
		(fill no)
		(layer "In1.Cu")
	)
	(gr_circle
		(center 70.099936 -280.699464)
		(end 70.353936 -280.699464)
		(stroke
			(width 0.1016)
			(type default)
		)
		(fill no)
		(layer "In1.Cu")
	)
	(gr_circle
		(center 70.099936 -279.749504)
		(end 70.353936 -279.749504)
		(stroke
			(width 0.1016)
			(type default)
		)
		(fill no)
		(layer "In1.Cu")
	)
	(gr_circle
		(center 71.049642 -278.799798)
		(end 71.303642 -278.799798)
		(stroke
			(width 0.1016)
			(type default)
		)
		(fill no)
		(layer "In1.Cu")
	)
	(gr_circle
		(center 71.049642 -277.849838)
		(end 71.303642 -277.849838)
		(stroke
			(width 0.1016)
			(type default)
		)
		(fill no)
		(layer "In1.Cu")
	)
	(gr_circle
		(center 71.049642 -274.049744)
		(end 71.303642 -274.049744)
		(stroke
			(width 0.1016)
			(type default)
		)
		(fill no)
		(layer "In1.Cu")
	)
	(gr_circle
		(center 71.049642 -273.099784)
		(end 71.303642 -273.099784)
		(stroke
			(width 0.1016)
			(type default)
		)
		(fill no)
		(layer "In1.Cu")
	)
	(gr_circle
		(center 71.049896 -318.699896)
		(end 71.303896 -318.699896)
		(stroke
			(width 0.1016)
			(type default)
		)
		(fill no)
		(layer "In1.Cu")
	)
	(gr_circle
		(center 71.049896 -317.749936)
		(end 71.303896 -317.749936)
		(stroke
			(width 0.1016)
			(type default)
		)
		(fill no)
		(layer "In1.Cu")
	)
	(gr_circle
		(center 71.049896 -313.949842)
		(end 71.303896 -313.949842)
		(stroke
			(width 0.1016)
			(type default)
		)
		(fill no)
		(layer "In1.Cu")
	)
	(gr_circle
		(center 71.049896 -312.999882)
		(end 71.303896 -312.999882)
		(stroke
			(width 0.1016)
			(type default)
		)
		(fill no)
		(layer "In1.Cu")
	)
	(gr_circle
		(center 71.999602 -275.949664)
		(end 72.253602 -275.949664)
		(stroke
			(width 0.1016)
			(type default)
		)
		(fill no)
		(layer "In1.Cu")
	)
	(gr_circle
		(center 71.999602 -274.999704)
		(end 72.253602 -274.999704)
		(stroke
			(width 0.1016)
			(type default)
		)
		(fill no)
		(layer "In1.Cu")
	)
	(gr_circle
		(center 71.999856 -316.799722)
		(end 72.253856 -316.799722)
		(stroke
			(width 0.1016)
			(type default)
		)
		(fill no)
		(layer "In1.Cu")
	)
	(gr_circle
		(center 71.999856 -315.849762)
		(end 72.253856 -315.849762)
		(stroke
			(width 0.1016)
			(type default)
		)
		(fill no)
		(layer "In1.Cu")
	)
	(gr_circle
		(center 71.999856 -312.049922)
		(end 72.253856 -312.049922)
		(stroke
			(width 0.1016)
			(type default)
		)
		(fill no)
		(layer "In1.Cu")
	)
	(gr_circle
		(center 71.999856 -311.099962)
		(end 72.253856 -311.099962)
		(stroke
			(width 0.1016)
			(type default)
		)
		(fill no)
		(layer "In1.Cu")
	)
	(gr_circle
		(center 71.999856 -280.699464)
		(end 72.253856 -280.699464)
		(stroke
			(width 0.1016)
			(type default)
		)
		(fill no)
		(layer "In1.Cu")
	)
	(gr_circle
		(center 71.999856 -279.749504)
		(end 72.253856 -279.749504)
		(stroke
			(width 0.1016)
			(type default)
		)
		(fill no)
		(layer "In1.Cu")
	)
	(gr_circle
		(center 72.949562 -278.799798)
		(end 73.203562 -278.799798)
		(stroke
			(width 0.1016)
			(type default)
		)
		(fill no)
		(layer "In1.Cu")
	)
	(gr_circle
		(center 72.949562 -277.849838)
		(end 73.203562 -277.849838)
		(stroke
			(width 0.1016)
			(type default)
		)
		(fill no)
		(layer "In1.Cu")
	)
	(gr_circle
		(center 72.949562 -274.049744)
		(end 73.203562 -274.049744)
		(stroke
			(width 0.1016)
			(type default)
		)
		(fill no)
		(layer "In1.Cu")
	)
	(gr_circle
		(center 72.949562 -273.099784)
		(end 73.203562 -273.099784)
		(stroke
			(width 0.1016)
			(type default)
		)
		(fill no)
		(layer "In1.Cu")
	)
	(gr_circle
		(center 72.949816 -318.699896)
		(end 73.203816 -318.699896)
		(stroke
			(width 0.1016)
			(type default)
		)
		(fill no)
		(layer "In1.Cu")
	)
	(gr_circle
		(center 72.949816 -317.749936)
		(end 73.203816 -317.749936)
		(stroke
			(width 0.1016)
			(type default)
		)
		(fill no)
		(layer "In1.Cu")
	)
	(gr_circle
		(center 72.949816 -313.949842)
		(end 73.203816 -313.949842)
		(stroke
			(width 0.1016)
			(type default)
		)
		(fill no)
		(layer "In1.Cu")
	)
	(gr_circle
		(center 72.949816 -312.999882)
		(end 73.203816 -312.999882)
		(stroke
			(width 0.1016)
			(type default)
		)
		(fill no)
		(layer "In1.Cu")
	)
	(gr_circle
		(center 73.899522 -275.949918)
		(end 74.153522 -275.949918)
		(stroke
			(width 0.1016)
			(type default)
		)
		(fill no)
		(layer "In1.Cu")
	)
	(gr_circle
		(center 73.899522 -274.999958)
		(end 74.153522 -274.999958)
		(stroke
			(width 0.1016)
			(type default)
		)
		(fill no)
		(layer "In1.Cu")
	)
	(gr_circle
		(center 73.899776 -316.799722)
		(end 74.153776 -316.799722)
		(stroke
			(width 0.1016)
			(type default)
		)
		(fill no)
		(layer "In1.Cu")
	)
	(gr_circle
		(center 73.899776 -315.849762)
		(end 74.153776 -315.849762)
		(stroke
			(width 0.1016)
			(type default)
		)
		(fill no)
		(layer "In1.Cu")
	)
	(gr_circle
		(center 73.899776 -312.049922)
		(end 74.153776 -312.049922)
		(stroke
			(width 0.1016)
			(type default)
		)
		(fill no)
		(layer "In1.Cu")
	)
	(gr_circle
		(center 73.899776 -311.099962)
		(end 74.153776 -311.099962)
		(stroke
			(width 0.1016)
			(type default)
		)
		(fill no)
		(layer "In1.Cu")
	)
	(gr_circle
		(center 73.899776 -280.699464)
		(end 74.153776 -280.699464)
		(stroke
			(width 0.1016)
			(type default)
		)
		(fill no)
		(layer "In1.Cu")
	)
	(gr_circle
		(center 73.899776 -279.749504)
		(end 74.153776 -279.749504)
		(stroke
			(width 0.1016)
			(type default)
		)
		(fill no)
		(layer "In1.Cu")
	)
	(gr_circle
		(center 74.849736 -278.799798)
		(end 75.103736 -278.799798)
		(stroke
			(width 0.1016)
			(type default)
		)
		(fill no)
		(layer "In1.Cu")
	)
	(gr_circle
		(center 74.849736 -277.849838)
		(end 75.103736 -277.849838)
		(stroke
			(width 0.1016)
			(type default)
		)
		(fill no)
		(layer "In1.Cu")
	)
	(gr_circle
		(center 74.849736 -274.049744)
		(end 75.103736 -274.049744)
		(stroke
			(width 0.1016)
			(type default)
		)
		(fill no)
		(layer "In1.Cu")
	)
	(gr_circle
		(center 74.849736 -273.099784)
		(end 75.103736 -273.099784)
		(stroke
			(width 0.1016)
			(type default)
		)
		(fill no)
		(layer "In1.Cu")
	)
	(gr_circle
		(center 74.84999 -318.699896)
		(end 75.10399 -318.699896)
		(stroke
			(width 0.1016)
			(type default)
		)
		(fill no)
		(layer "In1.Cu")
	)
	(gr_circle
		(center 74.84999 -317.749936)
		(end 75.10399 -317.749936)
		(stroke
			(width 0.1016)
			(type default)
		)
		(fill no)
		(layer "In1.Cu")
	)
	(gr_circle
		(center 74.84999 -313.949842)
		(end 75.10399 -313.949842)
		(stroke
			(width 0.1016)
			(type default)
		)
		(fill no)
		(layer "In1.Cu")
	)
	(gr_circle
		(center 74.84999 -312.999882)
		(end 75.10399 -312.999882)
		(stroke
			(width 0.1016)
			(type default)
		)
		(fill no)
		(layer "In1.Cu")
	)
	(gr_circle
		(center 74.84999 -308.249828)
		(end 75.10399 -308.249828)
		(stroke
			(width 0.1016)
			(type default)
		)
		(fill no)
		(layer "In1.Cu")
	)
	(gr_circle
		(center 74.84999 -306.349908)
		(end 75.10399 -306.349908)
		(stroke
			(width 0.1016)
			(type default)
		)
		(fill no)
		(layer "In1.Cu")
	)
	(gr_circle
		(center 74.84999 -304.449734)
		(end 75.10399 -304.449734)
		(stroke
			(width 0.1016)
			(type default)
		)
		(fill no)
		(layer "In1.Cu")
	)
	(gr_circle
		(center 74.84999 -287.349946)
		(end 75.10399 -287.349946)
		(stroke
			(width 0.1016)
			(type default)
		)
		(fill no)
		(layer "In1.Cu")
	)
	(gr_circle
		(center 74.84999 -285.449772)
		(end 75.10399 -285.449772)
		(stroke
			(width 0.1016)
			(type default)
		)
		(fill no)
		(layer "In1.Cu")
	)
	(gr_circle
		(center 74.84999 -283.549852)
		(end 75.10399 -283.549852)
		(stroke
			(width 0.1016)
			(type default)
		)
		(fill no)
		(layer "In1.Cu")
	)
	(gr_circle
		(center 75.799696 -275.949664)
		(end 76.053696 -275.949664)
		(stroke
			(width 0.1016)
			(type default)
		)
		(fill no)
		(layer "In1.Cu")
	)
	(gr_circle
		(center 75.799696 -274.999704)
		(end 76.053696 -274.999704)
		(stroke
			(width 0.1016)
			(type default)
		)
		(fill no)
		(layer "In1.Cu")
	)
	(gr_circle
		(center 75.79995 -316.799722)
		(end 76.05395 -316.799722)
		(stroke
			(width 0.1016)
			(type default)
		)
		(fill no)
		(layer "In1.Cu")
	)
	(gr_circle
		(center 75.79995 -315.849762)
		(end 76.05395 -315.849762)
		(stroke
			(width 0.1016)
			(type default)
		)
		(fill no)
		(layer "In1.Cu")
	)
	(gr_circle
		(center 75.79995 -312.049922)
		(end 76.05395 -312.049922)
		(stroke
			(width 0.1016)
			(type default)
		)
		(fill no)
		(layer "In1.Cu")
	)
	(gr_circle
		(center 75.79995 -311.099962)
		(end 76.05395 -311.099962)
		(stroke
			(width 0.1016)
			(type default)
		)
		(fill no)
		(layer "In1.Cu")
	)
	(gr_circle
		(center 75.79995 -308.249828)
		(end 76.05395 -308.249828)
		(stroke
			(width 0.1016)
			(type default)
		)
		(fill no)
		(layer "In1.Cu")
	)
	(gr_circle
		(center 75.79995 -306.349908)
		(end 76.05395 -306.349908)
		(stroke
			(width 0.1016)
			(type default)
		)
		(fill no)
		(layer "In1.Cu")
	)
	(gr_circle
		(center 75.79995 -304.449734)
		(end 76.05395 -304.449734)
		(stroke
			(width 0.1016)
			(type default)
		)
		(fill no)
		(layer "In1.Cu")
	)
	(gr_circle
		(center 75.79995 -287.349946)
		(end 76.05395 -287.349946)
		(stroke
			(width 0.1016)
			(type default)
		)
		(fill no)
		(layer "In1.Cu")
	)
	(gr_circle
		(center 75.79995 -285.449772)
		(end 76.05395 -285.449772)
		(stroke
			(width 0.1016)
			(type default)
		)
		(fill no)
		(layer "In1.Cu")
	)
	(gr_circle
		(center 75.79995 -283.549852)
		(end 76.05395 -283.549852)
		(stroke
			(width 0.1016)
			(type default)
		)
		(fill no)
		(layer "In1.Cu")
	)
	(gr_circle
		(center 75.79995 -280.699464)
		(end 76.05395 -280.699464)
		(stroke
			(width 0.1016)
			(type default)
		)
		(fill no)
		(layer "In1.Cu")
	)
	(gr_circle
		(center 75.79995 -279.749504)
		(end 76.05395 -279.749504)
		(stroke
			(width 0.1016)
			(type default)
		)
		(fill no)
		(layer "In1.Cu")
	)
	(gr_circle
		(center 76.749656 -278.799798)
		(end 77.003656 -278.799798)
		(stroke
			(width 0.1016)
			(type default)
		)
		(fill no)
		(layer "In1.Cu")
	)
	(gr_circle
		(center 76.749656 -277.849838)
		(end 77.003656 -277.849838)
		(stroke
			(width 0.1016)
			(type default)
		)
		(fill no)
		(layer "In1.Cu")
	)
	(gr_circle
		(center 76.749656 -274.049744)
		(end 77.003656 -274.049744)
		(stroke
			(width 0.1016)
			(type default)
		)
		(fill no)
		(layer "In1.Cu")
	)
	(gr_circle
		(center 76.749656 -273.099784)
		(end 77.003656 -273.099784)
		(stroke
			(width 0.1016)
			(type default)
		)
		(fill no)
		(layer "In1.Cu")
	)
	(gr_circle
		(center 76.74991 -318.699896)
		(end 77.00391 -318.699896)
		(stroke
			(width 0.1016)
			(type default)
		)
		(fill no)
		(layer "In1.Cu")
	)
	(gr_circle
		(center 76.74991 -317.749936)
		(end 77.00391 -317.749936)
		(stroke
			(width 0.1016)
			(type default)
		)
		(fill no)
		(layer "In1.Cu")
	)
	(gr_circle
		(center 76.74991 -313.949842)
		(end 77.00391 -313.949842)
		(stroke
			(width 0.1016)
			(type default)
		)
		(fill no)
		(layer "In1.Cu")
	)
	(gr_circle
		(center 76.74991 -312.999882)
		(end 77.00391 -312.999882)
		(stroke
			(width 0.1016)
			(type default)
		)
		(fill no)
		(layer "In1.Cu")
	)
	(gr_circle
		(center 76.74991 -309.199788)
		(end 77.00391 -309.199788)
		(stroke
			(width 0.1016)
			(type default)
		)
		(fill no)
		(layer "In1.Cu")
	)
	(gr_circle
		(center 76.74991 -307.299868)
		(end 77.00391 -307.299868)
		(stroke
			(width 0.1016)
			(type default)
		)
		(fill no)
		(layer "In1.Cu")
	)
	(gr_circle
		(center 76.74991 -305.399948)
		(end 77.00391 -305.399948)
		(stroke
			(width 0.1016)
			(type default)
		)
		(fill no)
		(layer "In1.Cu")
	)
	(gr_circle
		(center 76.74991 -288.299906)
		(end 77.00391 -288.299906)
		(stroke
			(width 0.1016)
			(type default)
		)
		(fill no)
		(layer "In1.Cu")
	)
	(gr_circle
		(center 76.74991 -286.399986)
		(end 77.00391 -286.399986)
		(stroke
			(width 0.1016)
			(type default)
		)
		(fill no)
		(layer "In1.Cu")
	)
	(gr_circle
		(center 76.74991 -284.499812)
		(end 77.00391 -284.499812)
		(stroke
			(width 0.1016)
			(type default)
		)
		(fill no)
		(layer "In1.Cu")
	)
	(gr_circle
		(center 76.74991 -282.599892)
		(end 77.00391 -282.599892)
		(stroke
			(width 0.1016)
			(type default)
		)
		(fill no)
		(layer "In1.Cu")
	)
	(gr_circle
		(center 77.699616 -275.949918)
		(end 77.953616 -275.949918)
		(stroke
			(width 0.1016)
			(type default)
		)
		(fill no)
		(layer "In1.Cu")
	)
	(gr_circle
		(center 77.699616 -274.999958)
		(end 77.953616 -274.999958)
		(stroke
			(width 0.1016)
			(type default)
		)
		(fill no)
		(layer "In1.Cu")
	)
	(gr_circle
		(center 77.69987 -316.799722)
		(end 77.95387 -316.799722)
		(stroke
			(width 0.1016)
			(type default)
		)
		(fill no)
		(layer "In1.Cu")
	)
	(gr_circle
		(center 77.69987 -315.849762)
		(end 77.95387 -315.849762)
		(stroke
			(width 0.1016)
			(type default)
		)
		(fill no)
		(layer "In1.Cu")
	)
	(gr_circle
		(center 77.69987 -312.049922)
		(end 77.95387 -312.049922)
		(stroke
			(width 0.1016)
			(type default)
		)
		(fill no)
		(layer "In1.Cu")
	)
	(gr_circle
		(center 77.69987 -311.099962)
		(end 77.95387 -311.099962)
		(stroke
			(width 0.1016)
			(type default)
		)
		(fill no)
		(layer "In1.Cu")
	)
	(gr_circle
		(center 77.69987 -309.199788)
		(end 77.95387 -309.199788)
		(stroke
			(width 0.1016)
			(type default)
		)
		(fill no)
		(layer "In1.Cu")
	)
	(gr_circle
		(center 77.69987 -307.299868)
		(end 77.95387 -307.299868)
		(stroke
			(width 0.1016)
			(type default)
		)
		(fill no)
		(layer "In1.Cu")
	)
	(gr_circle
		(center 77.69987 -305.399948)
		(end 77.95387 -305.399948)
		(stroke
			(width 0.1016)
			(type default)
		)
		(fill no)
		(layer "In1.Cu")
	)
	(gr_circle
		(center 77.69987 -288.299906)
		(end 77.95387 -288.299906)
		(stroke
			(width 0.1016)
			(type default)
		)
		(fill no)
		(layer "In1.Cu")
	)
	(gr_circle
		(center 77.69987 -286.399986)
		(end 77.95387 -286.399986)
		(stroke
			(width 0.1016)
			(type default)
		)
		(fill no)
		(layer "In1.Cu")
	)
	(gr_circle
		(center 77.69987 -284.499812)
		(end 77.95387 -284.499812)
		(stroke
			(width 0.1016)
			(type default)
		)
		(fill no)
		(layer "In1.Cu")
	)
	(gr_circle
		(center 77.69987 -282.599892)
		(end 77.95387 -282.599892)
		(stroke
			(width 0.1016)
			(type default)
		)
		(fill no)
		(layer "In1.Cu")
	)
	(gr_circle
		(center 77.69987 -280.699464)
		(end 77.95387 -280.699464)
		(stroke
			(width 0.1016)
			(type default)
		)
		(fill no)
		(layer "In1.Cu")
	)
	(gr_circle
		(center 77.69987 -279.749504)
		(end 77.95387 -279.749504)
		(stroke
			(width 0.1016)
			(type default)
		)
		(fill no)
		(layer "In1.Cu")
	)
	(gr_circle
		(center 78.649576 -278.799798)
		(end 78.903576 -278.799798)
		(stroke
			(width 0.1016)
			(type default)
		)
		(fill no)
		(layer "In1.Cu")
	)
	(gr_circle
		(center 78.649576 -277.849838)
		(end 78.903576 -277.849838)
		(stroke
			(width 0.1016)
			(type default)
		)
		(fill no)
		(layer "In1.Cu")
	)
	(gr_circle
		(center 78.649576 -274.049744)
		(end 78.903576 -274.049744)
		(stroke
			(width 0.1016)
			(type default)
		)
		(fill no)
		(layer "In1.Cu")
	)
	(gr_circle
		(center 78.649576 -273.099784)
		(end 78.903576 -273.099784)
		(stroke
			(width 0.1016)
			(type default)
		)
		(fill no)
		(layer "In1.Cu")
	)
	(gr_circle
		(center 78.64983 -318.699896)
		(end 78.90383 -318.699896)
		(stroke
			(width 0.1016)
			(type default)
		)
		(fill no)
		(layer "In1.Cu")
	)
	(gr_circle
		(center 78.64983 -317.749936)
		(end 78.90383 -317.749936)
		(stroke
			(width 0.1016)
			(type default)
		)
		(fill no)
		(layer "In1.Cu")
	)
	(gr_circle
		(center 78.64983 -313.949842)
		(end 78.90383 -313.949842)
		(stroke
			(width 0.1016)
			(type default)
		)
		(fill no)
		(layer "In1.Cu")
	)
	(gr_circle
		(center 78.64983 -312.999882)
		(end 78.90383 -312.999882)
		(stroke
			(width 0.1016)
			(type default)
		)
		(fill no)
		(layer "In1.Cu")
	)
	(gr_circle
		(center 79.599536 -275.949918)
		(end 79.853536 -275.949918)
		(stroke
			(width 0.1016)
			(type default)
		)
		(fill no)
		(layer "In1.Cu")
	)
	(gr_circle
		(center 79.599536 -274.999958)
		(end 79.853536 -274.999958)
		(stroke
			(width 0.1016)
			(type default)
		)
		(fill no)
		(layer "In1.Cu")
	)
	(gr_circle
		(center 79.59979 -316.799722)
		(end 79.85379 -316.799722)
		(stroke
			(width 0.1016)
			(type default)
		)
		(fill no)
		(layer "In1.Cu")
	)
	(gr_circle
		(center 79.59979 -315.849762)
		(end 79.85379 -315.849762)
		(stroke
			(width 0.1016)
			(type default)
		)
		(fill no)
		(layer "In1.Cu")
	)
	(gr_circle
		(center 79.59979 -312.049922)
		(end 79.85379 -312.049922)
		(stroke
			(width 0.1016)
			(type default)
		)
		(fill no)
		(layer "In1.Cu")
	)
	(gr_circle
		(center 79.59979 -311.099962)
		(end 79.85379 -311.099962)
		(stroke
			(width 0.1016)
			(type default)
		)
		(fill no)
		(layer "In1.Cu")
	)
	(gr_circle
		(center 79.59979 -309.199788)
		(end 79.85379 -309.199788)
		(stroke
			(width 0.1016)
			(type default)
		)
		(fill no)
		(layer "In1.Cu")
	)
	(gr_circle
		(center 79.59979 -307.299868)
		(end 79.85379 -307.299868)
		(stroke
			(width 0.1016)
			(type default)
		)
		(fill no)
		(layer "In1.Cu")
	)
	(gr_circle
		(center 79.59979 -305.399948)
		(end 79.85379 -305.399948)
		(stroke
			(width 0.1016)
			(type default)
		)
		(fill no)
		(layer "In1.Cu")
	)
	(gr_circle
		(center 79.59979 -288.299906)
		(end 79.85379 -288.299906)
		(stroke
			(width 0.1016)
			(type default)
		)
		(fill no)
		(layer "In1.Cu")
	)
	(gr_circle
		(center 79.59979 -286.399732)
		(end 79.85379 -286.399732)
		(stroke
			(width 0.1016)
			(type default)
		)
		(fill no)
		(layer "In1.Cu")
	)
	(gr_circle
		(center 79.59979 -284.499812)
		(end 79.85379 -284.499812)
		(stroke
			(width 0.1016)
			(type default)
		)
		(fill no)
		(layer "In1.Cu")
	)
	(gr_circle
		(center 79.59979 -282.599892)
		(end 79.85379 -282.599892)
		(stroke
			(width 0.1016)
			(type default)
		)
		(fill no)
		(layer "In1.Cu")
	)
	(gr_circle
		(center 79.59979 -280.699718)
		(end 79.85379 -280.699718)
		(stroke
			(width 0.1016)
			(type default)
		)
		(fill no)
		(layer "In1.Cu")
	)
	(gr_circle
		(center 79.59979 -279.749758)
		(end 79.85379 -279.749758)
		(stroke
			(width 0.1016)
			(type default)
		)
		(fill no)
		(layer "In1.Cu")
	)
	(gr_circle
		(center 80.549496 -274.049744)
		(end 80.803496 -274.049744)
		(stroke
			(width 0.1016)
			(type default)
		)
		(fill no)
		(layer "In1.Cu")
	)
	(gr_circle
		(center 80.549496 -273.099784)
		(end 80.803496 -273.099784)
		(stroke
			(width 0.1016)
			(type default)
		)
		(fill no)
		(layer "In1.Cu")
	)
	(gr_circle
		(center 80.54975 -318.699896)
		(end 80.80375 -318.699896)
		(stroke
			(width 0.1016)
			(type default)
		)
		(fill no)
		(layer "In1.Cu")
	)
	(gr_circle
		(center 80.54975 -317.749936)
		(end 80.80375 -317.749936)
		(stroke
			(width 0.1016)
			(type default)
		)
		(fill no)
		(layer "In1.Cu")
	)
	(gr_circle
		(center 80.54975 -313.949842)
		(end 80.80375 -313.949842)
		(stroke
			(width 0.1016)
			(type default)
		)
		(fill no)
		(layer "In1.Cu")
	)
	(gr_circle
		(center 80.54975 -312.999882)
		(end 80.80375 -312.999882)
		(stroke
			(width 0.1016)
			(type default)
		)
		(fill no)
		(layer "In1.Cu")
	)
	(gr_circle
		(center 80.54975 -309.199788)
		(end 80.80375 -309.199788)
		(stroke
			(width 0.1016)
			(type default)
		)
		(fill no)
		(layer "In1.Cu")
	)
	(gr_circle
		(center 80.54975 -307.299868)
		(end 80.80375 -307.299868)
		(stroke
			(width 0.1016)
			(type default)
		)
		(fill no)
		(layer "In1.Cu")
	)
	(gr_circle
		(center 80.54975 -305.399948)
		(end 80.80375 -305.399948)
		(stroke
			(width 0.1016)
			(type default)
		)
		(fill no)
		(layer "In1.Cu")
	)
	(gr_circle
		(center 80.54975 -288.299906)
		(end 80.80375 -288.299906)
		(stroke
			(width 0.1016)
			(type default)
		)
		(fill no)
		(layer "In1.Cu")
	)
	(gr_circle
		(center 80.54975 -286.399732)
		(end 80.80375 -286.399732)
		(stroke
			(width 0.1016)
			(type default)
		)
		(fill no)
		(layer "In1.Cu")
	)
	(gr_circle
		(center 80.54975 -284.499812)
		(end 80.80375 -284.499812)
		(stroke
			(width 0.1016)
			(type default)
		)
		(fill no)
		(layer "In1.Cu")
	)
	(gr_circle
		(center 80.54975 -282.599892)
		(end 80.80375 -282.599892)
		(stroke
			(width 0.1016)
			(type default)
		)
		(fill no)
		(layer "In1.Cu")
	)
	(gr_circle
		(center 80.54975 -278.799798)
		(end 80.80375 -278.799798)
		(stroke
			(width 0.1016)
			(type default)
		)
		(fill no)
		(layer "In1.Cu")
	)
	(gr_circle
		(center 80.54975 -277.849838)
		(end 80.80375 -277.849838)
		(stroke
			(width 0.1016)
			(type default)
		)
		(fill no)
		(layer "In1.Cu")
	)
	(gr_circle
		(center 81.499964 -316.799722)
		(end 81.753964 -316.799722)
		(stroke
			(width 0.1016)
			(type default)
		)
		(fill no)
		(layer "In1.Cu")
	)
	(gr_circle
		(center 81.499964 -314.899802)
		(end 81.753964 -314.899802)
		(stroke
			(width 0.1016)
			(type default)
		)
		(fill no)
		(layer "In1.Cu")
	)
	(gr_circle
		(center 81.499964 -312.049922)
		(end 81.753964 -312.049922)
		(stroke
			(width 0.1016)
			(type default)
		)
		(fill no)
		(layer "In1.Cu")
	)
	(gr_circle
		(center 81.499964 -310.149748)
		(end 81.753964 -310.149748)
		(stroke
			(width 0.1016)
			(type default)
		)
		(fill no)
		(layer "In1.Cu")
	)
	(gr_circle
		(center 81.499964 -308.249828)
		(end 81.753964 -308.249828)
		(stroke
			(width 0.1016)
			(type default)
		)
		(fill no)
		(layer "In1.Cu")
	)
	(gr_circle
		(center 81.499964 -306.349908)
		(end 81.753964 -306.349908)
		(stroke
			(width 0.1016)
			(type default)
		)
		(fill no)
		(layer "In1.Cu")
	)
	(gr_circle
		(center 81.499964 -304.449734)
		(end 81.753964 -304.449734)
		(stroke
			(width 0.1016)
			(type default)
		)
		(fill no)
		(layer "In1.Cu")
	)
	(gr_circle
		(center 81.499964 -287.349946)
		(end 81.753964 -287.349946)
		(stroke
			(width 0.1016)
			(type default)
		)
		(fill no)
		(layer "In1.Cu")
	)
	(gr_circle
		(center 81.499964 -285.449772)
		(end 81.753964 -285.449772)
		(stroke
			(width 0.1016)
			(type default)
		)
		(fill no)
		(layer "In1.Cu")
	)
	(gr_circle
		(center 81.499964 -283.549852)
		(end 81.753964 -283.549852)
		(stroke
			(width 0.1016)
			(type default)
		)
		(fill no)
		(layer "In1.Cu")
	)
	(gr_circle
		(center 81.499964 -281.649932)
		(end 81.753964 -281.649932)
		(stroke
			(width 0.1016)
			(type default)
		)
		(fill no)
		(layer "In1.Cu")
	)
	(gr_circle
		(center 81.499964 -279.749758)
		(end 81.753964 -279.749758)
		(stroke
			(width 0.1016)
			(type default)
		)
		(fill no)
		(layer "In1.Cu")
	)
	(gr_circle
		(center 81.499964 -276.899878)
		(end 81.753964 -276.899878)
		(stroke
			(width 0.1016)
			(type default)
		)
		(fill no)
		(layer "In1.Cu")
	)
	(gr_circle
		(center 81.499964 -274.999704)
		(end 81.753964 -274.999704)
		(stroke
			(width 0.1016)
			(type default)
		)
		(fill no)
		(layer "In1.Cu")
	)
	(gr_circle
		(center 82.449924 -316.799722)
		(end 82.703924 -316.799722)
		(stroke
			(width 0.1016)
			(type default)
		)
		(fill no)
		(layer "In1.Cu")
	)
	(gr_circle
		(center 82.449924 -314.899802)
		(end 82.703924 -314.899802)
		(stroke
			(width 0.1016)
			(type default)
		)
		(fill no)
		(layer "In1.Cu")
	)
	(gr_circle
		(center 82.449924 -312.049922)
		(end 82.703924 -312.049922)
		(stroke
			(width 0.1016)
			(type default)
		)
		(fill no)
		(layer "In1.Cu")
	)
	(gr_circle
		(center 82.449924 -310.149748)
		(end 82.703924 -310.149748)
		(stroke
			(width 0.1016)
			(type default)
		)
		(fill no)
		(layer "In1.Cu")
	)
	(gr_circle
		(center 82.449924 -308.249828)
		(end 82.703924 -308.249828)
		(stroke
			(width 0.1016)
			(type default)
		)
		(fill no)
		(layer "In1.Cu")
	)
	(gr_circle
		(center 82.449924 -306.349908)
		(end 82.703924 -306.349908)
		(stroke
			(width 0.1016)
			(type default)
		)
		(fill no)
		(layer "In1.Cu")
	)
	(gr_circle
		(center 82.449924 -304.449734)
		(end 82.703924 -304.449734)
		(stroke
			(width 0.1016)
			(type default)
		)
		(fill no)
		(layer "In1.Cu")
	)
	(gr_circle
		(center 82.449924 -287.349946)
		(end 82.703924 -287.349946)
		(stroke
			(width 0.1016)
			(type default)
		)
		(fill no)
		(layer "In1.Cu")
	)
	(gr_circle
		(center 82.449924 -285.449772)
		(end 82.703924 -285.449772)
		(stroke
			(width 0.1016)
			(type default)
		)
		(fill no)
		(layer "In1.Cu")
	)
	(gr_circle
		(center 82.449924 -283.549852)
		(end 82.703924 -283.549852)
		(stroke
			(width 0.1016)
			(type default)
		)
		(fill no)
		(layer "In1.Cu")
	)
	(gr_circle
		(center 82.449924 -281.649932)
		(end 82.703924 -281.649932)
		(stroke
			(width 0.1016)
			(type default)
		)
		(fill no)
		(layer "In1.Cu")
	)
	(gr_circle
		(center 82.449924 -279.749758)
		(end 82.703924 -279.749758)
		(stroke
			(width 0.1016)
			(type default)
		)
		(fill no)
		(layer "In1.Cu")
	)
	(gr_circle
		(center 82.449924 -276.899878)
		(end 82.703924 -276.899878)
		(stroke
			(width 0.1016)
			(type default)
		)
		(fill no)
		(layer "In1.Cu")
	)
	(gr_circle
		(center 82.449924 -274.999704)
		(end 82.703924 -274.999704)
		(stroke
			(width 0.1016)
			(type default)
		)
		(fill no)
		(layer "In1.Cu")
	)
	(gr_circle
		(center 152.94991 -316.799722)
		(end 153.20391 -316.799722)
		(stroke
			(width 0.1016)
			(type default)
		)
		(fill no)
		(layer "In1.Cu")
	)
	(gr_circle
		(center 152.94991 -314.899802)
		(end 153.20391 -314.899802)
		(stroke
			(width 0.1016)
			(type default)
		)
		(fill no)
		(layer "In1.Cu")
	)
	(gr_circle
		(center 152.94991 -312.049922)
		(end 153.20391 -312.049922)
		(stroke
			(width 0.1016)
			(type default)
		)
		(fill no)
		(layer "In1.Cu")
	)
	(gr_circle
		(center 152.94991 -310.149748)
		(end 153.20391 -310.149748)
		(stroke
			(width 0.1016)
			(type default)
		)
		(fill no)
		(layer "In1.Cu")
	)
	(gr_circle
		(center 152.94991 -308.249828)
		(end 153.20391 -308.249828)
		(stroke
			(width 0.1016)
			(type default)
		)
		(fill no)
		(layer "In1.Cu")
	)
	(gr_circle
		(center 152.94991 -306.349908)
		(end 153.20391 -306.349908)
		(stroke
			(width 0.1016)
			(type default)
		)
		(fill no)
		(layer "In1.Cu")
	)
	(gr_circle
		(center 152.94991 -304.449734)
		(end 153.20391 -304.449734)
		(stroke
			(width 0.1016)
			(type default)
		)
		(fill no)
		(layer "In1.Cu")
	)
	(gr_circle
		(center 152.94991 -302.549814)
		(end 153.20391 -302.549814)
		(stroke
			(width 0.1016)
			(type default)
		)
		(fill no)
		(layer "In1.Cu")
	)
	(gr_circle
		(center 153.89987 -316.799722)
		(end 154.15387 -316.799722)
		(stroke
			(width 0.1016)
			(type default)
		)
		(fill no)
		(layer "In1.Cu")
	)
	(gr_circle
		(center 153.89987 -314.899802)
		(end 154.15387 -314.899802)
		(stroke
			(width 0.1016)
			(type default)
		)
		(fill no)
		(layer "In1.Cu")
	)
	(gr_circle
		(center 153.89987 -312.049922)
		(end 154.15387 -312.049922)
		(stroke
			(width 0.1016)
			(type default)
		)
		(fill no)
		(layer "In1.Cu")
	)
	(gr_circle
		(center 153.89987 -310.149748)
		(end 154.15387 -310.149748)
		(stroke
			(width 0.1016)
			(type default)
		)
		(fill no)
		(layer "In1.Cu")
	)
	(gr_circle
		(center 153.89987 -308.249828)
		(end 154.15387 -308.249828)
		(stroke
			(width 0.1016)
			(type default)
		)
		(fill no)
		(layer "In1.Cu")
	)
	(gr_circle
		(center 153.89987 -306.349908)
		(end 154.15387 -306.349908)
		(stroke
			(width 0.1016)
			(type default)
		)
		(fill no)
		(layer "In1.Cu")
	)
	(gr_circle
		(center 153.89987 -304.449734)
		(end 154.15387 -304.449734)
		(stroke
			(width 0.1016)
			(type default)
		)
		(fill no)
		(layer "In1.Cu")
	)
	(gr_circle
		(center 153.89987 -302.549814)
		(end 154.15387 -302.549814)
		(stroke
			(width 0.1016)
			(type default)
		)
		(fill no)
		(layer "In1.Cu")
	)
	(gr_circle
		(center 154.850084 -318.699896)
		(end 155.104084 -318.699896)
		(stroke
			(width 0.1016)
			(type default)
		)
		(fill no)
		(layer "In1.Cu")
	)
	(gr_circle
		(center 154.850084 -317.749936)
		(end 155.104084 -317.749936)
		(stroke
			(width 0.1016)
			(type default)
		)
		(fill no)
		(layer "In1.Cu")
	)
	(gr_circle
		(center 154.850084 -313.949842)
		(end 155.104084 -313.949842)
		(stroke
			(width 0.1016)
			(type default)
		)
		(fill no)
		(layer "In1.Cu")
	)
	(gr_circle
		(center 154.850084 -312.999882)
		(end 155.104084 -312.999882)
		(stroke
			(width 0.1016)
			(type default)
		)
		(fill no)
		(layer "In1.Cu")
	)
	(gr_circle
		(center 154.850084 -309.199788)
		(end 155.104084 -309.199788)
		(stroke
			(width 0.1016)
			(type default)
		)
		(fill no)
		(layer "In1.Cu")
	)
	(gr_circle
		(center 154.850084 -307.299868)
		(end 155.104084 -307.299868)
		(stroke
			(width 0.1016)
			(type default)
		)
		(fill no)
		(layer "In1.Cu")
	)
	(gr_circle
		(center 154.850084 -305.399948)
		(end 155.104084 -305.399948)
		(stroke
			(width 0.1016)
			(type default)
		)
		(fill no)
		(layer "In1.Cu")
	)
	(gr_circle
		(center 154.850084 -303.499774)
		(end 155.104084 -303.499774)
		(stroke
			(width 0.1016)
			(type default)
		)
		(fill no)
		(layer "In1.Cu")
	)
	(gr_circle
		(center 154.850084 -301.599854)
		(end 155.104084 -301.599854)
		(stroke
			(width 0.1016)
			(type default)
		)
		(fill no)
		(layer "In1.Cu")
	)
	(gr_circle
		(center 155.800044 -316.799722)
		(end 156.054044 -316.799722)
		(stroke
			(width 0.1016)
			(type default)
		)
		(fill no)
		(layer "In1.Cu")
	)
	(gr_circle
		(center 155.800044 -315.849762)
		(end 156.054044 -315.849762)
		(stroke
			(width 0.1016)
			(type default)
		)
		(fill no)
		(layer "In1.Cu")
	)
	(gr_circle
		(center 155.800044 -312.049922)
		(end 156.054044 -312.049922)
		(stroke
			(width 0.1016)
			(type default)
		)
		(fill no)
		(layer "In1.Cu")
	)
	(gr_circle
		(center 155.800044 -311.099962)
		(end 156.054044 -311.099962)
		(stroke
			(width 0.1016)
			(type default)
		)
		(fill no)
		(layer "In1.Cu")
	)
	(gr_circle
		(center 155.800044 -309.199788)
		(end 156.054044 -309.199788)
		(stroke
			(width 0.1016)
			(type default)
		)
		(fill no)
		(layer "In1.Cu")
	)
	(gr_circle
		(center 155.800044 -307.299868)
		(end 156.054044 -307.299868)
		(stroke
			(width 0.1016)
			(type default)
		)
		(fill no)
		(layer "In1.Cu")
	)
	(gr_circle
		(center 155.800044 -305.399948)
		(end 156.054044 -305.399948)
		(stroke
			(width 0.1016)
			(type default)
		)
		(fill no)
		(layer "In1.Cu")
	)
	(gr_circle
		(center 155.800044 -303.499774)
		(end 156.054044 -303.499774)
		(stroke
			(width 0.1016)
			(type default)
		)
		(fill no)
		(layer "In1.Cu")
	)
	(gr_circle
		(center 155.800044 -301.599854)
		(end 156.054044 -301.599854)
		(stroke
			(width 0.1016)
			(type default)
		)
		(fill no)
		(layer "In1.Cu")
	)
	(gr_circle
		(center 156.750004 -318.699896)
		(end 157.004004 -318.699896)
		(stroke
			(width 0.1016)
			(type default)
		)
		(fill no)
		(layer "In1.Cu")
	)
	(gr_circle
		(center 156.750004 -317.749936)
		(end 157.004004 -317.749936)
		(stroke
			(width 0.1016)
			(type default)
		)
		(fill no)
		(layer "In1.Cu")
	)
	(gr_circle
		(center 156.750004 -313.949842)
		(end 157.004004 -313.949842)
		(stroke
			(width 0.1016)
			(type default)
		)
		(fill no)
		(layer "In1.Cu")
	)
	(gr_circle
		(center 156.750004 -312.999882)
		(end 157.004004 -312.999882)
		(stroke
			(width 0.1016)
			(type default)
		)
		(fill no)
		(layer "In1.Cu")
	)
	(gr_circle
		(center 157.699964 -316.799722)
		(end 157.953964 -316.799722)
		(stroke
			(width 0.1016)
			(type default)
		)
		(fill no)
		(layer "In1.Cu")
	)
	(gr_circle
		(center 157.699964 -315.849762)
		(end 157.953964 -315.849762)
		(stroke
			(width 0.1016)
			(type default)
		)
		(fill no)
		(layer "In1.Cu")
	)
	(gr_circle
		(center 157.699964 -312.049922)
		(end 157.953964 -312.049922)
		(stroke
			(width 0.1016)
			(type default)
		)
		(fill no)
		(layer "In1.Cu")
	)
	(gr_circle
		(center 157.699964 -311.099962)
		(end 157.953964 -311.099962)
		(stroke
			(width 0.1016)
			(type default)
		)
		(fill no)
		(layer "In1.Cu")
	)
	(gr_circle
		(center 157.699964 -309.199788)
		(end 157.953964 -309.199788)
		(stroke
			(width 0.1016)
			(type default)
		)
		(fill no)
		(layer "In1.Cu")
	)
	(gr_circle
		(center 157.699964 -307.299868)
		(end 157.953964 -307.299868)
		(stroke
			(width 0.1016)
			(type default)
		)
		(fill no)
		(layer "In1.Cu")
	)
	(gr_circle
		(center 157.699964 -305.399948)
		(end 157.953964 -305.399948)
		(stroke
			(width 0.1016)
			(type default)
		)
		(fill no)
		(layer "In1.Cu")
	)
	(gr_circle
		(center 157.699964 -303.499774)
		(end 157.953964 -303.499774)
		(stroke
			(width 0.1016)
			(type default)
		)
		(fill no)
		(layer "In1.Cu")
	)
	(gr_circle
		(center 157.699964 -301.599854)
		(end 157.953964 -301.599854)
		(stroke
			(width 0.1016)
			(type default)
		)
		(fill no)
		(layer "In1.Cu")
	)
	(gr_circle
		(center 158.649924 -318.699896)
		(end 158.903924 -318.699896)
		(stroke
			(width 0.1016)
			(type default)
		)
		(fill no)
		(layer "In1.Cu")
	)
	(gr_circle
		(center 158.649924 -317.749936)
		(end 158.903924 -317.749936)
		(stroke
			(width 0.1016)
			(type default)
		)
		(fill no)
		(layer "In1.Cu")
	)
	(gr_circle
		(center 158.649924 -313.949842)
		(end 158.903924 -313.949842)
		(stroke
			(width 0.1016)
			(type default)
		)
		(fill no)
		(layer "In1.Cu")
	)
	(gr_circle
		(center 158.649924 -312.999882)
		(end 158.903924 -312.999882)
		(stroke
			(width 0.1016)
			(type default)
		)
		(fill no)
		(layer "In1.Cu")
	)
	(gr_circle
		(center 158.649924 -309.199788)
		(end 158.903924 -309.199788)
		(stroke
			(width 0.1016)
			(type default)
		)
		(fill no)
		(layer "In1.Cu")
	)
	(gr_circle
		(center 158.649924 -307.299868)
		(end 158.903924 -307.299868)
		(stroke
			(width 0.1016)
			(type default)
		)
		(fill no)
		(layer "In1.Cu")
	)
	(gr_circle
		(center 158.649924 -305.399948)
		(end 158.903924 -305.399948)
		(stroke
			(width 0.1016)
			(type default)
		)
		(fill no)
		(layer "In1.Cu")
	)
	(gr_circle
		(center 158.649924 -303.499774)
		(end 158.903924 -303.499774)
		(stroke
			(width 0.1016)
			(type default)
		)
		(fill no)
		(layer "In1.Cu")
	)
	(gr_circle
		(center 158.649924 -301.599854)
		(end 158.903924 -301.599854)
		(stroke
			(width 0.1016)
			(type default)
		)
		(fill no)
		(layer "In1.Cu")
	)
	(gr_circle
		(center 159.599884 -316.799722)
		(end 159.853884 -316.799722)
		(stroke
			(width 0.1016)
			(type default)
		)
		(fill no)
		(layer "In1.Cu")
	)
	(gr_circle
		(center 159.599884 -315.849762)
		(end 159.853884 -315.849762)
		(stroke
			(width 0.1016)
			(type default)
		)
		(fill no)
		(layer "In1.Cu")
	)
	(gr_circle
		(center 159.599884 -312.049922)
		(end 159.853884 -312.049922)
		(stroke
			(width 0.1016)
			(type default)
		)
		(fill no)
		(layer "In1.Cu")
	)
	(gr_circle
		(center 159.599884 -311.099962)
		(end 159.853884 -311.099962)
		(stroke
			(width 0.1016)
			(type default)
		)
		(fill no)
		(layer "In1.Cu")
	)
	(gr_circle
		(center 159.599884 -308.249828)
		(end 159.853884 -308.249828)
		(stroke
			(width 0.1016)
			(type default)
		)
		(fill no)
		(layer "In1.Cu")
	)
	(gr_circle
		(center 159.599884 -306.349908)
		(end 159.853884 -306.349908)
		(stroke
			(width 0.1016)
			(type default)
		)
		(fill no)
		(layer "In1.Cu")
	)
	(gr_circle
		(center 159.599884 -304.449734)
		(end 159.853884 -304.449734)
		(stroke
			(width 0.1016)
			(type default)
		)
		(fill no)
		(layer "In1.Cu")
	)
	(gr_circle
		(center 159.599884 -302.549814)
		(end 159.853884 -302.549814)
		(stroke
			(width 0.1016)
			(type default)
		)
		(fill no)
		(layer "In1.Cu")
	)
	(gr_circle
		(center 160.549844 -318.699896)
		(end 160.803844 -318.699896)
		(stroke
			(width 0.1016)
			(type default)
		)
		(fill no)
		(layer "In1.Cu")
	)
	(gr_circle
		(center 160.549844 -317.749936)
		(end 160.803844 -317.749936)
		(stroke
			(width 0.1016)
			(type default)
		)
		(fill no)
		(layer "In1.Cu")
	)
	(gr_circle
		(center 160.549844 -313.949842)
		(end 160.803844 -313.949842)
		(stroke
			(width 0.1016)
			(type default)
		)
		(fill no)
		(layer "In1.Cu")
	)
	(gr_circle
		(center 160.549844 -312.999882)
		(end 160.803844 -312.999882)
		(stroke
			(width 0.1016)
			(type default)
		)
		(fill no)
		(layer "In1.Cu")
	)
	(gr_circle
		(center 160.549844 -308.249828)
		(end 160.803844 -308.249828)
		(stroke
			(width 0.1016)
			(type default)
		)
		(fill no)
		(layer "In1.Cu")
	)
	(gr_circle
		(center 160.549844 -306.349908)
		(end 160.803844 -306.349908)
		(stroke
			(width 0.1016)
			(type default)
		)
		(fill no)
		(layer "In1.Cu")
	)
	(gr_circle
		(center 160.549844 -304.449734)
		(end 160.803844 -304.449734)
		(stroke
			(width 0.1016)
			(type default)
		)
		(fill no)
		(layer "In1.Cu")
	)
	(gr_circle
		(center 160.549844 -302.549814)
		(end 160.803844 -302.549814)
		(stroke
			(width 0.1016)
			(type default)
		)
		(fill no)
		(layer "In1.Cu")
	)
	(gr_circle
		(center 160.549844 -278.799798)
		(end 160.803844 -278.799798)
		(stroke
			(width 0.1016)
			(type default)
		)
		(fill no)
		(layer "In1.Cu")
	)
	(gr_circle
		(center 160.549844 -277.849838)
		(end 160.803844 -277.849838)
		(stroke
			(width 0.1016)
			(type default)
		)
		(fill no)
		(layer "In1.Cu")
	)
	(gr_circle
		(center 160.549844 -274.049744)
		(end 160.803844 -274.049744)
		(stroke
			(width 0.1016)
			(type default)
		)
		(fill no)
		(layer "In1.Cu")
	)
	(gr_circle
		(center 160.549844 -273.099784)
		(end 160.803844 -273.099784)
		(stroke
			(width 0.1016)
			(type default)
		)
		(fill no)
		(layer "In1.Cu")
	)
	(gr_circle
		(center 161.500058 -316.799722)
		(end 161.754058 -316.799722)
		(stroke
			(width 0.1016)
			(type default)
		)
		(fill no)
		(layer "In1.Cu")
	)
	(gr_circle
		(center 161.500058 -315.849762)
		(end 161.754058 -315.849762)
		(stroke
			(width 0.1016)
			(type default)
		)
		(fill no)
		(layer "In1.Cu")
	)
	(gr_circle
		(center 161.500058 -312.049922)
		(end 161.754058 -312.049922)
		(stroke
			(width 0.1016)
			(type default)
		)
		(fill no)
		(layer "In1.Cu")
	)
	(gr_circle
		(center 161.500058 -311.099962)
		(end 161.754058 -311.099962)
		(stroke
			(width 0.1016)
			(type default)
		)
		(fill no)
		(layer "In1.Cu")
	)
	(gr_circle
		(center 161.500058 -280.699464)
		(end 161.754058 -280.699464)
		(stroke
			(width 0.1016)
			(type default)
		)
		(fill no)
		(layer "In1.Cu")
	)
	(gr_circle
		(center 161.500058 -279.749504)
		(end 161.754058 -279.749504)
		(stroke
			(width 0.1016)
			(type default)
		)
		(fill no)
		(layer "In1.Cu")
	)
	(gr_circle
		(center 161.500058 -275.949918)
		(end 161.754058 -275.949918)
		(stroke
			(width 0.1016)
			(type default)
		)
		(fill no)
		(layer "In1.Cu")
	)
	(gr_circle
		(center 161.500058 -274.999958)
		(end 161.754058 -274.999958)
		(stroke
			(width 0.1016)
			(type default)
		)
		(fill no)
		(layer "In1.Cu")
	)
	(gr_circle
		(center 162.450018 -318.699896)
		(end 162.704018 -318.699896)
		(stroke
			(width 0.1016)
			(type default)
		)
		(fill no)
		(layer "In1.Cu")
	)
	(gr_circle
		(center 162.450018 -317.749936)
		(end 162.704018 -317.749936)
		(stroke
			(width 0.1016)
			(type default)
		)
		(fill no)
		(layer "In1.Cu")
	)
	(gr_circle
		(center 162.450018 -313.949842)
		(end 162.704018 -313.949842)
		(stroke
			(width 0.1016)
			(type default)
		)
		(fill no)
		(layer "In1.Cu")
	)
	(gr_circle
		(center 162.450018 -312.999882)
		(end 162.704018 -312.999882)
		(stroke
			(width 0.1016)
			(type default)
		)
		(fill no)
		(layer "In1.Cu")
	)
	(gr_circle
		(center 162.450018 -278.799798)
		(end 162.704018 -278.799798)
		(stroke
			(width 0.1016)
			(type default)
		)
		(fill no)
		(layer "In1.Cu")
	)
	(gr_circle
		(center 162.450018 -277.849838)
		(end 162.704018 -277.849838)
		(stroke
			(width 0.1016)
			(type default)
		)
		(fill no)
		(layer "In1.Cu")
	)
	(gr_circle
		(center 162.450018 -274.049744)
		(end 162.704018 -274.049744)
		(stroke
			(width 0.1016)
			(type default)
		)
		(fill no)
		(layer "In1.Cu")
	)
	(gr_circle
		(center 162.450018 -273.099784)
		(end 162.704018 -273.099784)
		(stroke
			(width 0.1016)
			(type default)
		)
		(fill no)
		(layer "In1.Cu")
	)
	(gr_circle
		(center 163.399978 -316.799722)
		(end 163.653978 -316.799722)
		(stroke
			(width 0.1016)
			(type default)
		)
		(fill no)
		(layer "In1.Cu")
	)
	(gr_circle
		(center 163.399978 -315.849762)
		(end 163.653978 -315.849762)
		(stroke
			(width 0.1016)
			(type default)
		)
		(fill no)
		(layer "In1.Cu")
	)
	(gr_circle
		(center 163.399978 -312.049922)
		(end 163.653978 -312.049922)
		(stroke
			(width 0.1016)
			(type default)
		)
		(fill no)
		(layer "In1.Cu")
	)
	(gr_circle
		(center 163.399978 -311.099962)
		(end 163.653978 -311.099962)
		(stroke
			(width 0.1016)
			(type default)
		)
		(fill no)
		(layer "In1.Cu")
	)
	(gr_circle
		(center 163.399978 -280.699464)
		(end 163.653978 -280.699464)
		(stroke
			(width 0.1016)
			(type default)
		)
		(fill no)
		(layer "In1.Cu")
	)
	(gr_circle
		(center 163.399978 -279.749504)
		(end 163.653978 -279.749504)
		(stroke
			(width 0.1016)
			(type default)
		)
		(fill no)
		(layer "In1.Cu")
	)
	(gr_circle
		(center 163.399978 -275.949918)
		(end 163.653978 -275.949918)
		(stroke
			(width 0.1016)
			(type default)
		)
		(fill no)
		(layer "In1.Cu")
	)
	(gr_circle
		(center 163.399978 -274.999958)
		(end 163.653978 -274.999958)
		(stroke
			(width 0.1016)
			(type default)
		)
		(fill no)
		(layer "In1.Cu")
	)
	(gr_circle
		(center 164.349938 -318.699896)
		(end 164.603938 -318.699896)
		(stroke
			(width 0.1016)
			(type default)
		)
		(fill no)
		(layer "In1.Cu")
	)
	(gr_circle
		(center 164.349938 -317.749936)
		(end 164.603938 -317.749936)
		(stroke
			(width 0.1016)
			(type default)
		)
		(fill no)
		(layer "In1.Cu")
	)
	(gr_circle
		(center 164.349938 -313.949842)
		(end 164.603938 -313.949842)
		(stroke
			(width 0.1016)
			(type default)
		)
		(fill no)
		(layer "In1.Cu")
	)
	(gr_circle
		(center 164.349938 -312.999882)
		(end 164.603938 -312.999882)
		(stroke
			(width 0.1016)
			(type default)
		)
		(fill no)
		(layer "In1.Cu")
	)
	(gr_circle
		(center 164.349938 -278.799798)
		(end 164.603938 -278.799798)
		(stroke
			(width 0.1016)
			(type default)
		)
		(fill no)
		(layer "In1.Cu")
	)
	(gr_circle
		(center 164.349938 -277.849838)
		(end 164.603938 -277.849838)
		(stroke
			(width 0.1016)
			(type default)
		)
		(fill no)
		(layer "In1.Cu")
	)
	(gr_circle
		(center 164.349938 -274.049744)
		(end 164.603938 -274.049744)
		(stroke
			(width 0.1016)
			(type default)
		)
		(fill no)
		(layer "In1.Cu")
	)
	(gr_circle
		(center 164.349938 -273.099784)
		(end 164.603938 -273.099784)
		(stroke
			(width 0.1016)
			(type default)
		)
		(fill no)
		(layer "In1.Cu")
	)
	(gr_circle
		(center 165.299898 -316.799722)
		(end 165.553898 -316.799722)
		(stroke
			(width 0.1016)
			(type default)
		)
		(fill no)
		(layer "In1.Cu")
	)
	(gr_circle
		(center 165.299898 -315.849762)
		(end 165.553898 -315.849762)
		(stroke
			(width 0.1016)
			(type default)
		)
		(fill no)
		(layer "In1.Cu")
	)
	(gr_circle
		(center 165.299898 -312.049922)
		(end 165.553898 -312.049922)
		(stroke
			(width 0.1016)
			(type default)
		)
		(fill no)
		(layer "In1.Cu")
	)
	(gr_circle
		(center 165.299898 -311.099962)
		(end 165.553898 -311.099962)
		(stroke
			(width 0.1016)
			(type default)
		)
		(fill no)
		(layer "In1.Cu")
	)
	(gr_circle
		(center 165.299898 -280.699464)
		(end 165.553898 -280.699464)
		(stroke
			(width 0.1016)
			(type default)
		)
		(fill no)
		(layer "In1.Cu")
	)
	(gr_circle
		(center 165.299898 -279.749504)
		(end 165.553898 -279.749504)
		(stroke
			(width 0.1016)
			(type default)
		)
		(fill no)
		(layer "In1.Cu")
	)
	(gr_circle
		(center 165.299898 -275.949918)
		(end 165.553898 -275.949918)
		(stroke
			(width 0.1016)
			(type default)
		)
		(fill no)
		(layer "In1.Cu")
	)
	(gr_circle
		(center 165.299898 -274.999958)
		(end 165.553898 -274.999958)
		(stroke
			(width 0.1016)
			(type default)
		)
		(fill no)
		(layer "In1.Cu")
	)
	(gr_circle
		(center 166.249858 -318.699896)
		(end 166.503858 -318.699896)
		(stroke
			(width 0.1016)
			(type default)
		)
		(fill no)
		(layer "In1.Cu")
	)
	(gr_circle
		(center 166.249858 -317.749936)
		(end 166.503858 -317.749936)
		(stroke
			(width 0.1016)
			(type default)
		)
		(fill no)
		(layer "In1.Cu")
	)
	(gr_circle
		(center 166.249858 -313.949842)
		(end 166.503858 -313.949842)
		(stroke
			(width 0.1016)
			(type default)
		)
		(fill no)
		(layer "In1.Cu")
	)
	(gr_circle
		(center 166.249858 -312.999882)
		(end 166.503858 -312.999882)
		(stroke
			(width 0.1016)
			(type default)
		)
		(fill no)
		(layer "In1.Cu")
	)
	(gr_circle
		(center 166.249858 -278.799798)
		(end 166.503858 -278.799798)
		(stroke
			(width 0.1016)
			(type default)
		)
		(fill no)
		(layer "In1.Cu")
	)
	(gr_circle
		(center 166.249858 -277.849838)
		(end 166.503858 -277.849838)
		(stroke
			(width 0.1016)
			(type default)
		)
		(fill no)
		(layer "In1.Cu")
	)
	(gr_circle
		(center 166.249858 -274.049744)
		(end 166.503858 -274.049744)
		(stroke
			(width 0.1016)
			(type default)
		)
		(fill no)
		(layer "In1.Cu")
	)
	(gr_circle
		(center 166.249858 -273.099784)
		(end 166.503858 -273.099784)
		(stroke
			(width 0.1016)
			(type default)
		)
		(fill no)
		(layer "In1.Cu")
	)
	(gr_circle
		(center 167.200072 -316.799722)
		(end 167.454072 -316.799722)
		(stroke
			(width 0.1016)
			(type default)
		)
		(fill no)
		(layer "In1.Cu")
	)
	(gr_circle
		(center 167.200072 -315.849762)
		(end 167.454072 -315.849762)
		(stroke
			(width 0.1016)
			(type default)
		)
		(fill no)
		(layer "In1.Cu")
	)
	(gr_circle
		(center 167.200072 -312.049922)
		(end 167.454072 -312.049922)
		(stroke
			(width 0.1016)
			(type default)
		)
		(fill no)
		(layer "In1.Cu")
	)
	(gr_circle
		(center 167.200072 -311.099962)
		(end 167.454072 -311.099962)
		(stroke
			(width 0.1016)
			(type default)
		)
		(fill no)
		(layer "In1.Cu")
	)
	(gr_circle
		(center 167.200072 -280.699464)
		(end 167.454072 -280.699464)
		(stroke
			(width 0.1016)
			(type default)
		)
		(fill no)
		(layer "In1.Cu")
	)
	(gr_circle
		(center 167.200072 -279.749504)
		(end 167.454072 -279.749504)
		(stroke
			(width 0.1016)
			(type default)
		)
		(fill no)
		(layer "In1.Cu")
	)
	(gr_circle
		(center 167.200072 -275.949918)
		(end 167.454072 -275.949918)
		(stroke
			(width 0.1016)
			(type default)
		)
		(fill no)
		(layer "In1.Cu")
	)
	(gr_circle
		(center 167.200072 -274.999958)
		(end 167.454072 -274.999958)
		(stroke
			(width 0.1016)
			(type default)
		)
		(fill no)
		(layer "In1.Cu")
	)
	(gr_circle
		(center 168.150032 -318.699896)
		(end 168.404032 -318.699896)
		(stroke
			(width 0.1016)
			(type default)
		)
		(fill no)
		(layer "In1.Cu")
	)
	(gr_circle
		(center 168.150032 -317.749936)
		(end 168.404032 -317.749936)
		(stroke
			(width 0.1016)
			(type default)
		)
		(fill no)
		(layer "In1.Cu")
	)
	(gr_circle
		(center 168.150032 -313.949842)
		(end 168.404032 -313.949842)
		(stroke
			(width 0.1016)
			(type default)
		)
		(fill no)
		(layer "In1.Cu")
	)
	(gr_circle
		(center 168.150032 -312.999882)
		(end 168.404032 -312.999882)
		(stroke
			(width 0.1016)
			(type default)
		)
		(fill no)
		(layer "In1.Cu")
	)
	(gr_circle
		(center 168.150032 -278.799798)
		(end 168.404032 -278.799798)
		(stroke
			(width 0.1016)
			(type default)
		)
		(fill no)
		(layer "In1.Cu")
	)
	(gr_circle
		(center 168.150032 -277.849838)
		(end 168.404032 -277.849838)
		(stroke
			(width 0.1016)
			(type default)
		)
		(fill no)
		(layer "In1.Cu")
	)
	(gr_circle
		(center 168.150032 -274.049744)
		(end 168.404032 -274.049744)
		(stroke
			(width 0.1016)
			(type default)
		)
		(fill no)
		(layer "In1.Cu")
	)
	(gr_circle
		(center 168.150032 -273.099784)
		(end 168.404032 -273.099784)
		(stroke
			(width 0.1016)
			(type default)
		)
		(fill no)
		(layer "In1.Cu")
	)
	(gr_circle
		(center 169.099992 -316.799722)
		(end 169.353992 -316.799722)
		(stroke
			(width 0.1016)
			(type default)
		)
		(fill no)
		(layer "In1.Cu")
	)
	(gr_circle
		(center 169.099992 -315.849762)
		(end 169.353992 -315.849762)
		(stroke
			(width 0.1016)
			(type default)
		)
		(fill no)
		(layer "In1.Cu")
	)
	(gr_circle
		(center 169.099992 -312.049922)
		(end 169.353992 -312.049922)
		(stroke
			(width 0.1016)
			(type default)
		)
		(fill no)
		(layer "In1.Cu")
	)
	(gr_circle
		(center 169.099992 -311.099962)
		(end 169.353992 -311.099962)
		(stroke
			(width 0.1016)
			(type default)
		)
		(fill no)
		(layer "In1.Cu")
	)
	(gr_circle
		(center 169.099992 -280.699464)
		(end 169.353992 -280.699464)
		(stroke
			(width 0.1016)
			(type default)
		)
		(fill no)
		(layer "In1.Cu")
	)
	(gr_circle
		(center 169.099992 -279.749504)
		(end 169.353992 -279.749504)
		(stroke
			(width 0.1016)
			(type default)
		)
		(fill no)
		(layer "In1.Cu")
	)
	(gr_circle
		(center 169.099992 -275.949918)
		(end 169.353992 -275.949918)
		(stroke
			(width 0.1016)
			(type default)
		)
		(fill no)
		(layer "In1.Cu")
	)
	(gr_circle
		(center 169.099992 -274.999958)
		(end 169.353992 -274.999958)
		(stroke
			(width 0.1016)
			(type default)
		)
		(fill no)
		(layer "In1.Cu")
	)
	(gr_circle
		(center 170.049952 -318.699896)
		(end 170.303952 -318.699896)
		(stroke
			(width 0.1016)
			(type default)
		)
		(fill no)
		(layer "In1.Cu")
	)
	(gr_circle
		(center 170.049952 -317.749936)
		(end 170.303952 -317.749936)
		(stroke
			(width 0.1016)
			(type default)
		)
		(fill no)
		(layer "In1.Cu")
	)
	(gr_circle
		(center 170.049952 -313.949842)
		(end 170.303952 -313.949842)
		(stroke
			(width 0.1016)
			(type default)
		)
		(fill no)
		(layer "In1.Cu")
	)
	(gr_circle
		(center 170.049952 -312.999882)
		(end 170.303952 -312.999882)
		(stroke
			(width 0.1016)
			(type default)
		)
		(fill no)
		(layer "In1.Cu")
	)
	(gr_circle
		(center 170.049952 -278.799798)
		(end 170.303952 -278.799798)
		(stroke
			(width 0.1016)
			(type default)
		)
		(fill no)
		(layer "In1.Cu")
	)
	(gr_circle
		(center 170.049952 -277.849838)
		(end 170.303952 -277.849838)
		(stroke
			(width 0.1016)
			(type default)
		)
		(fill no)
		(layer "In1.Cu")
	)
	(gr_circle
		(center 170.049952 -274.049744)
		(end 170.303952 -274.049744)
		(stroke
			(width 0.1016)
			(type default)
		)
		(fill no)
		(layer "In1.Cu")
	)
	(gr_circle
		(center 170.049952 -273.099784)
		(end 170.303952 -273.099784)
		(stroke
			(width 0.1016)
			(type default)
		)
		(fill no)
		(layer "In1.Cu")
	)
	(gr_circle
		(center 170.999912 -316.799722)
		(end 171.253912 -316.799722)
		(stroke
			(width 0.1016)
			(type default)
		)
		(fill no)
		(layer "In1.Cu")
	)
	(gr_circle
		(center 170.999912 -315.849762)
		(end 171.253912 -315.849762)
		(stroke
			(width 0.1016)
			(type default)
		)
		(fill no)
		(layer "In1.Cu")
	)
	(gr_circle
		(center 170.999912 -312.049922)
		(end 171.253912 -312.049922)
		(stroke
			(width 0.1016)
			(type default)
		)
		(fill no)
		(layer "In1.Cu")
	)
	(gr_circle
		(center 170.999912 -311.099962)
		(end 171.253912 -311.099962)
		(stroke
			(width 0.1016)
			(type default)
		)
		(fill no)
		(layer "In1.Cu")
	)
	(gr_circle
		(center 170.999912 -280.699464)
		(end 171.253912 -280.699464)
		(stroke
			(width 0.1016)
			(type default)
		)
		(fill no)
		(layer "In1.Cu")
	)
	(gr_circle
		(center 170.999912 -279.749504)
		(end 171.253912 -279.749504)
		(stroke
			(width 0.1016)
			(type default)
		)
		(fill no)
		(layer "In1.Cu")
	)
	(gr_circle
		(center 170.999912 -275.949918)
		(end 171.253912 -275.949918)
		(stroke
			(width 0.1016)
			(type default)
		)
		(fill no)
		(layer "In1.Cu")
	)
	(gr_circle
		(center 170.999912 -274.999958)
		(end 171.253912 -274.999958)
		(stroke
			(width 0.1016)
			(type default)
		)
		(fill no)
		(layer "In1.Cu")
	)
	(gr_circle
		(center 171.949872 -318.699896)
		(end 172.203872 -318.699896)
		(stroke
			(width 0.1016)
			(type default)
		)
		(fill no)
		(layer "In1.Cu")
	)
	(gr_circle
		(center 171.949872 -317.749936)
		(end 172.203872 -317.749936)
		(stroke
			(width 0.1016)
			(type default)
		)
		(fill no)
		(layer "In1.Cu")
	)
	(gr_circle
		(center 171.949872 -313.949842)
		(end 172.203872 -313.949842)
		(stroke
			(width 0.1016)
			(type default)
		)
		(fill no)
		(layer "In1.Cu")
	)
	(gr_circle
		(center 171.949872 -312.999882)
		(end 172.203872 -312.999882)
		(stroke
			(width 0.1016)
			(type default)
		)
		(fill no)
		(layer "In1.Cu")
	)
	(gr_circle
		(center 171.949872 -278.799798)
		(end 172.203872 -278.799798)
		(stroke
			(width 0.1016)
			(type default)
		)
		(fill no)
		(layer "In1.Cu")
	)
	(gr_circle
		(center 171.949872 -277.849838)
		(end 172.203872 -277.849838)
		(stroke
			(width 0.1016)
			(type default)
		)
		(fill no)
		(layer "In1.Cu")
	)
	(gr_circle
		(center 171.949872 -274.049744)
		(end 172.203872 -274.049744)
		(stroke
			(width 0.1016)
			(type default)
		)
		(fill no)
		(layer "In1.Cu")
	)
	(gr_circle
		(center 171.949872 -273.099784)
		(end 172.203872 -273.099784)
		(stroke
			(width 0.1016)
			(type default)
		)
		(fill no)
		(layer "In1.Cu")
	)
	(gr_circle
		(center 172.899832 -280.699464)
		(end 173.153832 -280.699464)
		(stroke
			(width 0.1016)
			(type default)
		)
		(fill no)
		(layer "In1.Cu")
	)
	(gr_circle
		(center 172.899832 -279.749504)
		(end 173.153832 -279.749504)
		(stroke
			(width 0.1016)
			(type default)
		)
		(fill no)
		(layer "In1.Cu")
	)
	(gr_circle
		(center 172.900086 -316.799722)
		(end 173.154086 -316.799722)
		(stroke
			(width 0.1016)
			(type default)
		)
		(fill no)
		(layer "In1.Cu")
	)
	(gr_circle
		(center 172.900086 -315.849762)
		(end 173.154086 -315.849762)
		(stroke
			(width 0.1016)
			(type default)
		)
		(fill no)
		(layer "In1.Cu")
	)
	(gr_circle
		(center 172.900086 -312.049922)
		(end 173.154086 -312.049922)
		(stroke
			(width 0.1016)
			(type default)
		)
		(fill no)
		(layer "In1.Cu")
	)
	(gr_circle
		(center 172.900086 -311.099962)
		(end 173.154086 -311.099962)
		(stroke
			(width 0.1016)
			(type default)
		)
		(fill no)
		(layer "In1.Cu")
	)
	(gr_circle
		(center 172.900086 -275.949918)
		(end 173.154086 -275.949918)
		(stroke
			(width 0.1016)
			(type default)
		)
		(fill no)
		(layer "In1.Cu")
	)
	(gr_circle
		(center 172.900086 -274.999958)
		(end 173.154086 -274.999958)
		(stroke
			(width 0.1016)
			(type default)
		)
		(fill no)
		(layer "In1.Cu")
	)
	(gr_circle
		(center 173.850046 -318.699896)
		(end 174.104046 -318.699896)
		(stroke
			(width 0.1016)
			(type default)
		)
		(fill no)
		(layer "In1.Cu")
	)
	(gr_circle
		(center 173.850046 -317.749936)
		(end 174.104046 -317.749936)
		(stroke
			(width 0.1016)
			(type default)
		)
		(fill no)
		(layer "In1.Cu")
	)
	(gr_circle
		(center 173.850046 -313.949842)
		(end 174.104046 -313.949842)
		(stroke
			(width 0.1016)
			(type default)
		)
		(fill no)
		(layer "In1.Cu")
	)
	(gr_circle
		(center 173.850046 -312.999882)
		(end 174.104046 -312.999882)
		(stroke
			(width 0.1016)
			(type default)
		)
		(fill no)
		(layer "In1.Cu")
	)
	(gr_circle
		(center 173.850046 -278.799798)
		(end 174.104046 -278.799798)
		(stroke
			(width 0.1016)
			(type default)
		)
		(fill no)
		(layer "In1.Cu")
	)
	(gr_circle
		(center 173.850046 -277.849838)
		(end 174.104046 -277.849838)
		(stroke
			(width 0.1016)
			(type default)
		)
		(fill no)
		(layer "In1.Cu")
	)
	(gr_circle
		(center 173.850046 -274.049744)
		(end 174.104046 -274.049744)
		(stroke
			(width 0.1016)
			(type default)
		)
		(fill no)
		(layer "In1.Cu")
	)
	(gr_circle
		(center 173.850046 -273.099784)
		(end 174.104046 -273.099784)
		(stroke
			(width 0.1016)
			(type default)
		)
		(fill no)
		(layer "In1.Cu")
	)
	(gr_circle
		(center 174.800006 -316.799722)
		(end 175.054006 -316.799722)
		(stroke
			(width 0.1016)
			(type default)
		)
		(fill no)
		(layer "In1.Cu")
	)
	(gr_circle
		(center 174.800006 -315.849762)
		(end 175.054006 -315.849762)
		(stroke
			(width 0.1016)
			(type default)
		)
		(fill no)
		(layer "In1.Cu")
	)
	(gr_circle
		(center 174.800006 -312.049922)
		(end 175.054006 -312.049922)
		(stroke
			(width 0.1016)
			(type default)
		)
		(fill no)
		(layer "In1.Cu")
	)
	(gr_circle
		(center 174.800006 -311.099962)
		(end 175.054006 -311.099962)
		(stroke
			(width 0.1016)
			(type default)
		)
		(fill no)
		(layer "In1.Cu")
	)
	(gr_circle
		(center 174.800006 -280.699464)
		(end 175.054006 -280.699464)
		(stroke
			(width 0.1016)
			(type default)
		)
		(fill no)
		(layer "In1.Cu")
	)
	(gr_circle
		(center 174.800006 -279.749504)
		(end 175.054006 -279.749504)
		(stroke
			(width 0.1016)
			(type default)
		)
		(fill no)
		(layer "In1.Cu")
	)
	(gr_circle
		(center 174.800006 -275.949918)
		(end 175.054006 -275.949918)
		(stroke
			(width 0.1016)
			(type default)
		)
		(fill no)
		(layer "In1.Cu")
	)
	(gr_circle
		(center 174.800006 -274.999958)
		(end 175.054006 -274.999958)
		(stroke
			(width 0.1016)
			(type default)
		)
		(fill no)
		(layer "In1.Cu")
	)
	(gr_circle
		(center 175.749712 -278.799798)
		(end 176.003712 -278.799798)
		(stroke
			(width 0.1016)
			(type default)
		)
		(fill no)
		(layer "In1.Cu")
	)
	(gr_circle
		(center 175.749712 -277.849838)
		(end 176.003712 -277.849838)
		(stroke
			(width 0.1016)
			(type default)
		)
		(fill no)
		(layer "In1.Cu")
	)
	(gr_circle
		(center 175.749712 -274.04949)
		(end 176.003712 -274.04949)
		(stroke
			(width 0.1016)
			(type default)
		)
		(fill no)
		(layer "In1.Cu")
	)
	(gr_circle
		(center 175.749712 -273.09953)
		(end 176.003712 -273.09953)
		(stroke
			(width 0.1016)
			(type default)
		)
		(fill no)
		(layer "In1.Cu")
	)
	(gr_circle
		(center 175.749966 -318.699896)
		(end 176.003966 -318.699896)
		(stroke
			(width 0.1016)
			(type default)
		)
		(fill no)
		(layer "In1.Cu")
	)
	(gr_circle
		(center 175.749966 -317.749936)
		(end 176.003966 -317.749936)
		(stroke
			(width 0.1016)
			(type default)
		)
		(fill no)
		(layer "In1.Cu")
	)
	(gr_circle
		(center 175.749966 -313.949842)
		(end 176.003966 -313.949842)
		(stroke
			(width 0.1016)
			(type default)
		)
		(fill no)
		(layer "In1.Cu")
	)
	(gr_circle
		(center 175.749966 -312.999882)
		(end 176.003966 -312.999882)
		(stroke
			(width 0.1016)
			(type default)
		)
		(fill no)
		(layer "In1.Cu")
	)
	(gr_circle
		(center 176.699672 -275.949664)
		(end 176.953672 -275.949664)
		(stroke
			(width 0.1016)
			(type default)
		)
		(fill no)
		(layer "In1.Cu")
	)
	(gr_circle
		(center 176.699672 -274.999704)
		(end 176.953672 -274.999704)
		(stroke
			(width 0.1016)
			(type default)
		)
		(fill no)
		(layer "In1.Cu")
	)
	(gr_circle
		(center 176.699926 -316.799722)
		(end 176.953926 -316.799722)
		(stroke
			(width 0.1016)
			(type default)
		)
		(fill no)
		(layer "In1.Cu")
	)
	(gr_circle
		(center 176.699926 -315.849762)
		(end 176.953926 -315.849762)
		(stroke
			(width 0.1016)
			(type default)
		)
		(fill no)
		(layer "In1.Cu")
	)
	(gr_circle
		(center 176.699926 -312.049922)
		(end 176.953926 -312.049922)
		(stroke
			(width 0.1016)
			(type default)
		)
		(fill no)
		(layer "In1.Cu")
	)
	(gr_circle
		(center 176.699926 -311.099962)
		(end 176.953926 -311.099962)
		(stroke
			(width 0.1016)
			(type default)
		)
		(fill no)
		(layer "In1.Cu")
	)
	(gr_circle
		(center 176.699926 -280.699464)
		(end 176.953926 -280.699464)
		(stroke
			(width 0.1016)
			(type default)
		)
		(fill no)
		(layer "In1.Cu")
	)
	(gr_circle
		(center 176.699926 -279.749504)
		(end 176.953926 -279.749504)
		(stroke
			(width 0.1016)
			(type default)
		)
		(fill no)
		(layer "In1.Cu")
	)
	(gr_circle
		(center 177.649632 -278.799798)
		(end 177.903632 -278.799798)
		(stroke
			(width 0.1016)
			(type default)
		)
		(fill no)
		(layer "In1.Cu")
	)
	(gr_circle
		(center 177.649632 -277.849838)
		(end 177.903632 -277.849838)
		(stroke
			(width 0.1016)
			(type default)
		)
		(fill no)
		(layer "In1.Cu")
	)
	(gr_circle
		(center 177.649632 -274.049744)
		(end 177.903632 -274.049744)
		(stroke
			(width 0.1016)
			(type default)
		)
		(fill no)
		(layer "In1.Cu")
	)
	(gr_circle
		(center 177.649632 -273.099784)
		(end 177.903632 -273.099784)
		(stroke
			(width 0.1016)
			(type default)
		)
		(fill no)
		(layer "In1.Cu")
	)
	(gr_circle
		(center 177.649886 -318.699896)
		(end 177.903886 -318.699896)
		(stroke
			(width 0.1016)
			(type default)
		)
		(fill no)
		(layer "In1.Cu")
	)
	(gr_circle
		(center 177.649886 -317.749936)
		(end 177.903886 -317.749936)
		(stroke
			(width 0.1016)
			(type default)
		)
		(fill no)
		(layer "In1.Cu")
	)
	(gr_circle
		(center 177.649886 -313.949842)
		(end 177.903886 -313.949842)
		(stroke
			(width 0.1016)
			(type default)
		)
		(fill no)
		(layer "In1.Cu")
	)
	(gr_circle
		(center 177.649886 -312.999882)
		(end 177.903886 -312.999882)
		(stroke
			(width 0.1016)
			(type default)
		)
		(fill no)
		(layer "In1.Cu")
	)
	(gr_circle
		(center 178.599592 -275.949918)
		(end 178.853592 -275.949918)
		(stroke
			(width 0.1016)
			(type default)
		)
		(fill no)
		(layer "In1.Cu")
	)
	(gr_circle
		(center 178.599592 -274.999958)
		(end 178.853592 -274.999958)
		(stroke
			(width 0.1016)
			(type default)
		)
		(fill no)
		(layer "In1.Cu")
	)
	(gr_circle
		(center 178.599846 -316.799722)
		(end 178.853846 -316.799722)
		(stroke
			(width 0.1016)
			(type default)
		)
		(fill no)
		(layer "In1.Cu")
	)
	(gr_circle
		(center 178.599846 -315.849762)
		(end 178.853846 -315.849762)
		(stroke
			(width 0.1016)
			(type default)
		)
		(fill no)
		(layer "In1.Cu")
	)
	(gr_circle
		(center 178.599846 -312.049922)
		(end 178.853846 -312.049922)
		(stroke
			(width 0.1016)
			(type default)
		)
		(fill no)
		(layer "In1.Cu")
	)
	(gr_circle
		(center 178.599846 -311.099962)
		(end 178.853846 -311.099962)
		(stroke
			(width 0.1016)
			(type default)
		)
		(fill no)
		(layer "In1.Cu")
	)
	(gr_circle
		(center 178.599846 -280.699464)
		(end 178.853846 -280.699464)
		(stroke
			(width 0.1016)
			(type default)
		)
		(fill no)
		(layer "In1.Cu")
	)
	(gr_circle
		(center 178.599846 -279.749504)
		(end 178.853846 -279.749504)
		(stroke
			(width 0.1016)
			(type default)
		)
		(fill no)
		(layer "In1.Cu")
	)
	(gr_circle
		(center 179.549806 -278.799798)
		(end 179.803806 -278.799798)
		(stroke
			(width 0.1016)
			(type default)
		)
		(fill no)
		(layer "In1.Cu")
	)
	(gr_circle
		(center 179.549806 -277.849838)
		(end 179.803806 -277.849838)
		(stroke
			(width 0.1016)
			(type default)
		)
		(fill no)
		(layer "In1.Cu")
	)
	(gr_circle
		(center 179.549806 -274.049744)
		(end 179.803806 -274.049744)
		(stroke
			(width 0.1016)
			(type default)
		)
		(fill no)
		(layer "In1.Cu")
	)
	(gr_circle
		(center 179.549806 -273.099784)
		(end 179.803806 -273.099784)
		(stroke
			(width 0.1016)
			(type default)
		)
		(fill no)
		(layer "In1.Cu")
	)
	(gr_circle
		(center 179.55006 -318.699896)
		(end 179.80406 -318.699896)
		(stroke
			(width 0.1016)
			(type default)
		)
		(fill no)
		(layer "In1.Cu")
	)
	(gr_circle
		(center 179.55006 -317.749936)
		(end 179.80406 -317.749936)
		(stroke
			(width 0.1016)
			(type default)
		)
		(fill no)
		(layer "In1.Cu")
	)
	(gr_circle
		(center 179.55006 -313.949842)
		(end 179.80406 -313.949842)
		(stroke
			(width 0.1016)
			(type default)
		)
		(fill no)
		(layer "In1.Cu")
	)
	(gr_circle
		(center 179.55006 -312.999882)
		(end 179.80406 -312.999882)
		(stroke
			(width 0.1016)
			(type default)
		)
		(fill no)
		(layer "In1.Cu")
	)
	(gr_circle
		(center 180.499766 -275.949664)
		(end 180.753766 -275.949664)
		(stroke
			(width 0.1016)
			(type default)
		)
		(fill no)
		(layer "In1.Cu")
	)
	(gr_circle
		(center 180.499766 -274.999704)
		(end 180.753766 -274.999704)
		(stroke
			(width 0.1016)
			(type default)
		)
		(fill no)
		(layer "In1.Cu")
	)
	(gr_circle
		(center 180.50002 -316.799722)
		(end 180.75402 -316.799722)
		(stroke
			(width 0.1016)
			(type default)
		)
		(fill no)
		(layer "In1.Cu")
	)
	(gr_circle
		(center 180.50002 -315.849762)
		(end 180.75402 -315.849762)
		(stroke
			(width 0.1016)
			(type default)
		)
		(fill no)
		(layer "In1.Cu")
	)
	(gr_circle
		(center 180.50002 -312.049922)
		(end 180.75402 -312.049922)
		(stroke
			(width 0.1016)
			(type default)
		)
		(fill no)
		(layer "In1.Cu")
	)
	(gr_circle
		(center 180.50002 -311.099962)
		(end 180.75402 -311.099962)
		(stroke
			(width 0.1016)
			(type default)
		)
		(fill no)
		(layer "In1.Cu")
	)
	(gr_circle
		(center 180.50002 -280.699464)
		(end 180.75402 -280.699464)
		(stroke
			(width 0.1016)
			(type default)
		)
		(fill no)
		(layer "In1.Cu")
	)
	(gr_circle
		(center 180.50002 -279.749504)
		(end 180.75402 -279.749504)
		(stroke
			(width 0.1016)
			(type default)
		)
		(fill no)
		(layer "In1.Cu")
	)
	(gr_circle
		(center 181.449726 -278.799798)
		(end 181.703726 -278.799798)
		(stroke
			(width 0.1016)
			(type default)
		)
		(fill no)
		(layer "In1.Cu")
	)
	(gr_circle
		(center 181.449726 -277.849838)
		(end 181.703726 -277.849838)
		(stroke
			(width 0.1016)
			(type default)
		)
		(fill no)
		(layer "In1.Cu")
	)
	(gr_circle
		(center 181.449726 -274.049744)
		(end 181.703726 -274.049744)
		(stroke
			(width 0.1016)
			(type default)
		)
		(fill no)
		(layer "In1.Cu")
	)
	(gr_circle
		(center 181.449726 -273.099784)
		(end 181.703726 -273.099784)
		(stroke
			(width 0.1016)
			(type default)
		)
		(fill no)
		(layer "In1.Cu")
	)
	(gr_circle
		(center 181.44998 -318.699896)
		(end 181.70398 -318.699896)
		(stroke
			(width 0.1016)
			(type default)
		)
		(fill no)
		(layer "In1.Cu")
	)
	(gr_circle
		(center 181.44998 -317.749936)
		(end 181.70398 -317.749936)
		(stroke
			(width 0.1016)
			(type default)
		)
		(fill no)
		(layer "In1.Cu")
	)
	(gr_circle
		(center 181.44998 -313.949842)
		(end 181.70398 -313.949842)
		(stroke
			(width 0.1016)
			(type default)
		)
		(fill no)
		(layer "In1.Cu")
	)
	(gr_circle
		(center 181.44998 -312.999882)
		(end 181.70398 -312.999882)
		(stroke
			(width 0.1016)
			(type default)
		)
		(fill no)
		(layer "In1.Cu")
	)
	(gr_circle
		(center 182.399686 -275.949918)
		(end 182.653686 -275.949918)
		(stroke
			(width 0.1016)
			(type default)
		)
		(fill no)
		(layer "In1.Cu")
	)
	(gr_circle
		(center 182.399686 -274.999958)
		(end 182.653686 -274.999958)
		(stroke
			(width 0.1016)
			(type default)
		)
		(fill no)
		(layer "In1.Cu")
	)
	(gr_circle
		(center 182.39994 -316.799722)
		(end 182.65394 -316.799722)
		(stroke
			(width 0.1016)
			(type default)
		)
		(fill no)
		(layer "In1.Cu")
	)
	(gr_circle
		(center 182.39994 -315.849762)
		(end 182.65394 -315.849762)
		(stroke
			(width 0.1016)
			(type default)
		)
		(fill no)
		(layer "In1.Cu")
	)
	(gr_circle
		(center 182.39994 -312.049922)
		(end 182.65394 -312.049922)
		(stroke
			(width 0.1016)
			(type default)
		)
		(fill no)
		(layer "In1.Cu")
	)
	(gr_circle
		(center 182.39994 -311.099962)
		(end 182.65394 -311.099962)
		(stroke
			(width 0.1016)
			(type default)
		)
		(fill no)
		(layer "In1.Cu")
	)
	(gr_circle
		(center 182.39994 -280.699464)
		(end 182.65394 -280.699464)
		(stroke
			(width 0.1016)
			(type default)
		)
		(fill no)
		(layer "In1.Cu")
	)
	(gr_circle
		(center 182.39994 -279.749504)
		(end 182.65394 -279.749504)
		(stroke
			(width 0.1016)
			(type default)
		)
		(fill no)
		(layer "In1.Cu")
	)
	(gr_circle
		(center 183.349646 -278.799798)
		(end 183.603646 -278.799798)
		(stroke
			(width 0.1016)
			(type default)
		)
		(fill no)
		(layer "In1.Cu")
	)
	(gr_circle
		(center 183.349646 -277.849838)
		(end 183.603646 -277.849838)
		(stroke
			(width 0.1016)
			(type default)
		)
		(fill no)
		(layer "In1.Cu")
	)
	(gr_circle
		(center 183.349646 -274.049744)
		(end 183.603646 -274.049744)
		(stroke
			(width 0.1016)
			(type default)
		)
		(fill no)
		(layer "In1.Cu")
	)
	(gr_circle
		(center 183.349646 -273.099784)
		(end 183.603646 -273.099784)
		(stroke
			(width 0.1016)
			(type default)
		)
		(fill no)
		(layer "In1.Cu")
	)
	(gr_circle
		(center 183.3499 -318.699896)
		(end 183.6039 -318.699896)
		(stroke
			(width 0.1016)
			(type default)
		)
		(fill no)
		(layer "In1.Cu")
	)
	(gr_circle
		(center 183.3499 -317.749936)
		(end 183.6039 -317.749936)
		(stroke
			(width 0.1016)
			(type default)
		)
		(fill no)
		(layer "In1.Cu")
	)
	(gr_circle
		(center 183.3499 -313.949842)
		(end 183.6039 -313.949842)
		(stroke
			(width 0.1016)
			(type default)
		)
		(fill no)
		(layer "In1.Cu")
	)
	(gr_circle
		(center 183.3499 -312.999882)
		(end 183.6039 -312.999882)
		(stroke
			(width 0.1016)
			(type default)
		)
		(fill no)
		(layer "In1.Cu")
	)
	(gr_circle
		(center 184.299606 -275.949664)
		(end 184.553606 -275.949664)
		(stroke
			(width 0.1016)
			(type default)
		)
		(fill no)
		(layer "In1.Cu")
	)
	(gr_circle
		(center 184.299606 -274.999704)
		(end 184.553606 -274.999704)
		(stroke
			(width 0.1016)
			(type default)
		)
		(fill no)
		(layer "In1.Cu")
	)
	(gr_circle
		(center 184.29986 -316.799722)
		(end 184.55386 -316.799722)
		(stroke
			(width 0.1016)
			(type default)
		)
		(fill no)
		(layer "In1.Cu")
	)
	(gr_circle
		(center 184.29986 -315.849762)
		(end 184.55386 -315.849762)
		(stroke
			(width 0.1016)
			(type default)
		)
		(fill no)
		(layer "In1.Cu")
	)
	(gr_circle
		(center 184.29986 -312.049922)
		(end 184.55386 -312.049922)
		(stroke
			(width 0.1016)
			(type default)
		)
		(fill no)
		(layer "In1.Cu")
	)
	(gr_circle
		(center 184.29986 -311.099962)
		(end 184.55386 -311.099962)
		(stroke
			(width 0.1016)
			(type default)
		)
		(fill no)
		(layer "In1.Cu")
	)
	(gr_circle
		(center 184.29986 -280.699464)
		(end 184.55386 -280.699464)
		(stroke
			(width 0.1016)
			(type default)
		)
		(fill no)
		(layer "In1.Cu")
	)
	(gr_circle
		(center 184.29986 -279.749504)
		(end 184.55386 -279.749504)
		(stroke
			(width 0.1016)
			(type default)
		)
		(fill no)
		(layer "In1.Cu")
	)
	(gr_circle
		(center 185.24982 -278.799798)
		(end 185.50382 -278.799798)
		(stroke
			(width 0.1016)
			(type default)
		)
		(fill no)
		(layer "In1.Cu")
	)
	(gr_circle
		(center 185.24982 -277.849838)
		(end 185.50382 -277.849838)
		(stroke
			(width 0.1016)
			(type default)
		)
		(fill no)
		(layer "In1.Cu")
	)
	(gr_circle
		(center 185.24982 -274.049744)
		(end 185.50382 -274.049744)
		(stroke
			(width 0.1016)
			(type default)
		)
		(fill no)
		(layer "In1.Cu")
	)
	(gr_circle
		(center 185.24982 -273.099784)
		(end 185.50382 -273.099784)
		(stroke
			(width 0.1016)
			(type default)
		)
		(fill no)
		(layer "In1.Cu")
	)
	(gr_circle
		(center 185.250074 -318.699896)
		(end 185.504074 -318.699896)
		(stroke
			(width 0.1016)
			(type default)
		)
		(fill no)
		(layer "In1.Cu")
	)
	(gr_circle
		(center 185.250074 -317.749936)
		(end 185.504074 -317.749936)
		(stroke
			(width 0.1016)
			(type default)
		)
		(fill no)
		(layer "In1.Cu")
	)
	(gr_circle
		(center 185.250074 -313.949842)
		(end 185.504074 -313.949842)
		(stroke
			(width 0.1016)
			(type default)
		)
		(fill no)
		(layer "In1.Cu")
	)
	(gr_circle
		(center 185.250074 -312.999882)
		(end 185.504074 -312.999882)
		(stroke
			(width 0.1016)
			(type default)
		)
		(fill no)
		(layer "In1.Cu")
	)
	(gr_circle
		(center 186.199526 -275.949918)
		(end 186.453526 -275.949918)
		(stroke
			(width 0.1016)
			(type default)
		)
		(fill no)
		(layer "In1.Cu")
	)
	(gr_circle
		(center 186.199526 -274.999958)
		(end 186.453526 -274.999958)
		(stroke
			(width 0.1016)
			(type default)
		)
		(fill no)
		(layer "In1.Cu")
	)
	(gr_circle
		(center 186.200034 -316.799722)
		(end 186.454034 -316.799722)
		(stroke
			(width 0.1016)
			(type default)
		)
		(fill no)
		(layer "In1.Cu")
	)
	(gr_circle
		(center 186.200034 -315.849762)
		(end 186.454034 -315.849762)
		(stroke
			(width 0.1016)
			(type default)
		)
		(fill no)
		(layer "In1.Cu")
	)
	(gr_circle
		(center 186.200034 -312.049922)
		(end 186.454034 -312.049922)
		(stroke
			(width 0.1016)
			(type default)
		)
		(fill no)
		(layer "In1.Cu")
	)
	(gr_circle
		(center 186.200034 -311.099962)
		(end 186.454034 -311.099962)
		(stroke
			(width 0.1016)
			(type default)
		)
		(fill no)
		(layer "In1.Cu")
	)
	(gr_circle
		(center 186.200034 -280.699464)
		(end 186.454034 -280.699464)
		(stroke
			(width 0.1016)
			(type default)
		)
		(fill no)
		(layer "In1.Cu")
	)
	(gr_circle
		(center 186.200034 -279.749504)
		(end 186.454034 -279.749504)
		(stroke
			(width 0.1016)
			(type default)
		)
		(fill no)
		(layer "In1.Cu")
	)
	(gr_circle
		(center 187.14974 -278.799798)
		(end 187.40374 -278.799798)
		(stroke
			(width 0.1016)
			(type default)
		)
		(fill no)
		(layer "In1.Cu")
	)
	(gr_circle
		(center 187.14974 -277.849838)
		(end 187.40374 -277.849838)
		(stroke
			(width 0.1016)
			(type default)
		)
		(fill no)
		(layer "In1.Cu")
	)
	(gr_circle
		(center 187.14974 -274.049744)
		(end 187.40374 -274.049744)
		(stroke
			(width 0.1016)
			(type default)
		)
		(fill no)
		(layer "In1.Cu")
	)
	(gr_circle
		(center 187.14974 -273.099784)
		(end 187.40374 -273.099784)
		(stroke
			(width 0.1016)
			(type default)
		)
		(fill no)
		(layer "In1.Cu")
	)
	(gr_circle
		(center 187.149994 -318.699896)
		(end 187.403994 -318.699896)
		(stroke
			(width 0.1016)
			(type default)
		)
		(fill no)
		(layer "In1.Cu")
	)
	(gr_circle
		(center 187.149994 -317.749936)
		(end 187.403994 -317.749936)
		(stroke
			(width 0.1016)
			(type default)
		)
		(fill no)
		(layer "In1.Cu")
	)
	(gr_circle
		(center 187.149994 -313.949842)
		(end 187.403994 -313.949842)
		(stroke
			(width 0.1016)
			(type default)
		)
		(fill no)
		(layer "In1.Cu")
	)
	(gr_circle
		(center 187.149994 -312.999882)
		(end 187.403994 -312.999882)
		(stroke
			(width 0.1016)
			(type default)
		)
		(fill no)
		(layer "In1.Cu")
	)
	(gr_circle
		(center 188.0997 -275.949664)
		(end 188.3537 -275.949664)
		(stroke
			(width 0.1016)
			(type default)
		)
		(fill no)
		(layer "In1.Cu")
	)
	(gr_circle
		(center 188.0997 -274.999704)
		(end 188.3537 -274.999704)
		(stroke
			(width 0.1016)
			(type default)
		)
		(fill no)
		(layer "In1.Cu")
	)
	(gr_circle
		(center 188.099954 -316.799722)
		(end 188.353954 -316.799722)
		(stroke
			(width 0.1016)
			(type default)
		)
		(fill no)
		(layer "In1.Cu")
	)
	(gr_circle
		(center 188.099954 -315.849762)
		(end 188.353954 -315.849762)
		(stroke
			(width 0.1016)
			(type default)
		)
		(fill no)
		(layer "In1.Cu")
	)
	(gr_circle
		(center 188.099954 -312.049922)
		(end 188.353954 -312.049922)
		(stroke
			(width 0.1016)
			(type default)
		)
		(fill no)
		(layer "In1.Cu")
	)
	(gr_circle
		(center 188.099954 -311.099962)
		(end 188.353954 -311.099962)
		(stroke
			(width 0.1016)
			(type default)
		)
		(fill no)
		(layer "In1.Cu")
	)
	(gr_circle
		(center 188.099954 -280.699464)
		(end 188.353954 -280.699464)
		(stroke
			(width 0.1016)
			(type default)
		)
		(fill no)
		(layer "In1.Cu")
	)
	(gr_circle
		(center 188.099954 -279.749504)
		(end 188.353954 -279.749504)
		(stroke
			(width 0.1016)
			(type default)
		)
		(fill no)
		(layer "In1.Cu")
	)
	(gr_circle
		(center 189.04966 -278.799798)
		(end 189.30366 -278.799798)
		(stroke
			(width 0.1016)
			(type default)
		)
		(fill no)
		(layer "In1.Cu")
	)
	(gr_circle
		(center 189.04966 -277.849838)
		(end 189.30366 -277.849838)
		(stroke
			(width 0.1016)
			(type default)
		)
		(fill no)
		(layer "In1.Cu")
	)
	(gr_circle
		(center 189.04966 -274.049744)
		(end 189.30366 -274.049744)
		(stroke
			(width 0.1016)
			(type default)
		)
		(fill no)
		(layer "In1.Cu")
	)
	(gr_circle
		(center 189.04966 -273.099784)
		(end 189.30366 -273.099784)
		(stroke
			(width 0.1016)
			(type default)
		)
		(fill no)
		(layer "In1.Cu")
	)
	(gr_circle
		(center 189.049914 -318.699896)
		(end 189.303914 -318.699896)
		(stroke
			(width 0.1016)
			(type default)
		)
		(fill no)
		(layer "In1.Cu")
	)
	(gr_circle
		(center 189.049914 -317.749936)
		(end 189.303914 -317.749936)
		(stroke
			(width 0.1016)
			(type default)
		)
		(fill no)
		(layer "In1.Cu")
	)
	(gr_circle
		(center 189.049914 -313.949842)
		(end 189.303914 -313.949842)
		(stroke
			(width 0.1016)
			(type default)
		)
		(fill no)
		(layer "In1.Cu")
	)
	(gr_circle
		(center 189.049914 -312.999882)
		(end 189.303914 -312.999882)
		(stroke
			(width 0.1016)
			(type default)
		)
		(fill no)
		(layer "In1.Cu")
	)
	(gr_circle
		(center 189.99962 -275.949918)
		(end 190.25362 -275.949918)
		(stroke
			(width 0.1016)
			(type default)
		)
		(fill no)
		(layer "In1.Cu")
	)
	(gr_circle
		(center 189.99962 -274.999958)
		(end 190.25362 -274.999958)
		(stroke
			(width 0.1016)
			(type default)
		)
		(fill no)
		(layer "In1.Cu")
	)
	(gr_circle
		(center 189.999874 -316.799722)
		(end 190.253874 -316.799722)
		(stroke
			(width 0.1016)
			(type default)
		)
		(fill no)
		(layer "In1.Cu")
	)
	(gr_circle
		(center 189.999874 -315.849762)
		(end 190.253874 -315.849762)
		(stroke
			(width 0.1016)
			(type default)
		)
		(fill no)
		(layer "In1.Cu")
	)
	(gr_circle
		(center 189.999874 -312.049922)
		(end 190.253874 -312.049922)
		(stroke
			(width 0.1016)
			(type default)
		)
		(fill no)
		(layer "In1.Cu")
	)
	(gr_circle
		(center 189.999874 -311.099962)
		(end 190.253874 -311.099962)
		(stroke
			(width 0.1016)
			(type default)
		)
		(fill no)
		(layer "In1.Cu")
	)
	(gr_circle
		(center 189.999874 -280.699464)
		(end 190.253874 -280.699464)
		(stroke
			(width 0.1016)
			(type default)
		)
		(fill no)
		(layer "In1.Cu")
	)
	(gr_circle
		(center 189.999874 -279.749504)
		(end 190.253874 -279.749504)
		(stroke
			(width 0.1016)
			(type default)
		)
		(fill no)
		(layer "In1.Cu")
	)
	(gr_circle
		(center 190.949834 -278.799798)
		(end 191.203834 -278.799798)
		(stroke
			(width 0.1016)
			(type default)
		)
		(fill no)
		(layer "In1.Cu")
	)
	(gr_circle
		(center 190.949834 -277.849838)
		(end 191.203834 -277.849838)
		(stroke
			(width 0.1016)
			(type default)
		)
		(fill no)
		(layer "In1.Cu")
	)
	(gr_circle
		(center 190.949834 -274.049744)
		(end 191.203834 -274.049744)
		(stroke
			(width 0.1016)
			(type default)
		)
		(fill no)
		(layer "In1.Cu")
	)
	(gr_circle
		(center 190.949834 -273.099784)
		(end 191.203834 -273.099784)
		(stroke
			(width 0.1016)
			(type default)
		)
		(fill no)
		(layer "In1.Cu")
	)
	(gr_circle
		(center 190.950088 -318.699896)
		(end 191.204088 -318.699896)
		(stroke
			(width 0.1016)
			(type default)
		)
		(fill no)
		(layer "In1.Cu")
	)
	(gr_circle
		(center 190.950088 -317.749936)
		(end 191.204088 -317.749936)
		(stroke
			(width 0.1016)
			(type default)
		)
		(fill no)
		(layer "In1.Cu")
	)
	(gr_circle
		(center 190.950088 -313.949842)
		(end 191.204088 -313.949842)
		(stroke
			(width 0.1016)
			(type default)
		)
		(fill no)
		(layer "In1.Cu")
	)
	(gr_circle
		(center 190.950088 -312.999882)
		(end 191.204088 -312.999882)
		(stroke
			(width 0.1016)
			(type default)
		)
		(fill no)
		(layer "In1.Cu")
	)
	(gr_circle
		(center 190.950088 -308.249828)
		(end 191.204088 -308.249828)
		(stroke
			(width 0.1016)
			(type default)
		)
		(fill no)
		(layer "In1.Cu")
	)
	(gr_circle
		(center 190.950088 -306.349908)
		(end 191.204088 -306.349908)
		(stroke
			(width 0.1016)
			(type default)
		)
		(fill no)
		(layer "In1.Cu")
	)
	(gr_circle
		(center 190.950088 -304.449734)
		(end 191.204088 -304.449734)
		(stroke
			(width 0.1016)
			(type default)
		)
		(fill no)
		(layer "In1.Cu")
	)
	(gr_circle
		(center 190.950088 -287.349946)
		(end 191.204088 -287.349946)
		(stroke
			(width 0.1016)
			(type default)
		)
		(fill no)
		(layer "In1.Cu")
	)
	(gr_circle
		(center 190.950088 -285.449772)
		(end 191.204088 -285.449772)
		(stroke
			(width 0.1016)
			(type default)
		)
		(fill no)
		(layer "In1.Cu")
	)
	(gr_circle
		(center 190.950088 -283.549852)
		(end 191.204088 -283.549852)
		(stroke
			(width 0.1016)
			(type default)
		)
		(fill no)
		(layer "In1.Cu")
	)
	(gr_circle
		(center 191.899794 -275.949664)
		(end 192.153794 -275.949664)
		(stroke
			(width 0.1016)
			(type default)
		)
		(fill no)
		(layer "In1.Cu")
	)
	(gr_circle
		(center 191.899794 -274.999704)
		(end 192.153794 -274.999704)
		(stroke
			(width 0.1016)
			(type default)
		)
		(fill no)
		(layer "In1.Cu")
	)
	(gr_circle
		(center 191.900048 -316.799722)
		(end 192.154048 -316.799722)
		(stroke
			(width 0.1016)
			(type default)
		)
		(fill no)
		(layer "In1.Cu")
	)
	(gr_circle
		(center 191.900048 -315.849762)
		(end 192.154048 -315.849762)
		(stroke
			(width 0.1016)
			(type default)
		)
		(fill no)
		(layer "In1.Cu")
	)
	(gr_circle
		(center 191.900048 -312.049922)
		(end 192.154048 -312.049922)
		(stroke
			(width 0.1016)
			(type default)
		)
		(fill no)
		(layer "In1.Cu")
	)
	(gr_circle
		(center 191.900048 -311.099962)
		(end 192.154048 -311.099962)
		(stroke
			(width 0.1016)
			(type default)
		)
		(fill no)
		(layer "In1.Cu")
	)
	(gr_circle
		(center 191.900048 -308.249828)
		(end 192.154048 -308.249828)
		(stroke
			(width 0.1016)
			(type default)
		)
		(fill no)
		(layer "In1.Cu")
	)
	(gr_circle
		(center 191.900048 -306.349908)
		(end 192.154048 -306.349908)
		(stroke
			(width 0.1016)
			(type default)
		)
		(fill no)
		(layer "In1.Cu")
	)
	(gr_circle
		(center 191.900048 -304.449734)
		(end 192.154048 -304.449734)
		(stroke
			(width 0.1016)
			(type default)
		)
		(fill no)
		(layer "In1.Cu")
	)
	(gr_circle
		(center 191.900048 -287.349946)
		(end 192.154048 -287.349946)
		(stroke
			(width 0.1016)
			(type default)
		)
		(fill no)
		(layer "In1.Cu")
	)
	(gr_circle
		(center 191.900048 -285.449772)
		(end 192.154048 -285.449772)
		(stroke
			(width 0.1016)
			(type default)
		)
		(fill no)
		(layer "In1.Cu")
	)
	(gr_circle
		(center 191.900048 -283.549852)
		(end 192.154048 -283.549852)
		(stroke
			(width 0.1016)
			(type default)
		)
		(fill no)
		(layer "In1.Cu")
	)
	(gr_circle
		(center 191.900048 -280.699464)
		(end 192.154048 -280.699464)
		(stroke
			(width 0.1016)
			(type default)
		)
		(fill no)
		(layer "In1.Cu")
	)
	(gr_circle
		(center 191.900048 -279.749504)
		(end 192.154048 -279.749504)
		(stroke
			(width 0.1016)
			(type default)
		)
		(fill no)
		(layer "In1.Cu")
	)
	(gr_circle
		(center 192.849754 -278.799798)
		(end 193.103754 -278.799798)
		(stroke
			(width 0.1016)
			(type default)
		)
		(fill no)
		(layer "In1.Cu")
	)
	(gr_circle
		(center 192.849754 -277.849838)
		(end 193.103754 -277.849838)
		(stroke
			(width 0.1016)
			(type default)
		)
		(fill no)
		(layer "In1.Cu")
	)
	(gr_circle
		(center 192.849754 -274.049744)
		(end 193.103754 -274.049744)
		(stroke
			(width 0.1016)
			(type default)
		)
		(fill no)
		(layer "In1.Cu")
	)
	(gr_circle
		(center 192.849754 -273.099784)
		(end 193.103754 -273.099784)
		(stroke
			(width 0.1016)
			(type default)
		)
		(fill no)
		(layer "In1.Cu")
	)
	(gr_circle
		(center 192.850008 -318.699896)
		(end 193.104008 -318.699896)
		(stroke
			(width 0.1016)
			(type default)
		)
		(fill no)
		(layer "In1.Cu")
	)
	(gr_circle
		(center 192.850008 -317.749936)
		(end 193.104008 -317.749936)
		(stroke
			(width 0.1016)
			(type default)
		)
		(fill no)
		(layer "In1.Cu")
	)
	(gr_circle
		(center 192.850008 -313.949842)
		(end 193.104008 -313.949842)
		(stroke
			(width 0.1016)
			(type default)
		)
		(fill no)
		(layer "In1.Cu")
	)
	(gr_circle
		(center 192.850008 -312.999882)
		(end 193.104008 -312.999882)
		(stroke
			(width 0.1016)
			(type default)
		)
		(fill no)
		(layer "In1.Cu")
	)
	(gr_circle
		(center 192.850008 -309.199788)
		(end 193.104008 -309.199788)
		(stroke
			(width 0.1016)
			(type default)
		)
		(fill no)
		(layer "In1.Cu")
	)
	(gr_circle
		(center 192.850008 -307.299868)
		(end 193.104008 -307.299868)
		(stroke
			(width 0.1016)
			(type default)
		)
		(fill no)
		(layer "In1.Cu")
	)
	(gr_circle
		(center 192.850008 -305.399948)
		(end 193.104008 -305.399948)
		(stroke
			(width 0.1016)
			(type default)
		)
		(fill no)
		(layer "In1.Cu")
	)
	(gr_circle
		(center 192.850008 -288.299906)
		(end 193.104008 -288.299906)
		(stroke
			(width 0.1016)
			(type default)
		)
		(fill no)
		(layer "In1.Cu")
	)
	(gr_circle
		(center 192.850008 -286.399986)
		(end 193.104008 -286.399986)
		(stroke
			(width 0.1016)
			(type default)
		)
		(fill no)
		(layer "In1.Cu")
	)
	(gr_circle
		(center 192.850008 -284.499812)
		(end 193.104008 -284.499812)
		(stroke
			(width 0.1016)
			(type default)
		)
		(fill no)
		(layer "In1.Cu")
	)
	(gr_circle
		(center 192.850008 -282.599892)
		(end 193.104008 -282.599892)
		(stroke
			(width 0.1016)
			(type default)
		)
		(fill no)
		(layer "In1.Cu")
	)
	(gr_circle
		(center 193.799714 -275.949918)
		(end 194.053714 -275.949918)
		(stroke
			(width 0.1016)
			(type default)
		)
		(fill no)
		(layer "In1.Cu")
	)
	(gr_circle
		(center 193.799714 -274.999958)
		(end 194.053714 -274.999958)
		(stroke
			(width 0.1016)
			(type default)
		)
		(fill no)
		(layer "In1.Cu")
	)
	(gr_circle
		(center 193.799968 -316.799722)
		(end 194.053968 -316.799722)
		(stroke
			(width 0.1016)
			(type default)
		)
		(fill no)
		(layer "In1.Cu")
	)
	(gr_circle
		(center 193.799968 -315.849762)
		(end 194.053968 -315.849762)
		(stroke
			(width 0.1016)
			(type default)
		)
		(fill no)
		(layer "In1.Cu")
	)
	(gr_circle
		(center 193.799968 -312.049922)
		(end 194.053968 -312.049922)
		(stroke
			(width 0.1016)
			(type default)
		)
		(fill no)
		(layer "In1.Cu")
	)
	(gr_circle
		(center 193.799968 -311.099962)
		(end 194.053968 -311.099962)
		(stroke
			(width 0.1016)
			(type default)
		)
		(fill no)
		(layer "In1.Cu")
	)
	(gr_circle
		(center 193.799968 -309.199788)
		(end 194.053968 -309.199788)
		(stroke
			(width 0.1016)
			(type default)
		)
		(fill no)
		(layer "In1.Cu")
	)
	(gr_circle
		(center 193.799968 -307.299868)
		(end 194.053968 -307.299868)
		(stroke
			(width 0.1016)
			(type default)
		)
		(fill no)
		(layer "In1.Cu")
	)
	(gr_circle
		(center 193.799968 -305.399948)
		(end 194.053968 -305.399948)
		(stroke
			(width 0.1016)
			(type default)
		)
		(fill no)
		(layer "In1.Cu")
	)
	(gr_circle
		(center 193.799968 -288.299906)
		(end 194.053968 -288.299906)
		(stroke
			(width 0.1016)
			(type default)
		)
		(fill no)
		(layer "In1.Cu")
	)
	(gr_circle
		(center 193.799968 -286.399986)
		(end 194.053968 -286.399986)
		(stroke
			(width 0.1016)
			(type default)
		)
		(fill no)
		(layer "In1.Cu")
	)
	(gr_circle
		(center 193.799968 -284.499812)
		(end 194.053968 -284.499812)
		(stroke
			(width 0.1016)
			(type default)
		)
		(fill no)
		(layer "In1.Cu")
	)
	(gr_circle
		(center 193.799968 -282.599892)
		(end 194.053968 -282.599892)
		(stroke
			(width 0.1016)
			(type default)
		)
		(fill no)
		(layer "In1.Cu")
	)
	(gr_circle
		(center 193.799968 -280.699464)
		(end 194.053968 -280.699464)
		(stroke
			(width 0.1016)
			(type default)
		)
		(fill no)
		(layer "In1.Cu")
	)
	(gr_circle
		(center 193.799968 -279.749504)
		(end 194.053968 -279.749504)
		(stroke
			(width 0.1016)
			(type default)
		)
		(fill no)
		(layer "In1.Cu")
	)
	(gr_circle
		(center 194.749674 -278.799798)
		(end 195.003674 -278.799798)
		(stroke
			(width 0.1016)
			(type default)
		)
		(fill no)
		(layer "In1.Cu")
	)
	(gr_circle
		(center 194.749674 -277.849838)
		(end 195.003674 -277.849838)
		(stroke
			(width 0.1016)
			(type default)
		)
		(fill no)
		(layer "In1.Cu")
	)
	(gr_circle
		(center 194.749674 -274.049744)
		(end 195.003674 -274.049744)
		(stroke
			(width 0.1016)
			(type default)
		)
		(fill no)
		(layer "In1.Cu")
	)
	(gr_circle
		(center 194.749674 -273.099784)
		(end 195.003674 -273.099784)
		(stroke
			(width 0.1016)
			(type default)
		)
		(fill no)
		(layer "In1.Cu")
	)
	(gr_circle
		(center 194.749928 -318.699896)
		(end 195.003928 -318.699896)
		(stroke
			(width 0.1016)
			(type default)
		)
		(fill no)
		(layer "In1.Cu")
	)
	(gr_circle
		(center 194.749928 -317.749936)
		(end 195.003928 -317.749936)
		(stroke
			(width 0.1016)
			(type default)
		)
		(fill no)
		(layer "In1.Cu")
	)
	(gr_circle
		(center 194.749928 -313.949842)
		(end 195.003928 -313.949842)
		(stroke
			(width 0.1016)
			(type default)
		)
		(fill no)
		(layer "In1.Cu")
	)
	(gr_circle
		(center 194.749928 -312.999882)
		(end 195.003928 -312.999882)
		(stroke
			(width 0.1016)
			(type default)
		)
		(fill no)
		(layer "In1.Cu")
	)
	(gr_circle
		(center 195.699634 -275.949918)
		(end 195.953634 -275.949918)
		(stroke
			(width 0.1016)
			(type default)
		)
		(fill no)
		(layer "In1.Cu")
	)
	(gr_circle
		(center 195.699634 -274.999958)
		(end 195.953634 -274.999958)
		(stroke
			(width 0.1016)
			(type default)
		)
		(fill no)
		(layer "In1.Cu")
	)
	(gr_circle
		(center 195.699888 -316.799722)
		(end 195.953888 -316.799722)
		(stroke
			(width 0.1016)
			(type default)
		)
		(fill no)
		(layer "In1.Cu")
	)
	(gr_circle
		(center 195.699888 -315.849762)
		(end 195.953888 -315.849762)
		(stroke
			(width 0.1016)
			(type default)
		)
		(fill no)
		(layer "In1.Cu")
	)
	(gr_circle
		(center 195.699888 -312.049922)
		(end 195.953888 -312.049922)
		(stroke
			(width 0.1016)
			(type default)
		)
		(fill no)
		(layer "In1.Cu")
	)
	(gr_circle
		(center 195.699888 -311.099962)
		(end 195.953888 -311.099962)
		(stroke
			(width 0.1016)
			(type default)
		)
		(fill no)
		(layer "In1.Cu")
	)
	(gr_circle
		(center 195.699888 -309.199788)
		(end 195.953888 -309.199788)
		(stroke
			(width 0.1016)
			(type default)
		)
		(fill no)
		(layer "In1.Cu")
	)
	(gr_circle
		(center 195.699888 -307.299868)
		(end 195.953888 -307.299868)
		(stroke
			(width 0.1016)
			(type default)
		)
		(fill no)
		(layer "In1.Cu")
	)
	(gr_circle
		(center 195.699888 -305.399948)
		(end 195.953888 -305.399948)
		(stroke
			(width 0.1016)
			(type default)
		)
		(fill no)
		(layer "In1.Cu")
	)
	(gr_circle
		(center 195.699888 -288.299906)
		(end 195.953888 -288.299906)
		(stroke
			(width 0.1016)
			(type default)
		)
		(fill no)
		(layer "In1.Cu")
	)
	(gr_circle
		(center 195.699888 -286.399732)
		(end 195.953888 -286.399732)
		(stroke
			(width 0.1016)
			(type default)
		)
		(fill no)
		(layer "In1.Cu")
	)
	(gr_circle
		(center 195.699888 -284.499812)
		(end 195.953888 -284.499812)
		(stroke
			(width 0.1016)
			(type default)
		)
		(fill no)
		(layer "In1.Cu")
	)
	(gr_circle
		(center 195.699888 -282.599892)
		(end 195.953888 -282.599892)
		(stroke
			(width 0.1016)
			(type default)
		)
		(fill no)
		(layer "In1.Cu")
	)
	(gr_circle
		(center 195.699888 -280.699718)
		(end 195.953888 -280.699718)
		(stroke
			(width 0.1016)
			(type default)
		)
		(fill no)
		(layer "In1.Cu")
	)
	(gr_circle
		(center 195.699888 -279.749758)
		(end 195.953888 -279.749758)
		(stroke
			(width 0.1016)
			(type default)
		)
		(fill no)
		(layer "In1.Cu")
	)
	(gr_circle
		(center 196.649594 -274.049744)
		(end 196.903594 -274.049744)
		(stroke
			(width 0.1016)
			(type default)
		)
		(fill no)
		(layer "In1.Cu")
	)
	(gr_circle
		(center 196.649594 -273.099784)
		(end 196.903594 -273.099784)
		(stroke
			(width 0.1016)
			(type default)
		)
		(fill no)
		(layer "In1.Cu")
	)
	(gr_circle
		(center 196.649848 -318.699896)
		(end 196.903848 -318.699896)
		(stroke
			(width 0.1016)
			(type default)
		)
		(fill no)
		(layer "In1.Cu")
	)
	(gr_circle
		(center 196.649848 -317.749936)
		(end 196.903848 -317.749936)
		(stroke
			(width 0.1016)
			(type default)
		)
		(fill no)
		(layer "In1.Cu")
	)
	(gr_circle
		(center 196.649848 -313.949842)
		(end 196.903848 -313.949842)
		(stroke
			(width 0.1016)
			(type default)
		)
		(fill no)
		(layer "In1.Cu")
	)
	(gr_circle
		(center 196.649848 -312.999882)
		(end 196.903848 -312.999882)
		(stroke
			(width 0.1016)
			(type default)
		)
		(fill no)
		(layer "In1.Cu")
	)
	(gr_circle
		(center 196.649848 -309.199788)
		(end 196.903848 -309.199788)
		(stroke
			(width 0.1016)
			(type default)
		)
		(fill no)
		(layer "In1.Cu")
	)
	(gr_circle
		(center 196.649848 -307.299868)
		(end 196.903848 -307.299868)
		(stroke
			(width 0.1016)
			(type default)
		)
		(fill no)
		(layer "In1.Cu")
	)
	(gr_circle
		(center 196.649848 -305.399948)
		(end 196.903848 -305.399948)
		(stroke
			(width 0.1016)
			(type default)
		)
		(fill no)
		(layer "In1.Cu")
	)
	(gr_circle
		(center 196.649848 -288.299906)
		(end 196.903848 -288.299906)
		(stroke
			(width 0.1016)
			(type default)
		)
		(fill no)
		(layer "In1.Cu")
	)
	(gr_circle
		(center 196.649848 -286.399732)
		(end 196.903848 -286.399732)
		(stroke
			(width 0.1016)
			(type default)
		)
		(fill no)
		(layer "In1.Cu")
	)
	(gr_circle
		(center 196.649848 -284.499812)
		(end 196.903848 -284.499812)
		(stroke
			(width 0.1016)
			(type default)
		)
		(fill no)
		(layer "In1.Cu")
	)
	(gr_circle
		(center 196.649848 -282.599892)
		(end 196.903848 -282.599892)
		(stroke
			(width 0.1016)
			(type default)
		)
		(fill no)
		(layer "In1.Cu")
	)
	(gr_circle
		(center 196.649848 -278.799798)
		(end 196.903848 -278.799798)
		(stroke
			(width 0.1016)
			(type default)
		)
		(fill no)
		(layer "In1.Cu")
	)
	(gr_circle
		(center 196.649848 -277.849838)
		(end 196.903848 -277.849838)
		(stroke
			(width 0.1016)
			(type default)
		)
		(fill no)
		(layer "In1.Cu")
	)
	(gr_circle
		(center 197.600062 -316.799722)
		(end 197.854062 -316.799722)
		(stroke
			(width 0.1016)
			(type default)
		)
		(fill no)
		(layer "In1.Cu")
	)
	(gr_circle
		(center 197.600062 -314.899802)
		(end 197.854062 -314.899802)
		(stroke
			(width 0.1016)
			(type default)
		)
		(fill no)
		(layer "In1.Cu")
	)
	(gr_circle
		(center 197.600062 -312.049922)
		(end 197.854062 -312.049922)
		(stroke
			(width 0.1016)
			(type default)
		)
		(fill no)
		(layer "In1.Cu")
	)
	(gr_circle
		(center 197.600062 -310.149748)
		(end 197.854062 -310.149748)
		(stroke
			(width 0.1016)
			(type default)
		)
		(fill no)
		(layer "In1.Cu")
	)
	(gr_circle
		(center 197.600062 -308.249828)
		(end 197.854062 -308.249828)
		(stroke
			(width 0.1016)
			(type default)
		)
		(fill no)
		(layer "In1.Cu")
	)
	(gr_circle
		(center 197.600062 -306.349908)
		(end 197.854062 -306.349908)
		(stroke
			(width 0.1016)
			(type default)
		)
		(fill no)
		(layer "In1.Cu")
	)
	(gr_circle
		(center 197.600062 -304.449734)
		(end 197.854062 -304.449734)
		(stroke
			(width 0.1016)
			(type default)
		)
		(fill no)
		(layer "In1.Cu")
	)
	(gr_circle
		(center 197.600062 -287.349946)
		(end 197.854062 -287.349946)
		(stroke
			(width 0.1016)
			(type default)
		)
		(fill no)
		(layer "In1.Cu")
	)
	(gr_circle
		(center 197.600062 -285.449772)
		(end 197.854062 -285.449772)
		(stroke
			(width 0.1016)
			(type default)
		)
		(fill no)
		(layer "In1.Cu")
	)
	(gr_circle
		(center 197.600062 -283.549852)
		(end 197.854062 -283.549852)
		(stroke
			(width 0.1016)
			(type default)
		)
		(fill no)
		(layer "In1.Cu")
	)
	(gr_circle
		(center 197.600062 -281.649932)
		(end 197.854062 -281.649932)
		(stroke
			(width 0.1016)
			(type default)
		)
		(fill no)
		(layer "In1.Cu")
	)
	(gr_circle
		(center 197.600062 -279.749758)
		(end 197.854062 -279.749758)
		(stroke
			(width 0.1016)
			(type default)
		)
		(fill no)
		(layer "In1.Cu")
	)
	(gr_circle
		(center 197.600062 -276.899878)
		(end 197.854062 -276.899878)
		(stroke
			(width 0.1016)
			(type default)
		)
		(fill no)
		(layer "In1.Cu")
	)
	(gr_circle
		(center 197.600062 -274.999704)
		(end 197.854062 -274.999704)
		(stroke
			(width 0.1016)
			(type default)
		)
		(fill no)
		(layer "In1.Cu")
	)
	(gr_circle
		(center 198.550022 -316.799722)
		(end 198.804022 -316.799722)
		(stroke
			(width 0.1016)
			(type default)
		)
		(fill no)
		(layer "In1.Cu")
	)
	(gr_circle
		(center 198.550022 -314.899802)
		(end 198.804022 -314.899802)
		(stroke
			(width 0.1016)
			(type default)
		)
		(fill no)
		(layer "In1.Cu")
	)
	(gr_circle
		(center 198.550022 -312.049922)
		(end 198.804022 -312.049922)
		(stroke
			(width 0.1016)
			(type default)
		)
		(fill no)
		(layer "In1.Cu")
	)
	(gr_circle
		(center 198.550022 -310.149748)
		(end 198.804022 -310.149748)
		(stroke
			(width 0.1016)
			(type default)
		)
		(fill no)
		(layer "In1.Cu")
	)
	(gr_circle
		(center 198.550022 -308.249828)
		(end 198.804022 -308.249828)
		(stroke
			(width 0.1016)
			(type default)
		)
		(fill no)
		(layer "In1.Cu")
	)
	(gr_circle
		(center 198.550022 -306.349908)
		(end 198.804022 -306.349908)
		(stroke
			(width 0.1016)
			(type default)
		)
		(fill no)
		(layer "In1.Cu")
	)
	(gr_circle
		(center 198.550022 -304.449734)
		(end 198.804022 -304.449734)
		(stroke
			(width 0.1016)
			(type default)
		)
		(fill no)
		(layer "In1.Cu")
	)
	(gr_circle
		(center 198.550022 -287.349946)
		(end 198.804022 -287.349946)
		(stroke
			(width 0.1016)
			(type default)
		)
		(fill no)
		(layer "In1.Cu")
	)
	(gr_circle
		(center 198.550022 -285.449772)
		(end 198.804022 -285.449772)
		(stroke
			(width 0.1016)
			(type default)
		)
		(fill no)
		(layer "In1.Cu")
	)
	(gr_circle
		(center 198.550022 -283.549852)
		(end 198.804022 -283.549852)
		(stroke
			(width 0.1016)
			(type default)
		)
		(fill no)
		(layer "In1.Cu")
	)
	(gr_circle
		(center 198.550022 -281.649932)
		(end 198.804022 -281.649932)
		(stroke
			(width 0.1016)
			(type default)
		)
		(fill no)
		(layer "In1.Cu")
	)
	(gr_circle
		(center 198.550022 -279.749758)
		(end 198.804022 -279.749758)
		(stroke
			(width 0.1016)
			(type default)
		)
		(fill no)
		(layer "In1.Cu")
	)
	(gr_circle
		(center 198.550022 -276.899878)
		(end 198.804022 -276.899878)
		(stroke
			(width 0.1016)
			(type default)
		)
		(fill no)
		(layer "In1.Cu")
	)
	(gr_circle
		(center 198.550022 -274.999704)
		(end 198.804022 -274.999704)
		(stroke
			(width 0.1016)
			(type default)
		)
		(fill no)
		(layer "In1.Cu")
	)
	(gr_circle
		(center 269.049754 -316.799722)
		(end 269.303754 -316.799722)
		(stroke
			(width 0.1016)
			(type default)
		)
		(fill no)
		(layer "In1.Cu")
	)
	(gr_circle
		(center 269.049754 -314.899802)
		(end 269.303754 -314.899802)
		(stroke
			(width 0.1016)
			(type default)
		)
		(fill no)
		(layer "In1.Cu")
	)
	(gr_circle
		(center 269.049754 -312.049922)
		(end 269.303754 -312.049922)
		(stroke
			(width 0.1016)
			(type default)
		)
		(fill no)
		(layer "In1.Cu")
	)
	(gr_circle
		(center 269.049754 -310.149748)
		(end 269.303754 -310.149748)
		(stroke
			(width 0.1016)
			(type default)
		)
		(fill no)
		(layer "In1.Cu")
	)
	(gr_circle
		(center 269.049754 -308.249828)
		(end 269.303754 -308.249828)
		(stroke
			(width 0.1016)
			(type default)
		)
		(fill no)
		(layer "In1.Cu")
	)
	(gr_circle
		(center 269.049754 -306.349908)
		(end 269.303754 -306.349908)
		(stroke
			(width 0.1016)
			(type default)
		)
		(fill no)
		(layer "In1.Cu")
	)
	(gr_circle
		(center 269.049754 -304.449734)
		(end 269.303754 -304.449734)
		(stroke
			(width 0.1016)
			(type default)
		)
		(fill no)
		(layer "In1.Cu")
	)
	(gr_circle
		(center 269.049754 -302.549814)
		(end 269.303754 -302.549814)
		(stroke
			(width 0.1016)
			(type default)
		)
		(fill no)
		(layer "In1.Cu")
	)
	(gr_circle
		(center 269.999714 -316.799722)
		(end 270.253714 -316.799722)
		(stroke
			(width 0.1016)
			(type default)
		)
		(fill no)
		(layer "In1.Cu")
	)
	(gr_circle
		(center 269.999714 -314.899802)
		(end 270.253714 -314.899802)
		(stroke
			(width 0.1016)
			(type default)
		)
		(fill no)
		(layer "In1.Cu")
	)
	(gr_circle
		(center 269.999714 -312.049922)
		(end 270.253714 -312.049922)
		(stroke
			(width 0.1016)
			(type default)
		)
		(fill no)
		(layer "In1.Cu")
	)
	(gr_circle
		(center 269.999714 -310.149748)
		(end 270.253714 -310.149748)
		(stroke
			(width 0.1016)
			(type default)
		)
		(fill no)
		(layer "In1.Cu")
	)
	(gr_circle
		(center 269.999714 -308.249828)
		(end 270.253714 -308.249828)
		(stroke
			(width 0.1016)
			(type default)
		)
		(fill no)
		(layer "In1.Cu")
	)
	(gr_circle
		(center 269.999714 -306.349908)
		(end 270.253714 -306.349908)
		(stroke
			(width 0.1016)
			(type default)
		)
		(fill no)
		(layer "In1.Cu")
	)
	(gr_circle
		(center 269.999714 -304.449734)
		(end 270.253714 -304.449734)
		(stroke
			(width 0.1016)
			(type default)
		)
		(fill no)
		(layer "In1.Cu")
	)
	(gr_circle
		(center 269.999714 -302.549814)
		(end 270.253714 -302.549814)
		(stroke
			(width 0.1016)
			(type default)
		)
		(fill no)
		(layer "In1.Cu")
	)
	(gr_circle
		(center 270.949928 -318.699896)
		(end 271.203928 -318.699896)
		(stroke
			(width 0.1016)
			(type default)
		)
		(fill no)
		(layer "In1.Cu")
	)
	(gr_circle
		(center 270.949928 -317.749936)
		(end 271.203928 -317.749936)
		(stroke
			(width 0.1016)
			(type default)
		)
		(fill no)
		(layer "In1.Cu")
	)
	(gr_circle
		(center 270.949928 -313.949842)
		(end 271.203928 -313.949842)
		(stroke
			(width 0.1016)
			(type default)
		)
		(fill no)
		(layer "In1.Cu")
	)
	(gr_circle
		(center 270.949928 -312.999882)
		(end 271.203928 -312.999882)
		(stroke
			(width 0.1016)
			(type default)
		)
		(fill no)
		(layer "In1.Cu")
	)
	(gr_circle
		(center 270.949928 -309.199788)
		(end 271.203928 -309.199788)
		(stroke
			(width 0.1016)
			(type default)
		)
		(fill no)
		(layer "In1.Cu")
	)
	(gr_circle
		(center 270.949928 -307.299868)
		(end 271.203928 -307.299868)
		(stroke
			(width 0.1016)
			(type default)
		)
		(fill no)
		(layer "In1.Cu")
	)
	(gr_circle
		(center 270.949928 -305.399948)
		(end 271.203928 -305.399948)
		(stroke
			(width 0.1016)
			(type default)
		)
		(fill no)
		(layer "In1.Cu")
	)
	(gr_circle
		(center 270.949928 -303.499774)
		(end 271.203928 -303.499774)
		(stroke
			(width 0.1016)
			(type default)
		)
		(fill no)
		(layer "In1.Cu")
	)
	(gr_circle
		(center 270.949928 -301.599854)
		(end 271.203928 -301.599854)
		(stroke
			(width 0.1016)
			(type default)
		)
		(fill no)
		(layer "In1.Cu")
	)
	(gr_circle
		(center 271.899888 -316.799722)
		(end 272.153888 -316.799722)
		(stroke
			(width 0.1016)
			(type default)
		)
		(fill no)
		(layer "In1.Cu")
	)
	(gr_circle
		(center 271.899888 -315.849762)
		(end 272.153888 -315.849762)
		(stroke
			(width 0.1016)
			(type default)
		)
		(fill no)
		(layer "In1.Cu")
	)
	(gr_circle
		(center 271.899888 -312.049922)
		(end 272.153888 -312.049922)
		(stroke
			(width 0.1016)
			(type default)
		)
		(fill no)
		(layer "In1.Cu")
	)
	(gr_circle
		(center 271.899888 -311.099962)
		(end 272.153888 -311.099962)
		(stroke
			(width 0.1016)
			(type default)
		)
		(fill no)
		(layer "In1.Cu")
	)
	(gr_circle
		(center 271.899888 -309.199788)
		(end 272.153888 -309.199788)
		(stroke
			(width 0.1016)
			(type default)
		)
		(fill no)
		(layer "In1.Cu")
	)
	(gr_circle
		(center 271.899888 -307.299868)
		(end 272.153888 -307.299868)
		(stroke
			(width 0.1016)
			(type default)
		)
		(fill no)
		(layer "In1.Cu")
	)
	(gr_circle
		(center 271.899888 -305.399948)
		(end 272.153888 -305.399948)
		(stroke
			(width 0.1016)
			(type default)
		)
		(fill no)
		(layer "In1.Cu")
	)
	(gr_circle
		(center 271.899888 -303.499774)
		(end 272.153888 -303.499774)
		(stroke
			(width 0.1016)
			(type default)
		)
		(fill no)
		(layer "In1.Cu")
	)
	(gr_circle
		(center 271.899888 -301.599854)
		(end 272.153888 -301.599854)
		(stroke
			(width 0.1016)
			(type default)
		)
		(fill no)
		(layer "In1.Cu")
	)
	(gr_circle
		(center 272.849848 -318.699896)
		(end 273.103848 -318.699896)
		(stroke
			(width 0.1016)
			(type default)
		)
		(fill no)
		(layer "In1.Cu")
	)
	(gr_circle
		(center 272.849848 -317.749936)
		(end 273.103848 -317.749936)
		(stroke
			(width 0.1016)
			(type default)
		)
		(fill no)
		(layer "In1.Cu")
	)
	(gr_circle
		(center 272.849848 -313.949842)
		(end 273.103848 -313.949842)
		(stroke
			(width 0.1016)
			(type default)
		)
		(fill no)
		(layer "In1.Cu")
	)
	(gr_circle
		(center 272.849848 -312.999882)
		(end 273.103848 -312.999882)
		(stroke
			(width 0.1016)
			(type default)
		)
		(fill no)
		(layer "In1.Cu")
	)
	(gr_circle
		(center 273.799808 -316.799722)
		(end 274.053808 -316.799722)
		(stroke
			(width 0.1016)
			(type default)
		)
		(fill no)
		(layer "In1.Cu")
	)
	(gr_circle
		(center 273.799808 -315.849762)
		(end 274.053808 -315.849762)
		(stroke
			(width 0.1016)
			(type default)
		)
		(fill no)
		(layer "In1.Cu")
	)
	(gr_circle
		(center 273.799808 -312.049922)
		(end 274.053808 -312.049922)
		(stroke
			(width 0.1016)
			(type default)
		)
		(fill no)
		(layer "In1.Cu")
	)
	(gr_circle
		(center 273.799808 -311.099962)
		(end 274.053808 -311.099962)
		(stroke
			(width 0.1016)
			(type default)
		)
		(fill no)
		(layer "In1.Cu")
	)
	(gr_circle
		(center 273.799808 -309.199788)
		(end 274.053808 -309.199788)
		(stroke
			(width 0.1016)
			(type default)
		)
		(fill no)
		(layer "In1.Cu")
	)
	(gr_circle
		(center 273.799808 -307.299868)
		(end 274.053808 -307.299868)
		(stroke
			(width 0.1016)
			(type default)
		)
		(fill no)
		(layer "In1.Cu")
	)
	(gr_circle
		(center 273.799808 -305.399948)
		(end 274.053808 -305.399948)
		(stroke
			(width 0.1016)
			(type default)
		)
		(fill no)
		(layer "In1.Cu")
	)
	(gr_circle
		(center 273.799808 -303.499774)
		(end 274.053808 -303.499774)
		(stroke
			(width 0.1016)
			(type default)
		)
		(fill no)
		(layer "In1.Cu")
	)
	(gr_circle
		(center 273.799808 -301.599854)
		(end 274.053808 -301.599854)
		(stroke
			(width 0.1016)
			(type default)
		)
		(fill no)
		(layer "In1.Cu")
	)
	(gr_circle
		(center 274.749768 -318.699896)
		(end 275.003768 -318.699896)
		(stroke
			(width 0.1016)
			(type default)
		)
		(fill no)
		(layer "In1.Cu")
	)
	(gr_circle
		(center 274.749768 -317.749936)
		(end 275.003768 -317.749936)
		(stroke
			(width 0.1016)
			(type default)
		)
		(fill no)
		(layer "In1.Cu")
	)
	(gr_circle
		(center 274.749768 -313.949842)
		(end 275.003768 -313.949842)
		(stroke
			(width 0.1016)
			(type default)
		)
		(fill no)
		(layer "In1.Cu")
	)
	(gr_circle
		(center 274.749768 -312.999882)
		(end 275.003768 -312.999882)
		(stroke
			(width 0.1016)
			(type default)
		)
		(fill no)
		(layer "In1.Cu")
	)
	(gr_circle
		(center 274.749768 -309.199788)
		(end 275.003768 -309.199788)
		(stroke
			(width 0.1016)
			(type default)
		)
		(fill no)
		(layer "In1.Cu")
	)
	(gr_circle
		(center 274.749768 -307.299868)
		(end 275.003768 -307.299868)
		(stroke
			(width 0.1016)
			(type default)
		)
		(fill no)
		(layer "In1.Cu")
	)
	(gr_circle
		(center 274.749768 -305.399948)
		(end 275.003768 -305.399948)
		(stroke
			(width 0.1016)
			(type default)
		)
		(fill no)
		(layer "In1.Cu")
	)
	(gr_circle
		(center 274.749768 -303.499774)
		(end 275.003768 -303.499774)
		(stroke
			(width 0.1016)
			(type default)
		)
		(fill no)
		(layer "In1.Cu")
	)
	(gr_circle
		(center 274.749768 -301.599854)
		(end 275.003768 -301.599854)
		(stroke
			(width 0.1016)
			(type default)
		)
		(fill no)
		(layer "In1.Cu")
	)
	(gr_circle
		(center 275.699728 -316.799722)
		(end 275.953728 -316.799722)
		(stroke
			(width 0.1016)
			(type default)
		)
		(fill no)
		(layer "In1.Cu")
	)
	(gr_circle
		(center 275.699728 -315.849762)
		(end 275.953728 -315.849762)
		(stroke
			(width 0.1016)
			(type default)
		)
		(fill no)
		(layer "In1.Cu")
	)
	(gr_circle
		(center 275.699728 -312.049922)
		(end 275.953728 -312.049922)
		(stroke
			(width 0.1016)
			(type default)
		)
		(fill no)
		(layer "In1.Cu")
	)
	(gr_circle
		(center 275.699728 -311.099962)
		(end 275.953728 -311.099962)
		(stroke
			(width 0.1016)
			(type default)
		)
		(fill no)
		(layer "In1.Cu")
	)
	(gr_circle
		(center 275.699728 -308.249828)
		(end 275.953728 -308.249828)
		(stroke
			(width 0.1016)
			(type default)
		)
		(fill no)
		(layer "In1.Cu")
	)
	(gr_circle
		(center 275.699728 -306.349908)
		(end 275.953728 -306.349908)
		(stroke
			(width 0.1016)
			(type default)
		)
		(fill no)
		(layer "In1.Cu")
	)
	(gr_circle
		(center 275.699728 -304.449734)
		(end 275.953728 -304.449734)
		(stroke
			(width 0.1016)
			(type default)
		)
		(fill no)
		(layer "In1.Cu")
	)
	(gr_circle
		(center 275.699728 -302.549814)
		(end 275.953728 -302.549814)
		(stroke
			(width 0.1016)
			(type default)
		)
		(fill no)
		(layer "In1.Cu")
	)
	(gr_circle
		(center 276.649688 -318.699896)
		(end 276.903688 -318.699896)
		(stroke
			(width 0.1016)
			(type default)
		)
		(fill no)
		(layer "In1.Cu")
	)
	(gr_circle
		(center 276.649688 -317.749936)
		(end 276.903688 -317.749936)
		(stroke
			(width 0.1016)
			(type default)
		)
		(fill no)
		(layer "In1.Cu")
	)
	(gr_circle
		(center 276.649688 -313.949842)
		(end 276.903688 -313.949842)
		(stroke
			(width 0.1016)
			(type default)
		)
		(fill no)
		(layer "In1.Cu")
	)
	(gr_circle
		(center 276.649688 -312.999882)
		(end 276.903688 -312.999882)
		(stroke
			(width 0.1016)
			(type default)
		)
		(fill no)
		(layer "In1.Cu")
	)
	(gr_circle
		(center 276.649688 -308.249828)
		(end 276.903688 -308.249828)
		(stroke
			(width 0.1016)
			(type default)
		)
		(fill no)
		(layer "In1.Cu")
	)
	(gr_circle
		(center 276.649688 -306.349908)
		(end 276.903688 -306.349908)
		(stroke
			(width 0.1016)
			(type default)
		)
		(fill no)
		(layer "In1.Cu")
	)
	(gr_circle
		(center 276.649688 -304.449734)
		(end 276.903688 -304.449734)
		(stroke
			(width 0.1016)
			(type default)
		)
		(fill no)
		(layer "In1.Cu")
	)
	(gr_circle
		(center 276.649688 -302.549814)
		(end 276.903688 -302.549814)
		(stroke
			(width 0.1016)
			(type default)
		)
		(fill no)
		(layer "In1.Cu")
	)
	(gr_circle
		(center 276.649688 -278.799798)
		(end 276.903688 -278.799798)
		(stroke
			(width 0.1016)
			(type default)
		)
		(fill no)
		(layer "In1.Cu")
	)
	(gr_circle
		(center 276.649688 -277.849838)
		(end 276.903688 -277.849838)
		(stroke
			(width 0.1016)
			(type default)
		)
		(fill no)
		(layer "In1.Cu")
	)
	(gr_circle
		(center 276.649688 -274.049744)
		(end 276.903688 -274.049744)
		(stroke
			(width 0.1016)
			(type default)
		)
		(fill no)
		(layer "In1.Cu")
	)
	(gr_circle
		(center 276.649688 -273.099784)
		(end 276.903688 -273.099784)
		(stroke
			(width 0.1016)
			(type default)
		)
		(fill no)
		(layer "In1.Cu")
	)
	(gr_circle
		(center 277.599902 -316.799722)
		(end 277.853902 -316.799722)
		(stroke
			(width 0.1016)
			(type default)
		)
		(fill no)
		(layer "In1.Cu")
	)
	(gr_circle
		(center 277.599902 -315.849762)
		(end 277.853902 -315.849762)
		(stroke
			(width 0.1016)
			(type default)
		)
		(fill no)
		(layer "In1.Cu")
	)
	(gr_circle
		(center 277.599902 -312.049922)
		(end 277.853902 -312.049922)
		(stroke
			(width 0.1016)
			(type default)
		)
		(fill no)
		(layer "In1.Cu")
	)
	(gr_circle
		(center 277.599902 -311.099962)
		(end 277.853902 -311.099962)
		(stroke
			(width 0.1016)
			(type default)
		)
		(fill no)
		(layer "In1.Cu")
	)
	(gr_circle
		(center 277.599902 -280.699464)
		(end 277.853902 -280.699464)
		(stroke
			(width 0.1016)
			(type default)
		)
		(fill no)
		(layer "In1.Cu")
	)
	(gr_circle
		(center 277.599902 -279.749504)
		(end 277.853902 -279.749504)
		(stroke
			(width 0.1016)
			(type default)
		)
		(fill no)
		(layer "In1.Cu")
	)
	(gr_circle
		(center 277.599902 -275.949918)
		(end 277.853902 -275.949918)
		(stroke
			(width 0.1016)
			(type default)
		)
		(fill no)
		(layer "In1.Cu")
	)
	(gr_circle
		(center 277.599902 -274.999958)
		(end 277.853902 -274.999958)
		(stroke
			(width 0.1016)
			(type default)
		)
		(fill no)
		(layer "In1.Cu")
	)
	(gr_circle
		(center 278.549862 -318.699896)
		(end 278.803862 -318.699896)
		(stroke
			(width 0.1016)
			(type default)
		)
		(fill no)
		(layer "In1.Cu")
	)
	(gr_circle
		(center 278.549862 -317.749936)
		(end 278.803862 -317.749936)
		(stroke
			(width 0.1016)
			(type default)
		)
		(fill no)
		(layer "In1.Cu")
	)
	(gr_circle
		(center 278.549862 -313.949842)
		(end 278.803862 -313.949842)
		(stroke
			(width 0.1016)
			(type default)
		)
		(fill no)
		(layer "In1.Cu")
	)
	(gr_circle
		(center 278.549862 -312.999882)
		(end 278.803862 -312.999882)
		(stroke
			(width 0.1016)
			(type default)
		)
		(fill no)
		(layer "In1.Cu")
	)
	(gr_circle
		(center 278.549862 -278.799798)
		(end 278.803862 -278.799798)
		(stroke
			(width 0.1016)
			(type default)
		)
		(fill no)
		(layer "In1.Cu")
	)
	(gr_circle
		(center 278.549862 -277.849838)
		(end 278.803862 -277.849838)
		(stroke
			(width 0.1016)
			(type default)
		)
		(fill no)
		(layer "In1.Cu")
	)
	(gr_circle
		(center 278.549862 -274.049744)
		(end 278.803862 -274.049744)
		(stroke
			(width 0.1016)
			(type default)
		)
		(fill no)
		(layer "In1.Cu")
	)
	(gr_circle
		(center 278.549862 -273.099784)
		(end 278.803862 -273.099784)
		(stroke
			(width 0.1016)
			(type default)
		)
		(fill no)
		(layer "In1.Cu")
	)
	(gr_circle
		(center 279.499822 -316.799722)
		(end 279.753822 -316.799722)
		(stroke
			(width 0.1016)
			(type default)
		)
		(fill no)
		(layer "In1.Cu")
	)
	(gr_circle
		(center 279.499822 -315.849762)
		(end 279.753822 -315.849762)
		(stroke
			(width 0.1016)
			(type default)
		)
		(fill no)
		(layer "In1.Cu")
	)
	(gr_circle
		(center 279.499822 -312.049922)
		(end 279.753822 -312.049922)
		(stroke
			(width 0.1016)
			(type default)
		)
		(fill no)
		(layer "In1.Cu")
	)
	(gr_circle
		(center 279.499822 -311.099962)
		(end 279.753822 -311.099962)
		(stroke
			(width 0.1016)
			(type default)
		)
		(fill no)
		(layer "In1.Cu")
	)
	(gr_circle
		(center 279.499822 -280.699464)
		(end 279.753822 -280.699464)
		(stroke
			(width 0.1016)
			(type default)
		)
		(fill no)
		(layer "In1.Cu")
	)
	(gr_circle
		(center 279.499822 -279.749504)
		(end 279.753822 -279.749504)
		(stroke
			(width 0.1016)
			(type default)
		)
		(fill no)
		(layer "In1.Cu")
	)
	(gr_circle
		(center 279.499822 -275.949918)
		(end 279.753822 -275.949918)
		(stroke
			(width 0.1016)
			(type default)
		)
		(fill no)
		(layer "In1.Cu")
	)
	(gr_circle
		(center 279.499822 -274.999958)
		(end 279.753822 -274.999958)
		(stroke
			(width 0.1016)
			(type default)
		)
		(fill no)
		(layer "In1.Cu")
	)
	(gr_circle
		(center 280.449782 -318.699896)
		(end 280.703782 -318.699896)
		(stroke
			(width 0.1016)
			(type default)
		)
		(fill no)
		(layer "In1.Cu")
	)
	(gr_circle
		(center 280.449782 -317.749936)
		(end 280.703782 -317.749936)
		(stroke
			(width 0.1016)
			(type default)
		)
		(fill no)
		(layer "In1.Cu")
	)
	(gr_circle
		(center 280.449782 -313.949842)
		(end 280.703782 -313.949842)
		(stroke
			(width 0.1016)
			(type default)
		)
		(fill no)
		(layer "In1.Cu")
	)
	(gr_circle
		(center 280.449782 -312.999882)
		(end 280.703782 -312.999882)
		(stroke
			(width 0.1016)
			(type default)
		)
		(fill no)
		(layer "In1.Cu")
	)
	(gr_circle
		(center 280.449782 -278.799798)
		(end 280.703782 -278.799798)
		(stroke
			(width 0.1016)
			(type default)
		)
		(fill no)
		(layer "In1.Cu")
	)
	(gr_circle
		(center 280.449782 -277.849838)
		(end 280.703782 -277.849838)
		(stroke
			(width 0.1016)
			(type default)
		)
		(fill no)
		(layer "In1.Cu")
	)
	(gr_circle
		(center 280.449782 -274.049744)
		(end 280.703782 -274.049744)
		(stroke
			(width 0.1016)
			(type default)
		)
		(fill no)
		(layer "In1.Cu")
	)
	(gr_circle
		(center 280.449782 -273.099784)
		(end 280.703782 -273.099784)
		(stroke
			(width 0.1016)
			(type default)
		)
		(fill no)
		(layer "In1.Cu")
	)
	(gr_circle
		(center 281.399742 -316.799722)
		(end 281.653742 -316.799722)
		(stroke
			(width 0.1016)
			(type default)
		)
		(fill no)
		(layer "In1.Cu")
	)
	(gr_circle
		(center 281.399742 -315.849762)
		(end 281.653742 -315.849762)
		(stroke
			(width 0.1016)
			(type default)
		)
		(fill no)
		(layer "In1.Cu")
	)
	(gr_circle
		(center 281.399742 -312.049922)
		(end 281.653742 -312.049922)
		(stroke
			(width 0.1016)
			(type default)
		)
		(fill no)
		(layer "In1.Cu")
	)
	(gr_circle
		(center 281.399742 -311.099962)
		(end 281.653742 -311.099962)
		(stroke
			(width 0.1016)
			(type default)
		)
		(fill no)
		(layer "In1.Cu")
	)
	(gr_circle
		(center 281.399742 -280.699464)
		(end 281.653742 -280.699464)
		(stroke
			(width 0.1016)
			(type default)
		)
		(fill no)
		(layer "In1.Cu")
	)
	(gr_circle
		(center 281.399742 -279.749504)
		(end 281.653742 -279.749504)
		(stroke
			(width 0.1016)
			(type default)
		)
		(fill no)
		(layer "In1.Cu")
	)
	(gr_circle
		(center 281.399742 -275.949918)
		(end 281.653742 -275.949918)
		(stroke
			(width 0.1016)
			(type default)
		)
		(fill no)
		(layer "In1.Cu")
	)
	(gr_circle
		(center 281.399742 -274.999958)
		(end 281.653742 -274.999958)
		(stroke
			(width 0.1016)
			(type default)
		)
		(fill no)
		(layer "In1.Cu")
	)
	(gr_circle
		(center 282.349702 -318.699896)
		(end 282.603702 -318.699896)
		(stroke
			(width 0.1016)
			(type default)
		)
		(fill no)
		(layer "In1.Cu")
	)
	(gr_circle
		(center 282.349702 -317.749936)
		(end 282.603702 -317.749936)
		(stroke
			(width 0.1016)
			(type default)
		)
		(fill no)
		(layer "In1.Cu")
	)
	(gr_circle
		(center 282.349702 -313.949842)
		(end 282.603702 -313.949842)
		(stroke
			(width 0.1016)
			(type default)
		)
		(fill no)
		(layer "In1.Cu")
	)
	(gr_circle
		(center 282.349702 -312.999882)
		(end 282.603702 -312.999882)
		(stroke
			(width 0.1016)
			(type default)
		)
		(fill no)
		(layer "In1.Cu")
	)
	(gr_circle
		(center 282.349702 -278.799798)
		(end 282.603702 -278.799798)
		(stroke
			(width 0.1016)
			(type default)
		)
		(fill no)
		(layer "In1.Cu")
	)
	(gr_circle
		(center 282.349702 -277.849838)
		(end 282.603702 -277.849838)
		(stroke
			(width 0.1016)
			(type default)
		)
		(fill no)
		(layer "In1.Cu")
	)
	(gr_circle
		(center 282.349702 -274.049744)
		(end 282.603702 -274.049744)
		(stroke
			(width 0.1016)
			(type default)
		)
		(fill no)
		(layer "In1.Cu")
	)
	(gr_circle
		(center 282.349702 -273.099784)
		(end 282.603702 -273.099784)
		(stroke
			(width 0.1016)
			(type default)
		)
		(fill no)
		(layer "In1.Cu")
	)
	(gr_circle
		(center 283.299916 -316.799722)
		(end 283.553916 -316.799722)
		(stroke
			(width 0.1016)
			(type default)
		)
		(fill no)
		(layer "In1.Cu")
	)
	(gr_circle
		(center 283.299916 -315.849762)
		(end 283.553916 -315.849762)
		(stroke
			(width 0.1016)
			(type default)
		)
		(fill no)
		(layer "In1.Cu")
	)
	(gr_circle
		(center 283.299916 -312.049922)
		(end 283.553916 -312.049922)
		(stroke
			(width 0.1016)
			(type default)
		)
		(fill no)
		(layer "In1.Cu")
	)
	(gr_circle
		(center 283.299916 -311.099962)
		(end 283.553916 -311.099962)
		(stroke
			(width 0.1016)
			(type default)
		)
		(fill no)
		(layer "In1.Cu")
	)
	(gr_circle
		(center 283.299916 -280.699464)
		(end 283.553916 -280.699464)
		(stroke
			(width 0.1016)
			(type default)
		)
		(fill no)
		(layer "In1.Cu")
	)
	(gr_circle
		(center 283.299916 -279.749504)
		(end 283.553916 -279.749504)
		(stroke
			(width 0.1016)
			(type default)
		)
		(fill no)
		(layer "In1.Cu")
	)
	(gr_circle
		(center 283.299916 -275.949918)
		(end 283.553916 -275.949918)
		(stroke
			(width 0.1016)
			(type default)
		)
		(fill no)
		(layer "In1.Cu")
	)
	(gr_circle
		(center 283.299916 -274.999958)
		(end 283.553916 -274.999958)
		(stroke
			(width 0.1016)
			(type default)
		)
		(fill no)
		(layer "In1.Cu")
	)
	(gr_circle
		(center 284.249876 -318.699896)
		(end 284.503876 -318.699896)
		(stroke
			(width 0.1016)
			(type default)
		)
		(fill no)
		(layer "In1.Cu")
	)
	(gr_circle
		(center 284.249876 -317.749936)
		(end 284.503876 -317.749936)
		(stroke
			(width 0.1016)
			(type default)
		)
		(fill no)
		(layer "In1.Cu")
	)
	(gr_circle
		(center 284.249876 -313.949842)
		(end 284.503876 -313.949842)
		(stroke
			(width 0.1016)
			(type default)
		)
		(fill no)
		(layer "In1.Cu")
	)
	(gr_circle
		(center 284.249876 -312.999882)
		(end 284.503876 -312.999882)
		(stroke
			(width 0.1016)
			(type default)
		)
		(fill no)
		(layer "In1.Cu")
	)
	(gr_circle
		(center 284.249876 -278.799798)
		(end 284.503876 -278.799798)
		(stroke
			(width 0.1016)
			(type default)
		)
		(fill no)
		(layer "In1.Cu")
	)
	(gr_circle
		(center 284.249876 -277.849838)
		(end 284.503876 -277.849838)
		(stroke
			(width 0.1016)
			(type default)
		)
		(fill no)
		(layer "In1.Cu")
	)
	(gr_circle
		(center 284.249876 -274.049744)
		(end 284.503876 -274.049744)
		(stroke
			(width 0.1016)
			(type default)
		)
		(fill no)
		(layer "In1.Cu")
	)
	(gr_circle
		(center 284.249876 -273.099784)
		(end 284.503876 -273.099784)
		(stroke
			(width 0.1016)
			(type default)
		)
		(fill no)
		(layer "In1.Cu")
	)
	(gr_circle
		(center 285.199836 -316.799722)
		(end 285.453836 -316.799722)
		(stroke
			(width 0.1016)
			(type default)
		)
		(fill no)
		(layer "In1.Cu")
	)
	(gr_circle
		(center 285.199836 -315.849762)
		(end 285.453836 -315.849762)
		(stroke
			(width 0.1016)
			(type default)
		)
		(fill no)
		(layer "In1.Cu")
	)
	(gr_circle
		(center 285.199836 -312.049922)
		(end 285.453836 -312.049922)
		(stroke
			(width 0.1016)
			(type default)
		)
		(fill no)
		(layer "In1.Cu")
	)
	(gr_circle
		(center 285.199836 -311.099962)
		(end 285.453836 -311.099962)
		(stroke
			(width 0.1016)
			(type default)
		)
		(fill no)
		(layer "In1.Cu")
	)
	(gr_circle
		(center 285.199836 -280.699464)
		(end 285.453836 -280.699464)
		(stroke
			(width 0.1016)
			(type default)
		)
		(fill no)
		(layer "In1.Cu")
	)
	(gr_circle
		(center 285.199836 -279.749504)
		(end 285.453836 -279.749504)
		(stroke
			(width 0.1016)
			(type default)
		)
		(fill no)
		(layer "In1.Cu")
	)
	(gr_circle
		(center 285.199836 -275.949918)
		(end 285.453836 -275.949918)
		(stroke
			(width 0.1016)
			(type default)
		)
		(fill no)
		(layer "In1.Cu")
	)
	(gr_circle
		(center 285.199836 -274.999958)
		(end 285.453836 -274.999958)
		(stroke
			(width 0.1016)
			(type default)
		)
		(fill no)
		(layer "In1.Cu")
	)
	(gr_circle
		(center 286.149796 -318.699896)
		(end 286.403796 -318.699896)
		(stroke
			(width 0.1016)
			(type default)
		)
		(fill no)
		(layer "In1.Cu")
	)
	(gr_circle
		(center 286.149796 -317.749936)
		(end 286.403796 -317.749936)
		(stroke
			(width 0.1016)
			(type default)
		)
		(fill no)
		(layer "In1.Cu")
	)
	(gr_circle
		(center 286.149796 -313.949842)
		(end 286.403796 -313.949842)
		(stroke
			(width 0.1016)
			(type default)
		)
		(fill no)
		(layer "In1.Cu")
	)
	(gr_circle
		(center 286.149796 -312.999882)
		(end 286.403796 -312.999882)
		(stroke
			(width 0.1016)
			(type default)
		)
		(fill no)
		(layer "In1.Cu")
	)
	(gr_circle
		(center 286.149796 -278.799798)
		(end 286.403796 -278.799798)
		(stroke
			(width 0.1016)
			(type default)
		)
		(fill no)
		(layer "In1.Cu")
	)
	(gr_circle
		(center 286.149796 -277.849838)
		(end 286.403796 -277.849838)
		(stroke
			(width 0.1016)
			(type default)
		)
		(fill no)
		(layer "In1.Cu")
	)
	(gr_circle
		(center 286.149796 -274.049744)
		(end 286.403796 -274.049744)
		(stroke
			(width 0.1016)
			(type default)
		)
		(fill no)
		(layer "In1.Cu")
	)
	(gr_circle
		(center 286.149796 -273.099784)
		(end 286.403796 -273.099784)
		(stroke
			(width 0.1016)
			(type default)
		)
		(fill no)
		(layer "In1.Cu")
	)
	(gr_circle
		(center 287.099756 -316.799722)
		(end 287.353756 -316.799722)
		(stroke
			(width 0.1016)
			(type default)
		)
		(fill no)
		(layer "In1.Cu")
	)
	(gr_circle
		(center 287.099756 -315.849762)
		(end 287.353756 -315.849762)
		(stroke
			(width 0.1016)
			(type default)
		)
		(fill no)
		(layer "In1.Cu")
	)
	(gr_circle
		(center 287.099756 -312.049922)
		(end 287.353756 -312.049922)
		(stroke
			(width 0.1016)
			(type default)
		)
		(fill no)
		(layer "In1.Cu")
	)
	(gr_circle
		(center 287.099756 -311.099962)
		(end 287.353756 -311.099962)
		(stroke
			(width 0.1016)
			(type default)
		)
		(fill no)
		(layer "In1.Cu")
	)
	(gr_circle
		(center 287.099756 -280.699464)
		(end 287.353756 -280.699464)
		(stroke
			(width 0.1016)
			(type default)
		)
		(fill no)
		(layer "In1.Cu")
	)
	(gr_circle
		(center 287.099756 -279.749504)
		(end 287.353756 -279.749504)
		(stroke
			(width 0.1016)
			(type default)
		)
		(fill no)
		(layer "In1.Cu")
	)
	(gr_circle
		(center 287.099756 -275.949918)
		(end 287.353756 -275.949918)
		(stroke
			(width 0.1016)
			(type default)
		)
		(fill no)
		(layer "In1.Cu")
	)
	(gr_circle
		(center 287.099756 -274.999958)
		(end 287.353756 -274.999958)
		(stroke
			(width 0.1016)
			(type default)
		)
		(fill no)
		(layer "In1.Cu")
	)
	(gr_circle
		(center 288.049716 -318.699896)
		(end 288.303716 -318.699896)
		(stroke
			(width 0.1016)
			(type default)
		)
		(fill no)
		(layer "In1.Cu")
	)
	(gr_circle
		(center 288.049716 -317.749936)
		(end 288.303716 -317.749936)
		(stroke
			(width 0.1016)
			(type default)
		)
		(fill no)
		(layer "In1.Cu")
	)
	(gr_circle
		(center 288.049716 -313.949842)
		(end 288.303716 -313.949842)
		(stroke
			(width 0.1016)
			(type default)
		)
		(fill no)
		(layer "In1.Cu")
	)
	(gr_circle
		(center 288.049716 -312.999882)
		(end 288.303716 -312.999882)
		(stroke
			(width 0.1016)
			(type default)
		)
		(fill no)
		(layer "In1.Cu")
	)
	(gr_circle
		(center 288.049716 -278.799798)
		(end 288.303716 -278.799798)
		(stroke
			(width 0.1016)
			(type default)
		)
		(fill no)
		(layer "In1.Cu")
	)
	(gr_circle
		(center 288.049716 -277.849838)
		(end 288.303716 -277.849838)
		(stroke
			(width 0.1016)
			(type default)
		)
		(fill no)
		(layer "In1.Cu")
	)
	(gr_circle
		(center 288.049716 -274.049744)
		(end 288.303716 -274.049744)
		(stroke
			(width 0.1016)
			(type default)
		)
		(fill no)
		(layer "In1.Cu")
	)
	(gr_circle
		(center 288.049716 -273.099784)
		(end 288.303716 -273.099784)
		(stroke
			(width 0.1016)
			(type default)
		)
		(fill no)
		(layer "In1.Cu")
	)
	(gr_circle
		(center 288.999676 -280.699464)
		(end 289.253676 -280.699464)
		(stroke
			(width 0.1016)
			(type default)
		)
		(fill no)
		(layer "In1.Cu")
	)
	(gr_circle
		(center 288.999676 -279.749504)
		(end 289.253676 -279.749504)
		(stroke
			(width 0.1016)
			(type default)
		)
		(fill no)
		(layer "In1.Cu")
	)
	(gr_circle
		(center 288.99993 -316.799722)
		(end 289.25393 -316.799722)
		(stroke
			(width 0.1016)
			(type default)
		)
		(fill no)
		(layer "In1.Cu")
	)
	(gr_circle
		(center 288.99993 -315.849762)
		(end 289.25393 -315.849762)
		(stroke
			(width 0.1016)
			(type default)
		)
		(fill no)
		(layer "In1.Cu")
	)
	(gr_circle
		(center 288.99993 -312.049922)
		(end 289.25393 -312.049922)
		(stroke
			(width 0.1016)
			(type default)
		)
		(fill no)
		(layer "In1.Cu")
	)
	(gr_circle
		(center 288.99993 -311.099962)
		(end 289.25393 -311.099962)
		(stroke
			(width 0.1016)
			(type default)
		)
		(fill no)
		(layer "In1.Cu")
	)
	(gr_circle
		(center 288.99993 -275.949918)
		(end 289.25393 -275.949918)
		(stroke
			(width 0.1016)
			(type default)
		)
		(fill no)
		(layer "In1.Cu")
	)
	(gr_circle
		(center 288.99993 -274.999958)
		(end 289.25393 -274.999958)
		(stroke
			(width 0.1016)
			(type default)
		)
		(fill no)
		(layer "In1.Cu")
	)
	(gr_circle
		(center 289.94989 -318.699896)
		(end 290.20389 -318.699896)
		(stroke
			(width 0.1016)
			(type default)
		)
		(fill no)
		(layer "In1.Cu")
	)
	(gr_circle
		(center 289.94989 -317.749936)
		(end 290.20389 -317.749936)
		(stroke
			(width 0.1016)
			(type default)
		)
		(fill no)
		(layer "In1.Cu")
	)
	(gr_circle
		(center 289.94989 -313.949842)
		(end 290.20389 -313.949842)
		(stroke
			(width 0.1016)
			(type default)
		)
		(fill no)
		(layer "In1.Cu")
	)
	(gr_circle
		(center 289.94989 -312.999882)
		(end 290.20389 -312.999882)
		(stroke
			(width 0.1016)
			(type default)
		)
		(fill no)
		(layer "In1.Cu")
	)
	(gr_circle
		(center 289.94989 -278.799798)
		(end 290.20389 -278.799798)
		(stroke
			(width 0.1016)
			(type default)
		)
		(fill no)
		(layer "In1.Cu")
	)
	(gr_circle
		(center 289.94989 -277.849838)
		(end 290.20389 -277.849838)
		(stroke
			(width 0.1016)
			(type default)
		)
		(fill no)
		(layer "In1.Cu")
	)
	(gr_circle
		(center 289.94989 -274.049744)
		(end 290.20389 -274.049744)
		(stroke
			(width 0.1016)
			(type default)
		)
		(fill no)
		(layer "In1.Cu")
	)
	(gr_circle
		(center 289.94989 -273.099784)
		(end 290.20389 -273.099784)
		(stroke
			(width 0.1016)
			(type default)
		)
		(fill no)
		(layer "In1.Cu")
	)
	(gr_circle
		(center 290.89985 -316.799722)
		(end 291.15385 -316.799722)
		(stroke
			(width 0.1016)
			(type default)
		)
		(fill no)
		(layer "In1.Cu")
	)
	(gr_circle
		(center 290.89985 -315.849762)
		(end 291.15385 -315.849762)
		(stroke
			(width 0.1016)
			(type default)
		)
		(fill no)
		(layer "In1.Cu")
	)
	(gr_circle
		(center 290.89985 -312.049922)
		(end 291.15385 -312.049922)
		(stroke
			(width 0.1016)
			(type default)
		)
		(fill no)
		(layer "In1.Cu")
	)
	(gr_circle
		(center 290.89985 -311.099962)
		(end 291.15385 -311.099962)
		(stroke
			(width 0.1016)
			(type default)
		)
		(fill no)
		(layer "In1.Cu")
	)
	(gr_circle
		(center 290.89985 -280.699464)
		(end 291.15385 -280.699464)
		(stroke
			(width 0.1016)
			(type default)
		)
		(fill no)
		(layer "In1.Cu")
	)
	(gr_circle
		(center 290.89985 -279.749504)
		(end 291.15385 -279.749504)
		(stroke
			(width 0.1016)
			(type default)
		)
		(fill no)
		(layer "In1.Cu")
	)
	(gr_circle
		(center 290.89985 -275.949918)
		(end 291.15385 -275.949918)
		(stroke
			(width 0.1016)
			(type default)
		)
		(fill no)
		(layer "In1.Cu")
	)
	(gr_circle
		(center 290.89985 -274.999958)
		(end 291.15385 -274.999958)
		(stroke
			(width 0.1016)
			(type default)
		)
		(fill no)
		(layer "In1.Cu")
	)
	(gr_circle
		(center 291.849556 -278.799798)
		(end 292.103556 -278.799798)
		(stroke
			(width 0.1016)
			(type default)
		)
		(fill no)
		(layer "In1.Cu")
	)
	(gr_circle
		(center 291.849556 -277.849838)
		(end 292.103556 -277.849838)
		(stroke
			(width 0.1016)
			(type default)
		)
		(fill no)
		(layer "In1.Cu")
	)
	(gr_circle
		(center 291.849556 -274.04949)
		(end 292.103556 -274.04949)
		(stroke
			(width 0.1016)
			(type default)
		)
		(fill no)
		(layer "In1.Cu")
	)
	(gr_circle
		(center 291.849556 -273.09953)
		(end 292.103556 -273.09953)
		(stroke
			(width 0.1016)
			(type default)
		)
		(fill no)
		(layer "In1.Cu")
	)
	(gr_circle
		(center 291.84981 -318.699896)
		(end 292.10381 -318.699896)
		(stroke
			(width 0.1016)
			(type default)
		)
		(fill no)
		(layer "In1.Cu")
	)
	(gr_circle
		(center 291.84981 -317.749936)
		(end 292.10381 -317.749936)
		(stroke
			(width 0.1016)
			(type default)
		)
		(fill no)
		(layer "In1.Cu")
	)
	(gr_circle
		(center 291.84981 -313.949842)
		(end 292.10381 -313.949842)
		(stroke
			(width 0.1016)
			(type default)
		)
		(fill no)
		(layer "In1.Cu")
	)
	(gr_circle
		(center 291.84981 -312.999882)
		(end 292.10381 -312.999882)
		(stroke
			(width 0.1016)
			(type default)
		)
		(fill no)
		(layer "In1.Cu")
	)
	(gr_circle
		(center 292.799516 -275.949664)
		(end 293.053516 -275.949664)
		(stroke
			(width 0.1016)
			(type default)
		)
		(fill no)
		(layer "In1.Cu")
	)
	(gr_circle
		(center 292.799516 -274.999704)
		(end 293.053516 -274.999704)
		(stroke
			(width 0.1016)
			(type default)
		)
		(fill no)
		(layer "In1.Cu")
	)
	(gr_circle
		(center 292.79977 -316.799722)
		(end 293.05377 -316.799722)
		(stroke
			(width 0.1016)
			(type default)
		)
		(fill no)
		(layer "In1.Cu")
	)
	(gr_circle
		(center 292.79977 -315.849762)
		(end 293.05377 -315.849762)
		(stroke
			(width 0.1016)
			(type default)
		)
		(fill no)
		(layer "In1.Cu")
	)
	(gr_circle
		(center 292.79977 -312.049922)
		(end 293.05377 -312.049922)
		(stroke
			(width 0.1016)
			(type default)
		)
		(fill no)
		(layer "In1.Cu")
	)
	(gr_circle
		(center 292.79977 -311.099962)
		(end 293.05377 -311.099962)
		(stroke
			(width 0.1016)
			(type default)
		)
		(fill no)
		(layer "In1.Cu")
	)
	(gr_circle
		(center 292.79977 -280.699464)
		(end 293.05377 -280.699464)
		(stroke
			(width 0.1016)
			(type default)
		)
		(fill no)
		(layer "In1.Cu")
	)
	(gr_circle
		(center 292.79977 -279.749504)
		(end 293.05377 -279.749504)
		(stroke
			(width 0.1016)
			(type default)
		)
		(fill no)
		(layer "In1.Cu")
	)
	(gr_circle
		(center 293.749476 -278.799798)
		(end 294.003476 -278.799798)
		(stroke
			(width 0.1016)
			(type default)
		)
		(fill no)
		(layer "In1.Cu")
	)
	(gr_circle
		(center 293.749476 -277.849838)
		(end 294.003476 -277.849838)
		(stroke
			(width 0.1016)
			(type default)
		)
		(fill no)
		(layer "In1.Cu")
	)
	(gr_circle
		(center 293.749476 -274.049744)
		(end 294.003476 -274.049744)
		(stroke
			(width 0.1016)
			(type default)
		)
		(fill no)
		(layer "In1.Cu")
	)
	(gr_circle
		(center 293.749476 -273.099784)
		(end 294.003476 -273.099784)
		(stroke
			(width 0.1016)
			(type default)
		)
		(fill no)
		(layer "In1.Cu")
	)
	(gr_circle
		(center 293.74973 -318.699896)
		(end 294.00373 -318.699896)
		(stroke
			(width 0.1016)
			(type default)
		)
		(fill no)
		(layer "In1.Cu")
	)
	(gr_circle
		(center 293.74973 -317.749936)
		(end 294.00373 -317.749936)
		(stroke
			(width 0.1016)
			(type default)
		)
		(fill no)
		(layer "In1.Cu")
	)
	(gr_circle
		(center 293.74973 -313.949842)
		(end 294.00373 -313.949842)
		(stroke
			(width 0.1016)
			(type default)
		)
		(fill no)
		(layer "In1.Cu")
	)
	(gr_circle
		(center 293.74973 -312.999882)
		(end 294.00373 -312.999882)
		(stroke
			(width 0.1016)
			(type default)
		)
		(fill no)
		(layer "In1.Cu")
	)
	(gr_circle
		(center 294.699436 -275.949918)
		(end 294.953436 -275.949918)
		(stroke
			(width 0.1016)
			(type default)
		)
		(fill no)
		(layer "In1.Cu")
	)
	(gr_circle
		(center 294.699436 -274.999958)
		(end 294.953436 -274.999958)
		(stroke
			(width 0.1016)
			(type default)
		)
		(fill no)
		(layer "In1.Cu")
	)
	(gr_circle
		(center 294.69969 -316.799722)
		(end 294.95369 -316.799722)
		(stroke
			(width 0.1016)
			(type default)
		)
		(fill no)
		(layer "In1.Cu")
	)
	(gr_circle
		(center 294.69969 -315.849762)
		(end 294.95369 -315.849762)
		(stroke
			(width 0.1016)
			(type default)
		)
		(fill no)
		(layer "In1.Cu")
	)
	(gr_circle
		(center 294.69969 -312.049922)
		(end 294.95369 -312.049922)
		(stroke
			(width 0.1016)
			(type default)
		)
		(fill no)
		(layer "In1.Cu")
	)
	(gr_circle
		(center 294.69969 -311.099962)
		(end 294.95369 -311.099962)
		(stroke
			(width 0.1016)
			(type default)
		)
		(fill no)
		(layer "In1.Cu")
	)
	(gr_circle
		(center 294.69969 -280.699464)
		(end 294.95369 -280.699464)
		(stroke
			(width 0.1016)
			(type default)
		)
		(fill no)
		(layer "In1.Cu")
	)
	(gr_circle
		(center 294.69969 -279.749504)
		(end 294.95369 -279.749504)
		(stroke
			(width 0.1016)
			(type default)
		)
		(fill no)
		(layer "In1.Cu")
	)
	(gr_circle
		(center 295.64965 -278.799798)
		(end 295.90365 -278.799798)
		(stroke
			(width 0.1016)
			(type default)
		)
		(fill no)
		(layer "In1.Cu")
	)
	(gr_circle
		(center 295.64965 -277.849838)
		(end 295.90365 -277.849838)
		(stroke
			(width 0.1016)
			(type default)
		)
		(fill no)
		(layer "In1.Cu")
	)
	(gr_circle
		(center 295.64965 -274.049744)
		(end 295.90365 -274.049744)
		(stroke
			(width 0.1016)
			(type default)
		)
		(fill no)
		(layer "In1.Cu")
	)
	(gr_circle
		(center 295.64965 -273.099784)
		(end 295.90365 -273.099784)
		(stroke
			(width 0.1016)
			(type default)
		)
		(fill no)
		(layer "In1.Cu")
	)
	(gr_circle
		(center 295.649904 -318.699896)
		(end 295.903904 -318.699896)
		(stroke
			(width 0.1016)
			(type default)
		)
		(fill no)
		(layer "In1.Cu")
	)
	(gr_circle
		(center 295.649904 -317.749936)
		(end 295.903904 -317.749936)
		(stroke
			(width 0.1016)
			(type default)
		)
		(fill no)
		(layer "In1.Cu")
	)
	(gr_circle
		(center 295.649904 -313.949842)
		(end 295.903904 -313.949842)
		(stroke
			(width 0.1016)
			(type default)
		)
		(fill no)
		(layer "In1.Cu")
	)
	(gr_circle
		(center 295.649904 -312.999882)
		(end 295.903904 -312.999882)
		(stroke
			(width 0.1016)
			(type default)
		)
		(fill no)
		(layer "In1.Cu")
	)
	(gr_circle
		(center 296.59961 -275.949664)
		(end 296.85361 -275.949664)
		(stroke
			(width 0.1016)
			(type default)
		)
		(fill no)
		(layer "In1.Cu")
	)
	(gr_circle
		(center 296.59961 -274.999704)
		(end 296.85361 -274.999704)
		(stroke
			(width 0.1016)
			(type default)
		)
		(fill no)
		(layer "In1.Cu")
	)
	(gr_circle
		(center 296.599864 -316.799722)
		(end 296.853864 -316.799722)
		(stroke
			(width 0.1016)
			(type default)
		)
		(fill no)
		(layer "In1.Cu")
	)
	(gr_circle
		(center 296.599864 -315.849762)
		(end 296.853864 -315.849762)
		(stroke
			(width 0.1016)
			(type default)
		)
		(fill no)
		(layer "In1.Cu")
	)
	(gr_circle
		(center 296.599864 -312.049922)
		(end 296.853864 -312.049922)
		(stroke
			(width 0.1016)
			(type default)
		)
		(fill no)
		(layer "In1.Cu")
	)
	(gr_circle
		(center 296.599864 -311.099962)
		(end 296.853864 -311.099962)
		(stroke
			(width 0.1016)
			(type default)
		)
		(fill no)
		(layer "In1.Cu")
	)
	(gr_circle
		(center 296.599864 -280.699464)
		(end 296.853864 -280.699464)
		(stroke
			(width 0.1016)
			(type default)
		)
		(fill no)
		(layer "In1.Cu")
	)
	(gr_circle
		(center 296.599864 -279.749504)
		(end 296.853864 -279.749504)
		(stroke
			(width 0.1016)
			(type default)
		)
		(fill no)
		(layer "In1.Cu")
	)
	(gr_circle
		(center 297.54957 -278.799798)
		(end 297.80357 -278.799798)
		(stroke
			(width 0.1016)
			(type default)
		)
		(fill no)
		(layer "In1.Cu")
	)
	(gr_circle
		(center 297.54957 -277.849838)
		(end 297.80357 -277.849838)
		(stroke
			(width 0.1016)
			(type default)
		)
		(fill no)
		(layer "In1.Cu")
	)
	(gr_circle
		(center 297.54957 -274.049744)
		(end 297.80357 -274.049744)
		(stroke
			(width 0.1016)
			(type default)
		)
		(fill no)
		(layer "In1.Cu")
	)
	(gr_circle
		(center 297.54957 -273.099784)
		(end 297.80357 -273.099784)
		(stroke
			(width 0.1016)
			(type default)
		)
		(fill no)
		(layer "In1.Cu")
	)
	(gr_circle
		(center 297.549824 -318.699896)
		(end 297.803824 -318.699896)
		(stroke
			(width 0.1016)
			(type default)
		)
		(fill no)
		(layer "In1.Cu")
	)
	(gr_circle
		(center 297.549824 -317.749936)
		(end 297.803824 -317.749936)
		(stroke
			(width 0.1016)
			(type default)
		)
		(fill no)
		(layer "In1.Cu")
	)
	(gr_circle
		(center 297.549824 -313.949842)
		(end 297.803824 -313.949842)
		(stroke
			(width 0.1016)
			(type default)
		)
		(fill no)
		(layer "In1.Cu")
	)
	(gr_circle
		(center 297.549824 -312.999882)
		(end 297.803824 -312.999882)
		(stroke
			(width 0.1016)
			(type default)
		)
		(fill no)
		(layer "In1.Cu")
	)
	(gr_circle
		(center 298.49953 -275.949918)
		(end 298.75353 -275.949918)
		(stroke
			(width 0.1016)
			(type default)
		)
		(fill no)
		(layer "In1.Cu")
	)
	(gr_circle
		(center 298.49953 -274.999958)
		(end 298.75353 -274.999958)
		(stroke
			(width 0.1016)
			(type default)
		)
		(fill no)
		(layer "In1.Cu")
	)
	(gr_circle
		(center 298.499784 -316.799722)
		(end 298.753784 -316.799722)
		(stroke
			(width 0.1016)
			(type default)
		)
		(fill no)
		(layer "In1.Cu")
	)
	(gr_circle
		(center 298.499784 -315.849762)
		(end 298.753784 -315.849762)
		(stroke
			(width 0.1016)
			(type default)
		)
		(fill no)
		(layer "In1.Cu")
	)
	(gr_circle
		(center 298.499784 -312.049922)
		(end 298.753784 -312.049922)
		(stroke
			(width 0.1016)
			(type default)
		)
		(fill no)
		(layer "In1.Cu")
	)
	(gr_circle
		(center 298.499784 -311.099962)
		(end 298.753784 -311.099962)
		(stroke
			(width 0.1016)
			(type default)
		)
		(fill no)
		(layer "In1.Cu")
	)
	(gr_circle
		(center 298.499784 -280.699464)
		(end 298.753784 -280.699464)
		(stroke
			(width 0.1016)
			(type default)
		)
		(fill no)
		(layer "In1.Cu")
	)
	(gr_circle
		(center 298.499784 -279.749504)
		(end 298.753784 -279.749504)
		(stroke
			(width 0.1016)
			(type default)
		)
		(fill no)
		(layer "In1.Cu")
	)
	(gr_circle
		(center 299.44949 -278.799798)
		(end 299.70349 -278.799798)
		(stroke
			(width 0.1016)
			(type default)
		)
		(fill no)
		(layer "In1.Cu")
	)
	(gr_circle
		(center 299.44949 -277.849838)
		(end 299.70349 -277.849838)
		(stroke
			(width 0.1016)
			(type default)
		)
		(fill no)
		(layer "In1.Cu")
	)
	(gr_circle
		(center 299.44949 -274.049744)
		(end 299.70349 -274.049744)
		(stroke
			(width 0.1016)
			(type default)
		)
		(fill no)
		(layer "In1.Cu")
	)
	(gr_circle
		(center 299.44949 -273.099784)
		(end 299.70349 -273.099784)
		(stroke
			(width 0.1016)
			(type default)
		)
		(fill no)
		(layer "In1.Cu")
	)
	(gr_circle
		(center 299.449744 -318.699896)
		(end 299.703744 -318.699896)
		(stroke
			(width 0.1016)
			(type default)
		)
		(fill no)
		(layer "In1.Cu")
	)
	(gr_circle
		(center 299.449744 -317.749936)
		(end 299.703744 -317.749936)
		(stroke
			(width 0.1016)
			(type default)
		)
		(fill no)
		(layer "In1.Cu")
	)
	(gr_circle
		(center 299.449744 -313.949842)
		(end 299.703744 -313.949842)
		(stroke
			(width 0.1016)
			(type default)
		)
		(fill no)
		(layer "In1.Cu")
	)
	(gr_circle
		(center 299.449744 -312.999882)
		(end 299.703744 -312.999882)
		(stroke
			(width 0.1016)
			(type default)
		)
		(fill no)
		(layer "In1.Cu")
	)
	(gr_circle
		(center 300.39945 -275.949664)
		(end 300.65345 -275.949664)
		(stroke
			(width 0.1016)
			(type default)
		)
		(fill no)
		(layer "In1.Cu")
	)
	(gr_circle
		(center 300.39945 -274.999704)
		(end 300.65345 -274.999704)
		(stroke
			(width 0.1016)
			(type default)
		)
		(fill no)
		(layer "In1.Cu")
	)
	(gr_circle
		(center 300.399704 -316.799722)
		(end 300.653704 -316.799722)
		(stroke
			(width 0.1016)
			(type default)
		)
		(fill no)
		(layer "In1.Cu")
	)
	(gr_circle
		(center 300.399704 -315.849762)
		(end 300.653704 -315.849762)
		(stroke
			(width 0.1016)
			(type default)
		)
		(fill no)
		(layer "In1.Cu")
	)
	(gr_circle
		(center 300.399704 -312.049922)
		(end 300.653704 -312.049922)
		(stroke
			(width 0.1016)
			(type default)
		)
		(fill no)
		(layer "In1.Cu")
	)
	(gr_circle
		(center 300.399704 -311.099962)
		(end 300.653704 -311.099962)
		(stroke
			(width 0.1016)
			(type default)
		)
		(fill no)
		(layer "In1.Cu")
	)
	(gr_circle
		(center 300.399704 -280.699464)
		(end 300.653704 -280.699464)
		(stroke
			(width 0.1016)
			(type default)
		)
		(fill no)
		(layer "In1.Cu")
	)
	(gr_circle
		(center 300.399704 -279.749504)
		(end 300.653704 -279.749504)
		(stroke
			(width 0.1016)
			(type default)
		)
		(fill no)
		(layer "In1.Cu")
	)
	(gr_circle
		(center 301.349664 -278.799798)
		(end 301.603664 -278.799798)
		(stroke
			(width 0.1016)
			(type default)
		)
		(fill no)
		(layer "In1.Cu")
	)
	(gr_circle
		(center 301.349664 -277.849838)
		(end 301.603664 -277.849838)
		(stroke
			(width 0.1016)
			(type default)
		)
		(fill no)
		(layer "In1.Cu")
	)
	(gr_circle
		(center 301.349664 -274.049744)
		(end 301.603664 -274.049744)
		(stroke
			(width 0.1016)
			(type default)
		)
		(fill no)
		(layer "In1.Cu")
	)
	(gr_circle
		(center 301.349664 -273.099784)
		(end 301.603664 -273.099784)
		(stroke
			(width 0.1016)
			(type default)
		)
		(fill no)
		(layer "In1.Cu")
	)
	(gr_circle
		(center 301.349918 -318.699896)
		(end 301.603918 -318.699896)
		(stroke
			(width 0.1016)
			(type default)
		)
		(fill no)
		(layer "In1.Cu")
	)
	(gr_circle
		(center 301.349918 -317.749936)
		(end 301.603918 -317.749936)
		(stroke
			(width 0.1016)
			(type default)
		)
		(fill no)
		(layer "In1.Cu")
	)
	(gr_circle
		(center 301.349918 -313.949842)
		(end 301.603918 -313.949842)
		(stroke
			(width 0.1016)
			(type default)
		)
		(fill no)
		(layer "In1.Cu")
	)
	(gr_circle
		(center 301.349918 -312.999882)
		(end 301.603918 -312.999882)
		(stroke
			(width 0.1016)
			(type default)
		)
		(fill no)
		(layer "In1.Cu")
	)
	(gr_circle
		(center 302.29937 -275.949918)
		(end 302.55337 -275.949918)
		(stroke
			(width 0.1016)
			(type default)
		)
		(fill no)
		(layer "In1.Cu")
	)
	(gr_circle
		(center 302.29937 -274.999958)
		(end 302.55337 -274.999958)
		(stroke
			(width 0.1016)
			(type default)
		)
		(fill no)
		(layer "In1.Cu")
	)
	(gr_circle
		(center 302.299878 -316.799722)
		(end 302.553878 -316.799722)
		(stroke
			(width 0.1016)
			(type default)
		)
		(fill no)
		(layer "In1.Cu")
	)
	(gr_circle
		(center 302.299878 -315.849762)
		(end 302.553878 -315.849762)
		(stroke
			(width 0.1016)
			(type default)
		)
		(fill no)
		(layer "In1.Cu")
	)
	(gr_circle
		(center 302.299878 -312.049922)
		(end 302.553878 -312.049922)
		(stroke
			(width 0.1016)
			(type default)
		)
		(fill no)
		(layer "In1.Cu")
	)
	(gr_circle
		(center 302.299878 -311.099962)
		(end 302.553878 -311.099962)
		(stroke
			(width 0.1016)
			(type default)
		)
		(fill no)
		(layer "In1.Cu")
	)
	(gr_circle
		(center 302.299878 -280.699464)
		(end 302.553878 -280.699464)
		(stroke
			(width 0.1016)
			(type default)
		)
		(fill no)
		(layer "In1.Cu")
	)
	(gr_circle
		(center 302.299878 -279.749504)
		(end 302.553878 -279.749504)
		(stroke
			(width 0.1016)
			(type default)
		)
		(fill no)
		(layer "In1.Cu")
	)
	(gr_circle
		(center 303.249584 -278.799798)
		(end 303.503584 -278.799798)
		(stroke
			(width 0.1016)
			(type default)
		)
		(fill no)
		(layer "In1.Cu")
	)
	(gr_circle
		(center 303.249584 -277.849838)
		(end 303.503584 -277.849838)
		(stroke
			(width 0.1016)
			(type default)
		)
		(fill no)
		(layer "In1.Cu")
	)
	(gr_circle
		(center 303.249584 -274.049744)
		(end 303.503584 -274.049744)
		(stroke
			(width 0.1016)
			(type default)
		)
		(fill no)
		(layer "In1.Cu")
	)
	(gr_circle
		(center 303.249584 -273.099784)
		(end 303.503584 -273.099784)
		(stroke
			(width 0.1016)
			(type default)
		)
		(fill no)
		(layer "In1.Cu")
	)
	(gr_circle
		(center 303.249838 -318.699896)
		(end 303.503838 -318.699896)
		(stroke
			(width 0.1016)
			(type default)
		)
		(fill no)
		(layer "In1.Cu")
	)
	(gr_circle
		(center 303.249838 -317.749936)
		(end 303.503838 -317.749936)
		(stroke
			(width 0.1016)
			(type default)
		)
		(fill no)
		(layer "In1.Cu")
	)
	(gr_circle
		(center 303.249838 -313.949842)
		(end 303.503838 -313.949842)
		(stroke
			(width 0.1016)
			(type default)
		)
		(fill no)
		(layer "In1.Cu")
	)
	(gr_circle
		(center 303.249838 -312.999882)
		(end 303.503838 -312.999882)
		(stroke
			(width 0.1016)
			(type default)
		)
		(fill no)
		(layer "In1.Cu")
	)
	(gr_circle
		(center 304.199544 -275.949664)
		(end 304.453544 -275.949664)
		(stroke
			(width 0.1016)
			(type default)
		)
		(fill no)
		(layer "In1.Cu")
	)
	(gr_circle
		(center 304.199544 -274.999704)
		(end 304.453544 -274.999704)
		(stroke
			(width 0.1016)
			(type default)
		)
		(fill no)
		(layer "In1.Cu")
	)
	(gr_circle
		(center 304.199798 -316.799722)
		(end 304.453798 -316.799722)
		(stroke
			(width 0.1016)
			(type default)
		)
		(fill no)
		(layer "In1.Cu")
	)
	(gr_circle
		(center 304.199798 -315.849762)
		(end 304.453798 -315.849762)
		(stroke
			(width 0.1016)
			(type default)
		)
		(fill no)
		(layer "In1.Cu")
	)
	(gr_circle
		(center 304.199798 -312.049922)
		(end 304.453798 -312.049922)
		(stroke
			(width 0.1016)
			(type default)
		)
		(fill no)
		(layer "In1.Cu")
	)
	(gr_circle
		(center 304.199798 -311.099962)
		(end 304.453798 -311.099962)
		(stroke
			(width 0.1016)
			(type default)
		)
		(fill no)
		(layer "In1.Cu")
	)
	(gr_circle
		(center 304.199798 -280.699464)
		(end 304.453798 -280.699464)
		(stroke
			(width 0.1016)
			(type default)
		)
		(fill no)
		(layer "In1.Cu")
	)
	(gr_circle
		(center 304.199798 -279.749504)
		(end 304.453798 -279.749504)
		(stroke
			(width 0.1016)
			(type default)
		)
		(fill no)
		(layer "In1.Cu")
	)
	(gr_circle
		(center 305.149504 -278.799798)
		(end 305.403504 -278.799798)
		(stroke
			(width 0.1016)
			(type default)
		)
		(fill no)
		(layer "In1.Cu")
	)
	(gr_circle
		(center 305.149504 -277.849838)
		(end 305.403504 -277.849838)
		(stroke
			(width 0.1016)
			(type default)
		)
		(fill no)
		(layer "In1.Cu")
	)
	(gr_circle
		(center 305.149504 -274.049744)
		(end 305.403504 -274.049744)
		(stroke
			(width 0.1016)
			(type default)
		)
		(fill no)
		(layer "In1.Cu")
	)
	(gr_circle
		(center 305.149504 -273.099784)
		(end 305.403504 -273.099784)
		(stroke
			(width 0.1016)
			(type default)
		)
		(fill no)
		(layer "In1.Cu")
	)
	(gr_circle
		(center 305.149758 -318.699896)
		(end 305.403758 -318.699896)
		(stroke
			(width 0.1016)
			(type default)
		)
		(fill no)
		(layer "In1.Cu")
	)
	(gr_circle
		(center 305.149758 -317.749936)
		(end 305.403758 -317.749936)
		(stroke
			(width 0.1016)
			(type default)
		)
		(fill no)
		(layer "In1.Cu")
	)
	(gr_circle
		(center 305.149758 -313.949842)
		(end 305.403758 -313.949842)
		(stroke
			(width 0.1016)
			(type default)
		)
		(fill no)
		(layer "In1.Cu")
	)
	(gr_circle
		(center 305.149758 -312.999882)
		(end 305.403758 -312.999882)
		(stroke
			(width 0.1016)
			(type default)
		)
		(fill no)
		(layer "In1.Cu")
	)
	(gr_circle
		(center 306.099464 -275.949918)
		(end 306.353464 -275.949918)
		(stroke
			(width 0.1016)
			(type default)
		)
		(fill no)
		(layer "In1.Cu")
	)
	(gr_circle
		(center 306.099464 -274.999958)
		(end 306.353464 -274.999958)
		(stroke
			(width 0.1016)
			(type default)
		)
		(fill no)
		(layer "In1.Cu")
	)
	(gr_circle
		(center 306.099718 -316.799722)
		(end 306.353718 -316.799722)
		(stroke
			(width 0.1016)
			(type default)
		)
		(fill no)
		(layer "In1.Cu")
	)
	(gr_circle
		(center 306.099718 -315.849762)
		(end 306.353718 -315.849762)
		(stroke
			(width 0.1016)
			(type default)
		)
		(fill no)
		(layer "In1.Cu")
	)
	(gr_circle
		(center 306.099718 -312.049922)
		(end 306.353718 -312.049922)
		(stroke
			(width 0.1016)
			(type default)
		)
		(fill no)
		(layer "In1.Cu")
	)
	(gr_circle
		(center 306.099718 -311.099962)
		(end 306.353718 -311.099962)
		(stroke
			(width 0.1016)
			(type default)
		)
		(fill no)
		(layer "In1.Cu")
	)
	(gr_circle
		(center 306.099718 -280.699464)
		(end 306.353718 -280.699464)
		(stroke
			(width 0.1016)
			(type default)
		)
		(fill no)
		(layer "In1.Cu")
	)
	(gr_circle
		(center 306.099718 -279.749504)
		(end 306.353718 -279.749504)
		(stroke
			(width 0.1016)
			(type default)
		)
		(fill no)
		(layer "In1.Cu")
	)
	(gr_circle
		(center 307.049678 -278.799798)
		(end 307.303678 -278.799798)
		(stroke
			(width 0.1016)
			(type default)
		)
		(fill no)
		(layer "In1.Cu")
	)
	(gr_circle
		(center 307.049678 -277.849838)
		(end 307.303678 -277.849838)
		(stroke
			(width 0.1016)
			(type default)
		)
		(fill no)
		(layer "In1.Cu")
	)
	(gr_circle
		(center 307.049678 -274.049744)
		(end 307.303678 -274.049744)
		(stroke
			(width 0.1016)
			(type default)
		)
		(fill no)
		(layer "In1.Cu")
	)
	(gr_circle
		(center 307.049678 -273.099784)
		(end 307.303678 -273.099784)
		(stroke
			(width 0.1016)
			(type default)
		)
		(fill no)
		(layer "In1.Cu")
	)
	(gr_circle
		(center 307.049932 -318.699896)
		(end 307.303932 -318.699896)
		(stroke
			(width 0.1016)
			(type default)
		)
		(fill no)
		(layer "In1.Cu")
	)
	(gr_circle
		(center 307.049932 -317.749936)
		(end 307.303932 -317.749936)
		(stroke
			(width 0.1016)
			(type default)
		)
		(fill no)
		(layer "In1.Cu")
	)
	(gr_circle
		(center 307.049932 -313.949842)
		(end 307.303932 -313.949842)
		(stroke
			(width 0.1016)
			(type default)
		)
		(fill no)
		(layer "In1.Cu")
	)
	(gr_circle
		(center 307.049932 -312.999882)
		(end 307.303932 -312.999882)
		(stroke
			(width 0.1016)
			(type default)
		)
		(fill no)
		(layer "In1.Cu")
	)
	(gr_circle
		(center 307.049932 -308.249828)
		(end 307.303932 -308.249828)
		(stroke
			(width 0.1016)
			(type default)
		)
		(fill no)
		(layer "In1.Cu")
	)
	(gr_circle
		(center 307.049932 -306.349908)
		(end 307.303932 -306.349908)
		(stroke
			(width 0.1016)
			(type default)
		)
		(fill no)
		(layer "In1.Cu")
	)
	(gr_circle
		(center 307.049932 -304.449734)
		(end 307.303932 -304.449734)
		(stroke
			(width 0.1016)
			(type default)
		)
		(fill no)
		(layer "In1.Cu")
	)
	(gr_circle
		(center 307.049932 -287.349946)
		(end 307.303932 -287.349946)
		(stroke
			(width 0.1016)
			(type default)
		)
		(fill no)
		(layer "In1.Cu")
	)
	(gr_circle
		(center 307.049932 -285.449772)
		(end 307.303932 -285.449772)
		(stroke
			(width 0.1016)
			(type default)
		)
		(fill no)
		(layer "In1.Cu")
	)
	(gr_circle
		(center 307.049932 -283.549852)
		(end 307.303932 -283.549852)
		(stroke
			(width 0.1016)
			(type default)
		)
		(fill no)
		(layer "In1.Cu")
	)
	(gr_circle
		(center 307.999638 -275.949664)
		(end 308.253638 -275.949664)
		(stroke
			(width 0.1016)
			(type default)
		)
		(fill no)
		(layer "In1.Cu")
	)
	(gr_circle
		(center 307.999638 -274.999704)
		(end 308.253638 -274.999704)
		(stroke
			(width 0.1016)
			(type default)
		)
		(fill no)
		(layer "In1.Cu")
	)
	(gr_circle
		(center 307.999892 -316.799722)
		(end 308.253892 -316.799722)
		(stroke
			(width 0.1016)
			(type default)
		)
		(fill no)
		(layer "In1.Cu")
	)
	(gr_circle
		(center 307.999892 -315.849762)
		(end 308.253892 -315.849762)
		(stroke
			(width 0.1016)
			(type default)
		)
		(fill no)
		(layer "In1.Cu")
	)
	(gr_circle
		(center 307.999892 -312.049922)
		(end 308.253892 -312.049922)
		(stroke
			(width 0.1016)
			(type default)
		)
		(fill no)
		(layer "In1.Cu")
	)
	(gr_circle
		(center 307.999892 -311.099962)
		(end 308.253892 -311.099962)
		(stroke
			(width 0.1016)
			(type default)
		)
		(fill no)
		(layer "In1.Cu")
	)
	(gr_circle
		(center 307.999892 -308.249828)
		(end 308.253892 -308.249828)
		(stroke
			(width 0.1016)
			(type default)
		)
		(fill no)
		(layer "In1.Cu")
	)
	(gr_circle
		(center 307.999892 -306.349908)
		(end 308.253892 -306.349908)
		(stroke
			(width 0.1016)
			(type default)
		)
		(fill no)
		(layer "In1.Cu")
	)
	(gr_circle
		(center 307.999892 -304.449734)
		(end 308.253892 -304.449734)
		(stroke
			(width 0.1016)
			(type default)
		)
		(fill no)
		(layer "In1.Cu")
	)
	(gr_circle
		(center 307.999892 -287.349946)
		(end 308.253892 -287.349946)
		(stroke
			(width 0.1016)
			(type default)
		)
		(fill no)
		(layer "In1.Cu")
	)
	(gr_circle
		(center 307.999892 -285.449772)
		(end 308.253892 -285.449772)
		(stroke
			(width 0.1016)
			(type default)
		)
		(fill no)
		(layer "In1.Cu")
	)
	(gr_circle
		(center 307.999892 -283.549852)
		(end 308.253892 -283.549852)
		(stroke
			(width 0.1016)
			(type default)
		)
		(fill no)
		(layer "In1.Cu")
	)
	(gr_circle
		(center 307.999892 -280.699464)
		(end 308.253892 -280.699464)
		(stroke
			(width 0.1016)
			(type default)
		)
		(fill no)
		(layer "In1.Cu")
	)
	(gr_circle
		(center 307.999892 -279.749504)
		(end 308.253892 -279.749504)
		(stroke
			(width 0.1016)
			(type default)
		)
		(fill no)
		(layer "In1.Cu")
	)
	(gr_circle
		(center 308.949598 -278.799798)
		(end 309.203598 -278.799798)
		(stroke
			(width 0.1016)
			(type default)
		)
		(fill no)
		(layer "In1.Cu")
	)
	(gr_circle
		(center 308.949598 -277.849838)
		(end 309.203598 -277.849838)
		(stroke
			(width 0.1016)
			(type default)
		)
		(fill no)
		(layer "In1.Cu")
	)
	(gr_circle
		(center 308.949598 -274.049744)
		(end 309.203598 -274.049744)
		(stroke
			(width 0.1016)
			(type default)
		)
		(fill no)
		(layer "In1.Cu")
	)
	(gr_circle
		(center 308.949598 -273.099784)
		(end 309.203598 -273.099784)
		(stroke
			(width 0.1016)
			(type default)
		)
		(fill no)
		(layer "In1.Cu")
	)
	(gr_circle
		(center 308.949852 -318.699896)
		(end 309.203852 -318.699896)
		(stroke
			(width 0.1016)
			(type default)
		)
		(fill no)
		(layer "In1.Cu")
	)
	(gr_circle
		(center 308.949852 -317.749936)
		(end 309.203852 -317.749936)
		(stroke
			(width 0.1016)
			(type default)
		)
		(fill no)
		(layer "In1.Cu")
	)
	(gr_circle
		(center 308.949852 -313.949842)
		(end 309.203852 -313.949842)
		(stroke
			(width 0.1016)
			(type default)
		)
		(fill no)
		(layer "In1.Cu")
	)
	(gr_circle
		(center 308.949852 -312.999882)
		(end 309.203852 -312.999882)
		(stroke
			(width 0.1016)
			(type default)
		)
		(fill no)
		(layer "In1.Cu")
	)
	(gr_circle
		(center 308.949852 -309.199788)
		(end 309.203852 -309.199788)
		(stroke
			(width 0.1016)
			(type default)
		)
		(fill no)
		(layer "In1.Cu")
	)
	(gr_circle
		(center 308.949852 -307.299868)
		(end 309.203852 -307.299868)
		(stroke
			(width 0.1016)
			(type default)
		)
		(fill no)
		(layer "In1.Cu")
	)
	(gr_circle
		(center 308.949852 -305.399948)
		(end 309.203852 -305.399948)
		(stroke
			(width 0.1016)
			(type default)
		)
		(fill no)
		(layer "In1.Cu")
	)
	(gr_circle
		(center 308.949852 -288.299906)
		(end 309.203852 -288.299906)
		(stroke
			(width 0.1016)
			(type default)
		)
		(fill no)
		(layer "In1.Cu")
	)
	(gr_circle
		(center 308.949852 -286.399986)
		(end 309.203852 -286.399986)
		(stroke
			(width 0.1016)
			(type default)
		)
		(fill no)
		(layer "In1.Cu")
	)
	(gr_circle
		(center 308.949852 -284.499812)
		(end 309.203852 -284.499812)
		(stroke
			(width 0.1016)
			(type default)
		)
		(fill no)
		(layer "In1.Cu")
	)
	(gr_circle
		(center 308.949852 -282.599892)
		(end 309.203852 -282.599892)
		(stroke
			(width 0.1016)
			(type default)
		)
		(fill no)
		(layer "In1.Cu")
	)
	(gr_circle
		(center 309.899558 -275.949918)
		(end 310.153558 -275.949918)
		(stroke
			(width 0.1016)
			(type default)
		)
		(fill no)
		(layer "In1.Cu")
	)
	(gr_circle
		(center 309.899558 -274.999958)
		(end 310.153558 -274.999958)
		(stroke
			(width 0.1016)
			(type default)
		)
		(fill no)
		(layer "In1.Cu")
	)
	(gr_circle
		(center 309.899812 -316.799722)
		(end 310.153812 -316.799722)
		(stroke
			(width 0.1016)
			(type default)
		)
		(fill no)
		(layer "In1.Cu")
	)
	(gr_circle
		(center 309.899812 -315.849762)
		(end 310.153812 -315.849762)
		(stroke
			(width 0.1016)
			(type default)
		)
		(fill no)
		(layer "In1.Cu")
	)
	(gr_circle
		(center 309.899812 -312.049922)
		(end 310.153812 -312.049922)
		(stroke
			(width 0.1016)
			(type default)
		)
		(fill no)
		(layer "In1.Cu")
	)
	(gr_circle
		(center 309.899812 -311.099962)
		(end 310.153812 -311.099962)
		(stroke
			(width 0.1016)
			(type default)
		)
		(fill no)
		(layer "In1.Cu")
	)
	(gr_circle
		(center 309.899812 -309.199788)
		(end 310.153812 -309.199788)
		(stroke
			(width 0.1016)
			(type default)
		)
		(fill no)
		(layer "In1.Cu")
	)
	(gr_circle
		(center 309.899812 -307.299868)
		(end 310.153812 -307.299868)
		(stroke
			(width 0.1016)
			(type default)
		)
		(fill no)
		(layer "In1.Cu")
	)
	(gr_circle
		(center 309.899812 -305.399948)
		(end 310.153812 -305.399948)
		(stroke
			(width 0.1016)
			(type default)
		)
		(fill no)
		(layer "In1.Cu")
	)
	(gr_circle
		(center 309.899812 -288.299906)
		(end 310.153812 -288.299906)
		(stroke
			(width 0.1016)
			(type default)
		)
		(fill no)
		(layer "In1.Cu")
	)
	(gr_circle
		(center 309.899812 -286.399986)
		(end 310.153812 -286.399986)
		(stroke
			(width 0.1016)
			(type default)
		)
		(fill no)
		(layer "In1.Cu")
	)
	(gr_circle
		(center 309.899812 -284.499812)
		(end 310.153812 -284.499812)
		(stroke
			(width 0.1016)
			(type default)
		)
		(fill no)
		(layer "In1.Cu")
	)
	(gr_circle
		(center 309.899812 -282.599892)
		(end 310.153812 -282.599892)
		(stroke
			(width 0.1016)
			(type default)
		)
		(fill no)
		(layer "In1.Cu")
	)
	(gr_circle
		(center 309.899812 -280.699464)
		(end 310.153812 -280.699464)
		(stroke
			(width 0.1016)
			(type default)
		)
		(fill no)
		(layer "In1.Cu")
	)
	(gr_circle
		(center 309.899812 -279.749504)
		(end 310.153812 -279.749504)
		(stroke
			(width 0.1016)
			(type default)
		)
		(fill no)
		(layer "In1.Cu")
	)
	(gr_circle
		(center 310.849518 -278.799798)
		(end 311.103518 -278.799798)
		(stroke
			(width 0.1016)
			(type default)
		)
		(fill no)
		(layer "In1.Cu")
	)
	(gr_circle
		(center 310.849518 -277.849838)
		(end 311.103518 -277.849838)
		(stroke
			(width 0.1016)
			(type default)
		)
		(fill no)
		(layer "In1.Cu")
	)
	(gr_circle
		(center 310.849518 -274.049744)
		(end 311.103518 -274.049744)
		(stroke
			(width 0.1016)
			(type default)
		)
		(fill no)
		(layer "In1.Cu")
	)
	(gr_circle
		(center 310.849518 -273.099784)
		(end 311.103518 -273.099784)
		(stroke
			(width 0.1016)
			(type default)
		)
		(fill no)
		(layer "In1.Cu")
	)
	(gr_circle
		(center 310.849772 -318.699896)
		(end 311.103772 -318.699896)
		(stroke
			(width 0.1016)
			(type default)
		)
		(fill no)
		(layer "In1.Cu")
	)
	(gr_circle
		(center 310.849772 -317.749936)
		(end 311.103772 -317.749936)
		(stroke
			(width 0.1016)
			(type default)
		)
		(fill no)
		(layer "In1.Cu")
	)
	(gr_circle
		(center 310.849772 -313.949842)
		(end 311.103772 -313.949842)
		(stroke
			(width 0.1016)
			(type default)
		)
		(fill no)
		(layer "In1.Cu")
	)
	(gr_circle
		(center 310.849772 -312.999882)
		(end 311.103772 -312.999882)
		(stroke
			(width 0.1016)
			(type default)
		)
		(fill no)
		(layer "In1.Cu")
	)
	(gr_circle
		(center 311.799478 -275.949918)
		(end 312.053478 -275.949918)
		(stroke
			(width 0.1016)
			(type default)
		)
		(fill no)
		(layer "In1.Cu")
	)
	(gr_circle
		(center 311.799478 -274.999958)
		(end 312.053478 -274.999958)
		(stroke
			(width 0.1016)
			(type default)
		)
		(fill no)
		(layer "In1.Cu")
	)
	(gr_circle
		(center 311.799732 -316.799722)
		(end 312.053732 -316.799722)
		(stroke
			(width 0.1016)
			(type default)
		)
		(fill no)
		(layer "In1.Cu")
	)
	(gr_circle
		(center 311.799732 -315.849762)
		(end 312.053732 -315.849762)
		(stroke
			(width 0.1016)
			(type default)
		)
		(fill no)
		(layer "In1.Cu")
	)
	(gr_circle
		(center 311.799732 -312.049922)
		(end 312.053732 -312.049922)
		(stroke
			(width 0.1016)
			(type default)
		)
		(fill no)
		(layer "In1.Cu")
	)
	(gr_circle
		(center 311.799732 -311.099962)
		(end 312.053732 -311.099962)
		(stroke
			(width 0.1016)
			(type default)
		)
		(fill no)
		(layer "In1.Cu")
	)
	(gr_circle
		(center 311.799732 -309.199788)
		(end 312.053732 -309.199788)
		(stroke
			(width 0.1016)
			(type default)
		)
		(fill no)
		(layer "In1.Cu")
	)
	(gr_circle
		(center 311.799732 -307.299868)
		(end 312.053732 -307.299868)
		(stroke
			(width 0.1016)
			(type default)
		)
		(fill no)
		(layer "In1.Cu")
	)
	(gr_circle
		(center 311.799732 -305.399948)
		(end 312.053732 -305.399948)
		(stroke
			(width 0.1016)
			(type default)
		)
		(fill no)
		(layer "In1.Cu")
	)
	(gr_circle
		(center 311.799732 -288.299906)
		(end 312.053732 -288.299906)
		(stroke
			(width 0.1016)
			(type default)
		)
		(fill no)
		(layer "In1.Cu")
	)
	(gr_circle
		(center 311.799732 -286.399732)
		(end 312.053732 -286.399732)
		(stroke
			(width 0.1016)
			(type default)
		)
		(fill no)
		(layer "In1.Cu")
	)
	(gr_circle
		(center 311.799732 -284.499812)
		(end 312.053732 -284.499812)
		(stroke
			(width 0.1016)
			(type default)
		)
		(fill no)
		(layer "In1.Cu")
	)
	(gr_circle
		(center 311.799732 -282.599892)
		(end 312.053732 -282.599892)
		(stroke
			(width 0.1016)
			(type default)
		)
		(fill no)
		(layer "In1.Cu")
	)
	(gr_circle
		(center 311.799732 -280.699718)
		(end 312.053732 -280.699718)
		(stroke
			(width 0.1016)
			(type default)
		)
		(fill no)
		(layer "In1.Cu")
	)
	(gr_circle
		(center 311.799732 -279.749758)
		(end 312.053732 -279.749758)
		(stroke
			(width 0.1016)
			(type default)
		)
		(fill no)
		(layer "In1.Cu")
	)
	(gr_circle
		(center 312.749438 -274.049744)
		(end 313.003438 -274.049744)
		(stroke
			(width 0.1016)
			(type default)
		)
		(fill no)
		(layer "In1.Cu")
	)
	(gr_circle
		(center 312.749438 -273.099784)
		(end 313.003438 -273.099784)
		(stroke
			(width 0.1016)
			(type default)
		)
		(fill no)
		(layer "In1.Cu")
	)
	(gr_circle
		(center 312.749692 -318.699896)
		(end 313.003692 -318.699896)
		(stroke
			(width 0.1016)
			(type default)
		)
		(fill no)
		(layer "In1.Cu")
	)
	(gr_circle
		(center 312.749692 -317.749936)
		(end 313.003692 -317.749936)
		(stroke
			(width 0.1016)
			(type default)
		)
		(fill no)
		(layer "In1.Cu")
	)
	(gr_circle
		(center 312.749692 -313.949842)
		(end 313.003692 -313.949842)
		(stroke
			(width 0.1016)
			(type default)
		)
		(fill no)
		(layer "In1.Cu")
	)
	(gr_circle
		(center 312.749692 -312.999882)
		(end 313.003692 -312.999882)
		(stroke
			(width 0.1016)
			(type default)
		)
		(fill no)
		(layer "In1.Cu")
	)
	(gr_circle
		(center 312.749692 -309.199788)
		(end 313.003692 -309.199788)
		(stroke
			(width 0.1016)
			(type default)
		)
		(fill no)
		(layer "In1.Cu")
	)
	(gr_circle
		(center 312.749692 -307.299868)
		(end 313.003692 -307.299868)
		(stroke
			(width 0.1016)
			(type default)
		)
		(fill no)
		(layer "In1.Cu")
	)
	(gr_circle
		(center 312.749692 -305.399948)
		(end 313.003692 -305.399948)
		(stroke
			(width 0.1016)
			(type default)
		)
		(fill no)
		(layer "In1.Cu")
	)
	(gr_circle
		(center 312.749692 -288.299906)
		(end 313.003692 -288.299906)
		(stroke
			(width 0.1016)
			(type default)
		)
		(fill no)
		(layer "In1.Cu")
	)
	(gr_circle
		(center 312.749692 -286.399732)
		(end 313.003692 -286.399732)
		(stroke
			(width 0.1016)
			(type default)
		)
		(fill no)
		(layer "In1.Cu")
	)
	(gr_circle
		(center 312.749692 -284.499812)
		(end 313.003692 -284.499812)
		(stroke
			(width 0.1016)
			(type default)
		)
		(fill no)
		(layer "In1.Cu")
	)
	(gr_circle
		(center 312.749692 -282.599892)
		(end 313.003692 -282.599892)
		(stroke
			(width 0.1016)
			(type default)
		)
		(fill no)
		(layer "In1.Cu")
	)
	(gr_circle
		(center 312.749692 -278.799798)
		(end 313.003692 -278.799798)
		(stroke
			(width 0.1016)
			(type default)
		)
		(fill no)
		(layer "In1.Cu")
	)
	(gr_circle
		(center 312.749692 -277.849838)
		(end 313.003692 -277.849838)
		(stroke
			(width 0.1016)
			(type default)
		)
		(fill no)
		(layer "In1.Cu")
	)
	(gr_circle
		(center 313.699906 -316.799722)
		(end 313.953906 -316.799722)
		(stroke
			(width 0.1016)
			(type default)
		)
		(fill no)
		(layer "In1.Cu")
	)
	(gr_circle
		(center 313.699906 -314.899802)
		(end 313.953906 -314.899802)
		(stroke
			(width 0.1016)
			(type default)
		)
		(fill no)
		(layer "In1.Cu")
	)
	(gr_circle
		(center 313.699906 -312.049922)
		(end 313.953906 -312.049922)
		(stroke
			(width 0.1016)
			(type default)
		)
		(fill no)
		(layer "In1.Cu")
	)
	(gr_circle
		(center 313.699906 -310.149748)
		(end 313.953906 -310.149748)
		(stroke
			(width 0.1016)
			(type default)
		)
		(fill no)
		(layer "In1.Cu")
	)
	(gr_circle
		(center 313.699906 -308.249828)
		(end 313.953906 -308.249828)
		(stroke
			(width 0.1016)
			(type default)
		)
		(fill no)
		(layer "In1.Cu")
	)
	(gr_circle
		(center 313.699906 -306.349908)
		(end 313.953906 -306.349908)
		(stroke
			(width 0.1016)
			(type default)
		)
		(fill no)
		(layer "In1.Cu")
	)
	(gr_circle
		(center 313.699906 -304.449734)
		(end 313.953906 -304.449734)
		(stroke
			(width 0.1016)
			(type default)
		)
		(fill no)
		(layer "In1.Cu")
	)
	(gr_circle
		(center 313.699906 -287.349946)
		(end 313.953906 -287.349946)
		(stroke
			(width 0.1016)
			(type default)
		)
		(fill no)
		(layer "In1.Cu")
	)
	(gr_circle
		(center 313.699906 -285.449772)
		(end 313.953906 -285.449772)
		(stroke
			(width 0.1016)
			(type default)
		)
		(fill no)
		(layer "In1.Cu")
	)
	(gr_circle
		(center 313.699906 -283.549852)
		(end 313.953906 -283.549852)
		(stroke
			(width 0.1016)
			(type default)
		)
		(fill no)
		(layer "In1.Cu")
	)
	(gr_circle
		(center 313.699906 -281.649932)
		(end 313.953906 -281.649932)
		(stroke
			(width 0.1016)
			(type default)
		)
		(fill no)
		(layer "In1.Cu")
	)
	(gr_circle
		(center 313.699906 -279.749758)
		(end 313.953906 -279.749758)
		(stroke
			(width 0.1016)
			(type default)
		)
		(fill no)
		(layer "In1.Cu")
	)
	(gr_circle
		(center 313.699906 -276.899878)
		(end 313.953906 -276.899878)
		(stroke
			(width 0.1016)
			(type default)
		)
		(fill no)
		(layer "In1.Cu")
	)
	(gr_circle
		(center 313.699906 -274.999704)
		(end 313.953906 -274.999704)
		(stroke
			(width 0.1016)
			(type default)
		)
		(fill no)
		(layer "In1.Cu")
	)
	(gr_circle
		(center 314.649866 -316.799722)
		(end 314.903866 -316.799722)
		(stroke
			(width 0.1016)
			(type default)
		)
		(fill no)
		(layer "In1.Cu")
	)
	(gr_circle
		(center 314.649866 -314.899802)
		(end 314.903866 -314.899802)
		(stroke
			(width 0.1016)
			(type default)
		)
		(fill no)
		(layer "In1.Cu")
	)
	(gr_circle
		(center 314.649866 -312.049922)
		(end 314.903866 -312.049922)
		(stroke
			(width 0.1016)
			(type default)
		)
		(fill no)
		(layer "In1.Cu")
	)
	(gr_circle
		(center 314.649866 -310.149748)
		(end 314.903866 -310.149748)
		(stroke
			(width 0.1016)
			(type default)
		)
		(fill no)
		(layer "In1.Cu")
	)
	(gr_circle
		(center 314.649866 -308.249828)
		(end 314.903866 -308.249828)
		(stroke
			(width 0.1016)
			(type default)
		)
		(fill no)
		(layer "In1.Cu")
	)
	(gr_circle
		(center 314.649866 -306.349908)
		(end 314.903866 -306.349908)
		(stroke
			(width 0.1016)
			(type default)
		)
		(fill no)
		(layer "In1.Cu")
	)
	(gr_circle
		(center 314.649866 -304.449734)
		(end 314.903866 -304.449734)
		(stroke
			(width 0.1016)
			(type default)
		)
		(fill no)
		(layer "In1.Cu")
	)
	(gr_circle
		(center 314.649866 -287.349946)
		(end 314.903866 -287.349946)
		(stroke
			(width 0.1016)
			(type default)
		)
		(fill no)
		(layer "In1.Cu")
	)
	(gr_circle
		(center 314.649866 -285.449772)
		(end 314.903866 -285.449772)
		(stroke
			(width 0.1016)
			(type default)
		)
		(fill no)
		(layer "In1.Cu")
	)
	(gr_circle
		(center 314.649866 -283.549852)
		(end 314.903866 -283.549852)
		(stroke
			(width 0.1016)
			(type default)
		)
		(fill no)
		(layer "In1.Cu")
	)
	(gr_circle
		(center 314.649866 -281.649932)
		(end 314.903866 -281.649932)
		(stroke
			(width 0.1016)
			(type default)
		)
		(fill no)
		(layer "In1.Cu")
	)
	(gr_circle
		(center 314.649866 -279.749758)
		(end 314.903866 -279.749758)
		(stroke
			(width 0.1016)
			(type default)
		)
		(fill no)
		(layer "In1.Cu")
	)
	(gr_circle
		(center 314.649866 -276.899878)
		(end 314.903866 -276.899878)
		(stroke
			(width 0.1016)
			(type default)
		)
		(fill no)
		(layer "In1.Cu")
	)
	(gr_circle
		(center 314.649866 -274.999704)
		(end 314.903866 -274.999704)
		(stroke
			(width 0.1016)
			(type default)
		)
		(fill no)
		(layer "In1.Cu")
	)
	(gr_circle
		(center 385.149852 -316.799722)
		(end 385.403852 -316.799722)
		(stroke
			(width 0.1016)
			(type default)
		)
		(fill no)
		(layer "In1.Cu")
	)
	(gr_circle
		(center 385.149852 -314.899802)
		(end 385.403852 -314.899802)
		(stroke
			(width 0.1016)
			(type default)
		)
		(fill no)
		(layer "In1.Cu")
	)
	(gr_circle
		(center 385.149852 -312.049922)
		(end 385.403852 -312.049922)
		(stroke
			(width 0.1016)
			(type default)
		)
		(fill no)
		(layer "In1.Cu")
	)
	(gr_circle
		(center 385.149852 -310.149748)
		(end 385.403852 -310.149748)
		(stroke
			(width 0.1016)
			(type default)
		)
		(fill no)
		(layer "In1.Cu")
	)
	(gr_circle
		(center 385.149852 -308.249828)
		(end 385.403852 -308.249828)
		(stroke
			(width 0.1016)
			(type default)
		)
		(fill no)
		(layer "In1.Cu")
	)
	(gr_circle
		(center 385.149852 -306.349908)
		(end 385.403852 -306.349908)
		(stroke
			(width 0.1016)
			(type default)
		)
		(fill no)
		(layer "In1.Cu")
	)
	(gr_circle
		(center 385.149852 -304.449734)
		(end 385.403852 -304.449734)
		(stroke
			(width 0.1016)
			(type default)
		)
		(fill no)
		(layer "In1.Cu")
	)
	(gr_circle
		(center 385.149852 -302.549814)
		(end 385.403852 -302.549814)
		(stroke
			(width 0.1016)
			(type default)
		)
		(fill no)
		(layer "In1.Cu")
	)
	(gr_circle
		(center 386.099812 -316.799722)
		(end 386.353812 -316.799722)
		(stroke
			(width 0.1016)
			(type default)
		)
		(fill no)
		(layer "In1.Cu")
	)
	(gr_circle
		(center 386.099812 -314.899802)
		(end 386.353812 -314.899802)
		(stroke
			(width 0.1016)
			(type default)
		)
		(fill no)
		(layer "In1.Cu")
	)
	(gr_circle
		(center 386.099812 -312.049922)
		(end 386.353812 -312.049922)
		(stroke
			(width 0.1016)
			(type default)
		)
		(fill no)
		(layer "In1.Cu")
	)
	(gr_circle
		(center 386.099812 -310.149748)
		(end 386.353812 -310.149748)
		(stroke
			(width 0.1016)
			(type default)
		)
		(fill no)
		(layer "In1.Cu")
	)
	(gr_circle
		(center 386.099812 -308.249828)
		(end 386.353812 -308.249828)
		(stroke
			(width 0.1016)
			(type default)
		)
		(fill no)
		(layer "In1.Cu")
	)
	(gr_circle
		(center 386.099812 -306.349908)
		(end 386.353812 -306.349908)
		(stroke
			(width 0.1016)
			(type default)
		)
		(fill no)
		(layer "In1.Cu")
	)
	(gr_circle
		(center 386.099812 -304.449734)
		(end 386.353812 -304.449734)
		(stroke
			(width 0.1016)
			(type default)
		)
		(fill no)
		(layer "In1.Cu")
	)
	(gr_circle
		(center 386.099812 -302.549814)
		(end 386.353812 -302.549814)
		(stroke
			(width 0.1016)
			(type default)
		)
		(fill no)
		(layer "In1.Cu")
	)
	(gr_circle
		(center 387.050026 -318.699896)
		(end 387.304026 -318.699896)
		(stroke
			(width 0.1016)
			(type default)
		)
		(fill no)
		(layer "In1.Cu")
	)
	(gr_circle
		(center 387.050026 -317.749936)
		(end 387.304026 -317.749936)
		(stroke
			(width 0.1016)
			(type default)
		)
		(fill no)
		(layer "In1.Cu")
	)
	(gr_circle
		(center 387.050026 -313.949842)
		(end 387.304026 -313.949842)
		(stroke
			(width 0.1016)
			(type default)
		)
		(fill no)
		(layer "In1.Cu")
	)
	(gr_circle
		(center 387.050026 -312.999882)
		(end 387.304026 -312.999882)
		(stroke
			(width 0.1016)
			(type default)
		)
		(fill no)
		(layer "In1.Cu")
	)
	(gr_circle
		(center 387.050026 -309.199788)
		(end 387.304026 -309.199788)
		(stroke
			(width 0.1016)
			(type default)
		)
		(fill no)
		(layer "In1.Cu")
	)
	(gr_circle
		(center 387.050026 -307.299868)
		(end 387.304026 -307.299868)
		(stroke
			(width 0.1016)
			(type default)
		)
		(fill no)
		(layer "In1.Cu")
	)
	(gr_circle
		(center 387.050026 -305.399948)
		(end 387.304026 -305.399948)
		(stroke
			(width 0.1016)
			(type default)
		)
		(fill no)
		(layer "In1.Cu")
	)
	(gr_circle
		(center 387.050026 -303.499774)
		(end 387.304026 -303.499774)
		(stroke
			(width 0.1016)
			(type default)
		)
		(fill no)
		(layer "In1.Cu")
	)
	(gr_circle
		(center 387.050026 -301.599854)
		(end 387.304026 -301.599854)
		(stroke
			(width 0.1016)
			(type default)
		)
		(fill no)
		(layer "In1.Cu")
	)
	(gr_circle
		(center 387.999986 -316.799722)
		(end 388.253986 -316.799722)
		(stroke
			(width 0.1016)
			(type default)
		)
		(fill no)
		(layer "In1.Cu")
	)
	(gr_circle
		(center 387.999986 -315.849762)
		(end 388.253986 -315.849762)
		(stroke
			(width 0.1016)
			(type default)
		)
		(fill no)
		(layer "In1.Cu")
	)
	(gr_circle
		(center 387.999986 -312.049922)
		(end 388.253986 -312.049922)
		(stroke
			(width 0.1016)
			(type default)
		)
		(fill no)
		(layer "In1.Cu")
	)
	(gr_circle
		(center 387.999986 -311.099962)
		(end 388.253986 -311.099962)
		(stroke
			(width 0.1016)
			(type default)
		)
		(fill no)
		(layer "In1.Cu")
	)
	(gr_circle
		(center 387.999986 -309.199788)
		(end 388.253986 -309.199788)
		(stroke
			(width 0.1016)
			(type default)
		)
		(fill no)
		(layer "In1.Cu")
	)
	(gr_circle
		(center 387.999986 -307.299868)
		(end 388.253986 -307.299868)
		(stroke
			(width 0.1016)
			(type default)
		)
		(fill no)
		(layer "In1.Cu")
	)
	(gr_circle
		(center 387.999986 -305.399948)
		(end 388.253986 -305.399948)
		(stroke
			(width 0.1016)
			(type default)
		)
		(fill no)
		(layer "In1.Cu")
	)
	(gr_circle
		(center 387.999986 -303.499774)
		(end 388.253986 -303.499774)
		(stroke
			(width 0.1016)
			(type default)
		)
		(fill no)
		(layer "In1.Cu")
	)
	(gr_circle
		(center 387.999986 -301.599854)
		(end 388.253986 -301.599854)
		(stroke
			(width 0.1016)
			(type default)
		)
		(fill no)
		(layer "In1.Cu")
	)
	(gr_circle
		(center 388.949946 -318.699896)
		(end 389.203946 -318.699896)
		(stroke
			(width 0.1016)
			(type default)
		)
		(fill no)
		(layer "In1.Cu")
	)
	(gr_circle
		(center 388.949946 -317.749936)
		(end 389.203946 -317.749936)
		(stroke
			(width 0.1016)
			(type default)
		)
		(fill no)
		(layer "In1.Cu")
	)
	(gr_circle
		(center 388.949946 -313.949842)
		(end 389.203946 -313.949842)
		(stroke
			(width 0.1016)
			(type default)
		)
		(fill no)
		(layer "In1.Cu")
	)
	(gr_circle
		(center 388.949946 -312.999882)
		(end 389.203946 -312.999882)
		(stroke
			(width 0.1016)
			(type default)
		)
		(fill no)
		(layer "In1.Cu")
	)
	(gr_circle
		(center 389.899906 -316.799722)
		(end 390.153906 -316.799722)
		(stroke
			(width 0.1016)
			(type default)
		)
		(fill no)
		(layer "In1.Cu")
	)
	(gr_circle
		(center 389.899906 -315.849762)
		(end 390.153906 -315.849762)
		(stroke
			(width 0.1016)
			(type default)
		)
		(fill no)
		(layer "In1.Cu")
	)
	(gr_circle
		(center 389.899906 -312.049922)
		(end 390.153906 -312.049922)
		(stroke
			(width 0.1016)
			(type default)
		)
		(fill no)
		(layer "In1.Cu")
	)
	(gr_circle
		(center 389.899906 -311.099962)
		(end 390.153906 -311.099962)
		(stroke
			(width 0.1016)
			(type default)
		)
		(fill no)
		(layer "In1.Cu")
	)
	(gr_circle
		(center 389.899906 -309.199788)
		(end 390.153906 -309.199788)
		(stroke
			(width 0.1016)
			(type default)
		)
		(fill no)
		(layer "In1.Cu")
	)
	(gr_circle
		(center 389.899906 -307.299868)
		(end 390.153906 -307.299868)
		(stroke
			(width 0.1016)
			(type default)
		)
		(fill no)
		(layer "In1.Cu")
	)
	(gr_circle
		(center 389.899906 -305.399948)
		(end 390.153906 -305.399948)
		(stroke
			(width 0.1016)
			(type default)
		)
		(fill no)
		(layer "In1.Cu")
	)
	(gr_circle
		(center 389.899906 -303.499774)
		(end 390.153906 -303.499774)
		(stroke
			(width 0.1016)
			(type default)
		)
		(fill no)
		(layer "In1.Cu")
	)
	(gr_circle
		(center 389.899906 -301.599854)
		(end 390.153906 -301.599854)
		(stroke
			(width 0.1016)
			(type default)
		)
		(fill no)
		(layer "In1.Cu")
	)
	(gr_circle
		(center 390.849866 -318.699896)
		(end 391.103866 -318.699896)
		(stroke
			(width 0.1016)
			(type default)
		)
		(fill no)
		(layer "In1.Cu")
	)
	(gr_circle
		(center 390.849866 -317.749936)
		(end 391.103866 -317.749936)
		(stroke
			(width 0.1016)
			(type default)
		)
		(fill no)
		(layer "In1.Cu")
	)
	(gr_circle
		(center 390.849866 -313.949842)
		(end 391.103866 -313.949842)
		(stroke
			(width 0.1016)
			(type default)
		)
		(fill no)
		(layer "In1.Cu")
	)
	(gr_circle
		(center 390.849866 -312.999882)
		(end 391.103866 -312.999882)
		(stroke
			(width 0.1016)
			(type default)
		)
		(fill no)
		(layer "In1.Cu")
	)
	(gr_circle
		(center 390.849866 -309.199788)
		(end 391.103866 -309.199788)
		(stroke
			(width 0.1016)
			(type default)
		)
		(fill no)
		(layer "In1.Cu")
	)
	(gr_circle
		(center 390.849866 -307.299868)
		(end 391.103866 -307.299868)
		(stroke
			(width 0.1016)
			(type default)
		)
		(fill no)
		(layer "In1.Cu")
	)
	(gr_circle
		(center 390.849866 -305.399948)
		(end 391.103866 -305.399948)
		(stroke
			(width 0.1016)
			(type default)
		)
		(fill no)
		(layer "In1.Cu")
	)
	(gr_circle
		(center 390.849866 -303.499774)
		(end 391.103866 -303.499774)
		(stroke
			(width 0.1016)
			(type default)
		)
		(fill no)
		(layer "In1.Cu")
	)
	(gr_circle
		(center 390.849866 -301.599854)
		(end 391.103866 -301.599854)
		(stroke
			(width 0.1016)
			(type default)
		)
		(fill no)
		(layer "In1.Cu")
	)
	(gr_circle
		(center 391.799826 -316.799722)
		(end 392.053826 -316.799722)
		(stroke
			(width 0.1016)
			(type default)
		)
		(fill no)
		(layer "In1.Cu")
	)
	(gr_circle
		(center 391.799826 -315.849762)
		(end 392.053826 -315.849762)
		(stroke
			(width 0.1016)
			(type default)
		)
		(fill no)
		(layer "In1.Cu")
	)
	(gr_circle
		(center 391.799826 -312.049922)
		(end 392.053826 -312.049922)
		(stroke
			(width 0.1016)
			(type default)
		)
		(fill no)
		(layer "In1.Cu")
	)
	(gr_circle
		(center 391.799826 -311.099962)
		(end 392.053826 -311.099962)
		(stroke
			(width 0.1016)
			(type default)
		)
		(fill no)
		(layer "In1.Cu")
	)
	(gr_circle
		(center 391.799826 -308.249828)
		(end 392.053826 -308.249828)
		(stroke
			(width 0.1016)
			(type default)
		)
		(fill no)
		(layer "In1.Cu")
	)
	(gr_circle
		(center 391.799826 -306.349908)
		(end 392.053826 -306.349908)
		(stroke
			(width 0.1016)
			(type default)
		)
		(fill no)
		(layer "In1.Cu")
	)
	(gr_circle
		(center 391.799826 -304.449734)
		(end 392.053826 -304.449734)
		(stroke
			(width 0.1016)
			(type default)
		)
		(fill no)
		(layer "In1.Cu")
	)
	(gr_circle
		(center 391.799826 -302.549814)
		(end 392.053826 -302.549814)
		(stroke
			(width 0.1016)
			(type default)
		)
		(fill no)
		(layer "In1.Cu")
	)
	(gr_circle
		(center 392.749786 -318.699896)
		(end 393.003786 -318.699896)
		(stroke
			(width 0.1016)
			(type default)
		)
		(fill no)
		(layer "In1.Cu")
	)
	(gr_circle
		(center 392.749786 -317.749936)
		(end 393.003786 -317.749936)
		(stroke
			(width 0.1016)
			(type default)
		)
		(fill no)
		(layer "In1.Cu")
	)
	(gr_circle
		(center 392.749786 -313.949842)
		(end 393.003786 -313.949842)
		(stroke
			(width 0.1016)
			(type default)
		)
		(fill no)
		(layer "In1.Cu")
	)
	(gr_circle
		(center 392.749786 -312.999882)
		(end 393.003786 -312.999882)
		(stroke
			(width 0.1016)
			(type default)
		)
		(fill no)
		(layer "In1.Cu")
	)
	(gr_circle
		(center 392.749786 -308.249828)
		(end 393.003786 -308.249828)
		(stroke
			(width 0.1016)
			(type default)
		)
		(fill no)
		(layer "In1.Cu")
	)
	(gr_circle
		(center 392.749786 -306.349908)
		(end 393.003786 -306.349908)
		(stroke
			(width 0.1016)
			(type default)
		)
		(fill no)
		(layer "In1.Cu")
	)
	(gr_circle
		(center 392.749786 -304.449734)
		(end 393.003786 -304.449734)
		(stroke
			(width 0.1016)
			(type default)
		)
		(fill no)
		(layer "In1.Cu")
	)
	(gr_circle
		(center 392.749786 -302.549814)
		(end 393.003786 -302.549814)
		(stroke
			(width 0.1016)
			(type default)
		)
		(fill no)
		(layer "In1.Cu")
	)
	(gr_circle
		(center 392.749786 -278.799798)
		(end 393.003786 -278.799798)
		(stroke
			(width 0.1016)
			(type default)
		)
		(fill no)
		(layer "In1.Cu")
	)
	(gr_circle
		(center 392.749786 -277.849838)
		(end 393.003786 -277.849838)
		(stroke
			(width 0.1016)
			(type default)
		)
		(fill no)
		(layer "In1.Cu")
	)
	(gr_circle
		(center 392.749786 -274.049744)
		(end 393.003786 -274.049744)
		(stroke
			(width 0.1016)
			(type default)
		)
		(fill no)
		(layer "In1.Cu")
	)
	(gr_circle
		(center 392.749786 -273.099784)
		(end 393.003786 -273.099784)
		(stroke
			(width 0.1016)
			(type default)
		)
		(fill no)
		(layer "In1.Cu")
	)
	(gr_circle
		(center 393.7 -316.799722)
		(end 393.954 -316.799722)
		(stroke
			(width 0.1016)
			(type default)
		)
		(fill no)
		(layer "In1.Cu")
	)
	(gr_circle
		(center 393.7 -315.849762)
		(end 393.954 -315.849762)
		(stroke
			(width 0.1016)
			(type default)
		)
		(fill no)
		(layer "In1.Cu")
	)
	(gr_circle
		(center 393.7 -312.049922)
		(end 393.954 -312.049922)
		(stroke
			(width 0.1016)
			(type default)
		)
		(fill no)
		(layer "In1.Cu")
	)
	(gr_circle
		(center 393.7 -311.099962)
		(end 393.954 -311.099962)
		(stroke
			(width 0.1016)
			(type default)
		)
		(fill no)
		(layer "In1.Cu")
	)
	(gr_circle
		(center 393.7 -280.699464)
		(end 393.954 -280.699464)
		(stroke
			(width 0.1016)
			(type default)
		)
		(fill no)
		(layer "In1.Cu")
	)
	(gr_circle
		(center 393.7 -279.749504)
		(end 393.954 -279.749504)
		(stroke
			(width 0.1016)
			(type default)
		)
		(fill no)
		(layer "In1.Cu")
	)
	(gr_circle
		(center 393.7 -275.949918)
		(end 393.954 -275.949918)
		(stroke
			(width 0.1016)
			(type default)
		)
		(fill no)
		(layer "In1.Cu")
	)
	(gr_circle
		(center 393.7 -274.999958)
		(end 393.954 -274.999958)
		(stroke
			(width 0.1016)
			(type default)
		)
		(fill no)
		(layer "In1.Cu")
	)
	(gr_circle
		(center 394.64996 -318.699896)
		(end 394.90396 -318.699896)
		(stroke
			(width 0.1016)
			(type default)
		)
		(fill no)
		(layer "In1.Cu")
	)
	(gr_circle
		(center 394.64996 -317.749936)
		(end 394.90396 -317.749936)
		(stroke
			(width 0.1016)
			(type default)
		)
		(fill no)
		(layer "In1.Cu")
	)
	(gr_circle
		(center 394.64996 -313.949842)
		(end 394.90396 -313.949842)
		(stroke
			(width 0.1016)
			(type default)
		)
		(fill no)
		(layer "In1.Cu")
	)
	(gr_circle
		(center 394.64996 -312.999882)
		(end 394.90396 -312.999882)
		(stroke
			(width 0.1016)
			(type default)
		)
		(fill no)
		(layer "In1.Cu")
	)
	(gr_circle
		(center 394.64996 -278.799798)
		(end 394.90396 -278.799798)
		(stroke
			(width 0.1016)
			(type default)
		)
		(fill no)
		(layer "In1.Cu")
	)
	(gr_circle
		(center 394.64996 -277.849838)
		(end 394.90396 -277.849838)
		(stroke
			(width 0.1016)
			(type default)
		)
		(fill no)
		(layer "In1.Cu")
	)
	(gr_circle
		(center 394.64996 -274.049744)
		(end 394.90396 -274.049744)
		(stroke
			(width 0.1016)
			(type default)
		)
		(fill no)
		(layer "In1.Cu")
	)
	(gr_circle
		(center 394.64996 -273.099784)
		(end 394.90396 -273.099784)
		(stroke
			(width 0.1016)
			(type default)
		)
		(fill no)
		(layer "In1.Cu")
	)
	(gr_circle
		(center 395.59992 -316.799722)
		(end 395.85392 -316.799722)
		(stroke
			(width 0.1016)
			(type default)
		)
		(fill no)
		(layer "In1.Cu")
	)
	(gr_circle
		(center 395.59992 -315.849762)
		(end 395.85392 -315.849762)
		(stroke
			(width 0.1016)
			(type default)
		)
		(fill no)
		(layer "In1.Cu")
	)
	(gr_circle
		(center 395.59992 -312.049922)
		(end 395.85392 -312.049922)
		(stroke
			(width 0.1016)
			(type default)
		)
		(fill no)
		(layer "In1.Cu")
	)
	(gr_circle
		(center 395.59992 -311.099962)
		(end 395.85392 -311.099962)
		(stroke
			(width 0.1016)
			(type default)
		)
		(fill no)
		(layer "In1.Cu")
	)
	(gr_circle
		(center 395.59992 -280.699464)
		(end 395.85392 -280.699464)
		(stroke
			(width 0.1016)
			(type default)
		)
		(fill no)
		(layer "In1.Cu")
	)
	(gr_circle
		(center 395.59992 -279.749504)
		(end 395.85392 -279.749504)
		(stroke
			(width 0.1016)
			(type default)
		)
		(fill no)
		(layer "In1.Cu")
	)
	(gr_circle
		(center 395.59992 -275.949918)
		(end 395.85392 -275.949918)
		(stroke
			(width 0.1016)
			(type default)
		)
		(fill no)
		(layer "In1.Cu")
	)
	(gr_circle
		(center 395.59992 -274.999958)
		(end 395.85392 -274.999958)
		(stroke
			(width 0.1016)
			(type default)
		)
		(fill no)
		(layer "In1.Cu")
	)
	(gr_circle
		(center 396.54988 -318.699896)
		(end 396.80388 -318.699896)
		(stroke
			(width 0.1016)
			(type default)
		)
		(fill no)
		(layer "In1.Cu")
	)
	(gr_circle
		(center 396.54988 -317.749936)
		(end 396.80388 -317.749936)
		(stroke
			(width 0.1016)
			(type default)
		)
		(fill no)
		(layer "In1.Cu")
	)
	(gr_circle
		(center 396.54988 -313.949842)
		(end 396.80388 -313.949842)
		(stroke
			(width 0.1016)
			(type default)
		)
		(fill no)
		(layer "In1.Cu")
	)
	(gr_circle
		(center 396.54988 -312.999882)
		(end 396.80388 -312.999882)
		(stroke
			(width 0.1016)
			(type default)
		)
		(fill no)
		(layer "In1.Cu")
	)
	(gr_circle
		(center 396.54988 -278.799798)
		(end 396.80388 -278.799798)
		(stroke
			(width 0.1016)
			(type default)
		)
		(fill no)
		(layer "In1.Cu")
	)
	(gr_circle
		(center 396.54988 -277.849838)
		(end 396.80388 -277.849838)
		(stroke
			(width 0.1016)
			(type default)
		)
		(fill no)
		(layer "In1.Cu")
	)
	(gr_circle
		(center 396.54988 -274.049744)
		(end 396.80388 -274.049744)
		(stroke
			(width 0.1016)
			(type default)
		)
		(fill no)
		(layer "In1.Cu")
	)
	(gr_circle
		(center 396.54988 -273.099784)
		(end 396.80388 -273.099784)
		(stroke
			(width 0.1016)
			(type default)
		)
		(fill no)
		(layer "In1.Cu")
	)
	(gr_circle
		(center 397.49984 -316.799722)
		(end 397.75384 -316.799722)
		(stroke
			(width 0.1016)
			(type default)
		)
		(fill no)
		(layer "In1.Cu")
	)
	(gr_circle
		(center 397.49984 -315.849762)
		(end 397.75384 -315.849762)
		(stroke
			(width 0.1016)
			(type default)
		)
		(fill no)
		(layer "In1.Cu")
	)
	(gr_circle
		(center 397.49984 -312.049922)
		(end 397.75384 -312.049922)
		(stroke
			(width 0.1016)
			(type default)
		)
		(fill no)
		(layer "In1.Cu")
	)
	(gr_circle
		(center 397.49984 -311.099962)
		(end 397.75384 -311.099962)
		(stroke
			(width 0.1016)
			(type default)
		)
		(fill no)
		(layer "In1.Cu")
	)
	(gr_circle
		(center 397.49984 -280.699464)
		(end 397.75384 -280.699464)
		(stroke
			(width 0.1016)
			(type default)
		)
		(fill no)
		(layer "In1.Cu")
	)
	(gr_circle
		(center 397.49984 -279.749504)
		(end 397.75384 -279.749504)
		(stroke
			(width 0.1016)
			(type default)
		)
		(fill no)
		(layer "In1.Cu")
	)
	(gr_circle
		(center 397.49984 -275.949918)
		(end 397.75384 -275.949918)
		(stroke
			(width 0.1016)
			(type default)
		)
		(fill no)
		(layer "In1.Cu")
	)
	(gr_circle
		(center 397.49984 -274.999958)
		(end 397.75384 -274.999958)
		(stroke
			(width 0.1016)
			(type default)
		)
		(fill no)
		(layer "In1.Cu")
	)
	(gr_circle
		(center 398.4498 -318.699896)
		(end 398.7038 -318.699896)
		(stroke
			(width 0.1016)
			(type default)
		)
		(fill no)
		(layer "In1.Cu")
	)
	(gr_circle
		(center 398.4498 -317.749936)
		(end 398.7038 -317.749936)
		(stroke
			(width 0.1016)
			(type default)
		)
		(fill no)
		(layer "In1.Cu")
	)
	(gr_circle
		(center 398.4498 -313.949842)
		(end 398.7038 -313.949842)
		(stroke
			(width 0.1016)
			(type default)
		)
		(fill no)
		(layer "In1.Cu")
	)
	(gr_circle
		(center 398.4498 -312.999882)
		(end 398.7038 -312.999882)
		(stroke
			(width 0.1016)
			(type default)
		)
		(fill no)
		(layer "In1.Cu")
	)
	(gr_circle
		(center 398.4498 -278.799798)
		(end 398.7038 -278.799798)
		(stroke
			(width 0.1016)
			(type default)
		)
		(fill no)
		(layer "In1.Cu")
	)
	(gr_circle
		(center 398.4498 -277.849838)
		(end 398.7038 -277.849838)
		(stroke
			(width 0.1016)
			(type default)
		)
		(fill no)
		(layer "In1.Cu")
	)
	(gr_circle
		(center 398.4498 -274.049744)
		(end 398.7038 -274.049744)
		(stroke
			(width 0.1016)
			(type default)
		)
		(fill no)
		(layer "In1.Cu")
	)
	(gr_circle
		(center 398.4498 -273.099784)
		(end 398.7038 -273.099784)
		(stroke
			(width 0.1016)
			(type default)
		)
		(fill no)
		(layer "In1.Cu")
	)
	(gr_circle
		(center 399.400014 -316.799722)
		(end 399.654014 -316.799722)
		(stroke
			(width 0.1016)
			(type default)
		)
		(fill no)
		(layer "In1.Cu")
	)
	(gr_circle
		(center 399.400014 -315.849762)
		(end 399.654014 -315.849762)
		(stroke
			(width 0.1016)
			(type default)
		)
		(fill no)
		(layer "In1.Cu")
	)
	(gr_circle
		(center 399.400014 -312.049922)
		(end 399.654014 -312.049922)
		(stroke
			(width 0.1016)
			(type default)
		)
		(fill no)
		(layer "In1.Cu")
	)
	(gr_circle
		(center 399.400014 -311.099962)
		(end 399.654014 -311.099962)
		(stroke
			(width 0.1016)
			(type default)
		)
		(fill no)
		(layer "In1.Cu")
	)
	(gr_circle
		(center 399.400014 -280.699464)
		(end 399.654014 -280.699464)
		(stroke
			(width 0.1016)
			(type default)
		)
		(fill no)
		(layer "In1.Cu")
	)
	(gr_circle
		(center 399.400014 -279.749504)
		(end 399.654014 -279.749504)
		(stroke
			(width 0.1016)
			(type default)
		)
		(fill no)
		(layer "In1.Cu")
	)
	(gr_circle
		(center 399.400014 -275.949918)
		(end 399.654014 -275.949918)
		(stroke
			(width 0.1016)
			(type default)
		)
		(fill no)
		(layer "In1.Cu")
	)
	(gr_circle
		(center 399.400014 -274.999958)
		(end 399.654014 -274.999958)
		(stroke
			(width 0.1016)
			(type default)
		)
		(fill no)
		(layer "In1.Cu")
	)
	(gr_circle
		(center 400.349974 -318.699896)
		(end 400.603974 -318.699896)
		(stroke
			(width 0.1016)
			(type default)
		)
		(fill no)
		(layer "In1.Cu")
	)
	(gr_circle
		(center 400.349974 -317.749936)
		(end 400.603974 -317.749936)
		(stroke
			(width 0.1016)
			(type default)
		)
		(fill no)
		(layer "In1.Cu")
	)
	(gr_circle
		(center 400.349974 -313.949842)
		(end 400.603974 -313.949842)
		(stroke
			(width 0.1016)
			(type default)
		)
		(fill no)
		(layer "In1.Cu")
	)
	(gr_circle
		(center 400.349974 -312.999882)
		(end 400.603974 -312.999882)
		(stroke
			(width 0.1016)
			(type default)
		)
		(fill no)
		(layer "In1.Cu")
	)
	(gr_circle
		(center 400.349974 -278.799798)
		(end 400.603974 -278.799798)
		(stroke
			(width 0.1016)
			(type default)
		)
		(fill no)
		(layer "In1.Cu")
	)
	(gr_circle
		(center 400.349974 -277.849838)
		(end 400.603974 -277.849838)
		(stroke
			(width 0.1016)
			(type default)
		)
		(fill no)
		(layer "In1.Cu")
	)
	(gr_circle
		(center 400.349974 -274.049744)
		(end 400.603974 -274.049744)
		(stroke
			(width 0.1016)
			(type default)
		)
		(fill no)
		(layer "In1.Cu")
	)
	(gr_circle
		(center 400.349974 -273.099784)
		(end 400.603974 -273.099784)
		(stroke
			(width 0.1016)
			(type default)
		)
		(fill no)
		(layer "In1.Cu")
	)
	(gr_circle
		(center 401.299934 -316.799722)
		(end 401.553934 -316.799722)
		(stroke
			(width 0.1016)
			(type default)
		)
		(fill no)
		(layer "In1.Cu")
	)
	(gr_circle
		(center 401.299934 -315.849762)
		(end 401.553934 -315.849762)
		(stroke
			(width 0.1016)
			(type default)
		)
		(fill no)
		(layer "In1.Cu")
	)
	(gr_circle
		(center 401.299934 -312.049922)
		(end 401.553934 -312.049922)
		(stroke
			(width 0.1016)
			(type default)
		)
		(fill no)
		(layer "In1.Cu")
	)
	(gr_circle
		(center 401.299934 -311.099962)
		(end 401.553934 -311.099962)
		(stroke
			(width 0.1016)
			(type default)
		)
		(fill no)
		(layer "In1.Cu")
	)
	(gr_circle
		(center 401.299934 -280.699464)
		(end 401.553934 -280.699464)
		(stroke
			(width 0.1016)
			(type default)
		)
		(fill no)
		(layer "In1.Cu")
	)
	(gr_circle
		(center 401.299934 -279.749504)
		(end 401.553934 -279.749504)
		(stroke
			(width 0.1016)
			(type default)
		)
		(fill no)
		(layer "In1.Cu")
	)
	(gr_circle
		(center 401.299934 -275.949918)
		(end 401.553934 -275.949918)
		(stroke
			(width 0.1016)
			(type default)
		)
		(fill no)
		(layer "In1.Cu")
	)
	(gr_circle
		(center 401.299934 -274.999958)
		(end 401.553934 -274.999958)
		(stroke
			(width 0.1016)
			(type default)
		)
		(fill no)
		(layer "In1.Cu")
	)
	(gr_circle
		(center 402.249894 -318.699896)
		(end 402.503894 -318.699896)
		(stroke
			(width 0.1016)
			(type default)
		)
		(fill no)
		(layer "In1.Cu")
	)
	(gr_circle
		(center 402.249894 -317.749936)
		(end 402.503894 -317.749936)
		(stroke
			(width 0.1016)
			(type default)
		)
		(fill no)
		(layer "In1.Cu")
	)
	(gr_circle
		(center 402.249894 -313.949842)
		(end 402.503894 -313.949842)
		(stroke
			(width 0.1016)
			(type default)
		)
		(fill no)
		(layer "In1.Cu")
	)
	(gr_circle
		(center 402.249894 -312.999882)
		(end 402.503894 -312.999882)
		(stroke
			(width 0.1016)
			(type default)
		)
		(fill no)
		(layer "In1.Cu")
	)
	(gr_circle
		(center 402.249894 -278.799798)
		(end 402.503894 -278.799798)
		(stroke
			(width 0.1016)
			(type default)
		)
		(fill no)
		(layer "In1.Cu")
	)
	(gr_circle
		(center 402.249894 -277.849838)
		(end 402.503894 -277.849838)
		(stroke
			(width 0.1016)
			(type default)
		)
		(fill no)
		(layer "In1.Cu")
	)
	(gr_circle
		(center 402.249894 -274.049744)
		(end 402.503894 -274.049744)
		(stroke
			(width 0.1016)
			(type default)
		)
		(fill no)
		(layer "In1.Cu")
	)
	(gr_circle
		(center 402.249894 -273.099784)
		(end 402.503894 -273.099784)
		(stroke
			(width 0.1016)
			(type default)
		)
		(fill no)
		(layer "In1.Cu")
	)
	(gr_circle
		(center 403.199854 -316.799722)
		(end 403.453854 -316.799722)
		(stroke
			(width 0.1016)
			(type default)
		)
		(fill no)
		(layer "In1.Cu")
	)
	(gr_circle
		(center 403.199854 -315.849762)
		(end 403.453854 -315.849762)
		(stroke
			(width 0.1016)
			(type default)
		)
		(fill no)
		(layer "In1.Cu")
	)
	(gr_circle
		(center 403.199854 -312.049922)
		(end 403.453854 -312.049922)
		(stroke
			(width 0.1016)
			(type default)
		)
		(fill no)
		(layer "In1.Cu")
	)
	(gr_circle
		(center 403.199854 -311.099962)
		(end 403.453854 -311.099962)
		(stroke
			(width 0.1016)
			(type default)
		)
		(fill no)
		(layer "In1.Cu")
	)
	(gr_circle
		(center 403.199854 -280.699464)
		(end 403.453854 -280.699464)
		(stroke
			(width 0.1016)
			(type default)
		)
		(fill no)
		(layer "In1.Cu")
	)
	(gr_circle
		(center 403.199854 -279.749504)
		(end 403.453854 -279.749504)
		(stroke
			(width 0.1016)
			(type default)
		)
		(fill no)
		(layer "In1.Cu")
	)
	(gr_circle
		(center 403.199854 -275.949918)
		(end 403.453854 -275.949918)
		(stroke
			(width 0.1016)
			(type default)
		)
		(fill no)
		(layer "In1.Cu")
	)
	(gr_circle
		(center 403.199854 -274.999958)
		(end 403.453854 -274.999958)
		(stroke
			(width 0.1016)
			(type default)
		)
		(fill no)
		(layer "In1.Cu")
	)
	(gr_circle
		(center 404.149814 -318.699896)
		(end 404.403814 -318.699896)
		(stroke
			(width 0.1016)
			(type default)
		)
		(fill no)
		(layer "In1.Cu")
	)
	(gr_circle
		(center 404.149814 -317.749936)
		(end 404.403814 -317.749936)
		(stroke
			(width 0.1016)
			(type default)
		)
		(fill no)
		(layer "In1.Cu")
	)
	(gr_circle
		(center 404.149814 -313.949842)
		(end 404.403814 -313.949842)
		(stroke
			(width 0.1016)
			(type default)
		)
		(fill no)
		(layer "In1.Cu")
	)
	(gr_circle
		(center 404.149814 -312.999882)
		(end 404.403814 -312.999882)
		(stroke
			(width 0.1016)
			(type default)
		)
		(fill no)
		(layer "In1.Cu")
	)
	(gr_circle
		(center 404.149814 -278.799798)
		(end 404.403814 -278.799798)
		(stroke
			(width 0.1016)
			(type default)
		)
		(fill no)
		(layer "In1.Cu")
	)
	(gr_circle
		(center 404.149814 -277.849838)
		(end 404.403814 -277.849838)
		(stroke
			(width 0.1016)
			(type default)
		)
		(fill no)
		(layer "In1.Cu")
	)
	(gr_circle
		(center 404.149814 -274.049744)
		(end 404.403814 -274.049744)
		(stroke
			(width 0.1016)
			(type default)
		)
		(fill no)
		(layer "In1.Cu")
	)
	(gr_circle
		(center 404.149814 -273.099784)
		(end 404.403814 -273.099784)
		(stroke
			(width 0.1016)
			(type default)
		)
		(fill no)
		(layer "In1.Cu")
	)
	(gr_circle
		(center 405.099774 -280.699464)
		(end 405.353774 -280.699464)
		(stroke
			(width 0.1016)
			(type default)
		)
		(fill no)
		(layer "In1.Cu")
	)
	(gr_circle
		(center 405.099774 -279.749504)
		(end 405.353774 -279.749504)
		(stroke
			(width 0.1016)
			(type default)
		)
		(fill no)
		(layer "In1.Cu")
	)
	(gr_circle
		(center 405.100028 -316.799722)
		(end 405.354028 -316.799722)
		(stroke
			(width 0.1016)
			(type default)
		)
		(fill no)
		(layer "In1.Cu")
	)
	(gr_circle
		(center 405.100028 -315.849762)
		(end 405.354028 -315.849762)
		(stroke
			(width 0.1016)
			(type default)
		)
		(fill no)
		(layer "In1.Cu")
	)
	(gr_circle
		(center 405.100028 -312.049922)
		(end 405.354028 -312.049922)
		(stroke
			(width 0.1016)
			(type default)
		)
		(fill no)
		(layer "In1.Cu")
	)
	(gr_circle
		(center 405.100028 -311.099962)
		(end 405.354028 -311.099962)
		(stroke
			(width 0.1016)
			(type default)
		)
		(fill no)
		(layer "In1.Cu")
	)
	(gr_circle
		(center 405.100028 -275.949918)
		(end 405.354028 -275.949918)
		(stroke
			(width 0.1016)
			(type default)
		)
		(fill no)
		(layer "In1.Cu")
	)
	(gr_circle
		(center 405.100028 -274.999958)
		(end 405.354028 -274.999958)
		(stroke
			(width 0.1016)
			(type default)
		)
		(fill no)
		(layer "In1.Cu")
	)
	(gr_circle
		(center 406.049988 -318.699896)
		(end 406.303988 -318.699896)
		(stroke
			(width 0.1016)
			(type default)
		)
		(fill no)
		(layer "In1.Cu")
	)
	(gr_circle
		(center 406.049988 -317.749936)
		(end 406.303988 -317.749936)
		(stroke
			(width 0.1016)
			(type default)
		)
		(fill no)
		(layer "In1.Cu")
	)
	(gr_circle
		(center 406.049988 -313.949842)
		(end 406.303988 -313.949842)
		(stroke
			(width 0.1016)
			(type default)
		)
		(fill no)
		(layer "In1.Cu")
	)
	(gr_circle
		(center 406.049988 -312.999882)
		(end 406.303988 -312.999882)
		(stroke
			(width 0.1016)
			(type default)
		)
		(fill no)
		(layer "In1.Cu")
	)
	(gr_circle
		(center 406.049988 -278.799798)
		(end 406.303988 -278.799798)
		(stroke
			(width 0.1016)
			(type default)
		)
		(fill no)
		(layer "In1.Cu")
	)
	(gr_circle
		(center 406.049988 -277.849838)
		(end 406.303988 -277.849838)
		(stroke
			(width 0.1016)
			(type default)
		)
		(fill no)
		(layer "In1.Cu")
	)
	(gr_circle
		(center 406.049988 -274.049744)
		(end 406.303988 -274.049744)
		(stroke
			(width 0.1016)
			(type default)
		)
		(fill no)
		(layer "In1.Cu")
	)
	(gr_circle
		(center 406.049988 -273.099784)
		(end 406.303988 -273.099784)
		(stroke
			(width 0.1016)
			(type default)
		)
		(fill no)
		(layer "In1.Cu")
	)
	(gr_circle
		(center 406.999948 -316.799722)
		(end 407.253948 -316.799722)
		(stroke
			(width 0.1016)
			(type default)
		)
		(fill no)
		(layer "In1.Cu")
	)
	(gr_circle
		(center 406.999948 -315.849762)
		(end 407.253948 -315.849762)
		(stroke
			(width 0.1016)
			(type default)
		)
		(fill no)
		(layer "In1.Cu")
	)
	(gr_circle
		(center 406.999948 -312.049922)
		(end 407.253948 -312.049922)
		(stroke
			(width 0.1016)
			(type default)
		)
		(fill no)
		(layer "In1.Cu")
	)
	(gr_circle
		(center 406.999948 -311.099962)
		(end 407.253948 -311.099962)
		(stroke
			(width 0.1016)
			(type default)
		)
		(fill no)
		(layer "In1.Cu")
	)
	(gr_circle
		(center 406.999948 -280.699464)
		(end 407.253948 -280.699464)
		(stroke
			(width 0.1016)
			(type default)
		)
		(fill no)
		(layer "In1.Cu")
	)
	(gr_circle
		(center 406.999948 -279.749504)
		(end 407.253948 -279.749504)
		(stroke
			(width 0.1016)
			(type default)
		)
		(fill no)
		(layer "In1.Cu")
	)
	(gr_circle
		(center 406.999948 -275.949918)
		(end 407.253948 -275.949918)
		(stroke
			(width 0.1016)
			(type default)
		)
		(fill no)
		(layer "In1.Cu")
	)
	(gr_circle
		(center 406.999948 -274.999958)
		(end 407.253948 -274.999958)
		(stroke
			(width 0.1016)
			(type default)
		)
		(fill no)
		(layer "In1.Cu")
	)
	(gr_circle
		(center 407.949654 -278.799798)
		(end 408.203654 -278.799798)
		(stroke
			(width 0.1016)
			(type default)
		)
		(fill no)
		(layer "In1.Cu")
	)
	(gr_circle
		(center 407.949654 -277.849838)
		(end 408.203654 -277.849838)
		(stroke
			(width 0.1016)
			(type default)
		)
		(fill no)
		(layer "In1.Cu")
	)
	(gr_circle
		(center 407.949654 -274.04949)
		(end 408.203654 -274.04949)
		(stroke
			(width 0.1016)
			(type default)
		)
		(fill no)
		(layer "In1.Cu")
	)
	(gr_circle
		(center 407.949654 -273.09953)
		(end 408.203654 -273.09953)
		(stroke
			(width 0.1016)
			(type default)
		)
		(fill no)
		(layer "In1.Cu")
	)
	(gr_circle
		(center 407.949908 -318.699896)
		(end 408.203908 -318.699896)
		(stroke
			(width 0.1016)
			(type default)
		)
		(fill no)
		(layer "In1.Cu")
	)
	(gr_circle
		(center 407.949908 -317.749936)
		(end 408.203908 -317.749936)
		(stroke
			(width 0.1016)
			(type default)
		)
		(fill no)
		(layer "In1.Cu")
	)
	(gr_circle
		(center 407.949908 -313.949842)
		(end 408.203908 -313.949842)
		(stroke
			(width 0.1016)
			(type default)
		)
		(fill no)
		(layer "In1.Cu")
	)
	(gr_circle
		(center 407.949908 -312.999882)
		(end 408.203908 -312.999882)
		(stroke
			(width 0.1016)
			(type default)
		)
		(fill no)
		(layer "In1.Cu")
	)
	(gr_circle
		(center 408.899614 -275.949664)
		(end 409.153614 -275.949664)
		(stroke
			(width 0.1016)
			(type default)
		)
		(fill no)
		(layer "In1.Cu")
	)
	(gr_circle
		(center 408.899614 -274.999704)
		(end 409.153614 -274.999704)
		(stroke
			(width 0.1016)
			(type default)
		)
		(fill no)
		(layer "In1.Cu")
	)
	(gr_circle
		(center 408.899868 -316.799722)
		(end 409.153868 -316.799722)
		(stroke
			(width 0.1016)
			(type default)
		)
		(fill no)
		(layer "In1.Cu")
	)
	(gr_circle
		(center 408.899868 -315.849762)
		(end 409.153868 -315.849762)
		(stroke
			(width 0.1016)
			(type default)
		)
		(fill no)
		(layer "In1.Cu")
	)
	(gr_circle
		(center 408.899868 -312.049922)
		(end 409.153868 -312.049922)
		(stroke
			(width 0.1016)
			(type default)
		)
		(fill no)
		(layer "In1.Cu")
	)
	(gr_circle
		(center 408.899868 -311.099962)
		(end 409.153868 -311.099962)
		(stroke
			(width 0.1016)
			(type default)
		)
		(fill no)
		(layer "In1.Cu")
	)
	(gr_circle
		(center 408.899868 -280.699464)
		(end 409.153868 -280.699464)
		(stroke
			(width 0.1016)
			(type default)
		)
		(fill no)
		(layer "In1.Cu")
	)
	(gr_circle
		(center 408.899868 -279.749504)
		(end 409.153868 -279.749504)
		(stroke
			(width 0.1016)
			(type default)
		)
		(fill no)
		(layer "In1.Cu")
	)
	(gr_circle
		(center 409.849574 -278.799798)
		(end 410.103574 -278.799798)
		(stroke
			(width 0.1016)
			(type default)
		)
		(fill no)
		(layer "In1.Cu")
	)
	(gr_circle
		(center 409.849574 -277.849838)
		(end 410.103574 -277.849838)
		(stroke
			(width 0.1016)
			(type default)
		)
		(fill no)
		(layer "In1.Cu")
	)
	(gr_circle
		(center 409.849574 -274.049744)
		(end 410.103574 -274.049744)
		(stroke
			(width 0.1016)
			(type default)
		)
		(fill no)
		(layer "In1.Cu")
	)
	(gr_circle
		(center 409.849574 -273.099784)
		(end 410.103574 -273.099784)
		(stroke
			(width 0.1016)
			(type default)
		)
		(fill no)
		(layer "In1.Cu")
	)
	(gr_circle
		(center 409.849828 -318.699896)
		(end 410.103828 -318.699896)
		(stroke
			(width 0.1016)
			(type default)
		)
		(fill no)
		(layer "In1.Cu")
	)
	(gr_circle
		(center 409.849828 -317.749936)
		(end 410.103828 -317.749936)
		(stroke
			(width 0.1016)
			(type default)
		)
		(fill no)
		(layer "In1.Cu")
	)
	(gr_circle
		(center 409.849828 -313.949842)
		(end 410.103828 -313.949842)
		(stroke
			(width 0.1016)
			(type default)
		)
		(fill no)
		(layer "In1.Cu")
	)
	(gr_circle
		(center 409.849828 -312.999882)
		(end 410.103828 -312.999882)
		(stroke
			(width 0.1016)
			(type default)
		)
		(fill no)
		(layer "In1.Cu")
	)
	(gr_circle
		(center 410.799534 -275.949918)
		(end 411.053534 -275.949918)
		(stroke
			(width 0.1016)
			(type default)
		)
		(fill no)
		(layer "In1.Cu")
	)
	(gr_circle
		(center 410.799534 -274.999958)
		(end 411.053534 -274.999958)
		(stroke
			(width 0.1016)
			(type default)
		)
		(fill no)
		(layer "In1.Cu")
	)
	(gr_circle
		(center 410.799788 -316.799722)
		(end 411.053788 -316.799722)
		(stroke
			(width 0.1016)
			(type default)
		)
		(fill no)
		(layer "In1.Cu")
	)
	(gr_circle
		(center 410.799788 -315.849762)
		(end 411.053788 -315.849762)
		(stroke
			(width 0.1016)
			(type default)
		)
		(fill no)
		(layer "In1.Cu")
	)
	(gr_circle
		(center 410.799788 -312.049922)
		(end 411.053788 -312.049922)
		(stroke
			(width 0.1016)
			(type default)
		)
		(fill no)
		(layer "In1.Cu")
	)
	(gr_circle
		(center 410.799788 -311.099962)
		(end 411.053788 -311.099962)
		(stroke
			(width 0.1016)
			(type default)
		)
		(fill no)
		(layer "In1.Cu")
	)
	(gr_circle
		(center 410.799788 -280.699464)
		(end 411.053788 -280.699464)
		(stroke
			(width 0.1016)
			(type default)
		)
		(fill no)
		(layer "In1.Cu")
	)
	(gr_circle
		(center 410.799788 -279.749504)
		(end 411.053788 -279.749504)
		(stroke
			(width 0.1016)
			(type default)
		)
		(fill no)
		(layer "In1.Cu")
	)
	(gr_circle
		(center 411.749748 -278.799798)
		(end 412.003748 -278.799798)
		(stroke
			(width 0.1016)
			(type default)
		)
		(fill no)
		(layer "In1.Cu")
	)
	(gr_circle
		(center 411.749748 -277.849838)
		(end 412.003748 -277.849838)
		(stroke
			(width 0.1016)
			(type default)
		)
		(fill no)
		(layer "In1.Cu")
	)
	(gr_circle
		(center 411.749748 -274.049744)
		(end 412.003748 -274.049744)
		(stroke
			(width 0.1016)
			(type default)
		)
		(fill no)
		(layer "In1.Cu")
	)
	(gr_circle
		(center 411.749748 -273.099784)
		(end 412.003748 -273.099784)
		(stroke
			(width 0.1016)
			(type default)
		)
		(fill no)
		(layer "In1.Cu")
	)
	(gr_circle
		(center 411.750002 -318.699896)
		(end 412.004002 -318.699896)
		(stroke
			(width 0.1016)
			(type default)
		)
		(fill no)
		(layer "In1.Cu")
	)
	(gr_circle
		(center 411.750002 -317.749936)
		(end 412.004002 -317.749936)
		(stroke
			(width 0.1016)
			(type default)
		)
		(fill no)
		(layer "In1.Cu")
	)
	(gr_circle
		(center 411.750002 -313.949842)
		(end 412.004002 -313.949842)
		(stroke
			(width 0.1016)
			(type default)
		)
		(fill no)
		(layer "In1.Cu")
	)
	(gr_circle
		(center 411.750002 -312.999882)
		(end 412.004002 -312.999882)
		(stroke
			(width 0.1016)
			(type default)
		)
		(fill no)
		(layer "In1.Cu")
	)
	(gr_circle
		(center 412.699708 -275.949664)
		(end 412.953708 -275.949664)
		(stroke
			(width 0.1016)
			(type default)
		)
		(fill no)
		(layer "In1.Cu")
	)
	(gr_circle
		(center 412.699708 -274.999704)
		(end 412.953708 -274.999704)
		(stroke
			(width 0.1016)
			(type default)
		)
		(fill no)
		(layer "In1.Cu")
	)
	(gr_circle
		(center 412.699962 -316.799722)
		(end 412.953962 -316.799722)
		(stroke
			(width 0.1016)
			(type default)
		)
		(fill no)
		(layer "In1.Cu")
	)
	(gr_circle
		(center 412.699962 -315.849762)
		(end 412.953962 -315.849762)
		(stroke
			(width 0.1016)
			(type default)
		)
		(fill no)
		(layer "In1.Cu")
	)
	(gr_circle
		(center 412.699962 -312.049922)
		(end 412.953962 -312.049922)
		(stroke
			(width 0.1016)
			(type default)
		)
		(fill no)
		(layer "In1.Cu")
	)
	(gr_circle
		(center 412.699962 -311.099962)
		(end 412.953962 -311.099962)
		(stroke
			(width 0.1016)
			(type default)
		)
		(fill no)
		(layer "In1.Cu")
	)
	(gr_circle
		(center 412.699962 -280.699464)
		(end 412.953962 -280.699464)
		(stroke
			(width 0.1016)
			(type default)
		)
		(fill no)
		(layer "In1.Cu")
	)
	(gr_circle
		(center 412.699962 -279.749504)
		(end 412.953962 -279.749504)
		(stroke
			(width 0.1016)
			(type default)
		)
		(fill no)
		(layer "In1.Cu")
	)
	(gr_circle
		(center 413.649668 -278.799798)
		(end 413.903668 -278.799798)
		(stroke
			(width 0.1016)
			(type default)
		)
		(fill no)
		(layer "In1.Cu")
	)
	(gr_circle
		(center 413.649668 -277.849838)
		(end 413.903668 -277.849838)
		(stroke
			(width 0.1016)
			(type default)
		)
		(fill no)
		(layer "In1.Cu")
	)
	(gr_circle
		(center 413.649668 -274.049744)
		(end 413.903668 -274.049744)
		(stroke
			(width 0.1016)
			(type default)
		)
		(fill no)
		(layer "In1.Cu")
	)
	(gr_circle
		(center 413.649668 -273.099784)
		(end 413.903668 -273.099784)
		(stroke
			(width 0.1016)
			(type default)
		)
		(fill no)
		(layer "In1.Cu")
	)
	(gr_circle
		(center 413.649922 -318.699896)
		(end 413.903922 -318.699896)
		(stroke
			(width 0.1016)
			(type default)
		)
		(fill no)
		(layer "In1.Cu")
	)
	(gr_circle
		(center 413.649922 -317.749936)
		(end 413.903922 -317.749936)
		(stroke
			(width 0.1016)
			(type default)
		)
		(fill no)
		(layer "In1.Cu")
	)
	(gr_circle
		(center 413.649922 -313.949842)
		(end 413.903922 -313.949842)
		(stroke
			(width 0.1016)
			(type default)
		)
		(fill no)
		(layer "In1.Cu")
	)
	(gr_circle
		(center 413.649922 -312.999882)
		(end 413.903922 -312.999882)
		(stroke
			(width 0.1016)
			(type default)
		)
		(fill no)
		(layer "In1.Cu")
	)
	(gr_circle
		(center 414.599628 -275.949918)
		(end 414.853628 -275.949918)
		(stroke
			(width 0.1016)
			(type default)
		)
		(fill no)
		(layer "In1.Cu")
	)
	(gr_circle
		(center 414.599628 -274.999958)
		(end 414.853628 -274.999958)
		(stroke
			(width 0.1016)
			(type default)
		)
		(fill no)
		(layer "In1.Cu")
	)
	(gr_circle
		(center 414.599882 -316.799722)
		(end 414.853882 -316.799722)
		(stroke
			(width 0.1016)
			(type default)
		)
		(fill no)
		(layer "In1.Cu")
	)
	(gr_circle
		(center 414.599882 -315.849762)
		(end 414.853882 -315.849762)
		(stroke
			(width 0.1016)
			(type default)
		)
		(fill no)
		(layer "In1.Cu")
	)
	(gr_circle
		(center 414.599882 -312.049922)
		(end 414.853882 -312.049922)
		(stroke
			(width 0.1016)
			(type default)
		)
		(fill no)
		(layer "In1.Cu")
	)
	(gr_circle
		(center 414.599882 -311.099962)
		(end 414.853882 -311.099962)
		(stroke
			(width 0.1016)
			(type default)
		)
		(fill no)
		(layer "In1.Cu")
	)
	(gr_circle
		(center 414.599882 -280.699464)
		(end 414.853882 -280.699464)
		(stroke
			(width 0.1016)
			(type default)
		)
		(fill no)
		(layer "In1.Cu")
	)
	(gr_circle
		(center 414.599882 -279.749504)
		(end 414.853882 -279.749504)
		(stroke
			(width 0.1016)
			(type default)
		)
		(fill no)
		(layer "In1.Cu")
	)
	(gr_circle
		(center 415.549588 -278.799798)
		(end 415.803588 -278.799798)
		(stroke
			(width 0.1016)
			(type default)
		)
		(fill no)
		(layer "In1.Cu")
	)
	(gr_circle
		(center 415.549588 -277.849838)
		(end 415.803588 -277.849838)
		(stroke
			(width 0.1016)
			(type default)
		)
		(fill no)
		(layer "In1.Cu")
	)
	(gr_circle
		(center 415.549588 -274.049744)
		(end 415.803588 -274.049744)
		(stroke
			(width 0.1016)
			(type default)
		)
		(fill no)
		(layer "In1.Cu")
	)
	(gr_circle
		(center 415.549588 -273.099784)
		(end 415.803588 -273.099784)
		(stroke
			(width 0.1016)
			(type default)
		)
		(fill no)
		(layer "In1.Cu")
	)
	(gr_circle
		(center 415.549842 -318.699896)
		(end 415.803842 -318.699896)
		(stroke
			(width 0.1016)
			(type default)
		)
		(fill no)
		(layer "In1.Cu")
	)
	(gr_circle
		(center 415.549842 -317.749936)
		(end 415.803842 -317.749936)
		(stroke
			(width 0.1016)
			(type default)
		)
		(fill no)
		(layer "In1.Cu")
	)
	(gr_circle
		(center 415.549842 -313.949842)
		(end 415.803842 -313.949842)
		(stroke
			(width 0.1016)
			(type default)
		)
		(fill no)
		(layer "In1.Cu")
	)
	(gr_circle
		(center 415.549842 -312.999882)
		(end 415.803842 -312.999882)
		(stroke
			(width 0.1016)
			(type default)
		)
		(fill no)
		(layer "In1.Cu")
	)
	(gr_circle
		(center 416.499548 -275.949664)
		(end 416.753548 -275.949664)
		(stroke
			(width 0.1016)
			(type default)
		)
		(fill no)
		(layer "In1.Cu")
	)
	(gr_circle
		(center 416.499548 -274.999704)
		(end 416.753548 -274.999704)
		(stroke
			(width 0.1016)
			(type default)
		)
		(fill no)
		(layer "In1.Cu")
	)
	(gr_circle
		(center 416.499802 -316.799722)
		(end 416.753802 -316.799722)
		(stroke
			(width 0.1016)
			(type default)
		)
		(fill no)
		(layer "In1.Cu")
	)
	(gr_circle
		(center 416.499802 -315.849762)
		(end 416.753802 -315.849762)
		(stroke
			(width 0.1016)
			(type default)
		)
		(fill no)
		(layer "In1.Cu")
	)
	(gr_circle
		(center 416.499802 -312.049922)
		(end 416.753802 -312.049922)
		(stroke
			(width 0.1016)
			(type default)
		)
		(fill no)
		(layer "In1.Cu")
	)
	(gr_circle
		(center 416.499802 -311.099962)
		(end 416.753802 -311.099962)
		(stroke
			(width 0.1016)
			(type default)
		)
		(fill no)
		(layer "In1.Cu")
	)
	(gr_circle
		(center 416.499802 -280.699464)
		(end 416.753802 -280.699464)
		(stroke
			(width 0.1016)
			(type default)
		)
		(fill no)
		(layer "In1.Cu")
	)
	(gr_circle
		(center 416.499802 -279.749504)
		(end 416.753802 -279.749504)
		(stroke
			(width 0.1016)
			(type default)
		)
		(fill no)
		(layer "In1.Cu")
	)
	(gr_circle
		(center 417.449762 -278.799798)
		(end 417.703762 -278.799798)
		(stroke
			(width 0.1016)
			(type default)
		)
		(fill no)
		(layer "In1.Cu")
	)
	(gr_circle
		(center 417.449762 -277.849838)
		(end 417.703762 -277.849838)
		(stroke
			(width 0.1016)
			(type default)
		)
		(fill no)
		(layer "In1.Cu")
	)
	(gr_circle
		(center 417.449762 -274.049744)
		(end 417.703762 -274.049744)
		(stroke
			(width 0.1016)
			(type default)
		)
		(fill no)
		(layer "In1.Cu")
	)
	(gr_circle
		(center 417.449762 -273.099784)
		(end 417.703762 -273.099784)
		(stroke
			(width 0.1016)
			(type default)
		)
		(fill no)
		(layer "In1.Cu")
	)
	(gr_circle
		(center 417.450016 -318.699896)
		(end 417.704016 -318.699896)
		(stroke
			(width 0.1016)
			(type default)
		)
		(fill no)
		(layer "In1.Cu")
	)
	(gr_circle
		(center 417.450016 -317.749936)
		(end 417.704016 -317.749936)
		(stroke
			(width 0.1016)
			(type default)
		)
		(fill no)
		(layer "In1.Cu")
	)
	(gr_circle
		(center 417.450016 -313.949842)
		(end 417.704016 -313.949842)
		(stroke
			(width 0.1016)
			(type default)
		)
		(fill no)
		(layer "In1.Cu")
	)
	(gr_circle
		(center 417.450016 -312.999882)
		(end 417.704016 -312.999882)
		(stroke
			(width 0.1016)
			(type default)
		)
		(fill no)
		(layer "In1.Cu")
	)
	(gr_circle
		(center 418.399468 -275.949918)
		(end 418.653468 -275.949918)
		(stroke
			(width 0.1016)
			(type default)
		)
		(fill no)
		(layer "In1.Cu")
	)
	(gr_circle
		(center 418.399468 -274.999958)
		(end 418.653468 -274.999958)
		(stroke
			(width 0.1016)
			(type default)
		)
		(fill no)
		(layer "In1.Cu")
	)
	(gr_circle
		(center 418.399976 -316.799722)
		(end 418.653976 -316.799722)
		(stroke
			(width 0.1016)
			(type default)
		)
		(fill no)
		(layer "In1.Cu")
	)
	(gr_circle
		(center 418.399976 -315.849762)
		(end 418.653976 -315.849762)
		(stroke
			(width 0.1016)
			(type default)
		)
		(fill no)
		(layer "In1.Cu")
	)
	(gr_circle
		(center 418.399976 -312.049922)
		(end 418.653976 -312.049922)
		(stroke
			(width 0.1016)
			(type default)
		)
		(fill no)
		(layer "In1.Cu")
	)
	(gr_circle
		(center 418.399976 -311.099962)
		(end 418.653976 -311.099962)
		(stroke
			(width 0.1016)
			(type default)
		)
		(fill no)
		(layer "In1.Cu")
	)
	(gr_circle
		(center 418.399976 -280.699464)
		(end 418.653976 -280.699464)
		(stroke
			(width 0.1016)
			(type default)
		)
		(fill no)
		(layer "In1.Cu")
	)
	(gr_circle
		(center 418.399976 -279.749504)
		(end 418.653976 -279.749504)
		(stroke
			(width 0.1016)
			(type default)
		)
		(fill no)
		(layer "In1.Cu")
	)
	(gr_circle
		(center 419.349682 -278.799798)
		(end 419.603682 -278.799798)
		(stroke
			(width 0.1016)
			(type default)
		)
		(fill no)
		(layer "In1.Cu")
	)
	(gr_circle
		(center 419.349682 -277.849838)
		(end 419.603682 -277.849838)
		(stroke
			(width 0.1016)
			(type default)
		)
		(fill no)
		(layer "In1.Cu")
	)
	(gr_circle
		(center 419.349682 -274.049744)
		(end 419.603682 -274.049744)
		(stroke
			(width 0.1016)
			(type default)
		)
		(fill no)
		(layer "In1.Cu")
	)
	(gr_circle
		(center 419.349682 -273.099784)
		(end 419.603682 -273.099784)
		(stroke
			(width 0.1016)
			(type default)
		)
		(fill no)
		(layer "In1.Cu")
	)
	(gr_circle
		(center 419.349936 -318.699896)
		(end 419.603936 -318.699896)
		(stroke
			(width 0.1016)
			(type default)
		)
		(fill no)
		(layer "In1.Cu")
	)
	(gr_circle
		(center 419.349936 -317.749936)
		(end 419.603936 -317.749936)
		(stroke
			(width 0.1016)
			(type default)
		)
		(fill no)
		(layer "In1.Cu")
	)
	(gr_circle
		(center 419.349936 -313.949842)
		(end 419.603936 -313.949842)
		(stroke
			(width 0.1016)
			(type default)
		)
		(fill no)
		(layer "In1.Cu")
	)
	(gr_circle
		(center 419.349936 -312.999882)
		(end 419.603936 -312.999882)
		(stroke
			(width 0.1016)
			(type default)
		)
		(fill no)
		(layer "In1.Cu")
	)
	(gr_circle
		(center 420.299642 -275.949664)
		(end 420.553642 -275.949664)
		(stroke
			(width 0.1016)
			(type default)
		)
		(fill no)
		(layer "In1.Cu")
	)
	(gr_circle
		(center 420.299642 -274.999704)
		(end 420.553642 -274.999704)
		(stroke
			(width 0.1016)
			(type default)
		)
		(fill no)
		(layer "In1.Cu")
	)
	(gr_circle
		(center 420.299896 -316.799722)
		(end 420.553896 -316.799722)
		(stroke
			(width 0.1016)
			(type default)
		)
		(fill no)
		(layer "In1.Cu")
	)
	(gr_circle
		(center 420.299896 -315.849762)
		(end 420.553896 -315.849762)
		(stroke
			(width 0.1016)
			(type default)
		)
		(fill no)
		(layer "In1.Cu")
	)
	(gr_circle
		(center 420.299896 -312.049922)
		(end 420.553896 -312.049922)
		(stroke
			(width 0.1016)
			(type default)
		)
		(fill no)
		(layer "In1.Cu")
	)
	(gr_circle
		(center 420.299896 -311.099962)
		(end 420.553896 -311.099962)
		(stroke
			(width 0.1016)
			(type default)
		)
		(fill no)
		(layer "In1.Cu")
	)
	(gr_circle
		(center 420.299896 -280.699464)
		(end 420.553896 -280.699464)
		(stroke
			(width 0.1016)
			(type default)
		)
		(fill no)
		(layer "In1.Cu")
	)
	(gr_circle
		(center 420.299896 -279.749504)
		(end 420.553896 -279.749504)
		(stroke
			(width 0.1016)
			(type default)
		)
		(fill no)
		(layer "In1.Cu")
	)
	(gr_circle
		(center 421.249602 -278.799798)
		(end 421.503602 -278.799798)
		(stroke
			(width 0.1016)
			(type default)
		)
		(fill no)
		(layer "In1.Cu")
	)
	(gr_circle
		(center 421.249602 -277.849838)
		(end 421.503602 -277.849838)
		(stroke
			(width 0.1016)
			(type default)
		)
		(fill no)
		(layer "In1.Cu")
	)
	(gr_circle
		(center 421.249602 -274.049744)
		(end 421.503602 -274.049744)
		(stroke
			(width 0.1016)
			(type default)
		)
		(fill no)
		(layer "In1.Cu")
	)
	(gr_circle
		(center 421.249602 -273.099784)
		(end 421.503602 -273.099784)
		(stroke
			(width 0.1016)
			(type default)
		)
		(fill no)
		(layer "In1.Cu")
	)
	(gr_circle
		(center 421.249856 -318.699896)
		(end 421.503856 -318.699896)
		(stroke
			(width 0.1016)
			(type default)
		)
		(fill no)
		(layer "In1.Cu")
	)
	(gr_circle
		(center 421.249856 -317.749936)
		(end 421.503856 -317.749936)
		(stroke
			(width 0.1016)
			(type default)
		)
		(fill no)
		(layer "In1.Cu")
	)
	(gr_circle
		(center 421.249856 -313.949842)
		(end 421.503856 -313.949842)
		(stroke
			(width 0.1016)
			(type default)
		)
		(fill no)
		(layer "In1.Cu")
	)
	(gr_circle
		(center 421.249856 -312.999882)
		(end 421.503856 -312.999882)
		(stroke
			(width 0.1016)
			(type default)
		)
		(fill no)
		(layer "In1.Cu")
	)
	(gr_circle
		(center 422.199562 -275.949918)
		(end 422.453562 -275.949918)
		(stroke
			(width 0.1016)
			(type default)
		)
		(fill no)
		(layer "In1.Cu")
	)
	(gr_circle
		(center 422.199562 -274.999958)
		(end 422.453562 -274.999958)
		(stroke
			(width 0.1016)
			(type default)
		)
		(fill no)
		(layer "In1.Cu")
	)
	(gr_circle
		(center 422.199816 -316.799722)
		(end 422.453816 -316.799722)
		(stroke
			(width 0.1016)
			(type default)
		)
		(fill no)
		(layer "In1.Cu")
	)
	(gr_circle
		(center 422.199816 -315.849762)
		(end 422.453816 -315.849762)
		(stroke
			(width 0.1016)
			(type default)
		)
		(fill no)
		(layer "In1.Cu")
	)
	(gr_circle
		(center 422.199816 -312.049922)
		(end 422.453816 -312.049922)
		(stroke
			(width 0.1016)
			(type default)
		)
		(fill no)
		(layer "In1.Cu")
	)
	(gr_circle
		(center 422.199816 -311.099962)
		(end 422.453816 -311.099962)
		(stroke
			(width 0.1016)
			(type default)
		)
		(fill no)
		(layer "In1.Cu")
	)
	(gr_circle
		(center 422.199816 -280.699464)
		(end 422.453816 -280.699464)
		(stroke
			(width 0.1016)
			(type default)
		)
		(fill no)
		(layer "In1.Cu")
	)
	(gr_circle
		(center 422.199816 -279.749504)
		(end 422.453816 -279.749504)
		(stroke
			(width 0.1016)
			(type default)
		)
		(fill no)
		(layer "In1.Cu")
	)
	(gr_circle
		(center 423.149776 -278.799798)
		(end 423.403776 -278.799798)
		(stroke
			(width 0.1016)
			(type default)
		)
		(fill no)
		(layer "In1.Cu")
	)
	(gr_circle
		(center 423.149776 -277.849838)
		(end 423.403776 -277.849838)
		(stroke
			(width 0.1016)
			(type default)
		)
		(fill no)
		(layer "In1.Cu")
	)
	(gr_circle
		(center 423.149776 -274.049744)
		(end 423.403776 -274.049744)
		(stroke
			(width 0.1016)
			(type default)
		)
		(fill no)
		(layer "In1.Cu")
	)
	(gr_circle
		(center 423.149776 -273.099784)
		(end 423.403776 -273.099784)
		(stroke
			(width 0.1016)
			(type default)
		)
		(fill no)
		(layer "In1.Cu")
	)
	(gr_circle
		(center 423.15003 -318.699896)
		(end 423.40403 -318.699896)
		(stroke
			(width 0.1016)
			(type default)
		)
		(fill no)
		(layer "In1.Cu")
	)
	(gr_circle
		(center 423.15003 -317.749936)
		(end 423.40403 -317.749936)
		(stroke
			(width 0.1016)
			(type default)
		)
		(fill no)
		(layer "In1.Cu")
	)
	(gr_circle
		(center 423.15003 -313.949842)
		(end 423.40403 -313.949842)
		(stroke
			(width 0.1016)
			(type default)
		)
		(fill no)
		(layer "In1.Cu")
	)
	(gr_circle
		(center 423.15003 -312.999882)
		(end 423.40403 -312.999882)
		(stroke
			(width 0.1016)
			(type default)
		)
		(fill no)
		(layer "In1.Cu")
	)
	(gr_circle
		(center 423.15003 -308.249828)
		(end 423.40403 -308.249828)
		(stroke
			(width 0.1016)
			(type default)
		)
		(fill no)
		(layer "In1.Cu")
	)
	(gr_circle
		(center 423.15003 -306.349908)
		(end 423.40403 -306.349908)
		(stroke
			(width 0.1016)
			(type default)
		)
		(fill no)
		(layer "In1.Cu")
	)
	(gr_circle
		(center 423.15003 -304.449734)
		(end 423.40403 -304.449734)
		(stroke
			(width 0.1016)
			(type default)
		)
		(fill no)
		(layer "In1.Cu")
	)
	(gr_circle
		(center 423.15003 -287.349946)
		(end 423.40403 -287.349946)
		(stroke
			(width 0.1016)
			(type default)
		)
		(fill no)
		(layer "In1.Cu")
	)
	(gr_circle
		(center 423.15003 -285.449772)
		(end 423.40403 -285.449772)
		(stroke
			(width 0.1016)
			(type default)
		)
		(fill no)
		(layer "In1.Cu")
	)
	(gr_circle
		(center 423.15003 -283.549852)
		(end 423.40403 -283.549852)
		(stroke
			(width 0.1016)
			(type default)
		)
		(fill no)
		(layer "In1.Cu")
	)
	(gr_circle
		(center 424.099736 -275.949664)
		(end 424.353736 -275.949664)
		(stroke
			(width 0.1016)
			(type default)
		)
		(fill no)
		(layer "In1.Cu")
	)
	(gr_circle
		(center 424.099736 -274.999704)
		(end 424.353736 -274.999704)
		(stroke
			(width 0.1016)
			(type default)
		)
		(fill no)
		(layer "In1.Cu")
	)
	(gr_circle
		(center 424.09999 -316.799722)
		(end 424.35399 -316.799722)
		(stroke
			(width 0.1016)
			(type default)
		)
		(fill no)
		(layer "In1.Cu")
	)
	(gr_circle
		(center 424.09999 -315.849762)
		(end 424.35399 -315.849762)
		(stroke
			(width 0.1016)
			(type default)
		)
		(fill no)
		(layer "In1.Cu")
	)
	(gr_circle
		(center 424.09999 -312.049922)
		(end 424.35399 -312.049922)
		(stroke
			(width 0.1016)
			(type default)
		)
		(fill no)
		(layer "In1.Cu")
	)
	(gr_circle
		(center 424.09999 -311.099962)
		(end 424.35399 -311.099962)
		(stroke
			(width 0.1016)
			(type default)
		)
		(fill no)
		(layer "In1.Cu")
	)
	(gr_circle
		(center 424.09999 -308.249828)
		(end 424.35399 -308.249828)
		(stroke
			(width 0.1016)
			(type default)
		)
		(fill no)
		(layer "In1.Cu")
	)
	(gr_circle
		(center 424.09999 -306.349908)
		(end 424.35399 -306.349908)
		(stroke
			(width 0.1016)
			(type default)
		)
		(fill no)
		(layer "In1.Cu")
	)
	(gr_circle
		(center 424.09999 -304.449734)
		(end 424.35399 -304.449734)
		(stroke
			(width 0.1016)
			(type default)
		)
		(fill no)
		(layer "In1.Cu")
	)
	(gr_circle
		(center 424.09999 -287.349946)
		(end 424.35399 -287.349946)
		(stroke
			(width 0.1016)
			(type default)
		)
		(fill no)
		(layer "In1.Cu")
	)
	(gr_circle
		(center 424.09999 -285.449772)
		(end 424.35399 -285.449772)
		(stroke
			(width 0.1016)
			(type default)
		)
		(fill no)
		(layer "In1.Cu")
	)
	(gr_circle
		(center 424.09999 -283.549852)
		(end 424.35399 -283.549852)
		(stroke
			(width 0.1016)
			(type default)
		)
		(fill no)
		(layer "In1.Cu")
	)
	(gr_circle
		(center 424.09999 -280.699464)
		(end 424.35399 -280.699464)
		(stroke
			(width 0.1016)
			(type default)
		)
		(fill no)
		(layer "In1.Cu")
	)
	(gr_circle
		(center 424.09999 -279.749504)
		(end 424.35399 -279.749504)
		(stroke
			(width 0.1016)
			(type default)
		)
		(fill no)
		(layer "In1.Cu")
	)
	(gr_circle
		(center 425.049696 -278.799798)
		(end 425.303696 -278.799798)
		(stroke
			(width 0.1016)
			(type default)
		)
		(fill no)
		(layer "In1.Cu")
	)
	(gr_circle
		(center 425.049696 -277.849838)
		(end 425.303696 -277.849838)
		(stroke
			(width 0.1016)
			(type default)
		)
		(fill no)
		(layer "In1.Cu")
	)
	(gr_circle
		(center 425.049696 -274.049744)
		(end 425.303696 -274.049744)
		(stroke
			(width 0.1016)
			(type default)
		)
		(fill no)
		(layer "In1.Cu")
	)
	(gr_circle
		(center 425.049696 -273.099784)
		(end 425.303696 -273.099784)
		(stroke
			(width 0.1016)
			(type default)
		)
		(fill no)
		(layer "In1.Cu")
	)
	(gr_circle
		(center 425.04995 -318.699896)
		(end 425.30395 -318.699896)
		(stroke
			(width 0.1016)
			(type default)
		)
		(fill no)
		(layer "In1.Cu")
	)
	(gr_circle
		(center 425.04995 -317.749936)
		(end 425.30395 -317.749936)
		(stroke
			(width 0.1016)
			(type default)
		)
		(fill no)
		(layer "In1.Cu")
	)
	(gr_circle
		(center 425.04995 -313.949842)
		(end 425.30395 -313.949842)
		(stroke
			(width 0.1016)
			(type default)
		)
		(fill no)
		(layer "In1.Cu")
	)
	(gr_circle
		(center 425.04995 -312.999882)
		(end 425.30395 -312.999882)
		(stroke
			(width 0.1016)
			(type default)
		)
		(fill no)
		(layer "In1.Cu")
	)
	(gr_circle
		(center 425.04995 -309.199788)
		(end 425.30395 -309.199788)
		(stroke
			(width 0.1016)
			(type default)
		)
		(fill no)
		(layer "In1.Cu")
	)
	(gr_circle
		(center 425.04995 -307.299868)
		(end 425.30395 -307.299868)
		(stroke
			(width 0.1016)
			(type default)
		)
		(fill no)
		(layer "In1.Cu")
	)
	(gr_circle
		(center 425.04995 -305.399948)
		(end 425.30395 -305.399948)
		(stroke
			(width 0.1016)
			(type default)
		)
		(fill no)
		(layer "In1.Cu")
	)
	(gr_circle
		(center 425.04995 -288.299906)
		(end 425.30395 -288.299906)
		(stroke
			(width 0.1016)
			(type default)
		)
		(fill no)
		(layer "In1.Cu")
	)
	(gr_circle
		(center 425.04995 -286.399986)
		(end 425.30395 -286.399986)
		(stroke
			(width 0.1016)
			(type default)
		)
		(fill no)
		(layer "In1.Cu")
	)
	(gr_circle
		(center 425.04995 -284.499812)
		(end 425.30395 -284.499812)
		(stroke
			(width 0.1016)
			(type default)
		)
		(fill no)
		(layer "In1.Cu")
	)
	(gr_circle
		(center 425.04995 -282.599892)
		(end 425.30395 -282.599892)
		(stroke
			(width 0.1016)
			(type default)
		)
		(fill no)
		(layer "In1.Cu")
	)
	(gr_circle
		(center 425.999656 -275.949918)
		(end 426.253656 -275.949918)
		(stroke
			(width 0.1016)
			(type default)
		)
		(fill no)
		(layer "In1.Cu")
	)
	(gr_circle
		(center 425.999656 -274.999958)
		(end 426.253656 -274.999958)
		(stroke
			(width 0.1016)
			(type default)
		)
		(fill no)
		(layer "In1.Cu")
	)
	(gr_circle
		(center 425.99991 -316.799722)
		(end 426.25391 -316.799722)
		(stroke
			(width 0.1016)
			(type default)
		)
		(fill no)
		(layer "In1.Cu")
	)
	(gr_circle
		(center 425.99991 -315.849762)
		(end 426.25391 -315.849762)
		(stroke
			(width 0.1016)
			(type default)
		)
		(fill no)
		(layer "In1.Cu")
	)
	(gr_circle
		(center 425.99991 -312.049922)
		(end 426.25391 -312.049922)
		(stroke
			(width 0.1016)
			(type default)
		)
		(fill no)
		(layer "In1.Cu")
	)
	(gr_circle
		(center 425.99991 -311.099962)
		(end 426.25391 -311.099962)
		(stroke
			(width 0.1016)
			(type default)
		)
		(fill no)
		(layer "In1.Cu")
	)
	(gr_circle
		(center 425.99991 -309.199788)
		(end 426.25391 -309.199788)
		(stroke
			(width 0.1016)
			(type default)
		)
		(fill no)
		(layer "In1.Cu")
	)
	(gr_circle
		(center 425.99991 -307.299868)
		(end 426.25391 -307.299868)
		(stroke
			(width 0.1016)
			(type default)
		)
		(fill no)
		(layer "In1.Cu")
	)
	(gr_circle
		(center 425.99991 -305.399948)
		(end 426.25391 -305.399948)
		(stroke
			(width 0.1016)
			(type default)
		)
		(fill no)
		(layer "In1.Cu")
	)
	(gr_circle
		(center 425.99991 -288.299906)
		(end 426.25391 -288.299906)
		(stroke
			(width 0.1016)
			(type default)
		)
		(fill no)
		(layer "In1.Cu")
	)
	(gr_circle
		(center 425.99991 -286.399986)
		(end 426.25391 -286.399986)
		(stroke
			(width 0.1016)
			(type default)
		)
		(fill no)
		(layer "In1.Cu")
	)
	(gr_circle
		(center 425.99991 -284.499812)
		(end 426.25391 -284.499812)
		(stroke
			(width 0.1016)
			(type default)
		)
		(fill no)
		(layer "In1.Cu")
	)
	(gr_circle
		(center 425.99991 -282.599892)
		(end 426.25391 -282.599892)
		(stroke
			(width 0.1016)
			(type default)
		)
		(fill no)
		(layer "In1.Cu")
	)
	(gr_circle
		(center 425.99991 -280.699464)
		(end 426.25391 -280.699464)
		(stroke
			(width 0.1016)
			(type default)
		)
		(fill no)
		(layer "In1.Cu")
	)
	(gr_circle
		(center 425.99991 -279.749504)
		(end 426.25391 -279.749504)
		(stroke
			(width 0.1016)
			(type default)
		)
		(fill no)
		(layer "In1.Cu")
	)
	(gr_circle
		(center 426.949616 -278.799798)
		(end 427.203616 -278.799798)
		(stroke
			(width 0.1016)
			(type default)
		)
		(fill no)
		(layer "In1.Cu")
	)
	(gr_circle
		(center 426.949616 -277.849838)
		(end 427.203616 -277.849838)
		(stroke
			(width 0.1016)
			(type default)
		)
		(fill no)
		(layer "In1.Cu")
	)
	(gr_circle
		(center 426.949616 -274.049744)
		(end 427.203616 -274.049744)
		(stroke
			(width 0.1016)
			(type default)
		)
		(fill no)
		(layer "In1.Cu")
	)
	(gr_circle
		(center 426.949616 -273.099784)
		(end 427.203616 -273.099784)
		(stroke
			(width 0.1016)
			(type default)
		)
		(fill no)
		(layer "In1.Cu")
	)
	(gr_circle
		(center 426.94987 -318.699896)
		(end 427.20387 -318.699896)
		(stroke
			(width 0.1016)
			(type default)
		)
		(fill no)
		(layer "In1.Cu")
	)
	(gr_circle
		(center 426.94987 -317.749936)
		(end 427.20387 -317.749936)
		(stroke
			(width 0.1016)
			(type default)
		)
		(fill no)
		(layer "In1.Cu")
	)
	(gr_circle
		(center 426.94987 -313.949842)
		(end 427.20387 -313.949842)
		(stroke
			(width 0.1016)
			(type default)
		)
		(fill no)
		(layer "In1.Cu")
	)
	(gr_circle
		(center 426.94987 -312.999882)
		(end 427.20387 -312.999882)
		(stroke
			(width 0.1016)
			(type default)
		)
		(fill no)
		(layer "In1.Cu")
	)
	(gr_circle
		(center 427.899576 -275.949918)
		(end 428.153576 -275.949918)
		(stroke
			(width 0.1016)
			(type default)
		)
		(fill no)
		(layer "In1.Cu")
	)
	(gr_circle
		(center 427.899576 -274.999958)
		(end 428.153576 -274.999958)
		(stroke
			(width 0.1016)
			(type default)
		)
		(fill no)
		(layer "In1.Cu")
	)
	(gr_circle
		(center 427.89983 -316.799722)
		(end 428.15383 -316.799722)
		(stroke
			(width 0.1016)
			(type default)
		)
		(fill no)
		(layer "In1.Cu")
	)
	(gr_circle
		(center 427.89983 -315.849762)
		(end 428.15383 -315.849762)
		(stroke
			(width 0.1016)
			(type default)
		)
		(fill no)
		(layer "In1.Cu")
	)
	(gr_circle
		(center 427.89983 -312.049922)
		(end 428.15383 -312.049922)
		(stroke
			(width 0.1016)
			(type default)
		)
		(fill no)
		(layer "In1.Cu")
	)
	(gr_circle
		(center 427.89983 -311.099962)
		(end 428.15383 -311.099962)
		(stroke
			(width 0.1016)
			(type default)
		)
		(fill no)
		(layer "In1.Cu")
	)
	(gr_circle
		(center 427.89983 -309.199788)
		(end 428.15383 -309.199788)
		(stroke
			(width 0.1016)
			(type default)
		)
		(fill no)
		(layer "In1.Cu")
	)
	(gr_circle
		(center 427.89983 -307.299868)
		(end 428.15383 -307.299868)
		(stroke
			(width 0.1016)
			(type default)
		)
		(fill no)
		(layer "In1.Cu")
	)
	(gr_circle
		(center 427.89983 -305.399948)
		(end 428.15383 -305.399948)
		(stroke
			(width 0.1016)
			(type default)
		)
		(fill no)
		(layer "In1.Cu")
	)
	(gr_circle
		(center 427.89983 -288.299906)
		(end 428.15383 -288.299906)
		(stroke
			(width 0.1016)
			(type default)
		)
		(fill no)
		(layer "In1.Cu")
	)
	(gr_circle
		(center 427.89983 -286.399732)
		(end 428.15383 -286.399732)
		(stroke
			(width 0.1016)
			(type default)
		)
		(fill no)
		(layer "In1.Cu")
	)
	(gr_circle
		(center 427.89983 -284.499812)
		(end 428.15383 -284.499812)
		(stroke
			(width 0.1016)
			(type default)
		)
		(fill no)
		(layer "In1.Cu")
	)
	(gr_circle
		(center 427.89983 -282.599892)
		(end 428.15383 -282.599892)
		(stroke
			(width 0.1016)
			(type default)
		)
		(fill no)
		(layer "In1.Cu")
	)
	(gr_circle
		(center 427.89983 -280.699718)
		(end 428.15383 -280.699718)
		(stroke
			(width 0.1016)
			(type default)
		)
		(fill no)
		(layer "In1.Cu")
	)
	(gr_circle
		(center 427.89983 -279.749758)
		(end 428.15383 -279.749758)
		(stroke
			(width 0.1016)
			(type default)
		)
		(fill no)
		(layer "In1.Cu")
	)
	(gr_circle
		(center 428.849536 -274.049744)
		(end 429.103536 -274.049744)
		(stroke
			(width 0.1016)
			(type default)
		)
		(fill no)
		(layer "In1.Cu")
	)
	(gr_circle
		(center 428.849536 -273.099784)
		(end 429.103536 -273.099784)
		(stroke
			(width 0.1016)
			(type default)
		)
		(fill no)
		(layer "In1.Cu")
	)
	(gr_circle
		(center 428.84979 -318.699896)
		(end 429.10379 -318.699896)
		(stroke
			(width 0.1016)
			(type default)
		)
		(fill no)
		(layer "In1.Cu")
	)
	(gr_circle
		(center 428.84979 -317.749936)
		(end 429.10379 -317.749936)
		(stroke
			(width 0.1016)
			(type default)
		)
		(fill no)
		(layer "In1.Cu")
	)
	(gr_circle
		(center 428.84979 -313.949842)
		(end 429.10379 -313.949842)
		(stroke
			(width 0.1016)
			(type default)
		)
		(fill no)
		(layer "In1.Cu")
	)
	(gr_circle
		(center 428.84979 -312.999882)
		(end 429.10379 -312.999882)
		(stroke
			(width 0.1016)
			(type default)
		)
		(fill no)
		(layer "In1.Cu")
	)
	(gr_circle
		(center 428.84979 -309.199788)
		(end 429.10379 -309.199788)
		(stroke
			(width 0.1016)
			(type default)
		)
		(fill no)
		(layer "In1.Cu")
	)
	(gr_circle
		(center 428.84979 -307.299868)
		(end 429.10379 -307.299868)
		(stroke
			(width 0.1016)
			(type default)
		)
		(fill no)
		(layer "In1.Cu")
	)
	(gr_circle
		(center 428.84979 -305.399948)
		(end 429.10379 -305.399948)
		(stroke
			(width 0.1016)
			(type default)
		)
		(fill no)
		(layer "In1.Cu")
	)
	(gr_circle
		(center 428.84979 -288.299906)
		(end 429.10379 -288.299906)
		(stroke
			(width 0.1016)
			(type default)
		)
		(fill no)
		(layer "In1.Cu")
	)
	(gr_circle
		(center 428.84979 -286.399732)
		(end 429.10379 -286.399732)
		(stroke
			(width 0.1016)
			(type default)
		)
		(fill no)
		(layer "In1.Cu")
	)
	(gr_circle
		(center 428.84979 -284.499812)
		(end 429.10379 -284.499812)
		(stroke
			(width 0.1016)
			(type default)
		)
		(fill no)
		(layer "In1.Cu")
	)
	(gr_circle
		(center 428.84979 -282.599892)
		(end 429.10379 -282.599892)
		(stroke
			(width 0.1016)
			(type default)
		)
		(fill no)
		(layer "In1.Cu")
	)
	(gr_circle
		(center 428.84979 -278.799798)
		(end 429.10379 -278.799798)
		(stroke
			(width 0.1016)
			(type default)
		)
		(fill no)
		(layer "In1.Cu")
	)
	(gr_circle
		(center 428.84979 -277.849838)
		(end 429.10379 -277.849838)
		(stroke
			(width 0.1016)
			(type default)
		)
		(fill no)
		(layer "In1.Cu")
	)
	(gr_circle
		(center 429.800004 -316.799722)
		(end 430.054004 -316.799722)
		(stroke
			(width 0.1016)
			(type default)
		)
		(fill no)
		(layer "In1.Cu")
	)
	(gr_circle
		(center 429.800004 -314.899802)
		(end 430.054004 -314.899802)
		(stroke
			(width 0.1016)
			(type default)
		)
		(fill no)
		(layer "In1.Cu")
	)
	(gr_circle
		(center 429.800004 -312.049922)
		(end 430.054004 -312.049922)
		(stroke
			(width 0.1016)
			(type default)
		)
		(fill no)
		(layer "In1.Cu")
	)
	(gr_circle
		(center 429.800004 -310.149748)
		(end 430.054004 -310.149748)
		(stroke
			(width 0.1016)
			(type default)
		)
		(fill no)
		(layer "In1.Cu")
	)
	(gr_circle
		(center 429.800004 -308.249828)
		(end 430.054004 -308.249828)
		(stroke
			(width 0.1016)
			(type default)
		)
		(fill no)
		(layer "In1.Cu")
	)
	(gr_circle
		(center 429.800004 -306.349908)
		(end 430.054004 -306.349908)
		(stroke
			(width 0.1016)
			(type default)
		)
		(fill no)
		(layer "In1.Cu")
	)
	(gr_circle
		(center 429.800004 -304.449734)
		(end 430.054004 -304.449734)
		(stroke
			(width 0.1016)
			(type default)
		)
		(fill no)
		(layer "In1.Cu")
	)
	(gr_circle
		(center 429.800004 -287.349946)
		(end 430.054004 -287.349946)
		(stroke
			(width 0.1016)
			(type default)
		)
		(fill no)
		(layer "In1.Cu")
	)
	(gr_circle
		(center 429.800004 -285.449772)
		(end 430.054004 -285.449772)
		(stroke
			(width 0.1016)
			(type default)
		)
		(fill no)
		(layer "In1.Cu")
	)
	(gr_circle
		(center 429.800004 -283.549852)
		(end 430.054004 -283.549852)
		(stroke
			(width 0.1016)
			(type default)
		)
		(fill no)
		(layer "In1.Cu")
	)
	(gr_circle
		(center 429.800004 -281.649932)
		(end 430.054004 -281.649932)
		(stroke
			(width 0.1016)
			(type default)
		)
		(fill no)
		(layer "In1.Cu")
	)
	(gr_circle
		(center 429.800004 -279.749758)
		(end 430.054004 -279.749758)
		(stroke
			(width 0.1016)
			(type default)
		)
		(fill no)
		(layer "In1.Cu")
	)
	(gr_circle
		(center 429.800004 -276.899878)
		(end 430.054004 -276.899878)
		(stroke
			(width 0.1016)
			(type default)
		)
		(fill no)
		(layer "In1.Cu")
	)
	(gr_circle
		(center 429.800004 -274.999704)
		(end 430.054004 -274.999704)
		(stroke
			(width 0.1016)
			(type default)
		)
		(fill no)
		(layer "In1.Cu")
	)
	(gr_circle
		(center 430.749964 -316.799722)
		(end 431.003964 -316.799722)
		(stroke
			(width 0.1016)
			(type default)
		)
		(fill no)
		(layer "In1.Cu")
	)
	(gr_circle
		(center 430.749964 -314.899802)
		(end 431.003964 -314.899802)
		(stroke
			(width 0.1016)
			(type default)
		)
		(fill no)
		(layer "In1.Cu")
	)
	(gr_circle
		(center 430.749964 -312.049922)
		(end 431.003964 -312.049922)
		(stroke
			(width 0.1016)
			(type default)
		)
		(fill no)
		(layer "In1.Cu")
	)
	(gr_circle
		(center 430.749964 -310.149748)
		(end 431.003964 -310.149748)
		(stroke
			(width 0.1016)
			(type default)
		)
		(fill no)
		(layer "In1.Cu")
	)
	(gr_circle
		(center 430.749964 -308.249828)
		(end 431.003964 -308.249828)
		(stroke
			(width 0.1016)
			(type default)
		)
		(fill no)
		(layer "In1.Cu")
	)
	(gr_circle
		(center 430.749964 -306.349908)
		(end 431.003964 -306.349908)
		(stroke
			(width 0.1016)
			(type default)
		)
		(fill no)
		(layer "In1.Cu")
	)
	(gr_circle
		(center 430.749964 -304.449734)
		(end 431.003964 -304.449734)
		(stroke
			(width 0.1016)
			(type default)
		)
		(fill no)
		(layer "In1.Cu")
	)
	(gr_circle
		(center 430.749964 -287.349946)
		(end 431.003964 -287.349946)
		(stroke
			(width 0.1016)
			(type default)
		)
		(fill no)
		(layer "In1.Cu")
	)
	(gr_circle
		(center 430.749964 -285.449772)
		(end 431.003964 -285.449772)
		(stroke
			(width 0.1016)
			(type default)
		)
		(fill no)
		(layer "In1.Cu")
	)
	(gr_circle
		(center 430.749964 -283.549852)
		(end 431.003964 -283.549852)
		(stroke
			(width 0.1016)
			(type default)
		)
		(fill no)
		(layer "In1.Cu")
	)
	(gr_circle
		(center 430.749964 -281.649932)
		(end 431.003964 -281.649932)
		(stroke
			(width 0.1016)
			(type default)
		)
		(fill no)
		(layer "In1.Cu")
	)
	(gr_circle
		(center 430.749964 -279.749758)
		(end 431.003964 -279.749758)
		(stroke
			(width 0.1016)
			(type default)
		)
		(fill no)
		(layer "In1.Cu")
	)
	(gr_circle
		(center 430.749964 -276.899878)
		(end 431.003964 -276.899878)
		(stroke
			(width 0.1016)
			(type default)
		)
		(fill no)
		(layer "In1.Cu")
	)
	(gr_circle
		(center 430.749964 -274.999704)
		(end 431.003964 -274.999704)
		(stroke
			(width 0.1016)
			(type default)
		)
		(fill no)
		(layer "In1.Cu")
	)
	(gr_line
		(start 0 -416.589972)
		(end 0 -246.488458)
		(stroke
			(width 3.048)
			(type default)
		)
		(layer "In2.Cu")
	)
	(gr_arc
		(start 0 -416.589972)
		(mid 0.585785 -418.004183)
		(end 1.999996 -418.589968)
		(stroke
			(width 3.048)
			(type default)
		)
		(layer "In2.Cu")
	)
	(gr_line
		(start 0 -82.131662)
		(end 0 -1.999996)
		(stroke
			(width 3.048)
			(type default)
		)
		(layer "In2.Cu")
	)
	(gr_arc
		(start 0 -82.131662)
		(mid 0.152239 -82.89692)
		(end 0.585724 -83.54568)
		(stroke
			(width 3.048)
			(type default)
		)
		(layer "In2.Cu")
	)
	(gr_poly
		(pts
			(arc
				(start 265.615928 -377.679966)
				(mid 265.635451 -377.676065)
				(end 265.651996 -377.66498)
			)
			(arc
				(start 265.851386 -377.46559)
				(mid 265.862497 -377.449056)
				(end 265.866372 -377.429522)
			)
			(arc
				(start 265.866372 -368.884962)
				(mid 265.862471 -368.865439)
				(end 265.851386 -368.848894)
			)
			(arc
				(start 265.514582 -368.51209)
				(mid 265.498048 -368.500979)
				(end 265.478514 -368.497104)
			)
			(arc
				(start 242.901216 -368.497104)
				(mid 242.881693 -368.501005)
				(end 242.865148 -368.51209)
			)
			(arc
				(start 242.760754 -368.616484)
				(mid 242.749643 -368.633018)
				(end 242.745768 -368.652552)
			)
			(arc
				(start 242.745768 -377.268994)
				(mid 242.749669 -377.288517)
				(end 242.760754 -377.305062)
			)
			(arc
				(start 243.120672 -377.66498)
				(mid 243.137206 -377.676091)
				(end 243.15674 -377.679966)
			)
		)
		(stroke
			(width 0)
			(type solid)
		)
		(fill yes)
		(layer "In2.Cu")
		(net "P12V_STBY_R2")
	)
	(gr_poly
		(pts
			(arc
				(start 241.741198 -376.399806)
				(mid 241.763367 -376.39459)
				(end 241.781076 -376.380248)
			)
			(arc
				(start 241.781076 -376.380248)
				(mid 241.793461 -376.365378)
				(end 241.80673 -376.351292)
			)
			(xy 242.08994 -376.068082)
			(arc
				(start 242.09502 -376.063002)
				(mid 242.106647 -376.046325)
				(end 242.110768 -376.026426)
			)
			(arc
				(start 242.110768 -368.666268)
				(mid 242.106867 -368.646745)
				(end 242.095782 -368.6302)
			)
			(arc
				(start 241.977672 -368.51209)
				(mid 241.961138 -368.500979)
				(end 241.941604 -368.497104)
			)
			(arc
				(start 236.370368 -368.497104)
				(mid 236.350845 -368.501005)
				(end 236.3343 -368.51209)
			)
			(arc
				(start 236.123734 -368.722656)
				(mid 236.112623 -368.73919)
				(end 236.108748 -368.758724)
			)
			(arc
				(start 236.108748 -376.146314)
				(mid 236.112649 -376.165837)
				(end 236.123734 -376.182382)
			)
			(arc
				(start 236.326172 -376.38482)
				(mid 236.342706 -376.395931)
				(end 236.36224 -376.399806)
			)
		)
		(stroke
			(width 0)
			(type solid)
		)
		(fill yes)
		(layer "In2.Cu")
		(net "P12V_STBY_R1")
	)
	(gr_poly
		(pts
			(arc
				(start 342.894158 -293.920164)
				(mid 342.913017 -293.916534)
				(end 342.92921 -293.906194)
			)
			(arc
				(start 342.92921 -293.906194)
				(mid 343.191846 -293.801301)
				(end 343.454482 -293.906194)
			)
			(arc
				(start 343.454482 -293.906194)
				(mid 343.470659 -293.916575)
				(end 343.489534 -293.920164)
			)
			(arc
				(start 359.553256 -293.920164)
				(mid 359.572115 -293.916534)
				(end 359.588308 -293.906194)
			)
			(arc
				(start 359.588308 -293.906194)
				(mid 359.850944 -293.801301)
				(end 360.11358 -293.906194)
			)
			(arc
				(start 360.11358 -293.906194)
				(mid 360.129757 -293.916575)
				(end 360.148632 -293.920164)
			)
			(arc
				(start 367.00714 -293.920164)
				(mid 367.026663 -293.916263)
				(end 367.043208 -293.905178)
			)
			(arc
				(start 367.420144 -293.528242)
				(mid 367.431255 -293.511708)
				(end 367.43513 -293.492174)
			)
			(arc
				(start 367.43513 -279.269698)
				(mid 367.425447 -279.239864)
				(end 367.400078 -279.221438)
			)
			(arc
				(start 367.400078 -279.221438)
				(mid 366.889251 -279.006592)
				(end 366.4204 -278.711152)
			)
			(arc
				(start 366.4204 -278.711152)
				(mid 366.405984 -278.703599)
				(end 366.38992 -278.700992)
			)
			(arc
				(start 333.32928 -278.700992)
				(mid 333.309757 -278.704893)
				(end 333.293212 -278.715978)
			)
			(xy 333.276702 -278.732488) (xy 333.269082 -278.747728)
			(arc
				(start 333.268066 -278.75611)
				(mid 333.159317 -278.978323)
				(end 332.937104 -279.087072)
			)
			(xy 332.928722 -279.088088) (xy 332.913482 -279.095708)
			(arc
				(start 332.721458 -279.287732)
				(mid 332.710347 -279.304266)
				(end 332.706472 -279.3238)
			)
			(arc
				(start 332.706472 -286.692594)
				(mid 332.714606 -286.720167)
				(end 332.736444 -286.738822)
			)
			(arc
				(start 332.736444 -286.738822)
				(mid 334.728894 -289.820096)
				(end 332.736444 -292.90137)
			)
			(arc
				(start 332.736444 -292.90137)
				(mid 332.714687 -292.920077)
				(end 332.706472 -292.947598)
			)
			(arc
				(start 332.706472 -293.436548)
				(mid 332.710373 -293.456071)
				(end 332.721458 -293.472616)
			)
			(arc
				(start 333.15402 -293.905178)
				(mid 333.170554 -293.916289)
				(end 333.190088 -293.920164)
			)
		)
		(stroke
			(width 0)
			(type solid)
		)
		(fill yes)
		(layer "In2.Cu")
		(net "GND")
	)
	(gr_poly
		(pts
			(arc
				(start 110.752382 -293.920164)
				(mid 110.769948 -293.917124)
				(end 110.785402 -293.908226)
			)
			(arc
				(start 110.785402 -293.908226)
				(mid 110.900474 -293.841319)
				(end 111.031528 -293.818056)
			)
			(arc
				(start 111.031528 -293.818056)
				(mid 111.162567 -293.841359)
				(end 111.277654 -293.908226)
			)
			(arc
				(start 111.277654 -293.908226)
				(mid 111.293097 -293.917153)
				(end 111.310674 -293.920164)
			)
			(arc
				(start 127.35306 -293.920164)
				(mid 127.371919 -293.916534)
				(end 127.388112 -293.906194)
			)
			(arc
				(start 127.388112 -293.906194)
				(mid 127.650748 -293.801301)
				(end 127.913384 -293.906194)
			)
			(arc
				(start 127.913384 -293.906194)
				(mid 127.929561 -293.916575)
				(end 127.948436 -293.920164)
			)
			(arc
				(start 134.807198 -293.920164)
				(mid 134.826721 -293.916263)
				(end 134.843266 -293.905178)
			)
			(arc
				(start 135.220202 -293.528242)
				(mid 135.231313 -293.511708)
				(end 135.235188 -293.492174)
			)
			(arc
				(start 135.235188 -279.269698)
				(mid 135.225505 -279.239864)
				(end 135.200136 -279.221438)
			)
			(arc
				(start 135.200136 -279.221438)
				(mid 134.689309 -279.006592)
				(end 134.220458 -278.711152)
			)
			(arc
				(start 134.220458 -278.711152)
				(mid 134.206042 -278.703599)
				(end 134.189978 -278.700992)
			)
			(arc
				(start 101.129338 -278.700992)
				(mid 101.109815 -278.704893)
				(end 101.09327 -278.715978)
			)
			(xy 101.076252 -278.732996) (xy 101.068886 -278.747982)
			(arc
				(start 101.06787 -278.756364)
				(mid 100.959143 -278.978345)
				(end 100.737162 -279.087072)
			)
			(xy 100.72878 -279.088088) (xy 100.713794 -279.095454)
			(arc
				(start 100.521516 -279.287732)
				(mid 100.510405 -279.304266)
				(end 100.50653 -279.3238)
			)
			(arc
				(start 100.50653 -286.692594)
				(mid 100.514595 -286.720315)
				(end 100.536502 -286.739076)
			)
			(arc
				(start 100.536502 -286.739076)
				(mid 102.52857 -289.820096)
				(end 100.536502 -292.901116)
			)
			(arc
				(start 100.536502 -292.901116)
				(mid 100.514677 -292.91993)
				(end 100.50653 -292.947598)
			)
			(arc
				(start 100.50653 -293.436548)
				(mid 100.510431 -293.456071)
				(end 100.521516 -293.472616)
			)
			(arc
				(start 100.954078 -293.905178)
				(mid 100.970612 -293.916289)
				(end 100.990146 -293.920164)
			)
		)
		(stroke
			(width 0)
			(type solid)
		)
		(fill yes)
		(layer "In2.Cu")
		(net "GND")
	)
	(gr_poly
		(pts
			(arc
				(start 235.60151 -413.087058)
				(mid 235.621033 -413.083157)
				(end 235.637578 -413.072072)
			)
			(arc
				(start 236.756956 -411.952694)
				(mid 236.768067 -411.93616)
				(end 236.771942 -411.916626)
			)
			(arc
				(start 236.771942 -402.84527)
				(mid 236.796095 -402.723754)
				(end 236.864906 -402.620734)
			)
			(arc
				(start 238.766604 -400.719036)
				(mid 238.869636 -400.650255)
				(end 238.99114 -400.626072)
			)
			(arc
				(start 242.910868 -400.626072)
				(mid 242.930391 -400.622171)
				(end 242.946936 -400.611086)
			)
			(arc
				(start 243.79682 -399.761202)
				(mid 243.807931 -399.744668)
				(end 243.811806 -399.725134)
			)
			(arc
				(start 243.811806 -392.09472)
				(mid 243.835959 -391.973204)
				(end 243.90477 -391.870184)
			)
			(arc
				(start 244.93093 -390.844024)
				(mid 245.033962 -390.775243)
				(end 245.155466 -390.75106)
			)
			(arc
				(start 259.056124 -390.75106)
				(mid 259.075647 -390.747159)
				(end 259.092192 -390.736074)
			)
			(arc
				(start 262.00481 -387.823456)
				(mid 262.015921 -387.806922)
				(end 262.019796 -387.787388)
			)
			(arc
				(start 262.019796 -379.197616)
				(mid 262.015895 -379.178093)
				(end 262.00481 -379.161548)
			)
			(arc
				(start 261.967472 -379.12421)
				(mid 261.950938 -379.113099)
				(end 261.931404 -379.109224)
			)
			(arc
				(start 240.584482 -379.109224)
				(mid 240.564959 -379.113125)
				(end 240.548414 -379.12421)
			)
			(arc
				(start 239.998504 -379.67412)
				(mid 239.895472 -379.742901)
				(end 239.773968 -379.767084)
			)
			(arc
				(start 237.129066 -379.767084)
				(mid 237.00755 -379.742931)
				(end 236.90453 -379.67412)
			)
			(arc
				(start 232.953814 -375.723404)
				(mid 232.885033 -375.620372)
				(end 232.86085 -375.498868)
			)
			(arc
				(start 232.86085 -372.11508)
				(mid 232.856949 -372.095557)
				(end 232.845864 -372.079012)
			)
			(arc
				(start 232.203752 -371.4369)
				(mid 232.134971 -371.333868)
				(end 232.110788 -371.212364)
			)
			(arc
				(start 232.110788 -371.075712)
				(mid 232.106887 -371.056189)
				(end 232.095802 -371.039644)
			)
			(arc
				(start 232.035858 -370.9797)
				(mid 231.967077 -370.876668)
				(end 231.942894 -370.755164)
			)
			(arc
				(start 231.942894 -367.397792)
				(mid 231.938993 -367.378269)
				(end 231.927908 -367.361724)
			)
			(arc
				(start 231.89057 -367.324386)
				(mid 231.874036 -367.313275)
				(end 231.854502 -367.3094)
			)
			(arc
				(start 228.741986 -367.3094)
				(mid 228.722463 -367.313301)
				(end 228.705918 -367.324386)
			)
			(arc
				(start 228.66858 -367.361724)
				(mid 228.657469 -367.378258)
				(end 228.653594 -367.397792)
			)
			(arc
				(start 228.653594 -370.74856)
				(mid 228.629441 -370.870076)
				(end 228.56063 -370.973096)
			)
			(arc
				(start 228.481128 -371.052598)
				(mid 228.470017 -371.069132)
				(end 228.466142 -371.088666)
			)
			(arc
				(start 228.466142 -371.354096)
				(mid 228.441989 -371.475612)
				(end 228.373178 -371.578632)
			)
			(arc
				(start 227.178362 -372.773448)
				(mid 227.167251 -372.789982)
				(end 227.163376 -372.809516)
			)
			(arc
				(start 227.163376 -374.166384)
				(mid 227.139223 -374.2879)
				(end 227.070412 -374.39092)
			)
			(arc
				(start 225.794062 -375.66727)
				(mid 225.69103 -375.736051)
				(end 225.569526 -375.760234)
			)
			(arc
				(start 223.648016 -375.760234)
				(mid 223.5265 -375.736081)
				(end 223.42348 -375.66727)
			)
			(arc
				(start 221.55531 -373.7991)
				(mid 221.486529 -373.696068)
				(end 221.462346 -373.574564)
			)
			(arc
				(start 221.462346 -371.091714)
				(mid 221.458445 -371.072191)
				(end 221.44736 -371.055646)
			)
			(arc
				(start 221.361508 -370.969794)
				(mid 221.292727 -370.866762)
				(end 221.268544 -370.745258)
			)
			(arc
				(start 221.268544 -367.391442)
				(mid 221.264643 -367.371919)
				(end 221.253558 -367.355374)
			)
			(arc
				(start 221.225872 -367.327688)
				(mid 221.209338 -367.316577)
				(end 221.189804 -367.312702)
			)
			(arc
				(start 218.110308 -367.312702)
				(mid 218.090785 -367.316603)
				(end 218.07424 -367.327688)
			)
			(arc
				(start 217.967306 -367.434622)
				(mid 217.956195 -367.451156)
				(end 217.95232 -367.47069)
			)
			(arc
				(start 217.95232 -370.719096)
				(mid 217.928167 -370.840612)
				(end 217.859356 -370.943632)
			)
			(arc
				(start 216.82964 -371.973348)
				(mid 216.726608 -372.042129)
				(end 216.605104 -372.066312)
			)
			(arc
				(start 210.424014 -372.066312)
				(mid 210.302498 -372.042159)
				(end 210.199478 -371.973348)
			)
			(arc
				(start 210.067906 -371.841776)
				(mid 209.999125 -371.738744)
				(end 209.974942 -371.61724)
			)
			(arc
				(start 209.974942 -371.309138)
				(mid 209.971041 -371.289615)
				(end 209.959956 -371.27307)
			)
			(arc
				(start 209.949034 -371.262148)
				(mid 209.9325 -371.251037)
				(end 209.912966 -371.247162)
			)
			(arc
				(start 209.559144 -371.247162)
				(mid 209.437628 -371.223009)
				(end 209.334608 -371.154198)
			)
			(arc
				(start 208.669382 -370.488972)
				(mid 208.652848 -370.477861)
				(end 208.633314 -370.473986)
			)
			(arc
				(start 208.394554 -370.473986)
				(mid 208.273038 -370.449833)
				(end 208.170018 -370.381022)
			)
			(arc
				(start 208.11744 -370.328444)
				(mid 208.048659 -370.225412)
				(end 208.024476 -370.103908)
			)
			(arc
				(start 208.024476 -367.401348)
				(mid 208.020575 -367.381825)
				(end 208.00949 -367.36528)
			)
			(arc
				(start 207.981804 -367.337594)
				(mid 207.96527 -367.326483)
				(end 207.945736 -367.322608)
			)
			(arc
				(start 204.823822 -367.322608)
				(mid 204.804299 -367.326509)
				(end 204.787754 -367.337594)
			)
			(arc
				(start 204.740002 -367.385346)
				(mid 204.728891 -367.40188)
				(end 204.725016 -367.421414)
			)
			(arc
				(start 204.725016 -370.796312)
				(mid 204.728917 -370.815835)
				(end 204.740002 -370.83238)
			)
			(arc
				(start 204.77353 -370.865908)
				(mid 204.842311 -370.96894)
				(end 204.866494 -371.090444)
			)
			(arc
				(start 204.866494 -374.47474)
				(mid 204.870058 -374.493432)
				(end 204.88021 -374.509538)
			)
			(arc
				(start 204.88021 -374.509538)
				(mid 204.94326 -374.609679)
				(end 204.9653 -374.725946)
			)
			(arc
				(start 204.9653 -387.02361)
				(mid 204.969201 -387.043133)
				(end 204.980286 -387.059678)
			)
			(arc
				(start 207.47482 -389.554212)
				(mid 207.543601 -389.657244)
				(end 207.567784 -389.778748)
			)
			(arc
				(start 207.567784 -411.696662)
				(mid 207.571685 -411.716185)
				(end 207.58277 -411.73273)
			)
			(arc
				(start 208.922112 -413.072072)
				(mid 208.938646 -413.083183)
				(end 208.95818 -413.087058)
			)
		)
		(stroke
			(width 0)
			(type solid)
		)
		(fill yes)
		(layer "In2.Cu")
		(net "P12V_STBY")
	)
	(gr_poly
		(pts
			(xy 197.632828 -337.857338) (xy 197.642895 -337.856908) (xy 197.661486 -337.84918) (xy 197.668896 -337.842352)
			(xy 198.69277 -336.818478) (xy 198.699616 -336.81108) (xy 198.707347 -336.792481) (xy 198.707756 -336.78241)
			(xy 198.707756 -318.236346) (xy 198.707502 -318.224662) (xy 198.707502 -303.159414) (xy 198.703692 -303.150016)
			(xy 198.694406 -303.126048) (xy 198.682529 -303.076039) (xy 198.678538 -303.024794) (xy 198.682531 -302.97355)
			(xy 198.694409 -302.923542) (xy 198.703692 -302.899572) (xy 198.707502 -302.890174) (xy 198.707502 -302.167544)
			(xy 198.705724 -302.161194) (xy 198.700374 -302.140006) (xy 198.694636 -302.096684) (xy 198.694294 -302.074834)
			(xy 198.694628 -302.052983) (xy 198.700363 -302.00966) (xy 198.705724 -301.988474) (xy 198.707502 -301.982124)
			(xy 198.707502 -301.217584) (xy 198.705724 -301.211234) (xy 198.700378 -301.190046) (xy 198.694648 -301.146724)
			(xy 198.694294 -301.124874) (xy 198.694625 -301.103023) (xy 198.700355 -301.059698) (xy 198.705724 -301.038514)
			(xy 198.707502 -301.032164) (xy 198.707502 -300.267624) (xy 198.705724 -300.261274) (xy 198.700375 -300.240086)
			(xy 198.69464 -300.196764) (xy 198.694294 -300.174914) (xy 198.694629 -300.153063) (xy 198.700366 -300.109741)
			(xy 198.705724 -300.088554) (xy 198.707502 -300.082204) (xy 198.707502 -299.317664) (xy 198.705724 -299.311314)
			(xy 198.700379 -299.290126) (xy 198.694652 -299.246804) (xy 198.694294 -299.224954) (xy 198.694627 -299.203103)
			(xy 198.700359 -299.159779) (xy 198.705724 -299.138594) (xy 198.707502 -299.132244) (xy 198.707502 -298.36745)
			(xy 198.705724 -298.3611) (xy 198.700373 -298.339912) (xy 198.694635 -298.29659) (xy 198.694294 -298.27474)
			(xy 198.694628 -298.252889) (xy 198.700361 -298.209565) (xy 198.705724 -298.18838) (xy 198.707502 -298.18203)
			(xy 198.707502 -297.41749) (xy 198.705724 -297.41114) (xy 198.700377 -297.389952) (xy 198.694647 -297.34663)
			(xy 198.694294 -297.32478) (xy 198.694625 -297.302929) (xy 198.700354 -297.259604) (xy 198.705724 -297.23842)
			(xy 198.707502 -297.23207) (xy 198.707502 -296.46753) (xy 198.705724 -296.46118) (xy 198.700375 -296.439992)
			(xy 198.694639 -296.39667) (xy 198.694294 -296.37482) (xy 198.694629 -296.352969) (xy 198.700365 -296.309646)
			(xy 198.705724 -296.28846) (xy 198.707502 -296.28211) (xy 198.707502 -294.56761) (xy 198.705724 -294.56126)
			(xy 198.700376 -294.540072) (xy 198.694643 -294.49675) (xy 198.694294 -294.4749) (xy 198.69463 -294.453049)
			(xy 198.700369 -294.409727) (xy 198.705724 -294.38854) (xy 198.707502 -294.38219) (xy 198.707502 -293.61765)
			(xy 198.705724 -293.6113) (xy 198.700373 -293.590112) (xy 198.694635 -293.54679) (xy 198.694294 -293.52494)
			(xy 198.694628 -293.503089) (xy 198.700361 -293.459765) (xy 198.705724 -293.43858) (xy 198.707502 -293.43223)
			(xy 198.707502 -292.66769) (xy 198.705724 -292.66134) (xy 198.700377 -292.640152) (xy 198.694647 -292.59683)
			(xy 198.694294 -292.57498) (xy 198.694625 -292.553129) (xy 198.700354 -292.509804) (xy 198.705724 -292.48862)
			(xy 198.707502 -292.48227) (xy 198.707502 -291.717476) (xy 198.705724 -291.711126) (xy 198.700378 -291.689938)
			(xy 198.69465 -291.646616) (xy 198.694294 -291.624766) (xy 198.694626 -291.602915) (xy 198.700356 -291.55959)
			(xy 198.705724 -291.538406) (xy 198.707502 -291.532056) (xy 198.707502 -290.767516) (xy 198.705724 -290.761166)
			(xy 198.700376 -290.739978) (xy 198.694642 -290.696656) (xy 198.694294 -290.674806) (xy 198.69463 -290.652955)
			(xy 198.700368 -290.609633) (xy 198.705724 -290.588446) (xy 198.707502 -290.582096) (xy 198.707502 -289.817556)
			(xy 198.705724 -289.811206) (xy 198.700373 -289.790018) (xy 198.694634 -289.746696) (xy 198.694294 -289.724846)
			(xy 198.694627 -289.702995) (xy 198.70036 -289.659671) (xy 198.705724 -289.638486) (xy 198.707502 -289.632136)
			(xy 198.707502 -286.801814) (xy 198.707063 -286.791751) (xy 198.699327 -286.773169) (xy 198.692516 -286.765746)
			(xy 198.654924 -286.728154) (xy 198.63054 -286.720788) (xy 198.617586 -286.723328) (xy 198.600891 -286.726637)
			(xy 198.56704 -286.730198) (xy 198.550022 -286.73044) (xy 198.523374 -286.729906) (xy 198.470766 -286.721363)
			(xy 198.420209 -286.704494) (xy 198.373012 -286.679736) (xy 198.351394 -286.664146) (xy 198.344654 -286.659476)
			(xy 198.329108 -286.654291) (xy 198.320914 -286.653986) (xy 197.82917 -286.653986) (xy 197.820978 -286.654299)
			(xy 197.805437 -286.659488) (xy 197.79869 -286.664146) (xy 197.777062 -286.679723) (xy 197.729869 -286.704485)
			(xy 197.679315 -286.721357) (xy 197.62671 -286.729905) (xy 197.573414 -286.729905) (xy 197.520809 -286.721357)
			(xy 197.470255 -286.704485) (xy 197.423062 -286.679723) (xy 197.401434 -286.664146) (xy 197.394691 -286.659485)
			(xy 197.379145 -286.654318) (xy 197.370954 -286.653986) (xy 196.878956 -286.653986) (xy 196.870765 -286.654302)
			(xy 196.855226 -286.659493) (xy 196.848476 -286.664146) (xy 196.826848 -286.679723) (xy 196.779655 -286.704485)
			(xy 196.729101 -286.721357) (xy 196.676496 -286.729905) (xy 196.6232 -286.729905) (xy 196.570595 -286.721357)
			(xy 196.520041 -286.704485) (xy 196.472848 -286.679723) (xy 196.45122 -286.664146) (xy 196.444481 -286.659473)
			(xy 196.428935 -286.65428) (xy 196.42074 -286.653986) (xy 195.928996 -286.653986) (xy 195.920803 -286.654295)
			(xy 195.905256 -286.659477) (xy 195.898516 -286.664146) (xy 195.876888 -286.679723) (xy 195.829695 -286.704485)
			(xy 195.779141 -286.721357) (xy 195.726536 -286.729905) (xy 195.67324 -286.729905) (xy 195.620635 -286.721357)
			(xy 195.570081 -286.704485) (xy 195.522888 -286.679723) (xy 195.50126 -286.664146) (xy 195.494518 -286.659481)
			(xy 195.478972 -286.654307) (xy 195.47078 -286.653986) (xy 194.979036 -286.653986) (xy 194.97084 -286.654289)
			(xy 194.955287 -286.659461) (xy 194.948556 -286.664146) (xy 194.926928 -286.679723) (xy 194.879735 -286.704485)
			(xy 194.829181 -286.721357) (xy 194.776576 -286.729905) (xy 194.72328 -286.729905) (xy 194.670675 -286.721357)
			(xy 194.620121 -286.704485) (xy 194.572928 -286.679723) (xy 194.5513 -286.664146) (xy 194.54456 -286.659476)
			(xy 194.529014 -286.654289) (xy 194.52082 -286.653986) (xy 194.02933 -286.653986) (xy 194.021135 -286.65429)
			(xy 194.005582 -286.659464) (xy 193.99885 -286.664146) (xy 193.977225 -286.679803) (xy 193.92998 -286.704661)
			(xy 193.879353 -286.721602) (xy 193.826661 -286.730184) (xy 193.773275 -286.730184) (xy 193.720583 -286.721602)
			(xy 193.669956 -286.704661) (xy 193.622711 -286.679803) (xy 193.601086 -286.664146) (xy 193.594346 -286.659477)
			(xy 193.5788 -286.654295) (xy 193.570606 -286.653986) (xy 193.07937 -286.653986) (xy 193.071178 -286.654299)
			(xy 193.055637 -286.659488) (xy 193.04889 -286.664146) (xy 193.027265 -286.679803) (xy 192.98002 -286.704661)
			(xy 192.929393 -286.721602) (xy 192.876701 -286.730184) (xy 192.823315 -286.730184) (xy 192.770623 -286.721602)
			(xy 192.719996 -286.704661) (xy 192.672751 -286.679803) (xy 192.651126 -286.664146) (xy 192.644387 -286.659472)
			(xy 192.628841 -286.654277) (xy 192.620646 -286.653986) (xy 192.129156 -286.653986) (xy 192.120965 -286.654302)
			(xy 192.105426 -286.659493) (xy 192.098676 -286.664146) (xy 192.077048 -286.679723) (xy 192.029855 -286.704485)
			(xy 191.979301 -286.721357) (xy 191.926696 -286.729905) (xy 191.8734 -286.729905) (xy 191.820795 -286.721357)
			(xy 191.770241 -286.704485) (xy 191.723048 -286.679723) (xy 191.70142 -286.664146) (xy 191.694681 -286.659473)
			(xy 191.679135 -286.65428) (xy 191.67094 -286.653986) (xy 191.179196 -286.653986) (xy 191.171003 -286.654295)
			(xy 191.155456 -286.659477) (xy 191.148716 -286.664146) (xy 191.127088 -286.679723) (xy 191.079895 -286.704485)
			(xy 191.029341 -286.721357) (xy 190.976736 -286.729905) (xy 190.92344 -286.729905) (xy 190.870835 -286.721357)
			(xy 190.820281 -286.704485) (xy 190.773088 -286.679723) (xy 190.75146 -286.664146) (xy 190.744718 -286.659481)
			(xy 190.729172 -286.654307) (xy 190.72098 -286.653986) (xy 190.228982 -286.653986) (xy 190.220789 -286.654298)
			(xy 190.205246 -286.659483) (xy 190.198502 -286.664146) (xy 190.176874 -286.679723) (xy 190.129681 -286.704485)
			(xy 190.079127 -286.721357) (xy 190.026522 -286.729905) (xy 189.973226 -286.729905) (xy 189.920621 -286.721357)
			(xy 189.870067 -286.704485) (xy 189.822874 -286.679723) (xy 189.801246 -286.664146) (xy 189.794504 -286.659483)
			(xy 189.778958 -286.654313) (xy 189.770766 -286.653986) (xy 148.049742 -286.653986) (xy 148.043011 -286.654156)
			(xy 148.030007 -286.657634) (xy 148.024088 -286.660844) (xy 148.002054 -286.673313) (xy 147.955393 -286.692962)
			(xy 147.906543 -286.706263) (xy 147.856362 -286.712982) (xy 147.831048 -286.713422) (xy 147.805733 -286.712993)
			(xy 147.755552 -286.706267) (xy 147.706701 -286.692966) (xy 147.660037 -286.673324) (xy 147.638008 -286.660844)
			(xy 147.63207 -286.657683) (xy 147.619077 -286.654222) (xy 147.612354 -286.653986) (xy 144.876774 -286.653986)
			(xy 144.870041 -286.654152) (xy 144.857034 -286.657622) (xy 144.85112 -286.660844) (xy 144.829086 -286.673315)
			(xy 144.782426 -286.692967) (xy 144.733576 -286.706273) (xy 144.683395 -286.712996) (xy 144.65808 -286.713422)
			(xy 144.632767 -286.712988) (xy 144.582589 -286.706254) (xy 144.533742 -286.692946) (xy 144.487083 -286.673297)
			(xy 144.46504 -286.660844) (xy 144.459103 -286.657679) (xy 144.44611 -286.654209) (xy 144.439386 -286.653986)
			(xy 143.987774 -286.653986) (xy 143.981041 -286.654152) (xy 143.968034 -286.657622) (xy 143.96212 -286.660844)
			(xy 143.940086 -286.673315) (xy 143.893426 -286.692967) (xy 143.844576 -286.706273) (xy 143.794395 -286.712996)
			(xy 143.76908 -286.713422) (xy 143.743767 -286.712988) (xy 143.693589 -286.706254) (xy 143.644742 -286.692946)
			(xy 143.598083 -286.673297) (xy 143.57604 -286.660844) (xy 143.570103 -286.657679) (xy 143.55711 -286.654209)
			(xy 143.550386 -286.653986) (xy 142.512288 -286.653986) (xy 142.505559 -286.654163) (xy 142.492562 -286.657653)
			(xy 142.486634 -286.660844) (xy 142.4646 -286.673315) (xy 142.417941 -286.69297) (xy 142.36909 -286.706277)
			(xy 142.318909 -286.713003) (xy 142.293594 -286.713422) (xy 142.26828 -286.712989) (xy 142.218102 -286.706257)
			(xy 142.169254 -286.69295) (xy 142.122594 -286.673302) (xy 142.100554 -286.660844) (xy 142.094618 -286.657677)
			(xy 142.081625 -286.654204) (xy 142.0749 -286.653986) (xy 135.91413 -286.653986) (xy 135.904065 -286.654421)
			(xy 135.885478 -286.662152) (xy 135.878062 -286.668972) (xy 135.758174 -286.78886) (xy 135.751329 -286.796258)
			(xy 135.743604 -286.814857) (xy 135.743188 -286.824928) (xy 135.743188 -293.618412) (xy 135.742616 -293.643372)
			(xy 135.732874 -293.692332) (xy 135.713768 -293.738451) (xy 135.686031 -293.779956) (xy 135.668766 -293.79799)
			(xy 135.113014 -294.353742) (xy 135.094972 -294.370999) (xy 135.053477 -294.398749) (xy 135.007359 -294.417855)
			(xy 134.958396 -294.427579) (xy 134.933436 -294.428164) (xy 127.965708 -294.428164) (xy 127.955286 -294.428673)
			(xy 127.93615 -294.436938) (xy 127.928624 -294.444166) (xy 127.90885 -294.464436) (xy 127.864383 -294.499495)
			(xy 127.815222 -294.527595) (xy 127.762447 -294.54812) (xy 127.707218 -294.560618) (xy 127.650748 -294.564815)
			(xy 127.594278 -294.560618) (xy 127.539049 -294.54812) (xy 127.486274 -294.527595) (xy 127.437113 -294.499495)
			(xy 127.392646 -294.464436) (xy 127.372872 -294.444166) (xy 127.365371 -294.436904) (xy 127.346218 -294.428649)
			(xy 127.335788 -294.428164) (xy 118.272306 -294.428164) (xy 118.261016 -294.428766) (xy 118.24058 -294.438377)
			(xy 118.232936 -294.446706) (xy 118.216426 -294.464994) (xy 117.999764 -294.681656) (xy 117.992919 -294.689054)
			(xy 117.985195 -294.707653) (xy 117.984778 -294.717724) (xy 117.984778 -297.350788) (xy 152.144482 -297.350788)
			(xy 152.144482 -297.298812) (xy 152.152612 -297.247477) (xy 152.168672 -297.198046) (xy 152.192268 -297.151735)
			(xy 152.222816 -297.109685) (xy 152.259567 -297.072932) (xy 152.301615 -297.04238) (xy 152.347923 -297.018782)
			(xy 152.397354 -297.002717) (xy 152.448688 -296.994583) (xy 152.474676 -296.994072) (xy 153.424636 -296.994072)
			(xy 153.45062 -296.994624) (xy 153.501947 -297.002759) (xy 153.55137 -297.018822) (xy 153.597671 -297.042418)
			(xy 153.639712 -297.072967) (xy 153.676457 -297.109715) (xy 153.707001 -297.151759) (xy 153.730592 -297.198064)
			(xy 153.74665 -297.247488) (xy 153.754779 -297.298816) (xy 153.754779 -297.350784) (xy 153.74665 -297.402112)
			(xy 153.730592 -297.451536) (xy 153.707001 -297.497841) (xy 153.676457 -297.539885) (xy 153.639712 -297.576633)
			(xy 153.597671 -297.607182) (xy 153.55137 -297.630778) (xy 153.501947 -297.646841) (xy 153.45062 -297.654976)
			(xy 153.424636 -297.655488) (xy 152.474676 -297.655488) (xy 152.448688 -297.655017) (xy 152.397354 -297.646883)
			(xy 152.347923 -297.630818) (xy 152.301615 -297.60722) (xy 152.259567 -297.576668) (xy 152.222816 -297.539915)
			(xy 152.192268 -297.497865) (xy 152.168672 -297.451554) (xy 152.152612 -297.402123) (xy 152.144482 -297.350788)
			(xy 117.984778 -297.350788) (xy 117.984778 -299.25101) (xy 152.144202 -299.25101) (xy 152.144202 -299.19899)
			(xy 152.152339 -299.147612) (xy 152.168413 -299.098138) (xy 152.192028 -299.051788) (xy 152.222603 -299.009703)
			(xy 152.259385 -298.972919) (xy 152.301468 -298.942341) (xy 152.347816 -298.918722) (xy 152.397288 -298.902645)
			(xy 152.448666 -298.894504) (xy 152.474676 -298.893992) (xy 153.424636 -298.893992) (xy 153.450638 -298.894597)
			(xy 153.502 -298.902737) (xy 153.551457 -298.918811) (xy 153.59779 -298.942424) (xy 153.63986 -298.972993)
			(xy 153.67663 -299.009767) (xy 153.707195 -299.05184) (xy 153.730803 -299.098177) (xy 153.746871 -299.147635)
			(xy 153.755006 -299.198998) (xy 153.755006 -299.251002) (xy 153.755005 -299.251009) (xy 154.994602 -299.251009)
			(xy 154.994602 -299.198991) (xy 155.002739 -299.147613) (xy 155.018812 -299.098141) (xy 155.042426 -299.051792)
			(xy 155.073 -299.009707) (xy 155.10978 -298.972923) (xy 155.151861 -298.942345) (xy 155.198208 -298.918726)
			(xy 155.247678 -298.902647) (xy 155.299055 -298.894505) (xy 155.325064 -298.893992) (xy 156.275024 -298.893992)
			(xy 156.301026 -298.894596) (xy 156.35239 -298.902735) (xy 156.401848 -298.918808) (xy 156.448184 -298.94242)
			(xy 156.490255 -298.972989) (xy 156.527026 -299.009763) (xy 156.557593 -299.051837) (xy 156.581201 -299.098174)
			(xy 156.597271 -299.147633) (xy 156.605406 -299.198998) (xy 156.605406 -299.251002) (xy 156.597271 -299.302367)
			(xy 156.581201 -299.351826) (xy 156.557593 -299.398163) (xy 156.527026 -299.440237) (xy 156.490255 -299.477011)
			(xy 156.448184 -299.50758) (xy 156.401848 -299.531192) (xy 156.35239 -299.547265) (xy 156.301026 -299.555404)
			(xy 156.275024 -299.555916) (xy 155.325064 -299.555916) (xy 155.299055 -299.555495) (xy 155.247678 -299.547353)
			(xy 155.198208 -299.531274) (xy 155.151861 -299.507655) (xy 155.10978 -299.477077) (xy 155.073 -299.440293)
			(xy 155.042426 -299.398208) (xy 155.018812 -299.351859) (xy 155.002739 -299.302387) (xy 154.994602 -299.251009)
			(xy 153.755005 -299.251009) (xy 153.746871 -299.302365) (xy 153.730803 -299.351823) (xy 153.707195 -299.39816)
			(xy 153.67663 -299.440233) (xy 153.63986 -299.477007) (xy 153.59779 -299.507576) (xy 153.551457 -299.531189)
			(xy 153.502 -299.547263) (xy 153.450638 -299.555403) (xy 153.424636 -299.555916) (xy 152.474676 -299.555916)
			(xy 152.448666 -299.555496) (xy 152.397288 -299.547355) (xy 152.347816 -299.531278) (xy 152.301468 -299.507659)
			(xy 152.259385 -299.477081) (xy 152.222603 -299.440297) (xy 152.192028 -299.398212) (xy 152.168413 -299.351862)
			(xy 152.152339 -299.302388) (xy 152.144202 -299.25101) (xy 117.984778 -299.25101) (xy 117.984778 -315.781436)
			(xy 117.984967 -315.787875) (xy 117.988181 -315.800346) (xy 117.991128 -315.806074) (xy 118.003934 -315.830332)
			(xy 118.023224 -315.881681) (xy 118.034961 -315.935263) (xy 118.038903 -315.989974) (xy 118.034969 -316.044685)
			(xy 118.023239 -316.098269) (xy 118.003956 -316.14962) (xy 117.991128 -316.173866) (xy 117.988169 -316.17959)
			(xy 117.984951 -316.192063) (xy 117.984778 -316.198504) (xy 117.984778 -317.484506) (xy 117.984964 -317.490946)
			(xy 117.988171 -317.50342) (xy 117.991128 -317.509144) (xy 118.003929 -317.533402) (xy 118.023209 -317.584749)
			(xy 118.034937 -317.638328) (xy 118.03887 -317.693035) (xy 118.034927 -317.747741) (xy 118.023189 -317.801318)
			(xy 118.0039 -317.852662) (xy 117.991128 -317.876936) (xy 117.988177 -317.882662) (xy 117.984976 -317.895135)
			(xy 117.984778 -317.901574) (xy 117.984778 -318.349122) (xy 117.984966 -318.355561) (xy 117.988176 -318.368034)
			(xy 117.991128 -318.37376) (xy 118.003935 -318.398018) (xy 118.023227 -318.449367) (xy 118.034966 -318.50295)
			(xy 118.03891 -318.557661) (xy 118.034977 -318.612374) (xy 118.023249 -318.665959) (xy 118.003967 -318.717312)
			(xy 117.991128 -318.741552) (xy 117.988167 -318.747276) (xy 117.984946 -318.759749) (xy 117.984778 -318.76619)
			(xy 117.984778 -320.900044) (xy 140.998709 -320.900044) (xy 141.002715 -320.704989) (xy 141.014725 -320.510263)
			(xy 141.03472 -320.316194) (xy 141.062665 -320.12311) (xy 141.098514 -319.931335) (xy 141.142206 -319.741195)
			(xy 141.193667 -319.553008) (xy 141.252811 -319.367093) (xy 141.319538 -319.183762) (xy 141.393735 -319.003326)
			(xy 141.475277 -318.826088) (xy 141.564028 -318.652347) (xy 141.659836 -318.482396) (xy 141.762541 -318.316522)
			(xy 141.871969 -318.155004) (xy 141.987936 -317.998115) (xy 142.110247 -317.84612) (xy 142.238694 -317.699274)
			(xy 142.373062 -317.557825) (xy 142.513124 -317.422012) (xy 142.658643 -317.292063) (xy 142.809375 -317.168199)
			(xy 142.965065 -317.050627) (xy 143.125451 -316.939547) (xy 143.290262 -316.835144) (xy 143.45922 -316.737596)
			(xy 143.632041 -316.647067) (xy 143.808433 -316.563709) (xy 143.988098 -316.487663) (xy 144.170733 -316.419058)
			(xy 144.356032 -316.358008) (xy 144.54368 -316.304618) (xy 144.733362 -316.258976) (xy 144.924759 -316.22116)
			(xy 145.117546 -316.191234) (xy 145.311399 -316.169248) (xy 145.505992 -316.155239) (xy 145.700995 -316.149231)
			(xy 145.896081 -316.151234) (xy 146.09092 -316.161245) (xy 146.285184 -316.179246) (xy 146.478545 -316.205208)
			(xy 146.670678 -316.239086) (xy 146.861257 -316.280823) (xy 147.049962 -316.33035) (xy 147.236475 -316.387582)
			(xy 147.420481 -316.452423) (xy 147.601669 -316.524764) (xy 147.779735 -316.604482) (xy 147.954378 -316.691444)
			(xy 148.125304 -316.785503) (xy 148.292223 -316.886499) (xy 148.454856 -316.994264) (xy 148.612927 -317.108614)
			(xy 148.76617 -317.229357) (xy 148.914327 -317.356291) (xy 149.057148 -317.489199) (xy 149.194392 -317.627859)
			(xy 149.325828 -317.772037) (xy 149.451233 -317.92149) (xy 149.570397 -318.075964) (xy 149.683118 -318.235201)
			(xy 149.789207 -318.398932) (xy 149.888485 -318.566879) (xy 149.980783 -318.738762) (xy 150.065948 -318.914288)
			(xy 150.143834 -319.093163) (xy 150.214311 -319.275085) (xy 150.277259 -319.459747) (xy 150.332574 -319.646837)
			(xy 150.38016 -319.836041) (xy 150.419939 -320.027038) (xy 150.451843 -320.219508) (xy 150.475818 -320.413126)
			(xy 150.491824 -320.607564) (xy 150.499833 -320.802496) (xy 150.500334 -320.900044) (xy 150.499833 -320.997592)
			(xy 150.491824 -321.192524) (xy 150.475818 -321.386962) (xy 150.451843 -321.58058) (xy 150.419939 -321.77305)
			(xy 150.38016 -321.964047) (xy 150.332574 -322.153251) (xy 150.277259 -322.340341) (xy 150.214311 -322.525003)
			(xy 150.143834 -322.706925) (xy 150.065948 -322.8858) (xy 149.980783 -323.061326) (xy 149.888485 -323.233209)
			(xy 149.789207 -323.401156) (xy 149.683118 -323.564887) (xy 149.570397 -323.724124) (xy 149.451233 -323.878598)
			(xy 149.325828 -324.028051) (xy 149.194392 -324.172229) (xy 149.057148 -324.310889) (xy 148.914327 -324.443797)
			(xy 148.76617 -324.570731) (xy 148.612927 -324.691474) (xy 148.454856 -324.805824) (xy 148.292223 -324.913589)
			(xy 148.125304 -325.014585) (xy 147.954378 -325.108644) (xy 147.779735 -325.195606) (xy 147.601669 -325.275324)
			(xy 147.420481 -325.347665) (xy 147.236475 -325.412506) (xy 147.049962 -325.469738) (xy 146.861257 -325.519265)
			(xy 146.670678 -325.561002) (xy 146.478545 -325.59488) (xy 146.285184 -325.620842) (xy 146.09092 -325.638843)
			(xy 145.896081 -325.648854) (xy 145.700995 -325.650857) (xy 145.505992 -325.644849) (xy 145.311399 -325.63084)
			(xy 145.117546 -325.608854) (xy 144.924759 -325.578928) (xy 144.733362 -325.541112) (xy 144.54368 -325.49547)
			(xy 144.356032 -325.44208) (xy 144.170733 -325.38103) (xy 143.988098 -325.312425) (xy 143.808433 -325.236379)
			(xy 143.632041 -325.153021) (xy 143.45922 -325.062492) (xy 143.290262 -324.964944) (xy 143.125451 -324.860541)
			(xy 142.965065 -324.749461) (xy 142.809375 -324.631889) (xy 142.658643 -324.508025) (xy 142.513124 -324.378076)
			(xy 142.373062 -324.242263) (xy 142.238694 -324.100814) (xy 142.110247 -323.953968) (xy 141.987936 -323.801973)
			(xy 141.871969 -323.645084) (xy 141.762541 -323.483566) (xy 141.659836 -323.317692) (xy 141.564028 -323.147741)
			(xy 141.475277 -322.974) (xy 141.393735 -322.796762) (xy 141.319538 -322.616326) (xy 141.252811 -322.432995)
			(xy 141.193667 -322.24708) (xy 141.142206 -322.058893) (xy 141.098514 -321.868753) (xy 141.062665 -321.676978)
			(xy 141.03472 -321.483894) (xy 141.014725 -321.289825) (xy 141.002715 -321.095099) (xy 140.998709 -320.900044)
			(xy 117.984778 -320.900044) (xy 117.984778 -329.207368) (xy 117.985008 -329.214843) (xy 117.989276 -329.22917)
			(xy 117.99316 -329.235562) (xy 118.008289 -329.259148) (xy 118.03221 -329.309819) (xy 118.048455 -329.363446)
			(xy 118.056675 -329.418873) (xy 118.057168 -329.44689) (xy 118.056655 -329.474905) (xy 118.048425 -329.530328)
			(xy 118.032185 -329.583953) (xy 118.008282 -329.63463) (xy 117.99316 -329.658218) (xy 117.98927 -329.664606)
			(xy 117.985012 -329.678936) (xy 117.984778 -329.686412) (xy 117.984778 -337.580986) (xy 117.985285 -337.591036)
			(xy 117.993008 -337.609595) (xy 117.999764 -337.617054) (xy 118.208806 -337.826096) (xy 118.221506 -337.839812)
			(xy 118.229064 -337.847712) (xy 118.248939 -337.856772) (xy 118.25986 -337.857338)
		)
		(stroke
			(width 0)
			(type solid)
		)
		(fill yes)
		(layer "In2.Cu")
		(net "P0V8_SERDES_VDDA_PEX1")
	)
	(gr_poly
		(pts
			(xy 429.833024 -337.857338) (xy 429.843091 -337.856909) (xy 429.861683 -337.849181) (xy 429.869092 -337.842352)
			(xy 430.892966 -336.818478) (xy 430.899813 -336.81108) (xy 430.907545 -336.792482) (xy 430.907952 -336.78241)
			(xy 430.907952 -326.583802) (xy 430.907698 -326.572118) (xy 430.907698 -318.236346) (xy 430.907444 -318.224662)
			(xy 430.907444 -303.159414) (xy 430.903634 -303.150016) (xy 430.894349 -303.126047) (xy 430.882474 -303.076039)
			(xy 430.878485 -303.024794) (xy 430.882476 -302.97355) (xy 430.894353 -302.923542) (xy 430.903634 -302.899572)
			(xy 430.907444 -302.890174) (xy 430.907444 -302.167544) (xy 430.905666 -302.161194) (xy 430.900315 -302.140006)
			(xy 430.894577 -302.096684) (xy 430.894236 -302.074834) (xy 430.89457 -302.052983) (xy 430.900304 -302.009659)
			(xy 430.905666 -301.988474) (xy 430.907444 -301.982124) (xy 430.907444 -301.217584) (xy 430.905666 -301.211234)
			(xy 430.900319 -301.190046) (xy 430.894589 -301.146724) (xy 430.894236 -301.124874) (xy 430.894567 -301.103023)
			(xy 430.900296 -301.059698) (xy 430.905666 -301.038514) (xy 430.907444 -301.032164) (xy 430.907444 -300.267624)
			(xy 430.905666 -300.261274) (xy 430.900316 -300.240086) (xy 430.894581 -300.196764) (xy 430.894236 -300.174914)
			(xy 430.894571 -300.153063) (xy 430.900307 -300.10974) (xy 430.905666 -300.088554) (xy 430.907444 -300.082204)
			(xy 430.907444 -299.317664) (xy 430.905666 -299.311314) (xy 430.90032 -299.290126) (xy 430.894593 -299.246804)
			(xy 430.894236 -299.224954) (xy 430.894569 -299.203103) (xy 430.9003 -299.159779) (xy 430.905666 -299.138594)
			(xy 430.907444 -299.132244) (xy 430.907444 -298.36745) (xy 430.905666 -298.3611) (xy 430.900315 -298.339912)
			(xy 430.894576 -298.29659) (xy 430.894236 -298.27474) (xy 430.89457 -298.252889) (xy 430.900302 -298.209565)
			(xy 430.905666 -298.18838) (xy 430.907444 -298.18203) (xy 430.907444 -297.41749) (xy 430.905666 -297.41114)
			(xy 430.900319 -297.389952) (xy 430.894587 -297.34663) (xy 430.894236 -297.32478) (xy 430.894567 -297.302929)
			(xy 430.900295 -297.259603) (xy 430.905666 -297.23842) (xy 430.907444 -297.23207) (xy 430.907444 -296.46753)
			(xy 430.905666 -296.46118) (xy 430.900316 -296.439992) (xy 430.89458 -296.39667) (xy 430.894236 -296.37482)
			(xy 430.894571 -296.352969) (xy 430.900306 -296.309646) (xy 430.905666 -296.28846) (xy 430.907444 -296.28211)
			(xy 430.907444 -294.56761) (xy 430.905666 -294.56126) (xy 430.900317 -294.540072) (xy 430.894584 -294.49675)
			(xy 430.894236 -294.4749) (xy 430.894572 -294.453049) (xy 430.90031 -294.409727) (xy 430.905666 -294.38854)
			(xy 430.907444 -294.38219) (xy 430.907444 -293.61765) (xy 430.905666 -293.6113) (xy 430.900315 -293.590112)
			(xy 430.894576 -293.54679) (xy 430.894236 -293.52494) (xy 430.89457 -293.503089) (xy 430.900302 -293.459765)
			(xy 430.905666 -293.43858) (xy 430.907444 -293.43223) (xy 430.907444 -292.66769) (xy 430.905666 -292.66134)
			(xy 430.900319 -292.640152) (xy 430.894587 -292.59683) (xy 430.894236 -292.57498) (xy 430.894567 -292.553129)
			(xy 430.900295 -292.509803) (xy 430.905666 -292.48862) (xy 430.907444 -292.48227) (xy 430.907444 -291.717476)
			(xy 430.905666 -291.711126) (xy 430.90032 -291.689938) (xy 430.89459 -291.646616) (xy 430.894236 -291.624766)
			(xy 430.894568 -291.602915) (xy 430.900297 -291.55959) (xy 430.905666 -291.538406) (xy 430.907444 -291.532056)
			(xy 430.907444 -290.767516) (xy 430.905666 -290.761166) (xy 430.900317 -290.739978) (xy 430.894582 -290.696656)
			(xy 430.894236 -290.674806) (xy 430.894572 -290.652955) (xy 430.900309 -290.609633) (xy 430.905666 -290.588446)
			(xy 430.907444 -290.582096) (xy 430.907444 -289.817556) (xy 430.905666 -289.811206) (xy 430.900314 -289.790018)
			(xy 430.894575 -289.746696) (xy 430.894236 -289.724846) (xy 430.894569 -289.702995) (xy 430.900301 -289.659671)
			(xy 430.905666 -289.638486) (xy 430.907444 -289.632136) (xy 430.907444 -288.867596) (xy 430.905666 -288.861246)
			(xy 430.900318 -288.840058) (xy 430.894586 -288.796736) (xy 430.894236 -288.774886) (xy 430.894573 -288.753035)
			(xy 430.900313 -288.709714) (xy 430.905666 -288.688526) (xy 430.907444 -288.682176) (xy 430.907444 -286.801814)
			(xy 430.907004 -286.791752) (xy 430.899261 -286.773176) (xy 430.892458 -286.765746) (xy 430.854866 -286.728154)
			(xy 430.830482 -286.720788) (xy 430.817528 -286.723328) (xy 430.800833 -286.726639) (xy 430.766983 -286.730204)
			(xy 430.749964 -286.73044) (xy 430.723317 -286.729902) (xy 430.670714 -286.72135) (xy 430.620163 -286.704474)
			(xy 430.572972 -286.679711) (xy 430.551336 -286.664146) (xy 430.544593 -286.659485) (xy 430.529047 -286.654317)
			(xy 430.520856 -286.653986) (xy 430.029112 -286.653986) (xy 430.020918 -286.654293) (xy 430.005368 -286.659471)
			(xy 429.998632 -286.664146) (xy 429.977004 -286.679723) (xy 429.929811 -286.704485) (xy 429.879257 -286.721357)
			(xy 429.826652 -286.729905) (xy 429.773356 -286.729905) (xy 429.720751 -286.721357) (xy 429.670197 -286.704485)
			(xy 429.623004 -286.679723) (xy 429.601376 -286.664146) (xy 429.594635 -286.659479) (xy 429.579089 -286.654299)
			(xy 429.570896 -286.653986) (xy 429.078898 -286.653986) (xy 429.070704 -286.654295) (xy 429.055158 -286.659477)
			(xy 429.048418 -286.664146) (xy 429.02679 -286.679723) (xy 428.979597 -286.704485) (xy 428.929043 -286.721357)
			(xy 428.876438 -286.729905) (xy 428.823142 -286.729905) (xy 428.770537 -286.721357) (xy 428.719983 -286.704485)
			(xy 428.67279 -286.679723) (xy 428.651162 -286.664146) (xy 428.64442 -286.659481) (xy 428.628874 -286.654306)
			(xy 428.620682 -286.653986) (xy 428.128938 -286.653986) (xy 428.120742 -286.654289) (xy 428.105188 -286.659461)
			(xy 428.098458 -286.664146) (xy 428.07683 -286.679723) (xy 428.029637 -286.704485) (xy 427.979083 -286.721357)
			(xy 427.926478 -286.729905) (xy 427.873182 -286.729905) (xy 427.820577 -286.721357) (xy 427.770023 -286.704485)
			(xy 427.72283 -286.679723) (xy 427.701202 -286.664146) (xy 427.694462 -286.659475) (xy 427.678916 -286.654288)
			(xy 427.670722 -286.653986) (xy 427.178978 -286.653986) (xy 427.170786 -286.654298) (xy 427.155243 -286.659484)
			(xy 427.148498 -286.664146) (xy 427.12687 -286.679723) (xy 427.079677 -286.704485) (xy 427.029123 -286.721357)
			(xy 426.976518 -286.729905) (xy 426.923222 -286.729905) (xy 426.870617 -286.721357) (xy 426.820063 -286.704485)
			(xy 426.77287 -286.679723) (xy 426.751242 -286.664146) (xy 426.7445 -286.659484) (xy 426.728954 -286.654315)
			(xy 426.720762 -286.653986) (xy 426.229272 -286.653986) (xy 426.22108 -286.654299) (xy 426.205538 -286.659487)
			(xy 426.198792 -286.664146) (xy 426.177167 -286.679803) (xy 426.129922 -286.704661) (xy 426.079295 -286.721602)
			(xy 426.026603 -286.730184) (xy 425.973217 -286.730184) (xy 425.920525 -286.721602) (xy 425.869898 -286.704661)
			(xy 425.822653 -286.679803) (xy 425.801028 -286.664146) (xy 425.794289 -286.659472) (xy 425.778743 -286.654277)
			(xy 425.770548 -286.653986) (xy 425.279312 -286.653986) (xy 425.271118 -286.654293) (xy 425.255568 -286.659471)
			(xy 425.248832 -286.664146) (xy 425.227207 -286.679803) (xy 425.179962 -286.704661) (xy 425.129335 -286.721602)
			(xy 425.076643 -286.730184) (xy 425.023257 -286.730184) (xy 424.970565 -286.721602) (xy 424.919938 -286.704661)
			(xy 424.872693 -286.679803) (xy 424.851068 -286.664146) (xy 424.844327 -286.65948) (xy 424.828781 -286.654303)
			(xy 424.820588 -286.653986) (xy 424.329098 -286.653986) (xy 424.320904 -286.654295) (xy 424.305358 -286.659477)
			(xy 424.298618 -286.664146) (xy 424.27699 -286.679723) (xy 424.229797 -286.704485) (xy 424.179243 -286.721357)
			(xy 424.126638 -286.729905) (xy 424.073342 -286.729905) (xy 424.020737 -286.721357) (xy 423.970183 -286.704485)
			(xy 423.92299 -286.679723) (xy 423.901362 -286.664146) (xy 423.89462 -286.659481) (xy 423.879074 -286.654306)
			(xy 423.870882 -286.653986) (xy 423.379138 -286.653986) (xy 423.370942 -286.654289) (xy 423.355388 -286.659461)
			(xy 423.348658 -286.664146) (xy 423.32703 -286.679723) (xy 423.279837 -286.704485) (xy 423.229283 -286.721357)
			(xy 423.176678 -286.729905) (xy 423.123382 -286.729905) (xy 423.070777 -286.721357) (xy 423.020223 -286.704485)
			(xy 422.97303 -286.679723) (xy 422.951402 -286.664146) (xy 422.944662 -286.659475) (xy 422.929116 -286.654288)
			(xy 422.920922 -286.653986) (xy 422.428924 -286.653986) (xy 422.420729 -286.654291) (xy 422.405178 -286.659466)
			(xy 422.398444 -286.664146) (xy 422.376816 -286.679723) (xy 422.329623 -286.704485) (xy 422.279069 -286.721357)
			(xy 422.226464 -286.729905) (xy 422.173168 -286.729905) (xy 422.120563 -286.721357) (xy 422.070009 -286.704485)
			(xy 422.022816 -286.679723) (xy 422.001188 -286.664146) (xy 421.994448 -286.659477) (xy 421.978902 -286.654294)
			(xy 421.970708 -286.653986) (xy 380.249684 -286.653986) (xy 380.242951 -286.654151) (xy 380.229942 -286.657619)
			(xy 380.22403 -286.660844) (xy 380.201996 -286.673315) (xy 380.155336 -286.692969) (xy 380.106486 -286.706276)
			(xy 380.056305 -286.713001) (xy 380.03099 -286.713422) (xy 380.005676 -286.712989) (xy 379.955498 -286.706256)
			(xy 379.906651 -286.692949) (xy 379.859991 -286.673301) (xy 379.83795 -286.660844) (xy 379.832014 -286.657678)
			(xy 379.819021 -286.654206) (xy 379.812296 -286.653986) (xy 377.076716 -286.653986) (xy 377.069986 -286.65416)
			(xy 377.056986 -286.657643) (xy 377.051062 -286.660844) (xy 377.029029 -286.673317) (xy 376.982369 -286.692975)
			(xy 376.933519 -286.706286) (xy 376.883337 -286.713015) (xy 376.858022 -286.713422) (xy 376.832708 -286.712991)
			(xy 376.782528 -286.706262) (xy 376.733678 -286.692958) (xy 376.687016 -286.673313) (xy 376.664982 -286.660844)
			(xy 376.659046 -286.657674) (xy 376.646053 -286.654194) (xy 376.639328 -286.653986) (xy 376.187716 -286.653986)
			(xy 376.180986 -286.65416) (xy 376.167986 -286.657643) (xy 376.162062 -286.660844) (xy 376.140029 -286.673317)
			(xy 376.093369 -286.692975) (xy 376.044519 -286.706286) (xy 375.994337 -286.713015) (xy 375.969022 -286.713422)
			(xy 375.943708 -286.712991) (xy 375.893528 -286.706262) (xy 375.844678 -286.692958) (xy 375.798016 -286.673313)
			(xy 375.775982 -286.660844) (xy 375.770046 -286.657674) (xy 375.757053 -286.654194) (xy 375.750328 -286.653986)
			(xy 374.71223 -286.653986) (xy 374.705499 -286.654158) (xy 374.692497 -286.657638) (xy 374.686576 -286.660844)
			(xy 374.664543 -286.673318) (xy 374.617884 -286.692978) (xy 374.569034 -286.70629) (xy 374.518852 -286.713022)
			(xy 374.493536 -286.713422) (xy 374.468222 -286.712992) (xy 374.418041 -286.706264) (xy 374.369191 -286.692962)
			(xy 374.322527 -286.673319) (xy 374.300496 -286.660844) (xy 374.294561 -286.657672) (xy 374.281568 -286.654189)
			(xy 374.274842 -286.653986) (xy 368.114072 -286.653986) (xy 368.104004 -286.654414) (xy 368.085405 -286.662134)
			(xy 368.078004 -286.668972) (xy 367.958116 -286.78886) (xy 367.951277 -286.796261) (xy 367.943562 -286.814859)
			(xy 367.94313 -286.824928) (xy 367.94313 -293.618412) (xy 367.942517 -293.643368) (xy 367.932779 -293.692322)
			(xy 367.913678 -293.738436) (xy 367.885949 -293.779937) (xy 367.868708 -293.79799) (xy 367.312956 -294.353742)
			(xy 367.294915 -294.371002) (xy 367.253421 -294.398759) (xy 367.207303 -294.417872) (xy 367.158339 -294.427605)
			(xy 367.133378 -294.428164) (xy 360.165904 -294.428164) (xy 360.155483 -294.428674) (xy 360.136348 -294.43694)
			(xy 360.12882 -294.444166) (xy 360.109046 -294.464436) (xy 360.064579 -294.499495) (xy 360.015418 -294.527595)
			(xy 359.962643 -294.54812) (xy 359.907414 -294.560618) (xy 359.850944 -294.564815) (xy 359.794474 -294.560618)
			(xy 359.739245 -294.54812) (xy 359.68647 -294.527595) (xy 359.637309 -294.499495) (xy 359.592842 -294.464436)
			(xy 359.573068 -294.444166) (xy 359.565566 -294.436905) (xy 359.546414 -294.428651) (xy 359.535984 -294.428164)
			(xy 350.472502 -294.428164) (xy 350.461212 -294.428766) (xy 350.440778 -294.438379) (xy 350.433132 -294.446706)
			(xy 350.416622 -294.464994) (xy 350.19996 -294.681656) (xy 350.193116 -294.689055) (xy 350.185392 -294.707654)
			(xy 350.184974 -294.717724) (xy 350.184974 -297.350792) (xy 384.344355 -297.350792) (xy 384.344355 -297.298808)
			(xy 384.352488 -297.247465) (xy 384.368552 -297.198026) (xy 384.392153 -297.151709) (xy 384.422709 -297.109654)
			(xy 384.459467 -297.072897) (xy 384.501524 -297.042343) (xy 384.547842 -297.018745) (xy 384.597282 -297.002683)
			(xy 384.648626 -296.994554) (xy 384.674618 -296.994072) (xy 385.624578 -296.994072) (xy 385.650567 -296.994593)
			(xy 385.701905 -297.002721) (xy 385.751339 -297.018781) (xy 385.797653 -297.042376) (xy 385.839705 -297.072926)
			(xy 385.87646 -297.109678) (xy 385.907013 -297.151728) (xy 385.930611 -297.19804) (xy 385.946673 -297.247474)
			(xy 385.954805 -297.298811) (xy 385.954805 -297.350789) (xy 385.946673 -297.402126) (xy 385.930611 -297.45156)
			(xy 385.907013 -297.497872) (xy 385.87646 -297.539922) (xy 385.839705 -297.576674) (xy 385.797653 -297.607224)
			(xy 385.751339 -297.630819) (xy 385.701905 -297.646879) (xy 385.650567 -297.655007) (xy 385.624578 -297.655488)
			(xy 384.674618 -297.655488) (xy 384.648626 -297.655046) (xy 384.597282 -297.646917) (xy 384.547842 -297.630855)
			(xy 384.501524 -297.607257) (xy 384.459467 -297.576703) (xy 384.422709 -297.539946) (xy 384.392153 -297.497891)
			(xy 384.368552 -297.451574) (xy 384.352488 -297.402135) (xy 384.344355 -297.350792) (xy 350.184974 -297.350792)
			(xy 350.184974 -298.775685) (xy 387.669821 -298.775685) (xy 387.669821 -298.723715) (xy 387.677951 -298.672385)
			(xy 387.69401 -298.622959) (xy 387.717603 -298.576653) (xy 387.74815 -298.534608) (xy 387.784897 -298.497859)
			(xy 387.826941 -298.467311) (xy 387.873246 -298.443716) (xy 387.922671 -298.427654) (xy 387.974001 -298.419523)
			(xy 387.999986 -298.419012) (xy 388.949946 -298.419012) (xy 388.975932 -298.419485) (xy 389.027264 -298.427622)
			(xy 389.076692 -298.443688) (xy 389.122998 -298.467288) (xy 389.165042 -298.49784) (xy 389.20179 -298.534593)
			(xy 389.232337 -298.576642) (xy 389.25593 -298.622951) (xy 389.271989 -298.67238) (xy 389.280119 -298.723714)
			(xy 389.280119 -298.775686) (xy 389.271989 -298.82702) (xy 389.25593 -298.876449) (xy 389.232337 -298.922758)
			(xy 389.20179 -298.964807) (xy 389.165042 -299.00156) (xy 389.122998 -299.032112) (xy 389.076692 -299.055712)
			(xy 389.027264 -299.071778) (xy 388.975932 -299.079915) (xy 388.949946 -299.080428) (xy 387.999986 -299.080428)
			(xy 387.974001 -299.079877) (xy 387.922671 -299.071746) (xy 387.873246 -299.055684) (xy 387.826941 -299.032089)
			(xy 387.784897 -299.001541) (xy 387.74815 -298.964792) (xy 387.717603 -298.922747) (xy 387.69401 -298.876441)
			(xy 387.677951 -298.827015) (xy 387.669821 -298.775685) (xy 350.184974 -298.775685) (xy 350.184974 -299.251014)
			(xy 384.344076 -299.251014) (xy 384.344076 -299.198986) (xy 384.352215 -299.147599) (xy 384.368293 -299.098118)
			(xy 384.391913 -299.051762) (xy 384.422495 -299.009672) (xy 384.459285 -298.972884) (xy 384.501377 -298.942304)
			(xy 384.547735 -298.918686) (xy 384.597217 -298.902611) (xy 384.648604 -298.894474) (xy 384.674618 -298.893992)
			(xy 385.624578 -298.893992) (xy 385.650585 -298.894566) (xy 385.701958 -298.902699) (xy 385.751427 -298.91877)
			(xy 385.797772 -298.942381) (xy 385.839853 -298.972952) (xy 385.876634 -299.00973) (xy 385.907207 -299.051809)
			(xy 385.930822 -299.098153) (xy 385.946896 -299.14762) (xy 385.955033 -299.198993) (xy 385.955033 -299.251007)
			(xy 385.946896 -299.30238) (xy 385.930822 -299.351847) (xy 385.907207 -299.398191) (xy 385.876634 -299.44027)
			(xy 385.839853 -299.477048) (xy 385.797772 -299.507619) (xy 385.751427 -299.53123) (xy 385.701958 -299.547301)
			(xy 385.650585 -299.555434) (xy 385.624578 -299.555916) (xy 384.674618 -299.555916) (xy 384.648604 -299.555526)
			(xy 384.597217 -299.547389) (xy 384.547735 -299.531314) (xy 384.501377 -299.507696) (xy 384.459285 -299.477116)
			(xy 384.422495 -299.440328) (xy 384.391913 -299.398238) (xy 384.368293 -299.351882) (xy 384.352215 -299.302401)
			(xy 384.344076 -299.251014) (xy 350.184974 -299.251014) (xy 350.184974 -315.781436) (xy 350.185163 -315.787875)
			(xy 350.188377 -315.800346) (xy 350.191324 -315.806074) (xy 350.20413 -315.830332) (xy 350.223421 -315.881681)
			(xy 350.235158 -315.935263) (xy 350.2391 -315.989974) (xy 350.235165 -316.044685) (xy 350.223435 -316.098269)
			(xy 350.204152 -316.14962) (xy 350.191324 -316.173866) (xy 350.188365 -316.17959) (xy 350.185148 -316.192063)
			(xy 350.184974 -316.198504) (xy 350.184974 -317.484506) (xy 350.18516 -317.490946) (xy 350.188367 -317.503421)
			(xy 350.191324 -317.509144) (xy 350.204125 -317.533402) (xy 350.223406 -317.584749) (xy 350.235133 -317.638328)
			(xy 350.239066 -317.693035) (xy 350.235123 -317.747741) (xy 350.223386 -317.801318) (xy 350.204096 -317.852662)
			(xy 350.191324 -317.876936) (xy 350.188373 -317.882662) (xy 350.185173 -317.895135) (xy 350.184974 -317.901574)
			(xy 350.184974 -318.349122) (xy 350.185162 -318.355562) (xy 350.188372 -318.368034) (xy 350.191324 -318.37376)
			(xy 350.204131 -318.398018) (xy 350.223424 -318.449367) (xy 350.235163 -318.50295) (xy 350.239107 -318.557661)
			(xy 350.235174 -318.612374) (xy 350.223445 -318.665959) (xy 350.204163 -318.717312) (xy 350.191324 -318.741552)
			(xy 350.188364 -318.747276) (xy 350.185143 -318.759749) (xy 350.184974 -318.76619) (xy 350.184974 -320.900044)
			(xy 373.198651 -320.900044) (xy 373.202657 -320.704989) (xy 373.214667 -320.510263) (xy 373.234662 -320.316194)
			(xy 373.262607 -320.12311) (xy 373.298456 -319.931335) (xy 373.342148 -319.741195) (xy 373.393609 -319.553008)
			(xy 373.452753 -319.367093) (xy 373.51948 -319.183762) (xy 373.593677 -319.003326) (xy 373.675219 -318.826088)
			(xy 373.76397 -318.652347) (xy 373.859778 -318.482396) (xy 373.962483 -318.316522) (xy 374.071911 -318.155004)
			(xy 374.187878 -317.998115) (xy 374.310189 -317.84612) (xy 374.438636 -317.699274) (xy 374.573004 -317.557825)
			(xy 374.713066 -317.422012) (xy 374.858585 -317.292063) (xy 375.009317 -317.168199) (xy 375.165007 -317.050627)
			(xy 375.325393 -316.939547) (xy 375.490204 -316.835144) (xy 375.659162 -316.737596) (xy 375.831983 -316.647067)
			(xy 376.008375 -316.563709) (xy 376.18804 -316.487663) (xy 376.370675 -316.419058) (xy 376.555974 -316.358008)
			(xy 376.743622 -316.304618) (xy 376.933304 -316.258976) (xy 377.124701 -316.22116) (xy 377.317488 -316.191234)
			(xy 377.511341 -316.169248) (xy 377.705934 -316.155239) (xy 377.900937 -316.149231) (xy 378.096023 -316.151234)
			(xy 378.290862 -316.161245) (xy 378.485126 -316.179246) (xy 378.678487 -316.205208) (xy 378.87062 -316.239086)
			(xy 379.061199 -316.280823) (xy 379.249904 -316.33035) (xy 379.436417 -316.387582) (xy 379.620423 -316.452423)
			(xy 379.801611 -316.524764) (xy 379.979677 -316.604482) (xy 380.15432 -316.691444) (xy 380.325246 -316.785503)
			(xy 380.492165 -316.886499) (xy 380.654798 -316.994264) (xy 380.812869 -317.108614) (xy 380.966112 -317.229357)
			(xy 381.114269 -317.356291) (xy 381.25709 -317.489199) (xy 381.394334 -317.627859) (xy 381.52577 -317.772037)
			(xy 381.651175 -317.92149) (xy 381.770339 -318.075964) (xy 381.88306 -318.235201) (xy 381.989149 -318.398932)
			(xy 382.088427 -318.566879) (xy 382.180725 -318.738762) (xy 382.26589 -318.914288) (xy 382.343776 -319.093163)
			(xy 382.414253 -319.275085) (xy 382.477201 -319.459747) (xy 382.532516 -319.646837) (xy 382.580102 -319.836041)
			(xy 382.619881 -320.027038) (xy 382.651785 -320.219508) (xy 382.67576 -320.413126) (xy 382.691766 -320.607564)
			(xy 382.699775 -320.802496) (xy 382.700276 -320.900044) (xy 382.699775 -320.997592) (xy 382.691766 -321.192524)
			(xy 382.67576 -321.386962) (xy 382.651785 -321.58058) (xy 382.619881 -321.77305) (xy 382.580102 -321.964047)
			(xy 382.532516 -322.153251) (xy 382.477201 -322.340341) (xy 382.414253 -322.525003) (xy 382.343776 -322.706925)
			(xy 382.26589 -322.8858) (xy 382.180725 -323.061326) (xy 382.088427 -323.233209) (xy 381.989149 -323.401156)
			(xy 381.88306 -323.564887) (xy 381.770339 -323.724124) (xy 381.651175 -323.878598) (xy 381.52577 -324.028051)
			(xy 381.394334 -324.172229) (xy 381.25709 -324.310889) (xy 381.114269 -324.443797) (xy 380.966112 -324.570731)
			(xy 380.812869 -324.691474) (xy 380.654798 -324.805824) (xy 380.492165 -324.913589) (xy 380.325246 -325.014585)
			(xy 380.15432 -325.108644) (xy 379.979677 -325.195606) (xy 379.801611 -325.275324) (xy 379.620423 -325.347665)
			(xy 379.436417 -325.412506) (xy 379.249904 -325.469738) (xy 379.061199 -325.519265) (xy 378.87062 -325.561002)
			(xy 378.678487 -325.59488) (xy 378.485126 -325.620842) (xy 378.290862 -325.638843) (xy 378.096023 -325.648854)
			(xy 377.900937 -325.650857) (xy 377.705934 -325.644849) (xy 377.511341 -325.63084) (xy 377.317488 -325.608854)
			(xy 377.124701 -325.578928) (xy 376.933304 -325.541112) (xy 376.743622 -325.49547) (xy 376.555974 -325.44208)
			(xy 376.370675 -325.38103) (xy 376.18804 -325.312425) (xy 376.008375 -325.236379) (xy 375.831983 -325.153021)
			(xy 375.659162 -325.062492) (xy 375.490204 -324.964944) (xy 375.325393 -324.860541) (xy 375.165007 -324.749461)
			(xy 375.009317 -324.631889) (xy 374.858585 -324.508025) (xy 374.713066 -324.378076) (xy 374.573004 -324.242263)
			(xy 374.438636 -324.100814) (xy 374.310189 -323.953968) (xy 374.187878 -323.801973) (xy 374.071911 -323.645084)
			(xy 373.962483 -323.483566) (xy 373.859778 -323.317692) (xy 373.76397 -323.147741) (xy 373.675219 -322.974)
			(xy 373.593677 -322.796762) (xy 373.51948 -322.616326) (xy 373.452753 -322.432995) (xy 373.393609 -322.24708)
			(xy 373.342148 -322.058893) (xy 373.298456 -321.868753) (xy 373.262607 -321.676978) (xy 373.234662 -321.483894)
			(xy 373.214667 -321.289825) (xy 373.202657 -321.095099) (xy 373.198651 -320.900044) (xy 350.184974 -320.900044)
			(xy 350.184974 -332.947271) (xy 365.368753 -332.947271) (xy 365.368753 -332.887329) (xy 365.376578 -332.827899)
			(xy 365.392093 -332.77) (xy 365.415033 -332.71462) (xy 365.445006 -332.66271) (xy 365.481498 -332.615155)
			(xy 365.523886 -332.572772) (xy 365.571443 -332.536283) (xy 365.623356 -332.506315) (xy 365.678737 -332.48338)
			(xy 365.736639 -332.46787) (xy 365.796069 -332.460051) (xy 365.82604 -332.459584) (xy 366.68964 -332.459584)
			(xy 366.719605 -332.460093) (xy 366.779023 -332.46792) (xy 366.836911 -332.483435) (xy 366.892278 -332.506374)
			(xy 366.944178 -332.536342) (xy 366.991723 -332.572828) (xy 367.034098 -332.615207) (xy 367.07058 -332.662755)
			(xy 367.100544 -332.714658) (xy 367.123478 -332.770027) (xy 367.138988 -332.827916) (xy 367.14681 -332.887335)
			(xy 367.14681 -332.947265) (xy 367.138988 -333.006684) (xy 367.123478 -333.064573) (xy 367.100544 -333.119942)
			(xy 367.07058 -333.171845) (xy 367.034098 -333.219393) (xy 366.991723 -333.261772) (xy 366.944178 -333.298258)
			(xy 366.892278 -333.328226) (xy 366.836911 -333.351165) (xy 366.779023 -333.36668) (xy 366.719605 -333.374507)
			(xy 366.68964 -333.375) (xy 365.82604 -333.375) (xy 365.796069 -333.374549) (xy 365.736639 -333.36673)
			(xy 365.678737 -333.35122) (xy 365.623356 -333.328285) (xy 365.571443 -333.298317) (xy 365.523886 -333.261828)
			(xy 365.481498 -333.219445) (xy 365.445006 -333.17189) (xy 365.415033 -333.11998) (xy 365.392093 -333.0646)
			(xy 365.376578 -333.006701) (xy 365.368753 -332.947271) (xy 350.184974 -332.947271) (xy 350.184974 -337.580986)
			(xy 350.185481 -337.591036) (xy 350.193204 -337.609595) (xy 350.19996 -337.617054) (xy 350.409002 -337.826096)
			(xy 350.421702 -337.839812) (xy 350.42926 -337.847713) (xy 350.449135 -337.856775) (xy 350.460056 -337.857338)
		)
		(stroke
			(width 0)
			(type solid)
		)
		(fill yes)
		(layer "In2.Cu")
		(net "P0V8_SERDES_VDDA_PEX3")
	)
	(gr_poly
		(pts
			(xy 465.600034 -461.99552) (xy 465.655841 -461.994997) (xy 465.767141 -461.986654) (xy 465.877508 -461.970017)
			(xy 465.986322 -461.945179) (xy 466.092976 -461.912278) (xy 466.196873 -461.8715) (xy 466.297432 -461.823072)
			(xy 466.394091 -461.767264) (xy 466.48631 -461.70439) (xy 466.573572 -461.6348) (xy 466.65539 -461.558883)
			(xy 466.731306 -461.477065) (xy 466.800896 -461.389802) (xy 466.86377 -461.297583) (xy 466.919577 -461.200923)
			(xy 466.968004 -461.100364) (xy 467.008782 -460.996466) (xy 467.041681 -460.889812) (xy 467.066519 -460.780998)
			(xy 467.083155 -460.670631) (xy 467.091497 -460.559331) (xy 467.09203 -460.503524) (xy 467.09203 -422.58996)
			(xy 467.091507 -422.534153) (xy 467.083163 -422.422853) (xy 467.066526 -422.312487) (xy 467.041687 -422.203672)
			(xy 467.008787 -422.097019) (xy 466.968009 -421.993121) (xy 466.91958 -421.892562) (xy 466.863773 -421.795903)
			(xy 466.800898 -421.703684) (xy 466.731308 -421.616422) (xy 466.655392 -421.534604) (xy 466.573573 -421.458688)
			(xy 466.486311 -421.389098) (xy 466.394092 -421.326224) (xy 466.297433 -421.270417) (xy 466.196873 -421.221989)
			(xy 466.092976 -421.181211) (xy 465.986322 -421.148311) (xy 465.877508 -421.123473) (xy 465.767141 -421.106836)
			(xy 465.655841 -421.098493) (xy 465.600034 -421.097964) (xy 447.939922 -421.097964) (xy 447.884114 -421.098485)
			(xy 447.77281 -421.106824) (xy 447.66244 -421.123458) (xy 447.553622 -421.148293) (xy 447.446964 -421.181191)
			(xy 447.343062 -421.221967) (xy 447.242499 -421.270394) (xy 447.145835 -421.3262) (xy 447.053613 -421.389074)
			(xy 446.966346 -421.458664) (xy 446.884524 -421.53458) (xy 446.808604 -421.616399) (xy 446.739011 -421.703663)
			(xy 446.676133 -421.795883) (xy 446.620323 -421.892544) (xy 446.571892 -421.993106) (xy 446.531111 -422.097005)
			(xy 446.498209 -422.203662) (xy 446.47337 -422.312479) (xy 446.456731 -422.422848) (xy 446.448387 -422.534152)
			(xy 446.447926 -422.58996) (xy 446.447926 -429.090074) (xy 446.447433 -429.160429) (xy 446.439545 -429.300916)
			(xy 446.423792 -429.440741) (xy 446.400224 -429.579462) (xy 446.368915 -429.716643) (xy 446.329963 -429.851854)
			(xy 446.283491 -429.984667) (xy 446.229646 -430.114666) (xy 446.168596 -430.241441) (xy 446.100533 -430.364593)
			(xy 446.025673 -430.483736) (xy 445.94425 -430.598494) (xy 445.856521 -430.708505) (xy 445.762761 -430.813425)
			(xy 445.663266 -430.912922) (xy 445.558348 -431.006684) (xy 445.448338 -431.094416) (xy 445.333582 -431.175842)
			(xy 445.214442 -431.250705) (xy 445.091291 -431.31877) (xy 444.964517 -431.379823) (xy 444.834519 -431.433671)
			(xy 444.701707 -431.480146) (xy 444.566498 -431.519101) (xy 444.429317 -431.550413) (xy 444.290596 -431.573985)
			(xy 444.150772 -431.589741) (xy 444.010285 -431.597632) (xy 443.93993 -431.59807) (xy 371.24005 -431.59807)
			(xy 371.169695 -431.597587) (xy 371.029207 -431.5897) (xy 370.889383 -431.573948) (xy 370.750661 -431.550381)
			(xy 370.613479 -431.519072) (xy 370.478269 -431.480121) (xy 370.345455 -431.433649) (xy 370.215456 -431.379804)
			(xy 370.088681 -431.318754) (xy 369.965528 -431.250691) (xy 369.846385 -431.175831) (xy 369.731628 -431.094407)
			(xy 369.621616 -431.006677) (xy 369.516697 -430.912917) (xy 369.4172 -430.813421) (xy 369.323438 -430.708502)
			(xy 369.235707 -430.598492) (xy 369.154283 -430.483735) (xy 369.079421 -430.364593) (xy 369.011357 -430.241441)
			(xy 368.950306 -430.114666) (xy 368.896459 -429.984667) (xy 368.849986 -429.851854) (xy 368.811034 -429.716644)
			(xy 368.779724 -429.579463) (xy 368.756155 -429.440741) (xy 368.740402 -429.300917) (xy 368.732514 -429.160429)
			(xy 368.732054 -429.090074) (xy 368.732054 -422.58996) (xy 368.731543 -422.534154) (xy 368.7232 -422.422854)
			(xy 368.706562 -422.31249) (xy 368.681723 -422.203677) (xy 368.648822 -422.097024) (xy 368.608042 -421.993129)
			(xy 368.559613 -421.892571) (xy 368.503804 -421.795914) (xy 368.440929 -421.703697) (xy 368.371337 -421.616438)
			(xy 368.29542 -421.534622) (xy 368.2136 -421.458709) (xy 368.126337 -421.389123) (xy 368.034117 -421.326252)
			(xy 367.937456 -421.270449) (xy 367.836896 -421.222025) (xy 367.732998 -421.181251) (xy 367.626344 -421.148356)
			(xy 367.51753 -421.123523) (xy 367.407164 -421.106891) (xy 367.295864 -421.098554) (xy 367.240058 -421.097964)
			(xy 359.940098 -421.097964) (xy 359.88429 -421.098486) (xy 359.772988 -421.106827) (xy 359.662619 -421.123462)
			(xy 359.553802 -421.148298) (xy 359.447146 -421.181197) (xy 359.343246 -421.221974) (xy 359.242684 -421.270401)
			(xy 359.146022 -421.326208) (xy 359.053801 -421.389082) (xy 358.966536 -421.458672) (xy 358.884716 -421.534589)
			(xy 358.808797 -421.616407) (xy 358.739205 -421.70367) (xy 358.676328 -421.79589) (xy 358.620519 -421.892551)
			(xy 358.572089 -421.993111) (xy 358.53131 -422.09701) (xy 358.498408 -422.203666) (xy 358.473569 -422.312482)
			(xy 358.456931 -422.42285) (xy 358.448587 -422.534152) (xy 358.448102 -422.58996) (xy 358.448102 -429.090074)
			(xy 358.447618 -429.160429) (xy 358.43973 -429.300916) (xy 358.423977 -429.440741) (xy 358.400409 -429.579462)
			(xy 358.369099 -429.716643) (xy 358.330147 -429.851853) (xy 358.283675 -429.984667) (xy 358.229829 -430.114665)
			(xy 358.168779 -430.24144) (xy 358.100716 -430.364593) (xy 358.025856 -430.483735) (xy 357.944432 -430.598492)
			(xy 357.856702 -430.708504) (xy 357.762942 -430.813423) (xy 357.663446 -430.91292) (xy 357.558528 -431.006682)
			(xy 357.448518 -431.094413) (xy 357.333762 -431.175838) (xy 357.21462 -431.2507) (xy 357.091469 -431.318764)
			(xy 356.964695 -431.379816) (xy 356.834697 -431.433664) (xy 356.701884 -431.480138) (xy 356.566674 -431.519091)
			(xy 356.429493 -431.550403) (xy 356.290772 -431.573973) (xy 356.150948 -431.589728) (xy 356.010461 -431.597618)
			(xy 355.940106 -431.59807) (xy 283.239972 -431.59807) (xy 283.169619 -431.597576) (xy 283.029135 -431.589685)
			(xy 282.889313 -431.573929) (xy 282.750596 -431.550359) (xy 282.613418 -431.519047) (xy 282.478212 -431.480093)
			(xy 282.345402 -431.43362) (xy 282.215407 -431.379772) (xy 282.088636 -431.318721) (xy 281.965488 -431.250657)
			(xy 281.84635 -431.175796) (xy 281.731596 -431.094372) (xy 281.621589 -431.006642) (xy 281.516674 -430.912882)
			(xy 281.417181 -430.813387) (xy 281.323423 -430.70847) (xy 281.235695 -430.598461) (xy 281.154274 -430.483705)
			(xy 281.079415 -430.364565) (xy 281.011354 -430.241416) (xy 280.950306 -430.114643) (xy 280.896461 -429.984647)
			(xy 280.84999 -429.851837) (xy 280.811039 -429.71663) (xy 280.779731 -429.579451) (xy 280.756163 -429.440733)
			(xy 280.740411 -429.300912) (xy 280.732523 -429.160427) (xy 280.731976 -429.090074) (xy 280.731976 -422.58996)
			(xy 280.731453 -422.534154) (xy 280.723109 -422.422855) (xy 280.706471 -422.31249) (xy 280.681633 -422.203678)
			(xy 280.648732 -422.097025) (xy 280.607953 -421.99313) (xy 280.559525 -421.892573) (xy 280.503717 -421.795915)
			(xy 280.440842 -421.703699) (xy 280.371251 -421.616439) (xy 280.295334 -421.534623) (xy 280.213516 -421.45871)
			(xy 280.126253 -421.389123) (xy 280.034034 -421.326251) (xy 279.937374 -421.270447) (xy 279.836815 -421.222023)
			(xy 279.732918 -421.181248) (xy 279.626264 -421.148352) (xy 279.517451 -421.123517) (xy 279.407085 -421.106884)
			(xy 279.295786 -421.098545) (xy 279.23998 -421.097964) (xy 276.880066 -421.097964) (xy 276.824259 -421.098487)
			(xy 276.712958 -421.10683) (xy 276.602591 -421.123467) (xy 276.493777 -421.148305) (xy 276.387122 -421.181205)
			(xy 276.283225 -421.221984) (xy 276.182665 -421.270412) (xy 276.086005 -421.326219) (xy 275.993786 -421.389094)
			(xy 275.906523 -421.458684) (xy 275.824704 -421.5346) (xy 275.748787 -421.616418) (xy 275.679197 -421.703681)
			(xy 275.616322 -421.7959) (xy 275.560514 -421.892559) (xy 275.512086 -421.993119) (xy 275.471307 -422.097017)
			(xy 275.438407 -422.203671) (xy 275.413568 -422.312485) (xy 275.396931 -422.422852) (xy 275.388587 -422.534153)
			(xy 275.38807 -422.58996) (xy 275.38807 -430.55794) (xy 275.387576 -430.628293) (xy 275.379684 -430.768777)
			(xy 275.363928 -430.908597) (xy 275.340357 -431.047314) (xy 275.309045 -431.184492) (xy 275.27009 -431.319698)
			(xy 275.223616 -431.452506) (xy 275.169769 -431.582501) (xy 275.108717 -431.709271) (xy 275.040653 -431.832419)
			(xy 274.965792 -431.951557) (xy 274.884368 -432.066309) (xy 274.796638 -432.176316) (xy 274.702878 -432.281231)
			(xy 274.603383 -432.380723) (xy 274.498466 -432.474481) (xy 274.388457 -432.562208) (xy 274.273702 -432.643629)
			(xy 274.154562 -432.718487) (xy 274.031412 -432.786547) (xy 273.90464 -432.847596) (xy 273.774645 -432.90144)
			(xy 273.641835 -432.94791) (xy 273.506628 -432.986861) (xy 273.36945 -433.018169) (xy 273.230732 -433.041737)
			(xy 273.090911 -433.05749) (xy 272.950427 -433.065377) (xy 272.880074 -433.065936) (xy 202.360022 -433.065936)
			(xy 202.289667 -433.065443) (xy 202.14918 -433.057555) (xy 202.009355 -433.041802) (xy 201.870634 -433.018234)
			(xy 201.733452 -432.986924) (xy 201.598242 -432.947972) (xy 201.465429 -432.9015) (xy 201.33543 -432.847655)
			(xy 201.208655 -432.786605) (xy 201.085502 -432.718542) (xy 200.96636 -432.643682) (xy 200.851602 -432.562259)
			(xy 200.74159 -432.47453) (xy 200.63667 -432.38077) (xy 200.537173 -432.281275) (xy 200.44341 -432.176357)
			(xy 200.355678 -432.066348) (xy 200.274252 -431.951592) (xy 200.199389 -431.832451) (xy 200.131324 -431.7093)
			(xy 200.070271 -431.582527) (xy 200.016422 -431.452529) (xy 199.969947 -431.319717) (xy 199.930991 -431.184508)
			(xy 199.899679 -431.047327) (xy 199.876107 -430.908606) (xy 199.86035 -430.768782) (xy 199.852458 -430.628295)
			(xy 199.852026 -430.55794) (xy 199.852026 -422.58996) (xy 199.851503 -422.534154) (xy 199.843159 -422.422853)
			(xy 199.826522 -422.312487) (xy 199.801683 -422.203673) (xy 199.768783 -422.097019) (xy 199.728004 -421.993122)
			(xy 199.679576 -421.892563) (xy 199.623769 -421.795904) (xy 199.560894 -421.703685) (xy 199.491304 -421.616423)
			(xy 199.415387 -421.534606) (xy 199.333569 -421.45869) (xy 199.246306 -421.3891) (xy 199.154088 -421.326226)
			(xy 199.057428 -421.270419) (xy 198.956869 -421.221992) (xy 198.852972 -421.181214) (xy 198.746318 -421.148314)
			(xy 198.637503 -421.123476) (xy 198.527137 -421.10684) (xy 198.415836 -421.098497) (xy 198.36003 -421.097964)
			(xy 188.36005 -421.097964) (xy 188.304244 -421.098488) (xy 188.192943 -421.106832) (xy 188.082578 -421.12347)
			(xy 187.973764 -421.148309) (xy 187.86711 -421.18121) (xy 187.763214 -421.221988) (xy 187.662655 -421.270417)
			(xy 187.565996 -421.326225) (xy 187.473778 -421.389099) (xy 187.386516 -421.458689) (xy 187.304699 -421.534606)
			(xy 187.228783 -421.616424) (xy 187.159193 -421.703686) (xy 187.096319 -421.795905) (xy 187.040512 -421.892564)
			(xy 186.992084 -421.993123) (xy 186.951306 -422.09702) (xy 186.918406 -422.203673) (xy 186.893568 -422.312487)
			(xy 186.876931 -422.422853) (xy 186.868587 -422.534154) (xy 186.868054 -422.58996) (xy 186.868054 -429.090074)
			(xy 186.86757 -429.160428) (xy 186.859682 -429.300915) (xy 186.843929 -429.440738) (xy 186.820361 -429.579458)
			(xy 186.789051 -429.716639) (xy 186.750099 -429.851848) (xy 186.703626 -429.98466) (xy 186.64978 -430.114658)
			(xy 186.58873 -430.241431) (xy 186.520667 -430.364582) (xy 186.445806 -430.483723) (xy 186.364382 -430.598479)
			(xy 186.276652 -430.708489) (xy 186.182891 -430.813407) (xy 186.083395 -430.912902) (xy 185.978477 -431.006662)
			(xy 185.868467 -431.094392) (xy 185.75371 -431.175815) (xy 185.634569 -431.250675) (xy 185.511417 -431.318737)
			(xy 185.384643 -431.379787) (xy 185.254645 -431.433632) (xy 185.121833 -431.480104) (xy 184.986623 -431.519055)
			(xy 184.849443 -431.550364) (xy 184.710722 -431.573931) (xy 184.570899 -431.589684) (xy 184.430412 -431.597571)
			(xy 184.360058 -431.59807) (xy 111.660178 -431.59807) (xy 111.589825 -431.597585) (xy 111.449339 -431.589694)
			(xy 111.309518 -431.573939) (xy 111.170799 -431.550369) (xy 111.033621 -431.519057) (xy 110.898414 -431.480103)
			(xy 110.765603 -431.43363) (xy 110.635608 -431.379782) (xy 110.508836 -431.318731) (xy 110.385687 -431.250667)
			(xy 110.266548 -431.175806) (xy 110.151794 -431.094382) (xy 110.041786 -431.006651) (xy 109.93687 -430.912891)
			(xy 109.837376 -430.813395) (xy 109.743618 -430.708478) (xy 109.65589 -430.598468) (xy 109.574468 -430.483712)
			(xy 109.499608 -430.364572) (xy 109.431547 -430.241421) (xy 109.370498 -430.114648) (xy 109.316653 -429.984652)
			(xy 109.270182 -429.851841) (xy 109.231231 -429.716633) (xy 109.199922 -429.579454) (xy 109.176354 -429.440735)
			(xy 109.160602 -429.300913) (xy 109.152714 -429.160427) (xy 109.152182 -429.090074) (xy 109.152182 -422.58996)
			(xy 109.151659 -422.534154) (xy 109.143315 -422.422855) (xy 109.126678 -422.31249) (xy 109.101839 -422.203677)
			(xy 109.068938 -422.097025) (xy 109.02816 -421.993129) (xy 108.979731 -421.892571) (xy 108.923923 -421.795914)
			(xy 108.861048 -421.703697) (xy 108.791457 -421.616437) (xy 108.715541 -421.534621) (xy 108.633722 -421.458707)
			(xy 108.546459 -421.38912) (xy 108.45424 -421.326248) (xy 108.357581 -421.270444) (xy 108.257021 -421.222019)
			(xy 108.153124 -421.181244) (xy 108.046471 -421.148347) (xy 107.937657 -421.123512) (xy 107.827292 -421.106879)
			(xy 107.715992 -421.098539) (xy 107.660186 -421.097964) (xy 100.359972 -421.097964) (xy 100.304165 -421.098487)
			(xy 100.192864 -421.106829) (xy 100.082497 -421.123466) (xy 99.973681 -421.148304) (xy 99.867027 -421.181204)
			(xy 99.763129 -421.221982) (xy 99.662568 -421.27041) (xy 99.565908 -421.326217) (xy 99.473689 -421.389091)
			(xy 99.386425 -421.458681) (xy 99.304606 -421.534598) (xy 99.228689 -421.616416) (xy 99.159099 -421.703679)
			(xy 99.096223 -421.795898) (xy 99.040415 -421.892558) (xy 98.991987 -421.993118) (xy 98.951208 -422.097015)
			(xy 98.918307 -422.20367) (xy 98.893468 -422.312485) (xy 98.876831 -422.422852) (xy 98.868487 -422.534153)
			(xy 98.867976 -422.58996) (xy 98.867976 -429.090074) (xy 98.867492 -429.160428) (xy 98.859604 -429.300915)
			(xy 98.843851 -429.440739) (xy 98.820283 -429.57946) (xy 98.788973 -429.716641) (xy 98.750021 -429.85185)
			(xy 98.703549 -429.984663) (xy 98.649703 -430.114661) (xy 98.588652 -430.241435) (xy 98.520589 -430.364587)
			(xy 98.445729 -430.483729) (xy 98.364305 -430.598485) (xy 98.276575 -430.708496) (xy 98.182814 -430.813414)
			(xy 98.083319 -430.91291) (xy 97.9784 -431.006671) (xy 97.86839 -431.094401) (xy 97.753634 -431.175825)
			(xy 97.634492 -431.250686) (xy 97.511341 -431.31875) (xy 97.384567 -431.3798) (xy 97.254569 -431.433647)
			(xy 97.121756 -431.480119) (xy 96.986547 -431.519072) (xy 96.849366 -431.550382) (xy 96.710645 -431.57395)
			(xy 96.570821 -431.589704) (xy 96.430334 -431.597592) (xy 96.35998 -431.59807) (xy 23.6601 -431.59807)
			(xy 23.589746 -431.597586) (xy 23.44926 -431.589696) (xy 23.309437 -431.573942) (xy 23.170718 -431.550372)
			(xy 23.033539 -431.519062) (xy 22.89833 -431.480109) (xy 22.765519 -431.433636) (xy 22.635522 -431.379789)
			(xy 22.50875 -431.318738) (xy 22.385599 -431.250675) (xy 22.266459 -431.175813) (xy 22.151704 -431.094389)
			(xy 22.041695 -431.006659) (xy 21.936778 -430.912899) (xy 21.837283 -430.813403) (xy 21.743524 -430.708485)
			(xy 21.655795 -430.598475) (xy 21.574372 -430.483719) (xy 21.499512 -430.364578) (xy 21.43145 -430.241427)
			(xy 21.370401 -430.114654) (xy 21.316555 -429.984657) (xy 21.270083 -429.851845) (xy 21.231132 -429.716636)
			(xy 21.199823 -429.579456) (xy 21.176255 -429.440737) (xy 21.160502 -429.300914) (xy 21.152614 -429.160428)
			(xy 21.152104 -429.090074) (xy 21.152104 -422.58996) (xy 21.151595 -422.534153) (xy 21.143254 -422.42285)
			(xy 21.126618 -422.312481) (xy 21.101782 -422.203665) (xy 21.068883 -422.097009) (xy 21.028105 -421.993109)
			(xy 20.979677 -421.892548) (xy 20.92387 -421.795886) (xy 20.860995 -421.703666) (xy 20.791404 -421.616402)
			(xy 20.715486 -421.534582) (xy 20.633667 -421.458665) (xy 20.546403 -421.389074) (xy 20.454182 -421.326199)
			(xy 20.357521 -421.270392) (xy 20.256959 -421.221964) (xy 20.153059 -421.181187) (xy 20.046403 -421.148288)
			(xy 19.937587 -421.123451) (xy 19.827218 -421.106816) (xy 19.715915 -421.098475) (xy 19.660108 -421.097964)
			(xy 1.999996 -421.097964) (xy 1.944189 -421.098486) (xy 1.832887 -421.106827) (xy 1.72252 -421.123463)
			(xy 1.613705 -421.148299) (xy 1.50705 -421.181198) (xy 1.403151 -421.221976) (xy 1.302591 -421.270403)
			(xy 1.20593 -421.32621) (xy 1.113711 -421.389085) (xy 1.026448 -421.458675) (xy 0.944629 -421.534592)
			(xy 0.868712 -421.616411) (xy 0.799122 -421.703674) (xy 0.736248 -421.795894) (xy 0.680441 -421.892554)
			(xy 0.632014 -421.993115) (xy 0.591237 -422.097013) (xy 0.558338 -422.203669) (xy 0.533502 -422.312484)
			(xy 0.516867 -422.422851) (xy 0.508526 -422.534153) (xy 0.508 -422.58996) (xy 0.508 -457.5681) (xy 2.904225 -457.5681)
			(xy 2.904225 -457.43896) (xy 2.912175 -457.310065) (xy 2.928045 -457.181905) (xy 2.951774 -457.054964)
			(xy 2.983273 -456.929725) (xy 3.022422 -456.806662) (xy 3.069073 -456.686243) (xy 3.123048 -456.568924)
			(xy 3.184143 -456.45515) (xy 3.252126 -456.345353) (xy 3.32674 -456.23995) (xy 3.407701 -456.13934)
			(xy 3.494701 -456.043905) (xy 3.587412 -455.954006) (xy 3.685482 -455.869985) (xy 3.788537 -455.792161)
			(xy 3.896188 -455.720829) (xy 4.008027 -455.656259) (xy 4.123628 -455.598697) (xy 4.242553 -455.54836)
			(xy 4.364352 -455.50544) (xy 4.488562 -455.470099) (xy 4.614711 -455.442472) (xy 4.742323 -455.422663)
			(xy 4.870912 -455.410747) (xy 4.99999 -455.406771) (xy 5.129068 -455.410747) (xy 5.257657 -455.422663)
			(xy 5.385269 -455.442472) (xy 5.511418 -455.470099) (xy 5.635628 -455.50544) (xy 5.757427 -455.54836)
			(xy 5.876352 -455.598697) (xy 5.991953 -455.656259) (xy 6.103792 -455.720829) (xy 6.211443 -455.792161)
			(xy 6.314498 -455.869985) (xy 6.412568 -455.954006) (xy 6.505279 -456.043905) (xy 6.592279 -456.13934)
			(xy 6.67324 -456.23995) (xy 6.747854 -456.345353) (xy 6.815837 -456.45515) (xy 6.876932 -456.568924)
			(xy 6.930907 -456.686243) (xy 6.977558 -456.806662) (xy 7.016707 -456.929725) (xy 7.048206 -457.054964)
			(xy 7.071935 -457.181905) (xy 7.087805 -457.310065) (xy 7.095755 -457.43896) (xy 7.096252 -457.50353)
			(xy 7.095755 -457.5681) (xy 460.504275 -457.5681) (xy 460.504275 -457.43896) (xy 460.512225 -457.310065)
			(xy 460.528095 -457.181905) (xy 460.551824 -457.054964) (xy 460.583323 -456.929725) (xy 460.622472 -456.806662)
			(xy 460.669123 -456.686243) (xy 460.723098 -456.568924) (xy 460.784193 -456.45515) (xy 460.852176 -456.345353)
			(xy 460.92679 -456.23995) (xy 461.007751 -456.13934) (xy 461.094751 -456.043905) (xy 461.187462 -455.954006)
			(xy 461.285532 -455.869985) (xy 461.388587 -455.792161) (xy 461.496238 -455.720829) (xy 461.608077 -455.656259)
			(xy 461.723678 -455.598697) (xy 461.842603 -455.54836) (xy 461.964402 -455.50544) (xy 462.088612 -455.470099)
			(xy 462.214761 -455.442472) (xy 462.342373 -455.422663) (xy 462.470962 -455.410747) (xy 462.60004 -455.406771)
			(xy 462.729118 -455.410747) (xy 462.857707 -455.422663) (xy 462.985319 -455.442472) (xy 463.111468 -455.470099)
			(xy 463.235678 -455.50544) (xy 463.357477 -455.54836) (xy 463.476402 -455.598697) (xy 463.592003 -455.656259)
			(xy 463.703842 -455.720829) (xy 463.811493 -455.792161) (xy 463.914548 -455.869985) (xy 464.012618 -455.954006)
			(xy 464.105329 -456.043905) (xy 464.192329 -456.13934) (xy 464.27329 -456.23995) (xy 464.347904 -456.345353)
			(xy 464.415887 -456.45515) (xy 464.476982 -456.568924) (xy 464.530957 -456.686243) (xy 464.577608 -456.806662)
			(xy 464.616757 -456.929725) (xy 464.648256 -457.054964) (xy 464.671985 -457.181905) (xy 464.687855 -457.310065)
			(xy 464.695805 -457.43896) (xy 464.696302 -457.50353) (xy 464.695805 -457.5681) (xy 464.687855 -457.696995)
			(xy 464.671985 -457.825155) (xy 464.648256 -457.952096) (xy 464.616757 -458.077335) (xy 464.577608 -458.200398)
			(xy 464.530957 -458.320817) (xy 464.476982 -458.438136) (xy 464.415887 -458.55191) (xy 464.347904 -458.661707)
			(xy 464.27329 -458.76711) (xy 464.192329 -458.86772) (xy 464.105329 -458.963155) (xy 464.012618 -459.053054)
			(xy 463.914548 -459.137075) (xy 463.811493 -459.214899) (xy 463.703842 -459.286231) (xy 463.592003 -459.350801)
			(xy 463.476402 -459.408363) (xy 463.357477 -459.4587) (xy 463.235678 -459.50162) (xy 463.111468 -459.536961)
			(xy 462.985319 -459.564588) (xy 462.857707 -459.584397) (xy 462.729118 -459.596313) (xy 462.60004 -459.60029)
			(xy 462.470962 -459.596313) (xy 462.342373 -459.584397) (xy 462.214761 -459.564588) (xy 462.088612 -459.536961)
			(xy 461.964402 -459.50162) (xy 461.842603 -459.4587) (xy 461.723678 -459.408363) (xy 461.608077 -459.350801)
			(xy 461.496238 -459.286231) (xy 461.388587 -459.214899) (xy 461.285532 -459.137075) (xy 461.187462 -459.053054)
			(xy 461.094751 -458.963155) (xy 461.007751 -458.86772) (xy 460.92679 -458.76711) (xy 460.852176 -458.661707)
			(xy 460.784193 -458.55191) (xy 460.723098 -458.438136) (xy 460.669123 -458.320817) (xy 460.622472 -458.200398)
			(xy 460.583323 -458.077335) (xy 460.551824 -457.952096) (xy 460.528095 -457.825155) (xy 460.512225 -457.696995)
			(xy 460.504275 -457.5681) (xy 7.095755 -457.5681) (xy 7.087805 -457.696995) (xy 7.071935 -457.825155)
			(xy 7.048206 -457.952096) (xy 7.016707 -458.077335) (xy 6.977558 -458.200398) (xy 6.930907 -458.320817)
			(xy 6.876932 -458.438136) (xy 6.815837 -458.55191) (xy 6.747854 -458.661707) (xy 6.67324 -458.76711)
			(xy 6.592279 -458.86772) (xy 6.505279 -458.963155) (xy 6.412568 -459.053054) (xy 6.314498 -459.137075)
			(xy 6.211443 -459.214899) (xy 6.103792 -459.286231) (xy 5.991953 -459.350801) (xy 5.876352 -459.408363)
			(xy 5.757427 -459.4587) (xy 5.635628 -459.50162) (xy 5.511418 -459.536961) (xy 5.385269 -459.564588)
			(xy 5.257657 -459.584397) (xy 5.129068 -459.596313) (xy 4.99999 -459.60029) (xy 4.870912 -459.596313)
			(xy 4.742323 -459.584397) (xy 4.614711 -459.564588) (xy 4.488562 -459.536961) (xy 4.364352 -459.50162)
			(xy 4.242553 -459.4587) (xy 4.123628 -459.408363) (xy 4.008027 -459.350801) (xy 3.896188 -459.286231)
			(xy 3.788537 -459.214899) (xy 3.685482 -459.137075) (xy 3.587412 -459.053054) (xy 3.494701 -458.963155)
			(xy 3.407701 -458.86772) (xy 3.32674 -458.76711) (xy 3.252126 -458.661707) (xy 3.184143 -458.55191)
			(xy 3.123048 -458.438136) (xy 3.069073 -458.320817) (xy 3.022422 -458.200398) (xy 2.983273 -458.077335)
			(xy 2.951774 -457.952096) (xy 2.928045 -457.825155) (xy 2.912175 -457.696995) (xy 2.904225 -457.5681)
			(xy 0.508 -457.5681) (xy 0.508 -460.503524) (xy 0.508522 -460.559331) (xy 0.516863 -460.670633) (xy 0.533498 -460.781)
			(xy 0.558335 -460.889816) (xy 0.591234 -460.996471) (xy 0.632011 -461.10037) (xy 0.680438 -461.20093)
			(xy 0.736246 -461.297591) (xy 0.79912 -461.389811) (xy 0.86871 -461.477074) (xy 0.944627 -461.558893)
			(xy 1.026446 -461.63481) (xy 1.113709 -461.7044) (xy 1.205929 -461.767274) (xy 1.30259 -461.823082)
			(xy 1.40315 -461.871509) (xy 1.507049 -461.912286) (xy 1.613704 -461.945185) (xy 1.72252 -461.970022)
			(xy 1.832887 -461.986657) (xy 1.944189 -461.994998) (xy 1.999996 -461.99552)
		)
		(stroke
			(width 0)
			(type solid)
		)
		(fill yes)
		(layer "In2.Cu")
		(net "COUPON_GND1")
	)
	(gr_poly
		(pts
			(xy 349.494348 -337.850226) (xy 349.661988 -337.682586) (xy 349.668833 -337.675187) (xy 349.676565 -337.656589)
			(xy 349.676974 -337.646518) (xy 349.676974 -326.560942) (xy 349.67672 -326.550782) (xy 349.67672 -318.922908)
			(xy 349.676395 -318.914361) (xy 349.670771 -318.898218) (xy 349.660148 -318.884825) (xy 349.653098 -318.879982)
			(xy 349.630156 -318.864917) (xy 349.588447 -318.829244) (xy 349.552283 -318.787959) (xy 349.522414 -318.741915)
			(xy 349.499455 -318.692064) (xy 349.483881 -318.639436) (xy 349.476015 -318.585118) (xy 349.476018 -318.530235)
			(xy 349.483891 -318.475918) (xy 349.499471 -318.423292) (xy 349.522436 -318.373444) (xy 349.552312 -318.327404)
			(xy 349.58848 -318.286123) (xy 349.630194 -318.250456) (xy 349.653098 -318.23533) (xy 349.660143 -318.230481)
			(xy 349.670767 -318.217091) (xy 349.676394 -318.20095) (xy 349.67672 -318.192404) (xy 349.67672 -318.058292)
			(xy 349.676393 -318.049746) (xy 349.670765 -318.033607) (xy 349.660141 -318.020218) (xy 349.653098 -318.015366)
			(xy 349.63015 -318.0003) (xy 349.588429 -317.964626) (xy 349.552254 -317.923337) (xy 349.522373 -317.877288)
			(xy 349.499404 -317.827431) (xy 349.483821 -317.774795) (xy 349.475947 -317.720468) (xy 349.475944 -317.665574)
			(xy 349.483812 -317.611247) (xy 349.499389 -317.558609) (xy 349.522352 -317.508749) (xy 349.552228 -317.462697)
			(xy 349.588398 -317.421404) (xy 349.630116 -317.385725) (xy 349.653098 -317.370714) (xy 349.660141 -317.365864)
			(xy 349.670761 -317.352473) (xy 349.676383 -317.336333) (xy 349.67672 -317.327788) (xy 349.67672 -316.355222)
			(xy 349.676397 -316.346673) (xy 349.670777 -316.330527) (xy 349.660155 -316.31713) (xy 349.653098 -316.312296)
			(xy 349.630155 -316.29723) (xy 349.588444 -316.261557) (xy 349.552279 -316.220272) (xy 349.522407 -316.174227)
			(xy 349.499446 -316.124375) (xy 349.483871 -316.071746) (xy 349.476003 -316.017427) (xy 349.476006 -315.962541)
			(xy 349.483878 -315.908223) (xy 349.499457 -315.855595) (xy 349.522422 -315.805745) (xy 349.552298 -315.759703)
			(xy 349.588467 -315.71842) (xy 349.630181 -315.68275) (xy 349.653098 -315.667644) (xy 349.660144 -315.662795)
			(xy 349.670772 -315.649406) (xy 349.676403 -315.633265) (xy 349.67672 -315.624718) (xy 349.67672 -295.255442)
			(xy 349.654622 -295.227756) (xy 349.63735 -295.223692) (xy 349.609668 -295.216792) (xy 349.556588 -295.19589)
			(xy 349.507212 -295.167316) (xy 349.462643 -295.131708) (xy 349.423873 -295.089859) (xy 349.391767 -295.042704)
			(xy 349.367043 -294.991292) (xy 349.35025 -294.936773) (xy 349.341764 -294.88036) (xy 349.341186 -294.851836)
			(xy 349.341764 -294.8226) (xy 349.350719 -294.764818) (xy 349.36838 -294.709076) (xy 349.394333 -294.656679)
			(xy 349.427972 -294.608852) (xy 349.447866 -294.587422) (xy 349.454724 -294.580056) (xy 349.46209 -294.561768)
			(xy 349.461328 -294.480488) (xy 349.46076 -294.470564) (xy 349.453051 -294.452262) (xy 349.446342 -294.444928)
			(xy 349.444564 -294.44315) (xy 349.437166 -294.436304) (xy 349.418567 -294.428575) (xy 349.408496 -294.428164)
			(xy 343.506806 -294.428164) (xy 343.496385 -294.428673) (xy 343.477249 -294.436939) (xy 343.469722 -294.444166)
			(xy 343.449948 -294.464436) (xy 343.405481 -294.499495) (xy 343.35632 -294.527595) (xy 343.303545 -294.54812)
			(xy 343.248316 -294.560618) (xy 343.191846 -294.564815) (xy 343.135376 -294.560618) (xy 343.080147 -294.54812)
			(xy 343.027372 -294.527595) (xy 342.978211 -294.499495) (xy 342.933744 -294.464436) (xy 342.91397 -294.444166)
			(xy 342.906468 -294.436905) (xy 342.887316 -294.42865) (xy 342.876886 -294.428164) (xy 333.06385 -294.428164)
			(xy 333.038892 -294.427588) (xy 332.989936 -294.417839) (xy 332.943823 -294.398727) (xy 332.902325 -294.370985)
			(xy 332.884272 -294.353742) (xy 332.272894 -293.742364) (xy 332.255632 -293.724324) (xy 332.227869 -293.682832)
			(xy 332.208751 -293.636713) (xy 332.199016 -293.587748) (xy 332.198472 -293.562786) (xy 332.198472 -293.219378)
			(xy 332.197958 -293.20793) (xy 332.188054 -293.187289) (xy 332.179422 -293.179754) (xy 332.10881 -293.122858)
			(xy 332.086458 -293.117524) (xy 332.075028 -293.120064) (xy 331.985694 -293.139067) (xy 331.805431 -293.168577)
			(xy 331.623837 -293.188304) (xy 331.441443 -293.19819) (xy 331.350112 -293.198804) (xy 331.268458 -293.198319)
			(xy 331.105339 -293.190429) (xy 330.942793 -293.174668) (xy 330.781198 -293.151072) (xy 330.620931 -293.119697)
			(xy 330.462368 -293.080615) (xy 330.305877 -293.033918) (xy 330.151826 -292.979715) (xy 330.000573 -292.918132)
			(xy 329.852473 -292.849314) (xy 329.70787 -292.773421) (xy 329.567102 -292.69063) (xy 329.430499 -292.601135)
			(xy 329.298379 -292.505145) (xy 329.171051 -292.402884) (xy 329.048812 -292.29459) (xy 328.931949 -292.180517)
			(xy 328.820732 -292.060932) (xy 328.715424 -291.936112) (xy 328.616269 -291.806351) (xy 328.523498 -291.67195)
			(xy 328.43733 -291.533225) (xy 328.357964 -291.390498) (xy 328.285587 -291.244104) (xy 328.220367 -291.094384)
			(xy 328.162457 -290.941687) (xy 328.111992 -290.786371) (xy 328.069089 -290.628798) (xy 328.033849 -290.469337)
			(xy 328.006355 -290.308359) (xy 327.98667 -290.146241) (xy 327.974841 -289.983361) (xy 327.970895 -289.8201)
			(xy 327.974841 -289.656839) (xy 327.98667 -289.493959) (xy 328.006355 -289.331841) (xy 328.033849 -289.170863)
			(xy 328.069089 -289.011402) (xy 328.111992 -288.853829) (xy 328.162457 -288.698513) (xy 328.220367 -288.545816)
			(xy 328.285587 -288.396096) (xy 328.357964 -288.249702) (xy 328.43733 -288.106975) (xy 328.523498 -287.96825)
			(xy 328.616269 -287.833849) (xy 328.715424 -287.704088) (xy 328.820732 -287.579268) (xy 328.931949 -287.459683)
			(xy 329.048812 -287.34561) (xy 329.171051 -287.237316) (xy 329.298379 -287.135055) (xy 329.430499 -287.039065)
			(xy 329.567102 -286.94957) (xy 329.70787 -286.866779) (xy 329.852473 -286.790886) (xy 330.000573 -286.722068)
			(xy 330.151826 -286.660485) (xy 330.305877 -286.606282) (xy 330.462368 -286.559585) (xy 330.620931 -286.520503)
			(xy 330.781198 -286.489128) (xy 330.942793 -286.465532) (xy 331.105339 -286.449771) (xy 331.268458 -286.441881)
			(xy 331.350112 -286.441388) (xy 331.441443 -286.442009) (xy 331.623838 -286.45189) (xy 331.805432 -286.471613)
			(xy 331.985695 -286.501119) (xy 332.075028 -286.520128) (xy 332.086458 -286.522668) (xy 332.10881 -286.517334)
			(xy 332.179422 -286.460438) (xy 332.187945 -286.452811) (xy 332.197857 -286.432233) (xy 332.198472 -286.420814)
			(xy 332.198472 -286.227774) (xy 332.198047 -286.217758) (xy 332.190372 -286.199255) (xy 332.1762 -286.185098)
			(xy 332.157688 -286.177442) (xy 332.147672 -286.176974) (xy 332.144878 -286.176974) (xy 332.142084 -286.177228)
			(xy 332.114906 -286.178752) (xy 303.00422 -286.178752) (xy 302.996025 -286.179057) (xy 302.980472 -286.184231)
			(xy 302.97374 -286.188912) (xy 302.952115 -286.204569) (xy 302.90487 -286.229427) (xy 302.854243 -286.246368)
			(xy 302.801551 -286.25495) (xy 302.748165 -286.25495) (xy 302.695473 -286.246368) (xy 302.644846 -286.229427)
			(xy 302.597601 -286.204569) (xy 302.575976 -286.188912) (xy 302.569234 -286.184247) (xy 302.553688 -286.179072)
			(xy 302.545496 -286.178752) (xy 302.05426 -286.178752) (xy 302.046068 -286.179067) (xy 302.030527 -286.184254)
			(xy 302.02378 -286.188912) (xy 302.002155 -286.204569) (xy 301.95491 -286.229427) (xy 301.904283 -286.246368)
			(xy 301.851591 -286.25495) (xy 301.798205 -286.25495) (xy 301.745513 -286.246368) (xy 301.694886 -286.229427)
			(xy 301.647641 -286.204569) (xy 301.626016 -286.188912) (xy 301.619276 -286.184242) (xy 301.60373 -286.179054)
			(xy 301.595536 -286.178752) (xy 301.104046 -286.178752) (xy 301.095849 -286.179053) (xy 301.080292 -286.18422)
			(xy 301.073566 -286.188912) (xy 301.051941 -286.204569) (xy 301.004696 -286.229427) (xy 300.954069 -286.246368)
			(xy 300.901377 -286.25495) (xy 300.847991 -286.25495) (xy 300.795299 -286.246368) (xy 300.744672 -286.229427)
			(xy 300.697427 -286.204569) (xy 300.675802 -286.188912) (xy 300.669061 -286.184244) (xy 300.653515 -286.17906)
			(xy 300.645322 -286.178752) (xy 300.154086 -286.178752) (xy 300.145893 -286.179063) (xy 300.130347 -286.184244)
			(xy 300.123606 -286.188912) (xy 300.101981 -286.204569) (xy 300.054736 -286.229427) (xy 300.004109 -286.246368)
			(xy 299.951417 -286.25495) (xy 299.898031 -286.25495) (xy 299.845339 -286.246368) (xy 299.794712 -286.229427)
			(xy 299.747467 -286.204569) (xy 299.725842 -286.188912) (xy 299.719099 -286.184252) (xy 299.703553 -286.179087)
			(xy 299.695362 -286.178752) (xy 299.204126 -286.178752) (xy 299.19593 -286.179056) (xy 299.180377 -286.184228)
			(xy 299.173646 -286.188912) (xy 299.152021 -286.204569) (xy 299.104776 -286.229427) (xy 299.054149 -286.246368)
			(xy 299.001457 -286.25495) (xy 298.948071 -286.25495) (xy 298.895379 -286.246368) (xy 298.844752 -286.229427)
			(xy 298.797507 -286.204569) (xy 298.775882 -286.188912) (xy 298.76914 -286.184247) (xy 298.753595 -286.179069)
			(xy 298.745402 -286.178752) (xy 298.254166 -286.178752) (xy 298.245974 -286.179066) (xy 298.230431 -286.184252)
			(xy 298.223686 -286.188912) (xy 298.202061 -286.204569) (xy 298.154816 -286.229427) (xy 298.104189 -286.246368)
			(xy 298.051497 -286.25495) (xy 297.998111 -286.25495) (xy 297.945419 -286.246368) (xy 297.894792 -286.229427)
			(xy 297.847547 -286.204569) (xy 297.825922 -286.188912) (xy 297.819182 -286.184241) (xy 297.803636 -286.179052)
			(xy 297.795442 -286.178752) (xy 297.304206 -286.178752) (xy 297.296012 -286.17906) (xy 297.280462 -286.184236)
			(xy 297.273726 -286.188912) (xy 297.252101 -286.204569) (xy 297.204856 -286.229427) (xy 297.154229 -286.246368)
			(xy 297.101537 -286.25495) (xy 297.048151 -286.25495) (xy 296.995459 -286.246368) (xy 296.944832 -286.229427)
			(xy 296.897587 -286.204569) (xy 296.875962 -286.188912) (xy 296.86922 -286.184249) (xy 296.853674 -286.179078)
			(xy 296.845482 -286.178752) (xy 296.354246 -286.178752) (xy 296.346049 -286.179053) (xy 296.330492 -286.18422)
			(xy 296.323766 -286.188912) (xy 296.302141 -286.204569) (xy 296.254896 -286.229427) (xy 296.204269 -286.246368)
			(xy 296.151577 -286.25495) (xy 296.098191 -286.25495) (xy 296.045499 -286.246368) (xy 295.994872 -286.229427)
			(xy 295.947627 -286.204569) (xy 295.926002 -286.188912) (xy 295.919261 -286.184244) (xy 295.903715 -286.17906)
			(xy 295.895522 -286.178752) (xy 295.404286 -286.178752) (xy 295.396093 -286.179063) (xy 295.380547 -286.184244)
			(xy 295.373806 -286.188912) (xy 295.352181 -286.204569) (xy 295.304936 -286.229427) (xy 295.254309 -286.246368)
			(xy 295.201617 -286.25495) (xy 295.148231 -286.25495) (xy 295.095539 -286.246368) (xy 295.044912 -286.229427)
			(xy 294.997667 -286.204569) (xy 294.976042 -286.188912) (xy 294.969299 -286.184252) (xy 294.953753 -286.179087)
			(xy 294.945562 -286.178752) (xy 294.454072 -286.178752) (xy 294.445879 -286.179065) (xy 294.430336 -286.18425)
			(xy 294.423592 -286.188912) (xy 294.401967 -286.204569) (xy 294.354722 -286.229427) (xy 294.304095 -286.246368)
			(xy 294.251403 -286.25495) (xy 294.198017 -286.25495) (xy 294.145325 -286.246368) (xy 294.094698 -286.229427)
			(xy 294.047453 -286.204569) (xy 294.025828 -286.188912) (xy 294.019088 -286.184241) (xy 294.003543 -286.179049)
			(xy 293.995348 -286.178752) (xy 293.504112 -286.178752) (xy 293.495917 -286.179059) (xy 293.480366 -286.184234)
			(xy 293.473632 -286.188912) (xy 293.452007 -286.204569) (xy 293.404762 -286.229427) (xy 293.354135 -286.246368)
			(xy 293.301443 -286.25495) (xy 293.248057 -286.25495) (xy 293.195365 -286.246368) (xy 293.144738 -286.229427)
			(xy 293.097493 -286.204569) (xy 293.075868 -286.188912) (xy 293.069126 -286.184249) (xy 293.05358 -286.179075)
			(xy 293.045388 -286.178752) (xy 292.554152 -286.178752) (xy 292.545961 -286.179068) (xy 292.530421 -286.184257)
			(xy 292.523672 -286.188912) (xy 292.502047 -286.204569) (xy 292.454802 -286.229427) (xy 292.404175 -286.246368)
			(xy 292.351483 -286.25495) (xy 292.298097 -286.25495) (xy 292.245405 -286.246368) (xy 292.194778 -286.229427)
			(xy 292.147533 -286.204569) (xy 292.125908 -286.188912) (xy 292.119167 -286.184243) (xy 292.103622 -286.179058)
			(xy 292.095428 -286.178752) (xy 290.654232 -286.178752) (xy 290.646036 -286.179056) (xy 290.630482 -286.184226)
			(xy 290.623752 -286.188912) (xy 290.602127 -286.204569) (xy 290.554882 -286.229427) (xy 290.504255 -286.246368)
			(xy 290.451563 -286.25495) (xy 290.398177 -286.25495) (xy 290.345485 -286.246368) (xy 290.294858 -286.229427)
			(xy 290.247613 -286.204569) (xy 290.225988 -286.188912) (xy 290.219247 -286.184246) (xy 290.203701 -286.179066)
			(xy 290.195508 -286.178752) (xy 289.704272 -286.178752) (xy 289.696079 -286.179065) (xy 289.680536 -286.18425)
			(xy 289.673792 -286.188912) (xy 289.652167 -286.204569) (xy 289.604922 -286.229427) (xy 289.554295 -286.246368)
			(xy 289.501603 -286.25495) (xy 289.448217 -286.25495) (xy 289.395525 -286.246368) (xy 289.344898 -286.229427)
			(xy 289.297653 -286.204569) (xy 289.276028 -286.188912) (xy 289.269288 -286.184241) (xy 289.253743 -286.179049)
			(xy 289.245548 -286.178752) (xy 288.754058 -286.178752) (xy 288.745866 -286.179067) (xy 288.730325 -286.184255)
			(xy 288.723578 -286.188912) (xy 288.701953 -286.204569) (xy 288.654708 -286.229427) (xy 288.604081 -286.246368)
			(xy 288.551389 -286.25495) (xy 288.498003 -286.25495) (xy 288.445311 -286.246368) (xy 288.394684 -286.229427)
			(xy 288.347439 -286.204569) (xy 288.325814 -286.188912) (xy 288.319074 -286.184242) (xy 288.303528 -286.179055)
			(xy 288.295334 -286.178752) (xy 287.804098 -286.178752) (xy 287.795904 -286.179061) (xy 287.780356 -286.184239)
			(xy 287.773618 -286.188912) (xy 287.751993 -286.204569) (xy 287.704748 -286.229427) (xy 287.654121 -286.246368)
			(xy 287.601429 -286.25495) (xy 287.548043 -286.25495) (xy 287.495351 -286.246368) (xy 287.444724 -286.229427)
			(xy 287.397479 -286.204569) (xy 287.375854 -286.188912) (xy 287.369111 -286.18425) (xy 287.353566 -286.179081)
			(xy 287.345374 -286.178752) (xy 286.854138 -286.178752) (xy 286.845942 -286.179055) (xy 286.830386 -286.184223)
			(xy 286.823658 -286.188912) (xy 286.802033 -286.204569) (xy 286.754788 -286.229427) (xy 286.704161 -286.246368)
			(xy 286.651469 -286.25495) (xy 286.598083 -286.25495) (xy 286.545391 -286.246368) (xy 286.494764 -286.229427)
			(xy 286.447519 -286.204569) (xy 286.425894 -286.188912) (xy 286.419153 -286.184245) (xy 286.403607 -286.179064)
			(xy 286.395414 -286.178752) (xy 285.904178 -286.178752) (xy 285.895985 -286.179064) (xy 285.880441 -286.184247)
			(xy 285.873698 -286.188912) (xy 285.852073 -286.204569) (xy 285.804828 -286.229427) (xy 285.754201 -286.246368)
			(xy 285.701509 -286.25495) (xy 285.648123 -286.25495) (xy 285.595431 -286.246368) (xy 285.544804 -286.229427)
			(xy 285.497559 -286.204569) (xy 285.475934 -286.188912) (xy 285.469191 -286.184253) (xy 285.453645 -286.17909)
			(xy 285.445454 -286.178752) (xy 284.954218 -286.178752) (xy 284.946023 -286.179058) (xy 284.930471 -286.184231)
			(xy 284.923738 -286.188912) (xy 284.902113 -286.204569) (xy 284.854868 -286.229427) (xy 284.804241 -286.246368)
			(xy 284.751549 -286.25495) (xy 284.698163 -286.25495) (xy 284.645471 -286.246368) (xy 284.594844 -286.229427)
			(xy 284.547599 -286.204569) (xy 284.525974 -286.188912) (xy 284.519232 -286.184248) (xy 284.503686 -286.179073)
			(xy 284.495494 -286.178752) (xy 284.004258 -286.178752) (xy 283.996066 -286.179067) (xy 283.980525 -286.184255)
			(xy 283.973778 -286.188912) (xy 283.952153 -286.204569) (xy 283.904908 -286.229427) (xy 283.854281 -286.246368)
			(xy 283.801589 -286.25495) (xy 283.748203 -286.25495) (xy 283.695511 -286.246368) (xy 283.644884 -286.229427)
			(xy 283.597639 -286.204569) (xy 283.576014 -286.188912) (xy 283.569274 -286.184242) (xy 283.553728 -286.179055)
			(xy 283.545534 -286.178752) (xy 283.054298 -286.178752) (xy 283.046104 -286.179061) (xy 283.030556 -286.184239)
			(xy 283.023818 -286.188912) (xy 283.002193 -286.204569) (xy 282.954948 -286.229427) (xy 282.904321 -286.246368)
			(xy 282.851629 -286.25495) (xy 282.798243 -286.25495) (xy 282.745551 -286.246368) (xy 282.694924 -286.229427)
			(xy 282.647679 -286.204569) (xy 282.626054 -286.188912) (xy 282.619311 -286.18425) (xy 282.603766 -286.179081)
			(xy 282.595574 -286.178752) (xy 282.104084 -286.178752) (xy 282.095891 -286.179063) (xy 282.080345 -286.184245)
			(xy 282.073604 -286.188912) (xy 282.051979 -286.204569) (xy 282.004734 -286.229427) (xy 281.954107 -286.246368)
			(xy 281.901415 -286.25495) (xy 281.848029 -286.25495) (xy 281.795337 -286.246368) (xy 281.74471 -286.229427)
			(xy 281.697465 -286.204569) (xy 281.67584 -286.188912) (xy 281.669097 -286.184252) (xy 281.653551 -286.179087)
			(xy 281.64536 -286.178752) (xy 281.154124 -286.178752) (xy 281.145929 -286.179057) (xy 281.130375 -286.184229)
			(xy 281.123644 -286.188912) (xy 281.102019 -286.204569) (xy 281.054774 -286.229427) (xy 281.004147 -286.246368)
			(xy 280.951455 -286.25495) (xy 280.898069 -286.25495) (xy 280.845377 -286.246368) (xy 280.79475 -286.229427)
			(xy 280.747505 -286.204569) (xy 280.72588 -286.188912) (xy 280.719138 -286.184247) (xy 280.703593 -286.17907)
			(xy 280.6954 -286.178752) (xy 280.204164 -286.178752) (xy 280.195972 -286.179066) (xy 280.18043 -286.184253)
			(xy 280.173684 -286.188912) (xy 280.152059 -286.204569) (xy 280.104814 -286.229427) (xy 280.054187 -286.246368)
			(xy 280.001495 -286.25495) (xy 279.948109 -286.25495) (xy 279.895417 -286.246368) (xy 279.84479 -286.229427)
			(xy 279.797545 -286.204569) (xy 279.77592 -286.188912) (xy 279.76918 -286.184242) (xy 279.753634 -286.179052)
			(xy 279.74544 -286.178752) (xy 279.254204 -286.178752) (xy 279.24601 -286.17906) (xy 279.23046 -286.184237)
			(xy 279.223724 -286.188912) (xy 279.202099 -286.204569) (xy 279.154854 -286.229427) (xy 279.104227 -286.246368)
			(xy 279.051535 -286.25495) (xy 278.998149 -286.25495) (xy 278.945457 -286.246368) (xy 278.89483 -286.229427)
			(xy 278.847585 -286.204569) (xy 278.82596 -286.188912) (xy 278.819218 -286.18425) (xy 278.803672 -286.179079)
			(xy 278.79548 -286.178752) (xy 278.304244 -286.178752) (xy 278.296047 -286.179054) (xy 278.280491 -286.184221)
			(xy 278.273764 -286.188912) (xy 278.252139 -286.204569) (xy 278.204894 -286.229427) (xy 278.154267 -286.246368)
			(xy 278.101575 -286.25495) (xy 278.048189 -286.25495) (xy 277.995497 -286.246368) (xy 277.94487 -286.229427)
			(xy 277.897625 -286.204569) (xy 277.876 -286.188912) (xy 277.869259 -286.184244) (xy 277.853713 -286.179061)
			(xy 277.84552 -286.178752) (xy 277.354284 -286.178752) (xy 277.346091 -286.179063) (xy 277.330545 -286.184245)
			(xy 277.323804 -286.188912) (xy 277.302179 -286.204569) (xy 277.254934 -286.229427) (xy 277.204307 -286.246368)
			(xy 277.151615 -286.25495) (xy 277.098229 -286.25495) (xy 277.045537 -286.246368) (xy 276.99491 -286.229427)
			(xy 276.947665 -286.204569) (xy 276.92604 -286.188912) (xy 276.919297 -286.184252) (xy 276.903751 -286.179087)
			(xy 276.89556 -286.178752) (xy 273.55419 -286.178752) (xy 273.545996 -286.179062) (xy 273.53045 -286.184242)
			(xy 273.52371 -286.188912) (xy 273.502085 -286.204569) (xy 273.45484 -286.229427) (xy 273.404213 -286.246368)
			(xy 273.351521 -286.25495) (xy 273.298135 -286.25495) (xy 273.245443 -286.246368) (xy 273.194816 -286.229427)
			(xy 273.147571 -286.204569) (xy 273.125946 -286.188912) (xy 273.119203 -286.184252) (xy 273.103657 -286.179085)
			(xy 273.095466 -286.178752) (xy 272.60423 -286.178752) (xy 272.596034 -286.179056) (xy 272.58048 -286.184227)
			(xy 272.57375 -286.188912) (xy 272.552125 -286.204569) (xy 272.50488 -286.229427) (xy 272.454253 -286.246368)
			(xy 272.401561 -286.25495) (xy 272.348175 -286.25495) (xy 272.295483 -286.246368) (xy 272.244856 -286.229427)
			(xy 272.197611 -286.204569) (xy 272.175986 -286.188912) (xy 272.169245 -286.184246) (xy 272.153699 -286.179067)
			(xy 272.145506 -286.178752) (xy 271.65427 -286.178752) (xy 271.646078 -286.179065) (xy 271.630534 -286.18425)
			(xy 271.62379 -286.188912) (xy 271.602165 -286.204569) (xy 271.55492 -286.229427) (xy 271.504293 -286.246368)
			(xy 271.451601 -286.25495) (xy 271.398215 -286.25495) (xy 271.345523 -286.246368) (xy 271.294896 -286.229427)
			(xy 271.247651 -286.204569) (xy 271.226026 -286.188912) (xy 271.219286 -286.184241) (xy 271.20374 -286.17905)
			(xy 271.195546 -286.178752) (xy 270.70431 -286.178752) (xy 270.696115 -286.179059) (xy 270.680565 -286.184234)
			(xy 270.67383 -286.188912) (xy 270.652205 -286.204569) (xy 270.60496 -286.229427) (xy 270.554333 -286.246368)
			(xy 270.501641 -286.25495) (xy 270.448255 -286.25495) (xy 270.395563 -286.246368) (xy 270.344936 -286.229427)
			(xy 270.297691 -286.204569) (xy 270.276066 -286.188912) (xy 270.269324 -286.184249) (xy 270.253778 -286.179076)
			(xy 270.245586 -286.178752) (xy 269.754096 -286.178752) (xy 269.745902 -286.179061) (xy 269.730354 -286.18424)
			(xy 269.723616 -286.188912) (xy 269.701991 -286.204569) (xy 269.654746 -286.229427) (xy 269.604119 -286.246368)
			(xy 269.551427 -286.25495) (xy 269.498041 -286.25495) (xy 269.445349 -286.246368) (xy 269.394722 -286.229427)
			(xy 269.347477 -286.204569) (xy 269.325852 -286.188912) (xy 269.319109 -286.184251) (xy 269.303563 -286.179082)
			(xy 269.295372 -286.178752) (xy 268.998954 -286.178752) (xy 268.988889 -286.179185) (xy 268.970301 -286.186917)
			(xy 268.962886 -286.193738) (xy 268.907006 -286.249618) (xy 268.900162 -286.257017) (xy 268.892433 -286.275615)
			(xy 268.89202 -286.285686) (xy 268.89202 -286.78124) (xy 268.893798 -286.787844) (xy 268.899256 -286.80921)
			(xy 268.905119 -286.852917) (xy 268.905482 -286.874966) (xy 268.905148 -286.896817) (xy 268.899415 -286.940141)
			(xy 268.894052 -286.961326) (xy 268.892274 -286.967676) (xy 268.892274 -287.732216) (xy 268.894052 -287.738566)
			(xy 268.899399 -287.759754) (xy 268.905129 -287.803076) (xy 268.905482 -287.824926) (xy 268.905151 -287.846777)
			(xy 268.899423 -287.890102) (xy 268.894052 -287.911286) (xy 268.892274 -287.917636) (xy 268.892274 -288.682176)
			(xy 268.894052 -288.688526) (xy 268.899401 -288.709714) (xy 268.905137 -288.753036) (xy 268.905482 -288.774886)
			(xy 268.905147 -288.796737) (xy 268.899411 -288.84006) (xy 268.894052 -288.861246) (xy 268.892274 -288.867596)
			(xy 268.892274 -289.632136) (xy 268.894052 -289.638486) (xy 268.899397 -289.659674) (xy 268.905125 -289.702996)
			(xy 268.905482 -289.724846) (xy 268.905149 -289.746697) (xy 268.899419 -289.790022) (xy 268.894052 -289.811206)
			(xy 268.892274 -289.817556) (xy 268.892274 -290.582096) (xy 268.894052 -290.588446) (xy 268.8994 -290.609634)
			(xy 268.905133 -290.652956) (xy 268.905482 -290.674806) (xy 268.905145 -290.696657) (xy 268.899407 -290.739979)
			(xy 268.894052 -290.761166) (xy 268.892274 -290.767516) (xy 268.892274 -291.532056) (xy 268.894052 -291.538406)
			(xy 268.899403 -291.559594) (xy 268.90514 -291.602916) (xy 268.905482 -291.624766) (xy 268.905148 -291.646617)
			(xy 268.899415 -291.689941) (xy 268.894052 -291.711126) (xy 268.892274 -291.717476) (xy 268.892274 -292.48227)
			(xy 268.894052 -292.48862) (xy 268.899402 -292.509808) (xy 268.905138 -292.55313) (xy 268.905482 -292.57498)
			(xy 268.905147 -292.596831) (xy 268.899412 -292.640154) (xy 268.894052 -292.66134) (xy 268.892274 -292.66769)
			(xy 268.892274 -294.38219) (xy 268.894052 -294.38854) (xy 268.8994 -294.409728) (xy 268.905134 -294.45305)
			(xy 268.905482 -294.4749) (xy 268.905146 -294.496751) (xy 268.899408 -294.540073) (xy 268.894052 -294.56126)
			(xy 268.892274 -294.56761) (xy 268.892274 -296.943272) (xy 268.892689 -296.953299) (xy 268.900353 -296.97183)
			(xy 268.914525 -296.986017) (xy 268.933048 -296.993701) (xy 268.943074 -296.994072) (xy 269.52448 -296.994072)
			(xy 269.550472 -296.994554) (xy 269.601816 -297.002683) (xy 269.651256 -297.018744) (xy 269.697575 -297.042342)
			(xy 269.739632 -297.072896) (xy 269.776391 -297.109653) (xy 269.806947 -297.151708) (xy 269.830548 -297.198025)
			(xy 269.846612 -297.247465) (xy 269.854745 -297.298808) (xy 269.854745 -297.350792) (xy 269.846612 -297.402135)
			(xy 269.830548 -297.451575) (xy 269.806947 -297.497892) (xy 269.776391 -297.539947) (xy 269.739632 -297.576704)
			(xy 269.697575 -297.607258) (xy 269.651256 -297.630856) (xy 269.601816 -297.646917) (xy 269.550472 -297.655046)
			(xy 269.52448 -297.655488) (xy 268.943074 -297.655488) (xy 268.933069 -297.655981) (xy 268.914584 -297.663644)
			(xy 268.900436 -297.677796) (xy 268.892778 -297.696283) (xy 268.892274 -297.706288) (xy 268.892274 -298.843192)
			(xy 268.89276 -298.853203) (xy 268.900417 -298.871702) (xy 268.91457 -298.885864) (xy 268.933064 -298.893533)
			(xy 268.943074 -298.893992) (xy 269.52448 -298.893992) (xy 269.550494 -298.894474) (xy 269.601881 -298.90261)
			(xy 269.651363 -298.918685) (xy 269.697721 -298.942303) (xy 269.739814 -298.972883) (xy 269.776604 -299.009671)
			(xy 269.807186 -299.051761) (xy 269.830807 -299.098118) (xy 269.846885 -299.147599) (xy 269.855024 -299.198986)
			(xy 269.855024 -299.251013) (xy 271.094376 -299.251013) (xy 271.094376 -299.198987) (xy 271.102514 -299.147601)
			(xy 271.118592 -299.098121) (xy 271.142212 -299.051765) (xy 271.172792 -299.009675) (xy 271.209581 -298.972887)
			(xy 271.251672 -298.942307) (xy 271.298028 -298.918689) (xy 271.347509 -298.902613) (xy 271.398895 -298.894475)
			(xy 271.424908 -298.893992) (xy 272.374868 -298.893992) (xy 272.400875 -298.894565) (xy 272.45225 -298.902697)
			(xy 272.50172 -298.918767) (xy 272.548067 -298.942378) (xy 272.590149 -298.972949) (xy 272.626931 -299.009727)
			(xy 272.657506 -299.051806) (xy 272.681121 -299.09815) (xy 272.697195 -299.147619) (xy 272.705333 -299.198993)
			(xy 272.705333 -299.251007) (xy 272.697195 -299.302381) (xy 272.681121 -299.35185) (xy 272.657506 -299.398194)
			(xy 272.626931 -299.440273) (xy 272.590149 -299.477051) (xy 272.548067 -299.507622) (xy 272.50172 -299.531233)
			(xy 272.45225 -299.547303) (xy 272.400875 -299.555435) (xy 272.374868 -299.555916) (xy 271.424908 -299.555916)
			(xy 271.398895 -299.555525) (xy 271.347509 -299.547387) (xy 271.298028 -299.531311) (xy 271.251672 -299.507693)
			(xy 271.209581 -299.477113) (xy 271.172792 -299.440325) (xy 271.142212 -299.398235) (xy 271.118592 -299.351879)
			(xy 271.102514 -299.302399) (xy 271.094376 -299.251013) (xy 269.855024 -299.251013) (xy 269.855024 -299.251014)
			(xy 269.846885 -299.302401) (xy 269.830807 -299.351882) (xy 269.807186 -299.398239) (xy 269.776604 -299.440329)
			(xy 269.739814 -299.477117) (xy 269.697721 -299.507697) (xy 269.651363 -299.531315) (xy 269.601881 -299.54739)
			(xy 269.550494 -299.555526) (xy 269.52448 -299.555916) (xy 268.943074 -299.555916) (xy 268.933071 -299.556409)
			(xy 268.914591 -299.564073) (xy 268.90045 -299.578226) (xy 268.8928 -299.596713) (xy 268.892274 -299.606716)
			(xy 268.892274 -320.900044) (xy 317.098687 -320.900044) (xy 317.102693 -320.704989) (xy 317.114703 -320.510263)
			(xy 317.134698 -320.316194) (xy 317.162643 -320.12311) (xy 317.198492 -319.931335) (xy 317.242184 -319.741195)
			(xy 317.293645 -319.553008) (xy 317.352789 -319.367093) (xy 317.419516 -319.183762) (xy 317.493713 -319.003326)
			(xy 317.575255 -318.826088) (xy 317.664006 -318.652347) (xy 317.759814 -318.482396) (xy 317.862519 -318.316522)
			(xy 317.971947 -318.155004) (xy 318.087914 -317.998115) (xy 318.210225 -317.84612) (xy 318.338672 -317.699274)
			(xy 318.47304 -317.557825) (xy 318.613102 -317.422012) (xy 318.758621 -317.292063) (xy 318.909353 -317.168199)
			(xy 319.065043 -317.050627) (xy 319.225429 -316.939547) (xy 319.39024 -316.835144) (xy 319.559198 -316.737596)
			(xy 319.732019 -316.647067) (xy 319.908411 -316.563709) (xy 320.088076 -316.487663) (xy 320.270711 -316.419058)
			(xy 320.45601 -316.358008) (xy 320.643658 -316.304618) (xy 320.83334 -316.258976) (xy 321.024737 -316.22116)
			(xy 321.217524 -316.191234) (xy 321.411377 -316.169248) (xy 321.60597 -316.155239) (xy 321.800973 -316.149231)
			(xy 321.996059 -316.151234) (xy 322.190898 -316.161245) (xy 322.385162 -316.179246) (xy 322.578523 -316.205208)
			(xy 322.770656 -316.239086) (xy 322.961235 -316.280823) (xy 323.14994 -316.33035) (xy 323.336453 -316.387582)
			(xy 323.520459 -316.452423) (xy 323.701647 -316.524764) (xy 323.879713 -316.604482) (xy 324.054356 -316.691444)
			(xy 324.225282 -316.785503) (xy 324.392201 -316.886499) (xy 324.554834 -316.994264) (xy 324.712905 -317.108614)
			(xy 324.866148 -317.229357) (xy 325.014305 -317.356291) (xy 325.157126 -317.489199) (xy 325.29437 -317.627859)
			(xy 325.425806 -317.772037) (xy 325.551211 -317.92149) (xy 325.670375 -318.075964) (xy 325.783096 -318.235201)
			(xy 325.889185 -318.398932) (xy 325.988463 -318.566879) (xy 326.080761 -318.738762) (xy 326.165926 -318.914288)
			(xy 326.243812 -319.093163) (xy 326.314289 -319.275085) (xy 326.377237 -319.459747) (xy 326.432552 -319.646837)
			(xy 326.480138 -319.836041) (xy 326.519917 -320.027038) (xy 326.551821 -320.219508) (xy 326.575796 -320.413126)
			(xy 326.591802 -320.607564) (xy 326.599811 -320.802496) (xy 326.600312 -320.900044) (xy 326.599811 -320.997592)
			(xy 326.591802 -321.192524) (xy 326.575796 -321.386962) (xy 326.551821 -321.58058) (xy 326.519917 -321.77305)
			(xy 326.480138 -321.964047) (xy 326.432552 -322.153251) (xy 326.377237 -322.340341) (xy 326.314289 -322.525003)
			(xy 326.243812 -322.706925) (xy 326.165926 -322.8858) (xy 326.080761 -323.061326) (xy 325.988463 -323.233209)
			(xy 325.889185 -323.401156) (xy 325.783096 -323.564887) (xy 325.670375 -323.724124) (xy 325.551211 -323.878598)
			(xy 325.425806 -324.028051) (xy 325.29437 -324.172229) (xy 325.157126 -324.310889) (xy 325.014305 -324.443797)
			(xy 324.866148 -324.570731) (xy 324.712905 -324.691474) (xy 324.554834 -324.805824) (xy 324.392201 -324.913589)
			(xy 324.225282 -325.014585) (xy 324.054356 -325.108644) (xy 323.879713 -325.195606) (xy 323.701647 -325.275324)
			(xy 323.520459 -325.347665) (xy 323.336453 -325.412506) (xy 323.14994 -325.469738) (xy 322.961235 -325.519265)
			(xy 322.770656 -325.561002) (xy 322.578523 -325.59488) (xy 322.385162 -325.620842) (xy 322.190898 -325.638843)
			(xy 321.996059 -325.648854) (xy 321.800973 -325.650857) (xy 321.60597 -325.644849) (xy 321.411377 -325.63084)
			(xy 321.217524 -325.608854) (xy 321.024737 -325.578928) (xy 320.83334 -325.541112) (xy 320.643658 -325.49547)
			(xy 320.45601 -325.44208) (xy 320.270711 -325.38103) (xy 320.088076 -325.312425) (xy 319.908411 -325.236379)
			(xy 319.732019 -325.153021) (xy 319.559198 -325.062492) (xy 319.39024 -324.964944) (xy 319.225429 -324.860541)
			(xy 319.065043 -324.749461) (xy 318.909353 -324.631889) (xy 318.758621 -324.508025) (xy 318.613102 -324.378076)
			(xy 318.47304 -324.242263) (xy 318.338672 -324.100814) (xy 318.210225 -323.953968) (xy 318.087914 -323.801973)
			(xy 317.971947 -323.645084) (xy 317.862519 -323.483566) (xy 317.759814 -323.317692) (xy 317.664006 -323.147741)
			(xy 317.575255 -322.974) (xy 317.493713 -322.796762) (xy 317.419516 -322.616326) (xy 317.352789 -322.432995)
			(xy 317.293645 -322.24708) (xy 317.242184 -322.058893) (xy 317.198492 -321.868753) (xy 317.162643 -321.676978)
			(xy 317.134698 -321.483894) (xy 317.114703 -321.289825) (xy 317.102693 -321.095099) (xy 317.098687 -320.900044)
			(xy 268.892274 -320.900044) (xy 268.892274 -337.464908) (xy 268.892698 -337.474978) (xy 268.900411 -337.493583)
			(xy 268.90726 -337.500976) (xy 269.248636 -337.842352) (xy 269.256034 -337.849198) (xy 269.274633 -337.856927)
			(xy 269.284704 -337.857338) (xy 349.48749 -337.857338)
		)
		(stroke
			(width 0)
			(type solid)
		)
		(fill yes)
		(layer "In2.Cu")
		(net "P0V8_SERDES_VDDA_PEX2")
	)
	(gr_poly
		(pts
			(xy 117.294152 -337.850226) (xy 117.461792 -337.682586) (xy 117.468637 -337.675187) (xy 117.476368 -337.656589)
			(xy 117.476778 -337.646518) (xy 117.476778 -329.799696) (xy 117.476086 -329.787534) (xy 117.464949 -329.765909)
			(xy 117.455442 -329.758294) (xy 117.432822 -329.741708) (xy 117.392245 -329.702983) (xy 117.357779 -329.658731)
			(xy 117.330169 -329.609907) (xy 117.310011 -329.557564) (xy 117.29774 -329.502833) (xy 117.293621 -329.446894)
			(xy 117.297742 -329.390956) (xy 117.310015 -329.336225) (xy 117.330174 -329.283883) (xy 117.357785 -329.235059)
			(xy 117.392252 -329.190808) (xy 117.432831 -329.152085) (xy 117.455442 -329.135486) (xy 117.46495 -329.127869)
			(xy 117.476098 -329.106247) (xy 117.476778 -329.094084) (xy 117.476778 -318.923162) (xy 117.476445 -318.91462)
			(xy 117.470808 -318.898491) (xy 117.460177 -318.885117) (xy 117.453156 -318.880236) (xy 117.430191 -318.865163)
			(xy 117.388436 -318.829468) (xy 117.352233 -318.788153) (xy 117.32233 -318.742073) (xy 117.299345 -318.692181)
			(xy 117.283754 -318.639508) (xy 117.275879 -318.585143) (xy 117.275882 -318.53021) (xy 117.283764 -318.475847)
			(xy 117.299362 -318.423175) (xy 117.322353 -318.373286) (xy 117.352262 -318.327209) (xy 117.38847 -318.285899)
			(xy 117.430228 -318.250209) (xy 117.453156 -318.235076) (xy 117.4602 -318.230227) (xy 117.470819 -318.216837)
			(xy 117.476433 -318.200695) (xy 117.476778 -318.19215) (xy 117.476778 -318.058546) (xy 117.476443 -318.050005)
			(xy 117.470802 -318.03388) (xy 117.460169 -318.020511) (xy 117.453156 -318.01562) (xy 117.430184 -318.000547)
			(xy 117.388418 -317.96485) (xy 117.352203 -317.923532) (xy 117.322289 -317.877447) (xy 117.299294 -317.827548)
			(xy 117.283694 -317.774867) (xy 117.27581 -317.720493) (xy 117.275807 -317.66555) (xy 117.283685 -317.611175)
			(xy 117.299279 -317.558492) (xy 117.322268 -317.50859) (xy 117.352177 -317.462502) (xy 117.388387 -317.42118)
			(xy 117.43015 -317.385478) (xy 117.453156 -317.37046) (xy 117.460198 -317.365611) (xy 117.470813 -317.352219)
			(xy 117.476422 -317.336078) (xy 117.476778 -317.327534) (xy 117.476778 -316.355476) (xy 117.476447 -316.346933)
			(xy 117.470814 -316.330801) (xy 117.460183 -316.317423) (xy 117.453156 -316.31255) (xy 117.43019 -316.297477)
			(xy 117.388433 -316.261781) (xy 117.352228 -316.220466) (xy 117.322323 -316.174385) (xy 117.299337 -316.124492)
			(xy 117.283744 -316.071817) (xy 117.275867 -316.017451) (xy 117.27587 -315.962517) (xy 117.283751 -315.908151)
			(xy 117.299348 -315.855478) (xy 117.322339 -315.805587) (xy 117.352248 -315.759508) (xy 117.388456 -315.718196)
			(xy 117.430215 -315.682504) (xy 117.453156 -315.66739) (xy 117.460201 -315.662542) (xy 117.470824 -315.649152)
			(xy 117.476443 -315.63301) (xy 117.476778 -315.624464) (xy 117.476778 -295.255442) (xy 117.45468 -295.227756)
			(xy 117.437408 -295.223692) (xy 117.409715 -295.216802) (xy 117.356609 -295.195917) (xy 117.307206 -295.167355)
			(xy 117.262608 -295.131753) (xy 117.22381 -295.089906) (xy 117.191678 -295.042747) (xy 117.166929 -294.991328)
			(xy 117.150114 -294.936796) (xy 117.14161 -294.880369) (xy 117.14099 -294.851836) (xy 117.141519 -294.822573)
			(xy 117.150452 -294.764733) (xy 117.168113 -294.708936) (xy 117.194088 -294.656491) (xy 117.227767 -294.608627)
			(xy 117.24767 -294.587168) (xy 117.254782 -294.579802) (xy 117.261894 -294.561514) (xy 117.261132 -294.480234)
			(xy 117.260572 -294.470403) (xy 117.252984 -294.452252) (xy 117.2464 -294.444928) (xy 117.244622 -294.44315)
			(xy 117.237222 -294.43631) (xy 117.218623 -294.428596) (xy 117.208554 -294.428164) (xy 111.361474 -294.428164)
			(xy 111.350366 -294.428725) (xy 111.330213 -294.438078) (xy 111.322612 -294.446198) (xy 111.304394 -294.466944)
			(xy 111.263004 -294.503483) (xy 111.216779 -294.533675) (xy 111.166685 -294.556888) (xy 111.113768 -294.572639)
			(xy 111.059134 -294.580597) (xy 111.003922 -294.580597) (xy 110.949288 -294.572639) (xy 110.896371 -294.556888)
			(xy 110.846277 -294.533675) (xy 110.800052 -294.503483) (xy 110.758662 -294.466944) (xy 110.740444 -294.446198)
			(xy 110.732855 -294.438061) (xy 110.712696 -294.428706) (xy 110.701582 -294.428164) (xy 100.863908 -294.428164)
			(xy 100.838955 -294.427544) (xy 100.790012 -294.41779) (xy 100.743912 -294.398675) (xy 100.702427 -294.370934)
			(xy 100.68433 -294.353742) (xy 100.072952 -293.742364) (xy 100.055692 -293.724323) (xy 100.027934 -293.682829)
			(xy 100.00882 -293.636711) (xy 99.999086 -293.587747) (xy 99.99853 -293.562786) (xy 99.99853 -293.219378)
			(xy 99.998014 -293.207931) (xy 99.988105 -293.187296) (xy 99.97948 -293.179754) (xy 99.908868 -293.122858)
			(xy 99.886516 -293.117524) (xy 99.875086 -293.120064) (xy 99.78572 -293.139072) (xy 99.605394 -293.168585)
			(xy 99.423737 -293.188309) (xy 99.241279 -293.198186) (xy 99.149916 -293.198804) (xy 99.068262 -293.198319)
			(xy 98.905143 -293.190429) (xy 98.742597 -293.174669) (xy 98.581001 -293.151073) (xy 98.420734 -293.119698)
			(xy 98.262171 -293.080616) (xy 98.10568 -293.033919) (xy 97.951629 -292.979716) (xy 97.800376 -292.918133)
			(xy 97.652275 -292.849315) (xy 97.507672 -292.773422) (xy 97.366904 -292.690632) (xy 97.230301 -292.601137)
			(xy 97.098181 -292.505147) (xy 96.970853 -292.402885) (xy 96.848614 -292.294592) (xy 96.73175 -292.180519)
			(xy 96.620534 -292.060933) (xy 96.515225 -291.936114) (xy 96.416069 -291.806352) (xy 96.323299 -291.671952)
			(xy 96.237131 -291.533226) (xy 96.157765 -291.390499) (xy 96.085387 -291.244105) (xy 96.020167 -291.094384)
			(xy 95.962257 -290.941688) (xy 95.911792 -290.786372) (xy 95.868889 -290.628799) (xy 95.83365 -290.469337)
			(xy 95.806155 -290.30836) (xy 95.78647 -290.146241) (xy 95.774641 -289.983361) (xy 95.770695 -289.8201)
			(xy 95.774641 -289.656839) (xy 95.78647 -289.493959) (xy 95.806155 -289.33184) (xy 95.83365 -289.170863)
			(xy 95.868889 -289.011401) (xy 95.911792 -288.853828) (xy 95.962257 -288.698512) (xy 96.020167 -288.545816)
			(xy 96.085387 -288.396095) (xy 96.157765 -288.249701) (xy 96.237131 -288.106974) (xy 96.323299 -287.968248)
			(xy 96.416069 -287.833848) (xy 96.515225 -287.704086) (xy 96.620534 -287.579267) (xy 96.73175 -287.459681)
			(xy 96.848614 -287.345608) (xy 96.970853 -287.237315) (xy 97.098181 -287.135053) (xy 97.230301 -287.039063)
			(xy 97.366904 -286.949568) (xy 97.507672 -286.866778) (xy 97.652275 -286.790885) (xy 97.800376 -286.722067)
			(xy 97.951629 -286.660484) (xy 98.10568 -286.606281) (xy 98.262171 -286.559584) (xy 98.420734 -286.520502)
			(xy 98.581001 -286.489127) (xy 98.742597 -286.465531) (xy 98.905143 -286.449771) (xy 99.068262 -286.441881)
			(xy 99.149916 -286.441388) (xy 99.241279 -286.442004) (xy 99.423737 -286.451882) (xy 99.605394 -286.471609)
			(xy 99.785719 -286.501126) (xy 99.875086 -286.520128) (xy 99.886516 -286.522668) (xy 99.908868 -286.517334)
			(xy 99.97948 -286.460438) (xy 99.987995 -286.452807) (xy 99.997896 -286.43223) (xy 99.99853 -286.420814)
			(xy 99.99853 -286.227774) (xy 99.998038 -286.217768) (xy 99.990375 -286.199279) (xy 99.976224 -286.185127)
			(xy 99.957736 -286.177463) (xy 99.94773 -286.176974) (xy 99.944936 -286.176974) (xy 99.942142 -286.177228)
			(xy 99.914964 -286.178752) (xy 70.804278 -286.178752) (xy 70.796085 -286.179064) (xy 70.780541 -286.184247)
			(xy 70.773798 -286.188912) (xy 70.752173 -286.204569) (xy 70.704928 -286.229427) (xy 70.654301 -286.246368)
			(xy 70.601609 -286.25495) (xy 70.548223 -286.25495) (xy 70.495531 -286.246368) (xy 70.444904 -286.229427)
			(xy 70.397659 -286.204569) (xy 70.376034 -286.188912) (xy 70.369291 -286.184253) (xy 70.353745 -286.17909)
			(xy 70.345554 -286.178752) (xy 69.854318 -286.178752) (xy 69.846123 -286.179058) (xy 69.830571 -286.184231)
			(xy 69.823838 -286.188912) (xy 69.802213 -286.204569) (xy 69.754968 -286.229427) (xy 69.704341 -286.246368)
			(xy 69.651649 -286.25495) (xy 69.598263 -286.25495) (xy 69.545571 -286.246368) (xy 69.494944 -286.229427)
			(xy 69.447699 -286.204569) (xy 69.426074 -286.188912) (xy 69.419332 -286.184248) (xy 69.403786 -286.179073)
			(xy 69.395594 -286.178752) (xy 68.904104 -286.178752) (xy 68.89591 -286.17906) (xy 68.88036 -286.184237)
			(xy 68.873624 -286.188912) (xy 68.851999 -286.204569) (xy 68.804754 -286.229427) (xy 68.754127 -286.246368)
			(xy 68.701435 -286.25495) (xy 68.648049 -286.25495) (xy 68.595357 -286.246368) (xy 68.54473 -286.229427)
			(xy 68.497485 -286.204569) (xy 68.47586 -286.188912) (xy 68.469118 -286.18425) (xy 68.453572 -286.179079)
			(xy 68.44538 -286.178752) (xy 67.954144 -286.178752) (xy 67.945947 -286.179054) (xy 67.930391 -286.184221)
			(xy 67.923664 -286.188912) (xy 67.902039 -286.204569) (xy 67.854794 -286.229427) (xy 67.804167 -286.246368)
			(xy 67.751475 -286.25495) (xy 67.698089 -286.25495) (xy 67.645397 -286.246368) (xy 67.59477 -286.229427)
			(xy 67.547525 -286.204569) (xy 67.5259 -286.188912) (xy 67.519159 -286.184244) (xy 67.503613 -286.179061)
			(xy 67.49542 -286.178752) (xy 67.004184 -286.178752) (xy 66.995991 -286.179063) (xy 66.980445 -286.184245)
			(xy 66.973704 -286.188912) (xy 66.952079 -286.204569) (xy 66.904834 -286.229427) (xy 66.854207 -286.246368)
			(xy 66.801515 -286.25495) (xy 66.748129 -286.25495) (xy 66.695437 -286.246368) (xy 66.64481 -286.229427)
			(xy 66.597565 -286.204569) (xy 66.57594 -286.188912) (xy 66.569197 -286.184252) (xy 66.553651 -286.179087)
			(xy 66.54546 -286.178752) (xy 66.054224 -286.178752) (xy 66.046029 -286.179057) (xy 66.030475 -286.184229)
			(xy 66.023744 -286.188912) (xy 66.002119 -286.204569) (xy 65.954874 -286.229427) (xy 65.904247 -286.246368)
			(xy 65.851555 -286.25495) (xy 65.798169 -286.25495) (xy 65.745477 -286.246368) (xy 65.69485 -286.229427)
			(xy 65.647605 -286.204569) (xy 65.62598 -286.188912) (xy 65.619238 -286.184247) (xy 65.603693 -286.17907)
			(xy 65.5955 -286.178752) (xy 65.104264 -286.178752) (xy 65.096072 -286.179066) (xy 65.08053 -286.184253)
			(xy 65.073784 -286.188912) (xy 65.052159 -286.204569) (xy 65.004914 -286.229427) (xy 64.954287 -286.246368)
			(xy 64.901595 -286.25495) (xy 64.848209 -286.25495) (xy 64.795517 -286.246368) (xy 64.74489 -286.229427)
			(xy 64.697645 -286.204569) (xy 64.67602 -286.188912) (xy 64.66928 -286.184242) (xy 64.653734 -286.179052)
			(xy 64.64554 -286.178752) (xy 64.154304 -286.178752) (xy 64.14611 -286.17906) (xy 64.13056 -286.184237)
			(xy 64.123824 -286.188912) (xy 64.102199 -286.204569) (xy 64.054954 -286.229427) (xy 64.004327 -286.246368)
			(xy 63.951635 -286.25495) (xy 63.898249 -286.25495) (xy 63.845557 -286.246368) (xy 63.79493 -286.229427)
			(xy 63.747685 -286.204569) (xy 63.72606 -286.188912) (xy 63.719318 -286.18425) (xy 63.703772 -286.179079)
			(xy 63.69558 -286.178752) (xy 63.204344 -286.178752) (xy 63.196147 -286.179054) (xy 63.180591 -286.184221)
			(xy 63.173864 -286.188912) (xy 63.152239 -286.204569) (xy 63.104994 -286.229427) (xy 63.054367 -286.246368)
			(xy 63.001675 -286.25495) (xy 62.948289 -286.25495) (xy 62.895597 -286.246368) (xy 62.84497 -286.229427)
			(xy 62.797725 -286.204569) (xy 62.7761 -286.188912) (xy 62.769359 -286.184244) (xy 62.753813 -286.179061)
			(xy 62.74562 -286.178752) (xy 62.25413 -286.178752) (xy 62.245934 -286.179056) (xy 62.23038 -286.184227)
			(xy 62.22365 -286.188912) (xy 62.202025 -286.204569) (xy 62.15478 -286.229427) (xy 62.104153 -286.246368)
			(xy 62.051461 -286.25495) (xy 61.998075 -286.25495) (xy 61.945383 -286.246368) (xy 61.894756 -286.229427)
			(xy 61.847511 -286.204569) (xy 61.825886 -286.188912) (xy 61.819145 -286.184246) (xy 61.803599 -286.179067)
			(xy 61.795406 -286.178752) (xy 61.30417 -286.178752) (xy 61.295978 -286.179065) (xy 61.280434 -286.18425)
			(xy 61.27369 -286.188912) (xy 61.252065 -286.204569) (xy 61.20482 -286.229427) (xy 61.154193 -286.246368)
			(xy 61.101501 -286.25495) (xy 61.048115 -286.25495) (xy 60.995423 -286.246368) (xy 60.944796 -286.229427)
			(xy 60.897551 -286.204569) (xy 60.875926 -286.188912) (xy 60.869186 -286.184241) (xy 60.85364 -286.17905)
			(xy 60.845446 -286.178752) (xy 60.35421 -286.178752) (xy 60.346015 -286.179059) (xy 60.330465 -286.184234)
			(xy 60.32373 -286.188912) (xy 60.302105 -286.204569) (xy 60.25486 -286.229427) (xy 60.204233 -286.246368)
			(xy 60.151541 -286.25495) (xy 60.098155 -286.25495) (xy 60.045463 -286.246368) (xy 59.994836 -286.229427)
			(xy 59.947591 -286.204569) (xy 59.925966 -286.188912) (xy 59.919224 -286.184249) (xy 59.903678 -286.179076)
			(xy 59.895486 -286.178752) (xy 58.45429 -286.178752) (xy 58.446096 -286.179062) (xy 58.43055 -286.184242)
			(xy 58.42381 -286.188912) (xy 58.402185 -286.204569) (xy 58.35494 -286.229427) (xy 58.304313 -286.246368)
			(xy 58.251621 -286.25495) (xy 58.198235 -286.25495) (xy 58.145543 -286.246368) (xy 58.094916 -286.229427)
			(xy 58.047671 -286.204569) (xy 58.026046 -286.188912) (xy 58.019303 -286.184252) (xy 58.003757 -286.179085)
			(xy 57.995566 -286.178752) (xy 57.50433 -286.178752) (xy 57.496134 -286.179056) (xy 57.48058 -286.184227)
			(xy 57.47385 -286.188912) (xy 57.452225 -286.204569) (xy 57.40498 -286.229427) (xy 57.354353 -286.246368)
			(xy 57.301661 -286.25495) (xy 57.248275 -286.25495) (xy 57.195583 -286.246368) (xy 57.144956 -286.229427)
			(xy 57.097711 -286.204569) (xy 57.076086 -286.188912) (xy 57.069345 -286.184246) (xy 57.053799 -286.179067)
			(xy 57.045606 -286.178752) (xy 56.554116 -286.178752) (xy 56.545921 -286.179058) (xy 56.530369 -286.184232)
			(xy 56.523636 -286.188912) (xy 56.502011 -286.204569) (xy 56.454766 -286.229427) (xy 56.404139 -286.246368)
			(xy 56.351447 -286.25495) (xy 56.298061 -286.25495) (xy 56.245369 -286.246368) (xy 56.194742 -286.229427)
			(xy 56.147497 -286.204569) (xy 56.125872 -286.188912) (xy 56.11913 -286.184248) (xy 56.103584 -286.179073)
			(xy 56.095392 -286.178752) (xy 55.604156 -286.178752) (xy 55.595964 -286.179067) (xy 55.580424 -286.184256)
			(xy 55.573676 -286.188912) (xy 55.552051 -286.204569) (xy 55.504806 -286.229427) (xy 55.454179 -286.246368)
			(xy 55.401487 -286.25495) (xy 55.348101 -286.25495) (xy 55.295409 -286.246368) (xy 55.244782 -286.229427)
			(xy 55.197537 -286.204569) (xy 55.175912 -286.188912) (xy 55.169171 -286.184243) (xy 55.153626 -286.179056)
			(xy 55.145432 -286.178752) (xy 54.654196 -286.178752) (xy 54.646002 -286.179061) (xy 54.630454 -286.18424)
			(xy 54.623716 -286.188912) (xy 54.602091 -286.204569) (xy 54.554846 -286.229427) (xy 54.504219 -286.246368)
			(xy 54.451527 -286.25495) (xy 54.398141 -286.25495) (xy 54.345449 -286.246368) (xy 54.294822 -286.229427)
			(xy 54.247577 -286.204569) (xy 54.225952 -286.188912) (xy 54.219209 -286.184251) (xy 54.203663 -286.179082)
			(xy 54.195472 -286.178752) (xy 53.704236 -286.178752) (xy 53.69604 -286.179055) (xy 53.680485 -286.184224)
			(xy 53.673756 -286.188912) (xy 53.652131 -286.204569) (xy 53.604886 -286.229427) (xy 53.554259 -286.246368)
			(xy 53.501567 -286.25495) (xy 53.448181 -286.25495) (xy 53.395489 -286.246368) (xy 53.344862 -286.229427)
			(xy 53.297617 -286.204569) (xy 53.275992 -286.188912) (xy 53.269251 -286.184245) (xy 53.253705 -286.179065)
			(xy 53.245512 -286.178752) (xy 52.754276 -286.178752) (xy 52.746083 -286.179064) (xy 52.730539 -286.184248)
			(xy 52.723796 -286.188912) (xy 52.702171 -286.204569) (xy 52.654926 -286.229427) (xy 52.604299 -286.246368)
			(xy 52.551607 -286.25495) (xy 52.498221 -286.25495) (xy 52.445529 -286.246368) (xy 52.394902 -286.229427)
			(xy 52.347657 -286.204569) (xy 52.326032 -286.188912) (xy 52.319289 -286.184253) (xy 52.303743 -286.179091)
			(xy 52.295552 -286.178752) (xy 51.804316 -286.178752) (xy 51.796121 -286.179058) (xy 51.780569 -286.184232)
			(xy 51.773836 -286.188912) (xy 51.752211 -286.204569) (xy 51.704966 -286.229427) (xy 51.654339 -286.246368)
			(xy 51.601647 -286.25495) (xy 51.548261 -286.25495) (xy 51.495569 -286.246368) (xy 51.444942 -286.229427)
			(xy 51.397697 -286.204569) (xy 51.376072 -286.188912) (xy 51.36933 -286.184248) (xy 51.353784 -286.179073)
			(xy 51.345592 -286.178752) (xy 50.854356 -286.178752) (xy 50.846164 -286.179067) (xy 50.830624 -286.184256)
			(xy 50.823876 -286.188912) (xy 50.802251 -286.204569) (xy 50.755006 -286.229427) (xy 50.704379 -286.246368)
			(xy 50.651687 -286.25495) (xy 50.598301 -286.25495) (xy 50.545609 -286.246368) (xy 50.494982 -286.229427)
			(xy 50.447737 -286.204569) (xy 50.426112 -286.188912) (xy 50.419371 -286.184243) (xy 50.403826 -286.179056)
			(xy 50.395632 -286.178752) (xy 49.904142 -286.178752) (xy 49.895946 -286.179054) (xy 49.880389 -286.184222)
			(xy 49.873662 -286.188912) (xy 49.852037 -286.204569) (xy 49.804792 -286.229427) (xy 49.754165 -286.246368)
			(xy 49.701473 -286.25495) (xy 49.648087 -286.25495) (xy 49.595395 -286.246368) (xy 49.544768 -286.229427)
			(xy 49.497523 -286.204569) (xy 49.475898 -286.188912) (xy 49.469157 -286.184245) (xy 49.453611 -286.179062)
			(xy 49.445418 -286.178752) (xy 48.954182 -286.178752) (xy 48.945989 -286.179063) (xy 48.930444 -286.184246)
			(xy 48.923702 -286.188912) (xy 48.902077 -286.204569) (xy 48.854832 -286.229427) (xy 48.804205 -286.246368)
			(xy 48.751513 -286.25495) (xy 48.698127 -286.25495) (xy 48.645435 -286.246368) (xy 48.594808 -286.229427)
			(xy 48.547563 -286.204569) (xy 48.525938 -286.188912) (xy 48.519195 -286.184253) (xy 48.503649 -286.179088)
			(xy 48.495458 -286.178752) (xy 48.004222 -286.178752) (xy 47.996027 -286.179057) (xy 47.980474 -286.18423)
			(xy 47.973742 -286.188912) (xy 47.952117 -286.204569) (xy 47.904872 -286.229427) (xy 47.854245 -286.246368)
			(xy 47.801553 -286.25495) (xy 47.748167 -286.25495) (xy 47.695475 -286.246368) (xy 47.644848 -286.229427)
			(xy 47.597603 -286.204569) (xy 47.575978 -286.188912) (xy 47.569236 -286.184247) (xy 47.55369 -286.179071)
			(xy 47.545498 -286.178752) (xy 47.054262 -286.178752) (xy 47.04607 -286.179066) (xy 47.030528 -286.184254)
			(xy 47.023782 -286.188912) (xy 47.002157 -286.204569) (xy 46.954912 -286.229427) (xy 46.904285 -286.246368)
			(xy 46.851593 -286.25495) (xy 46.798207 -286.25495) (xy 46.745515 -286.246368) (xy 46.694888 -286.229427)
			(xy 46.647643 -286.204569) (xy 46.626018 -286.188912) (xy 46.619278 -286.184242) (xy 46.603732 -286.179053)
			(xy 46.595538 -286.178752) (xy 46.104302 -286.178752) (xy 46.096108 -286.17906) (xy 46.080559 -286.184238)
			(xy 46.073822 -286.188912) (xy 46.052197 -286.204569) (xy 46.004952 -286.229427) (xy 45.954325 -286.246368)
			(xy 45.901633 -286.25495) (xy 45.848247 -286.25495) (xy 45.795555 -286.246368) (xy 45.744928 -286.229427)
			(xy 45.697683 -286.204569) (xy 45.676058 -286.188912) (xy 45.669316 -286.18425) (xy 45.65377 -286.17908)
			(xy 45.645578 -286.178752) (xy 45.154342 -286.178752) (xy 45.146146 -286.179054) (xy 45.130589 -286.184222)
			(xy 45.123862 -286.188912) (xy 45.102237 -286.204569) (xy 45.054992 -286.229427) (xy 45.004365 -286.246368)
			(xy 44.951673 -286.25495) (xy 44.898287 -286.25495) (xy 44.845595 -286.246368) (xy 44.794968 -286.229427)
			(xy 44.747723 -286.204569) (xy 44.726098 -286.188912) (xy 44.719357 -286.184245) (xy 44.703811 -286.179062)
			(xy 44.695618 -286.178752) (xy 41.354248 -286.178752) (xy 41.346051 -286.179053) (xy 41.330494 -286.184219)
			(xy 41.323768 -286.188912) (xy 41.302143 -286.204569) (xy 41.254898 -286.229427) (xy 41.204271 -286.246368)
			(xy 41.151579 -286.25495) (xy 41.098193 -286.25495) (xy 41.045501 -286.246368) (xy 40.994874 -286.229427)
			(xy 40.947629 -286.204569) (xy 40.926004 -286.188912) (xy 40.919263 -286.184244) (xy 40.903718 -286.179059)
			(xy 40.895524 -286.178752) (xy 40.404288 -286.178752) (xy 40.396095 -286.179062) (xy 40.380548 -286.184243)
			(xy 40.373808 -286.188912) (xy 40.352183 -286.204569) (xy 40.304938 -286.229427) (xy 40.254311 -286.246368)
			(xy 40.201619 -286.25495) (xy 40.148233 -286.25495) (xy 40.095541 -286.246368) (xy 40.044914 -286.229427)
			(xy 39.997669 -286.204569) (xy 39.976044 -286.188912) (xy 39.969301 -286.184252) (xy 39.953755 -286.179086)
			(xy 39.945564 -286.178752) (xy 39.454328 -286.178752) (xy 39.446132 -286.179056) (xy 39.430578 -286.184227)
			(xy 39.423848 -286.188912) (xy 39.402223 -286.204569) (xy 39.354978 -286.229427) (xy 39.304351 -286.246368)
			(xy 39.251659 -286.25495) (xy 39.198273 -286.25495) (xy 39.145581 -286.246368) (xy 39.094954 -286.229427)
			(xy 39.047709 -286.204569) (xy 39.026084 -286.188912) (xy 39.019342 -286.184246) (xy 39.003797 -286.179068)
			(xy 38.995604 -286.178752) (xy 38.504368 -286.178752) (xy 38.496176 -286.179065) (xy 38.480633 -286.184251)
			(xy 38.473888 -286.188912) (xy 38.452263 -286.204569) (xy 38.405018 -286.229427) (xy 38.354391 -286.246368)
			(xy 38.301699 -286.25495) (xy 38.248313 -286.25495) (xy 38.195621 -286.246368) (xy 38.144994 -286.229427)
			(xy 38.097749 -286.204569) (xy 38.076124 -286.188912) (xy 38.069384 -286.184241) (xy 38.053838 -286.179051)
			(xy 38.045644 -286.178752) (xy 37.554154 -286.178752) (xy 37.545962 -286.179067) (xy 37.530422 -286.184257)
			(xy 37.523674 -286.188912) (xy 37.502049 -286.204569) (xy 37.454804 -286.229427) (xy 37.404177 -286.246368)
			(xy 37.351485 -286.25495) (xy 37.298099 -286.25495) (xy 37.245407 -286.246368) (xy 37.19478 -286.229427)
			(xy 37.147535 -286.204569) (xy 37.12591 -286.188912) (xy 37.119169 -286.184243) (xy 37.103624 -286.179057)
			(xy 37.09543 -286.178752) (xy 36.799012 -286.178752) (xy 36.788942 -286.179174) (xy 36.770339 -286.186892)
			(xy 36.762944 -286.193738) (xy 36.707064 -286.249618) (xy 36.700214 -286.257015) (xy 36.692476 -286.275613)
			(xy 36.692078 -286.285686) (xy 36.692078 -286.78124) (xy 36.693856 -286.787844) (xy 36.700989 -286.816382)
			(xy 36.706214 -286.874967) (xy 36.701001 -286.933553) (xy 36.693856 -286.962088) (xy 36.692078 -286.968692)
			(xy 36.692078 -287.7312) (xy 36.693856 -287.737804) (xy 36.700984 -287.766342) (xy 36.706199 -287.824925)
			(xy 36.703927 -287.850408) (xy 37.944539 -287.850408) (xy 37.944539 -287.798392) (xy 37.952677 -287.747016)
			(xy 37.968751 -287.697546) (xy 37.992366 -287.651199) (xy 38.02294 -287.609117) (xy 38.059722 -287.572337)
			(xy 38.101804 -287.541763) (xy 38.148151 -287.518148) (xy 38.197622 -287.502075) (xy 38.248998 -287.493939)
			(xy 38.275006 -287.493456) (xy 39.224966 -287.493456) (xy 39.250978 -287.493901) (xy 39.302363 -287.502035)
			(xy 39.351843 -287.518107) (xy 39.398199 -287.541722) (xy 39.44029 -287.572299) (xy 39.477079 -287.609084)
			(xy 39.50766 -287.651172) (xy 39.53128 -287.697525) (xy 39.547357 -287.747004) (xy 39.555496 -287.798388)
			(xy 39.555496 -287.850405) (xy 40.794466 -287.850405) (xy 40.794466 -287.798395) (xy 40.802602 -287.747025)
			(xy 40.818674 -287.697561) (xy 40.842285 -287.651219) (xy 40.872855 -287.609142) (xy 40.909631 -287.572364)
			(xy 40.951707 -287.541792) (xy 40.998048 -287.518179) (xy 41.047512 -287.502105) (xy 41.098881 -287.493967)
			(xy 41.124886 -287.493456) (xy 42.074846 -287.493456) (xy 42.100852 -287.493934) (xy 42.152223 -287.502077)
			(xy 42.201688 -287.518155) (xy 42.248029 -287.541773) (xy 42.290106 -287.572348) (xy 42.326882 -287.609129)
			(xy 42.357451 -287.65121) (xy 42.381063 -287.697554) (xy 42.397134 -287.747022) (xy 42.40527 -287.798394)
			(xy 42.40527 -287.850406) (xy 42.397134 -287.901778) (xy 42.381063 -287.951246) (xy 42.357451 -287.99759)
			(xy 42.326882 -288.039671) (xy 42.290106 -288.076452) (xy 42.248029 -288.107027) (xy 42.201688 -288.130645)
			(xy 42.152223 -288.146723) (xy 42.100852 -288.154866) (xy 42.074846 -288.15538) (xy 41.124886 -288.15538)
			(xy 41.098881 -288.154833) (xy 41.047512 -288.146695) (xy 40.998048 -288.130621) (xy 40.951707 -288.107008)
			(xy 40.909631 -288.076436) (xy 40.872855 -288.039658) (xy 40.842285 -287.997581) (xy 40.818674 -287.951239)
			(xy 40.802602 -287.901775) (xy 40.794466 -287.850405) (xy 39.555496 -287.850405) (xy 39.555496 -287.850412)
			(xy 39.547357 -287.901796) (xy 39.53128 -287.951275) (xy 39.50766 -287.997628) (xy 39.477079 -288.039716)
			(xy 39.44029 -288.076501) (xy 39.398199 -288.107078) (xy 39.351843 -288.130693) (xy 39.302363 -288.146765)
			(xy 39.250978 -288.154899) (xy 39.224966 -288.15538) (xy 38.275006 -288.15538) (xy 38.248998 -288.154861)
			(xy 38.197622 -288.146725) (xy 38.148151 -288.130652) (xy 38.101804 -288.107037) (xy 38.059722 -288.076463)
			(xy 38.02294 -288.039683) (xy 37.992366 -287.997601) (xy 37.968751 -287.951254) (xy 37.952677 -287.901784)
			(xy 37.944539 -287.850408) (xy 36.703927 -287.850408) (xy 36.700975 -287.883508) (xy 36.693856 -287.912048)
			(xy 36.692078 -287.918652) (xy 36.692078 -288.392616) (xy 36.692568 -288.402623) (xy 36.70023 -288.421113)
			(xy 36.714382 -288.435267) (xy 36.732871 -288.442931) (xy 36.742878 -288.443416) (xy 37.324792 -288.443416)
			(xy 37.350803 -288.443899) (xy 37.402186 -288.452036) (xy 37.451663 -288.468111) (xy 37.498016 -288.491728)
			(xy 37.540103 -288.522305) (xy 37.576889 -288.559091) (xy 37.607468 -288.601178) (xy 37.631086 -288.64753)
			(xy 37.647162 -288.697006) (xy 37.6553 -288.748389) (xy 37.6553 -288.800411) (xy 42.694299 -288.800411)
			(xy 42.694299 -288.748389) (xy 42.702438 -288.697007) (xy 42.718514 -288.64753) (xy 42.742132 -288.601178)
			(xy 42.77271 -288.559091) (xy 42.809496 -288.522306) (xy 42.851583 -288.491729) (xy 42.897936 -288.468111)
			(xy 42.947413 -288.452036) (xy 42.998795 -288.443899) (xy 43.024806 -288.443416) (xy 43.974766 -288.443416)
			(xy 44.000775 -288.443941) (xy 44.052154 -288.452074) (xy 44.101628 -288.468144) (xy 44.147978 -288.491757)
			(xy 44.190064 -288.52233) (xy 44.226848 -288.55911) (xy 44.257426 -288.601193) (xy 44.281043 -288.647541)
			(xy 44.297119 -288.697013) (xy 44.305257 -288.748391) (xy 44.305257 -288.800409) (xy 44.297119 -288.851787)
			(xy 44.281043 -288.901259) (xy 44.257426 -288.947607) (xy 44.226848 -288.98969) (xy 44.190064 -289.02647)
			(xy 44.147978 -289.057043) (xy 44.101628 -289.080656) (xy 44.052154 -289.096726) (xy 44.000775 -289.104859)
			(xy 43.974766 -289.10534) (xy 43.024806 -289.10534) (xy 42.998795 -289.104901) (xy 42.947413 -289.096764)
			(xy 42.897936 -289.080689) (xy 42.851583 -289.057071) (xy 42.809496 -289.026494) (xy 42.77271 -288.989709)
			(xy 42.742132 -288.947622) (xy 42.718514 -288.90127) (xy 42.702438 -288.851793) (xy 42.694299 -288.800411)
			(xy 37.6553 -288.800411) (xy 37.647162 -288.851794) (xy 37.631086 -288.90127) (xy 37.607468 -288.947622)
			(xy 37.576889 -288.989709) (xy 37.540103 -289.026495) (xy 37.498016 -289.057072) (xy 37.451663 -289.080689)
			(xy 37.402186 -289.096764) (xy 37.350803 -289.104901) (xy 37.324792 -289.10534) (xy 36.742878 -289.10534)
			(xy 36.732863 -289.105764) (xy 36.71436 -289.113439) (xy 36.700205 -289.127612) (xy 36.692552 -289.146124)
			(xy 36.692078 -289.15614) (xy 36.692078 -289.63112) (xy 36.693856 -289.637724) (xy 36.700982 -289.666262)
			(xy 36.706193 -289.724844) (xy 36.700967 -289.783426) (xy 36.693856 -289.811968) (xy 36.692078 -289.818572)
			(xy 36.692078 -290.58108) (xy 36.693856 -290.587684) (xy 36.700986 -290.616222) (xy 36.706204 -290.674806)
			(xy 36.700984 -290.73339) (xy 36.693856 -290.761928) (xy 36.692078 -290.768532) (xy 36.692078 -291.53104)
			(xy 36.693856 -291.537644) (xy 36.700989 -291.566182) (xy 36.706214 -291.624767) (xy 36.701001 -291.683353)
			(xy 36.693856 -291.711888) (xy 36.692078 -291.718492) (xy 36.692078 -292.481254) (xy 36.693856 -292.487858)
			(xy 36.700988 -292.516396) (xy 36.706211 -292.574981) (xy 36.700995 -292.633566) (xy 36.693856 -292.662102)
			(xy 36.692078 -292.668706) (xy 36.692078 -294.381174) (xy 36.693856 -294.387778) (xy 36.700986 -294.416316)
			(xy 36.706206 -294.4749) (xy 36.700986 -294.533484) (xy 36.693856 -294.562022) (xy 36.692078 -294.568626)
			(xy 36.692078 -296.943272) (xy 36.692493 -296.953299) (xy 36.700157 -296.971829) (xy 36.714329 -296.986015)
			(xy 36.732852 -296.993698) (xy 36.742878 -296.994072) (xy 37.324538 -296.994072) (xy 37.350525 -296.994584)
			(xy 37.401858 -297.00272) (xy 37.451286 -297.018786) (xy 37.497593 -297.042385) (xy 37.539639 -297.072937)
			(xy 37.576388 -297.10969) (xy 37.606935 -297.151739) (xy 37.630529 -297.198049) (xy 37.646589 -297.247479)
			(xy 37.654719 -297.298813) (xy 37.654719 -297.350787) (xy 37.646589 -297.402121) (xy 37.630529 -297.451551)
			(xy 37.606935 -297.497861) (xy 37.576388 -297.53991) (xy 37.539639 -297.576663) (xy 37.497593 -297.607215)
			(xy 37.451286 -297.630814) (xy 37.401858 -297.64688) (xy 37.350525 -297.655016) (xy 37.324538 -297.655488)
			(xy 36.742878 -297.655488) (xy 36.732872 -297.65598) (xy 36.714386 -297.663643) (xy 36.700237 -297.677795)
			(xy 36.692578 -297.696282) (xy 36.692078 -297.706288) (xy 36.692078 -298.77569) (xy 39.369695 -298.77569)
			(xy 39.369695 -298.72371) (xy 39.377827 -298.67237) (xy 39.393891 -298.622935) (xy 39.417492 -298.576621)
			(xy 39.448047 -298.53457) (xy 39.484805 -298.497817) (xy 39.52686 -298.467268) (xy 39.573177 -298.443674)
			(xy 39.622615 -298.427617) (xy 39.673956 -298.419492) (xy 39.699946 -298.419012) (xy 40.649906 -298.419012)
			(xy 40.675894 -298.419482) (xy 40.727231 -298.427614) (xy 40.776664 -298.443676) (xy 40.822975 -298.467274)
			(xy 40.865025 -298.497826) (xy 40.901778 -298.534579) (xy 40.932329 -298.57663) (xy 40.955926 -298.622942)
			(xy 40.971988 -298.672375) (xy 40.980118 -298.723712) (xy 40.980118 -298.775688) (xy 40.971988 -298.827025)
			(xy 40.955926 -298.876458) (xy 40.932329 -298.92277) (xy 40.901778 -298.964821) (xy 40.865025 -299.001574)
			(xy 40.822975 -299.032126) (xy 40.776664 -299.055724) (xy 40.727231 -299.071786) (xy 40.675894 -299.079918)
			(xy 40.649906 -299.080428) (xy 39.699946 -299.080428) (xy 39.673956 -299.079908) (xy 39.622615 -299.071783)
			(xy 39.573177 -299.055726) (xy 39.52686 -299.032132) (xy 39.484805 -299.001583) (xy 39.448047 -298.96483)
			(xy 39.417492 -298.922779) (xy 39.393891 -298.876465) (xy 39.377827 -298.82703) (xy 39.369695 -298.77569)
			(xy 36.692078 -298.77569) (xy 36.692078 -298.843192) (xy 36.692564 -298.853202) (xy 36.700222 -298.871701)
			(xy 36.714374 -298.885862) (xy 36.732868 -298.89353) (xy 36.742878 -298.893992) (xy 37.324538 -298.893992)
			(xy 37.350547 -298.894505) (xy 37.401923 -298.902647) (xy 37.451394 -298.918726) (xy 37.49774 -298.942346)
			(xy 37.539821 -298.972924) (xy 37.576601 -299.009708) (xy 37.607174 -299.051793) (xy 37.630788 -299.098142)
			(xy 37.646861 -299.147614) (xy 37.654998 -299.198991) (xy 37.654998 -299.251009) (xy 37.646861 -299.302386)
			(xy 37.630788 -299.351858) (xy 37.607174 -299.398207) (xy 37.576601 -299.440292) (xy 37.539821 -299.477076)
			(xy 37.49774 -299.507654) (xy 37.451394 -299.531274) (xy 37.401923 -299.547353) (xy 37.350547 -299.555495)
			(xy 37.324538 -299.555916) (xy 36.742878 -299.555916) (xy 36.732874 -299.556408) (xy 36.714393 -299.564072)
			(xy 36.700251 -299.578225) (xy 36.692601 -299.596712) (xy 36.692078 -299.606716) (xy 36.692078 -320.900044)
			(xy 84.898745 -320.900044) (xy 84.902751 -320.704989) (xy 84.914761 -320.510263) (xy 84.934756 -320.316194)
			(xy 84.962701 -320.12311) (xy 84.99855 -319.931335) (xy 85.042242 -319.741195) (xy 85.093703 -319.553008)
			(xy 85.152847 -319.367093) (xy 85.219574 -319.183762) (xy 85.293771 -319.003326) (xy 85.375313 -318.826088)
			(xy 85.464064 -318.652347) (xy 85.559872 -318.482396) (xy 85.662577 -318.316522) (xy 85.772005 -318.155004)
			(xy 85.887972 -317.998115) (xy 86.010283 -317.84612) (xy 86.13873 -317.699274) (xy 86.273098 -317.557825)
			(xy 86.41316 -317.422012) (xy 86.558679 -317.292063) (xy 86.709411 -317.168199) (xy 86.865101 -317.050627)
			(xy 87.025487 -316.939547) (xy 87.190298 -316.835144) (xy 87.359256 -316.737596) (xy 87.532077 -316.647067)
			(xy 87.708469 -316.563709) (xy 87.888134 -316.487663) (xy 88.070769 -316.419058) (xy 88.256068 -316.358008)
			(xy 88.443716 -316.304618) (xy 88.633398 -316.258976) (xy 88.824795 -316.22116) (xy 89.017582 -316.191234)
			(xy 89.211435 -316.169248) (xy 89.406028 -316.155239) (xy 89.601031 -316.149231) (xy 89.796117 -316.151234)
			(xy 89.990956 -316.161245) (xy 90.18522 -316.179246) (xy 90.378581 -316.205208) (xy 90.570714 -316.239086)
			(xy 90.761293 -316.280823) (xy 90.949998 -316.33035) (xy 91.136511 -316.387582) (xy 91.320517 -316.452423)
			(xy 91.501705 -316.524764) (xy 91.679771 -316.604482) (xy 91.854414 -316.691444) (xy 92.02534 -316.785503)
			(xy 92.192259 -316.886499) (xy 92.354892 -316.994264) (xy 92.512963 -317.108614) (xy 92.666206 -317.229357)
			(xy 92.814363 -317.356291) (xy 92.957184 -317.489199) (xy 93.094428 -317.627859) (xy 93.225864 -317.772037)
			(xy 93.351269 -317.92149) (xy 93.470433 -318.075964) (xy 93.583154 -318.235201) (xy 93.689243 -318.398932)
			(xy 93.788521 -318.566879) (xy 93.880819 -318.738762) (xy 93.965984 -318.914288) (xy 94.04387 -319.093163)
			(xy 94.114347 -319.275085) (xy 94.177295 -319.459747) (xy 94.23261 -319.646837) (xy 94.280196 -319.836041)
			(xy 94.319975 -320.027038) (xy 94.351879 -320.219508) (xy 94.375854 -320.413126) (xy 94.39186 -320.607564)
			(xy 94.399869 -320.802496) (xy 94.40037 -320.900044) (xy 94.399869 -320.997592) (xy 94.39186 -321.192524)
			(xy 94.375854 -321.386962) (xy 94.351879 -321.58058) (xy 94.319975 -321.77305) (xy 94.280196 -321.964047)
			(xy 94.23261 -322.153251) (xy 94.177295 -322.340341) (xy 94.114347 -322.525003) (xy 94.04387 -322.706925)
			(xy 93.965984 -322.8858) (xy 93.880819 -323.061326) (xy 93.788521 -323.233209) (xy 93.689243 -323.401156)
			(xy 93.583154 -323.564887) (xy 93.470433 -323.724124) (xy 93.351269 -323.878598) (xy 93.225864 -324.028051)
			(xy 93.094428 -324.172229) (xy 92.957184 -324.310889) (xy 92.814363 -324.443797) (xy 92.666206 -324.570731)
			(xy 92.512963 -324.691474) (xy 92.354892 -324.805824) (xy 92.192259 -324.913589) (xy 92.02534 -325.014585)
			(xy 91.854414 -325.108644) (xy 91.679771 -325.195606) (xy 91.501705 -325.275324) (xy 91.320517 -325.347665)
			(xy 91.136511 -325.412506) (xy 90.949998 -325.469738) (xy 90.761293 -325.519265) (xy 90.570714 -325.561002)
			(xy 90.378581 -325.59488) (xy 90.18522 -325.620842) (xy 89.990956 -325.638843) (xy 89.796117 -325.648854)
			(xy 89.601031 -325.650857) (xy 89.406028 -325.644849) (xy 89.211435 -325.63084) (xy 89.017582 -325.608854)
			(xy 88.824795 -325.578928) (xy 88.633398 -325.541112) (xy 88.443716 -325.49547) (xy 88.256068 -325.44208)
			(xy 88.070769 -325.38103) (xy 87.888134 -325.312425) (xy 87.708469 -325.236379) (xy 87.532077 -325.153021)
			(xy 87.359256 -325.062492) (xy 87.190298 -324.964944) (xy 87.025487 -324.860541) (xy 86.865101 -324.749461)
			(xy 86.709411 -324.631889) (xy 86.558679 -324.508025) (xy 86.41316 -324.378076) (xy 86.273098 -324.242263)
			(xy 86.13873 -324.100814) (xy 86.010283 -323.953968) (xy 85.887972 -323.801973) (xy 85.772005 -323.645084)
			(xy 85.662577 -323.483566) (xy 85.559872 -323.317692) (xy 85.464064 -323.147741) (xy 85.375313 -322.974)
			(xy 85.293771 -322.796762) (xy 85.219574 -322.616326) (xy 85.152847 -322.432995) (xy 85.093703 -322.24708)
			(xy 85.042242 -322.058893) (xy 84.99855 -321.868753) (xy 84.962701 -321.676978) (xy 84.934756 -321.483894)
			(xy 84.914761 -321.289825) (xy 84.902751 -321.095099) (xy 84.898745 -320.900044) (xy 36.692078 -320.900044)
			(xy 36.692078 -330.416662) (xy 97.355152 -330.416662) (xy 97.355152 -329.553062) (xy 97.355642 -329.523078)
			(xy 97.36347 -329.463622) (xy 97.378991 -329.405697) (xy 97.40194 -329.350293) (xy 97.431924 -329.298359)
			(xy 97.46843 -329.250783) (xy 97.510835 -329.208378) (xy 97.558411 -329.171872) (xy 97.610345 -329.141888)
			(xy 97.665749 -329.118939) (xy 97.723674 -329.103418) (xy 97.78313 -329.09559) (xy 97.843098 -329.09559)
			(xy 97.902554 -329.103418) (xy 97.960479 -329.118939) (xy 98.015883 -329.141888) (xy 98.067817 -329.171872)
			(xy 98.115393 -329.208378) (xy 98.157798 -329.250783) (xy 98.194304 -329.298359) (xy 98.224288 -329.350293)
			(xy 98.247237 -329.405697) (xy 98.262758 -329.463622) (xy 98.270586 -329.523078) (xy 98.271076 -329.553062)
			(xy 98.271076 -330.416662) (xy 98.270586 -330.446646) (xy 98.262758 -330.506102) (xy 98.247237 -330.564027)
			(xy 98.224288 -330.619431) (xy 98.194304 -330.671365) (xy 98.157798 -330.718941) (xy 98.115393 -330.761346)
			(xy 98.067817 -330.797852) (xy 98.015883 -330.827836) (xy 97.960479 -330.850785) (xy 97.902554 -330.866306)
			(xy 97.843098 -330.874134) (xy 97.78313 -330.874134) (xy 97.723674 -330.866306) (xy 97.665749 -330.850785)
			(xy 97.610345 -330.827836) (xy 97.558411 -330.797852) (xy 97.510835 -330.761346) (xy 97.46843 -330.718941)
			(xy 97.431924 -330.671365) (xy 97.40194 -330.619431) (xy 97.378991 -330.564027) (xy 97.36347 -330.506102)
			(xy 97.355642 -330.446646) (xy 97.355152 -330.416662) (xy 36.692078 -330.416662) (xy 36.692078 -331.53223)
			(xy 114.955828 -331.53223) (xy 114.955828 -330.66863) (xy 114.956318 -330.638646) (xy 114.964146 -330.57919)
			(xy 114.979667 -330.521265) (xy 115.002616 -330.465861) (xy 115.0326 -330.413927) (xy 115.069106 -330.366351)
			(xy 115.111511 -330.323946) (xy 115.159087 -330.28744) (xy 115.211021 -330.257456) (xy 115.266425 -330.234507)
			(xy 115.32435 -330.218986) (xy 115.383806 -330.211158) (xy 115.443774 -330.211158) (xy 115.50323 -330.218986)
			(xy 115.561155 -330.234507) (xy 115.616559 -330.257456) (xy 115.668493 -330.28744) (xy 115.716069 -330.323946)
			(xy 115.758474 -330.366351) (xy 115.79498 -330.413927) (xy 115.824964 -330.465861) (xy 115.847913 -330.521265)
			(xy 115.863434 -330.57919) (xy 115.871262 -330.638646) (xy 115.871752 -330.66863) (xy 115.871752 -331.53223)
			(xy 115.871262 -331.562214) (xy 115.863434 -331.62167) (xy 115.847913 -331.679595) (xy 115.824964 -331.734999)
			(xy 115.79498 -331.786933) (xy 115.758474 -331.834509) (xy 115.716069 -331.876914) (xy 115.668493 -331.91342)
			(xy 115.616559 -331.943404) (xy 115.561155 -331.966353) (xy 115.50323 -331.981874) (xy 115.443774 -331.989702)
			(xy 115.383806 -331.989702) (xy 115.32435 -331.981874) (xy 115.266425 -331.966353) (xy 115.211021 -331.943404)
			(xy 115.159087 -331.91342) (xy 115.111511 -331.876914) (xy 115.069106 -331.834509) (xy 115.0326 -331.786933)
			(xy 115.002616 -331.734999) (xy 114.979667 -331.679595) (xy 114.964146 -331.62167) (xy 114.956318 -331.562214)
			(xy 114.955828 -331.53223) (xy 36.692078 -331.53223) (xy 36.692078 -333.950056) (xy 93.5736 -333.950056)
			(xy 93.5736 -333.086456) (xy 93.57409 -333.056488) (xy 93.581913 -332.997066) (xy 93.597426 -332.939173)
			(xy 93.620362 -332.8838) (xy 93.650329 -332.831894) (xy 93.686816 -332.784344) (xy 93.729196 -332.741964)
			(xy 93.776746 -332.705477) (xy 93.828652 -332.67551) (xy 93.884025 -332.652574) (xy 93.941918 -332.637061)
			(xy 94.00134 -332.629238) (xy 94.061276 -332.629238) (xy 94.120698 -332.637061) (xy 94.178591 -332.652574)
			(xy 94.233964 -332.67551) (xy 94.28587 -332.705477) (xy 94.33342 -332.741964) (xy 94.3758 -332.784344)
			(xy 94.412287 -332.831894) (xy 94.442254 -332.8838) (xy 94.46519 -332.939173) (xy 94.480703 -332.997066)
			(xy 94.488526 -333.056488) (xy 94.489016 -333.086456) (xy 94.489016 -333.950056) (xy 94.488526 -333.980024)
			(xy 94.480703 -334.039446) (xy 94.46519 -334.097339) (xy 94.442254 -334.152712) (xy 94.412287 -334.204618)
			(xy 94.3758 -334.252168) (xy 94.33342 -334.294548) (xy 94.28587 -334.331035) (xy 94.233964 -334.361002)
			(xy 94.178591 -334.383938) (xy 94.120698 -334.399451) (xy 94.061276 -334.407274) (xy 94.00134 -334.407274)
			(xy 93.941918 -334.399451) (xy 93.884025 -334.383938) (xy 93.828652 -334.361002) (xy 93.776746 -334.331035)
			(xy 93.729196 -334.294548) (xy 93.686816 -334.252168) (xy 93.650329 -334.204618) (xy 93.620362 -334.152712)
			(xy 93.597426 -334.097339) (xy 93.581913 -334.039446) (xy 93.57409 -333.980024) (xy 93.5736 -333.950056)
			(xy 36.692078 -333.950056) (xy 36.692078 -337.464908) (xy 36.692502 -337.474978) (xy 36.700216 -337.493583)
			(xy 36.707064 -337.500976) (xy 37.04844 -337.842352) (xy 37.055838 -337.849197) (xy 37.074437 -337.856925)
			(xy 37.084508 -337.857338) (xy 117.287294 -337.857338)
		)
		(stroke
			(width 0)
			(type solid)
		)
		(fill yes)
		(layer "In2.Cu")
		(net "P0V8_SERDES_VDDA_PEX0")
	)
	(gr_poly
		(pts
			(arc
				(start 141.931898 -286.145986)
				(mid 141.955993 -286.139908)
				(end 141.974316 -286.123126)
			)
			(arc
				(start 141.974316 -286.123126)
				(mid 142.293594 -285.950429)
				(end 142.612872 -286.123126)
			)
			(arc
				(start 142.612872 -286.123126)
				(mid 142.631199 -286.139902)
				(end 142.65529 -286.145986)
			)
			(arc
				(start 143.407384 -286.145986)
				(mid 143.431479 -286.139908)
				(end 143.449802 -286.123126)
			)
			(arc
				(start 143.449802 -286.123126)
				(mid 143.76908 -285.950429)
				(end 144.088358 -286.123126)
			)
			(arc
				(start 144.088358 -286.123126)
				(mid 144.106685 -286.139902)
				(end 144.130776 -286.145986)
			)
			(arc
				(start 144.296384 -286.145986)
				(mid 144.320479 -286.139908)
				(end 144.338802 -286.123126)
			)
			(arc
				(start 144.338802 -286.123126)
				(mid 144.65808 -285.950429)
				(end 144.977358 -286.123126)
			)
			(arc
				(start 144.977358 -286.123126)
				(mid 144.995685 -286.139902)
				(end 145.019776 -286.145986)
			)
			(arc
				(start 147.469352 -286.145986)
				(mid 147.493447 -286.139908)
				(end 147.51177 -286.123126)
			)
			(arc
				(start 147.51177 -286.123126)
				(mid 147.831048 -285.950429)
				(end 148.150326 -286.123126)
			)
			(arc
				(start 148.150326 -286.123126)
				(mid 148.168653 -286.139902)
				(end 148.192744 -286.145986)
			)
			(arc
				(start 189.770004 -286.145986)
				(mid 189.786202 -286.14342)
				(end 189.800738 -286.135826)
			)
			(arc
				(start 189.800738 -286.135826)
				(mid 189.894858 -286.08617)
				(end 189.999874 -286.069024)
			)
			(arc
				(start 189.999874 -286.069024)
				(mid 190.104873 -286.08622)
				(end 190.19901 -286.135826)
			)
			(arc
				(start 190.19901 -286.135826)
				(mid 190.213546 -286.143419)
				(end 190.229744 -286.145986)
			)
			(arc
				(start 190.720218 -286.145986)
				(mid 190.736416 -286.14342)
				(end 190.750952 -286.135826)
			)
			(arc
				(start 190.750952 -286.135826)
				(mid 190.845072 -286.08617)
				(end 190.950088 -286.069024)
			)
			(arc
				(start 190.950088 -286.069024)
				(mid 191.055087 -286.08622)
				(end 191.149224 -286.135826)
			)
			(arc
				(start 191.149224 -286.135826)
				(mid 191.16376 -286.143419)
				(end 191.179958 -286.145986)
			)
			(arc
				(start 191.670178 -286.145986)
				(mid 191.686376 -286.14342)
				(end 191.700912 -286.135826)
			)
			(arc
				(start 191.700912 -286.135826)
				(mid 191.795032 -286.08617)
				(end 191.900048 -286.069024)
			)
			(arc
				(start 191.900048 -286.069024)
				(mid 192.005047 -286.08622)
				(end 192.099184 -286.135826)
			)
			(arc
				(start 192.099184 -286.135826)
				(mid 192.11372 -286.143419)
				(end 192.129918 -286.145986)
			)
			(arc
				(start 192.620646 -286.145986)
				(mid 192.63671 -286.143379)
				(end 192.651126 -286.135826)
			)
			(arc
				(start 192.651126 -286.135826)
				(mid 192.850008 -286.069277)
				(end 193.04889 -286.135826)
			)
			(arc
				(start 193.04889 -286.135826)
				(mid 193.063306 -286.143379)
				(end 193.07937 -286.145986)
			)
			(arc
				(start 193.570606 -286.145986)
				(mid 193.58667 -286.143379)
				(end 193.601086 -286.135826)
			)
			(arc
				(start 193.601086 -286.135826)
				(mid 193.799968 -286.069277)
				(end 193.99885 -286.135826)
			)
			(arc
				(start 193.99885 -286.135826)
				(mid 194.013266 -286.143379)
				(end 194.02933 -286.145986)
			)
			(arc
				(start 194.520058 -286.145986)
				(mid 194.536256 -286.14342)
				(end 194.550792 -286.135826)
			)
			(arc
				(start 194.550792 -286.135826)
				(mid 194.644912 -286.08617)
				(end 194.749928 -286.069024)
			)
			(arc
				(start 194.749928 -286.069024)
				(mid 194.854927 -286.08622)
				(end 194.949064 -286.135826)
			)
			(arc
				(start 194.949064 -286.135826)
				(mid 194.9636 -286.143419)
				(end 194.979798 -286.145986)
			)
			(arc
				(start 195.470018 -286.145986)
				(mid 195.486216 -286.14342)
				(end 195.500752 -286.135826)
			)
			(arc
				(start 195.500752 -286.135826)
				(mid 195.594872 -286.08617)
				(end 195.699888 -286.069024)
			)
			(arc
				(start 195.699888 -286.069024)
				(mid 195.804887 -286.08622)
				(end 195.899024 -286.135826)
			)
			(arc
				(start 195.899024 -286.135826)
				(mid 195.91356 -286.143419)
				(end 195.929758 -286.145986)
			)
			(arc
				(start 196.419978 -286.145986)
				(mid 196.436176 -286.14342)
				(end 196.450712 -286.135826)
			)
			(arc
				(start 196.450712 -286.135826)
				(mid 196.544832 -286.08617)
				(end 196.649848 -286.069024)
			)
			(arc
				(start 196.649848 -286.069024)
				(mid 196.754847 -286.08622)
				(end 196.848984 -286.135826)
			)
			(arc
				(start 196.848984 -286.135826)
				(mid 196.86352 -286.143419)
				(end 196.879718 -286.145986)
			)
			(arc
				(start 197.370192 -286.145986)
				(mid 197.38639 -286.14342)
				(end 197.400926 -286.135826)
			)
			(arc
				(start 197.400926 -286.135826)
				(mid 197.495046 -286.08617)
				(end 197.600062 -286.069024)
			)
			(arc
				(start 197.600062 -286.069024)
				(mid 197.705061 -286.08622)
				(end 197.799198 -286.135826)
			)
			(arc
				(start 197.799198 -286.135826)
				(mid 197.813734 -286.143419)
				(end 197.829932 -286.145986)
			)
			(arc
				(start 198.320152 -286.145986)
				(mid 198.33635 -286.14342)
				(end 198.350886 -286.135826)
			)
			(arc
				(start 198.350886 -286.135826)
				(mid 198.445006 -286.08617)
				(end 198.550022 -286.069024)
			)
			(arc
				(start 198.550022 -286.069024)
				(mid 198.568465 -286.069525)
				(end 198.586852 -286.071056)
			)
			(xy 198.598536 -286.072326) (xy 198.620126 -286.06496)
			(arc
				(start 198.692516 -285.99257)
				(mid 198.703627 -285.976036)
				(end 198.707502 -285.956502)
			)
			(arc
				(start 198.707502 -272.836894)
				(mid 198.703601 -272.817371)
				(end 198.692516 -272.800826)
			)
			(xy 198.216266 -272.324576) (xy 198.199756 -272.316956)
			(arc
				(start 198.190866 -272.316194)
				(mid 198.166332 -272.31334)
				(end 198.142098 -272.308574)
			)
			(xy 198.136256 -272.307304)
			(arc
				(start 196.96938 -272.307304)
				(mid 196.945131 -272.313465)
				(end 196.926708 -272.330418)
			)
			(arc
				(start 196.926708 -272.330418)
				(mid 196.649848 -272.480262)
				(end 196.372988 -272.330418)
			)
			(arc
				(start 196.372988 -272.330418)
				(mid 196.354597 -272.313407)
				(end 196.330316 -272.307304)
			)
			(arc
				(start 195.06946 -272.307304)
				(mid 195.045211 -272.313465)
				(end 195.026788 -272.330418)
			)
			(arc
				(start 195.026788 -272.330418)
				(mid 194.749928 -272.480262)
				(end 194.473068 -272.330418)
			)
			(arc
				(start 194.473068 -272.330418)
				(mid 194.454677 -272.313407)
				(end 194.430396 -272.307304)
			)
			(arc
				(start 193.16954 -272.307304)
				(mid 193.145291 -272.313465)
				(end 193.126868 -272.330418)
			)
			(arc
				(start 193.126868 -272.330418)
				(mid 192.850008 -272.480262)
				(end 192.573148 -272.330418)
			)
			(arc
				(start 192.573148 -272.330418)
				(mid 192.554757 -272.313407)
				(end 192.530476 -272.307304)
			)
			(arc
				(start 191.269366 -272.307304)
				(mid 191.245117 -272.313465)
				(end 191.226694 -272.330418)
			)
			(arc
				(start 191.226694 -272.330418)
				(mid 190.949834 -272.480262)
				(end 190.672974 -272.330418)
			)
			(arc
				(start 190.672974 -272.330418)
				(mid 190.654583 -272.313407)
				(end 190.630302 -272.307304)
			)
			(arc
				(start 189.369192 -272.307304)
				(mid 189.344943 -272.313465)
				(end 189.32652 -272.330418)
			)
			(arc
				(start 189.32652 -272.330418)
				(mid 189.04966 -272.480262)
				(end 188.7728 -272.330418)
			)
			(arc
				(start 188.7728 -272.330418)
				(mid 188.754409 -272.313407)
				(end 188.730128 -272.307304)
			)
			(arc
				(start 187.469272 -272.307304)
				(mid 187.445023 -272.313465)
				(end 187.4266 -272.330418)
			)
			(arc
				(start 187.4266 -272.330418)
				(mid 187.14974 -272.480262)
				(end 186.87288 -272.330418)
			)
			(arc
				(start 186.87288 -272.330418)
				(mid 186.854489 -272.313407)
				(end 186.830208 -272.307304)
			)
			(arc
				(start 185.569352 -272.307304)
				(mid 185.545103 -272.313465)
				(end 185.52668 -272.330418)
			)
			(arc
				(start 185.52668 -272.330418)
				(mid 185.24982 -272.480262)
				(end 184.97296 -272.330418)
			)
			(arc
				(start 184.97296 -272.330418)
				(mid 184.954569 -272.313407)
				(end 184.930288 -272.307304)
			)
			(arc
				(start 183.669178 -272.307304)
				(mid 183.644929 -272.313465)
				(end 183.626506 -272.330418)
			)
			(arc
				(start 183.626506 -272.330418)
				(mid 183.349646 -272.480262)
				(end 183.072786 -272.330418)
			)
			(arc
				(start 183.072786 -272.330418)
				(mid 183.054395 -272.313407)
				(end 183.030114 -272.307304)
			)
			(arc
				(start 181.769258 -272.307304)
				(mid 181.745009 -272.313465)
				(end 181.726586 -272.330418)
			)
			(arc
				(start 181.726586 -272.330418)
				(mid 181.449726 -272.480262)
				(end 181.172866 -272.330418)
			)
			(arc
				(start 181.172866 -272.330418)
				(mid 181.154475 -272.313407)
				(end 181.130194 -272.307304)
			)
			(arc
				(start 179.869338 -272.307304)
				(mid 179.845089 -272.313465)
				(end 179.826666 -272.330418)
			)
			(arc
				(start 179.826666 -272.330418)
				(mid 179.549806 -272.480262)
				(end 179.272946 -272.330418)
			)
			(arc
				(start 179.272946 -272.330418)
				(mid 179.254555 -272.313407)
				(end 179.230274 -272.307304)
			)
			(arc
				(start 177.969164 -272.307304)
				(mid 177.944915 -272.313465)
				(end 177.926492 -272.330418)
			)
			(arc
				(start 177.926492 -272.330418)
				(mid 177.649632 -272.480262)
				(end 177.372772 -272.330418)
			)
			(arc
				(start 177.372772 -272.330418)
				(mid 177.354381 -272.313407)
				(end 177.3301 -272.307304)
			)
			(arc
				(start 176.06899 -272.307304)
				(mid 176.044883 -272.313525)
				(end 176.026572 -272.330418)
			)
			(arc
				(start 176.026572 -272.330418)
				(mid 175.749712 -272.480032)
				(end 175.472852 -272.330418)
			)
			(arc
				(start 175.472852 -272.330418)
				(mid 175.454573 -272.313467)
				(end 175.430434 -272.307304)
			)
			(arc
				(start 174.169324 -272.307304)
				(mid 174.145075 -272.313465)
				(end 174.126652 -272.330418)
			)
			(arc
				(start 174.126652 -272.330418)
				(mid 173.849792 -272.480262)
				(end 173.572932 -272.330418)
			)
			(arc
				(start 173.572932 -272.330418)
				(mid 173.554541 -272.313407)
				(end 173.53026 -272.307304)
			)
			(arc
				(start 172.26915 -272.307304)
				(mid 172.244901 -272.313465)
				(end 172.226478 -272.330418)
			)
			(arc
				(start 172.226478 -272.330418)
				(mid 171.949618 -272.480262)
				(end 171.672758 -272.330418)
			)
			(arc
				(start 171.672758 -272.330418)
				(mid 171.654367 -272.313407)
				(end 171.630086 -272.307304)
			)
			(arc
				(start 170.36923 -272.307304)
				(mid 170.344981 -272.313465)
				(end 170.326558 -272.330418)
			)
			(arc
				(start 170.326558 -272.330418)
				(mid 170.049698 -272.480262)
				(end 169.772838 -272.330418)
			)
			(arc
				(start 169.772838 -272.330418)
				(mid 169.754447 -272.313407)
				(end 169.730166 -272.307304)
			)
			(arc
				(start 168.46931 -272.307304)
				(mid 168.445061 -272.313465)
				(end 168.426638 -272.330418)
			)
			(arc
				(start 168.426638 -272.330418)
				(mid 168.149778 -272.480262)
				(end 167.872918 -272.330418)
			)
			(arc
				(start 167.872918 -272.330418)
				(mid 167.854527 -272.313407)
				(end 167.830246 -272.307304)
			)
			(arc
				(start 166.569136 -272.307304)
				(mid 166.544887 -272.313465)
				(end 166.526464 -272.330418)
			)
			(arc
				(start 166.526464 -272.330418)
				(mid 166.249604 -272.480262)
				(end 165.972744 -272.330418)
			)
			(arc
				(start 165.972744 -272.330418)
				(mid 165.954353 -272.313407)
				(end 165.930072 -272.307304)
			)
			(arc
				(start 164.669216 -272.307304)
				(mid 164.644967 -272.313465)
				(end 164.626544 -272.330418)
			)
			(arc
				(start 164.626544 -272.330418)
				(mid 164.349684 -272.480262)
				(end 164.072824 -272.330418)
			)
			(arc
				(start 164.072824 -272.330418)
				(mid 164.054433 -272.313407)
				(end 164.030152 -272.307304)
			)
			(arc
				(start 162.769296 -272.307304)
				(mid 162.745047 -272.313465)
				(end 162.726624 -272.330418)
			)
			(arc
				(start 162.726624 -272.330418)
				(mid 162.449764 -272.480262)
				(end 162.172904 -272.330418)
			)
			(arc
				(start 162.172904 -272.330418)
				(mid 162.154513 -272.313407)
				(end 162.130232 -272.307304)
			)
			(arc
				(start 160.869122 -272.307304)
				(mid 160.844873 -272.313465)
				(end 160.82645 -272.330418)
			)
			(arc
				(start 160.82645 -272.330418)
				(mid 160.54959 -272.480262)
				(end 160.27273 -272.330418)
			)
			(arc
				(start 160.27273 -272.330418)
				(mid 160.254339 -272.313407)
				(end 160.230058 -272.307304)
			)
			(arc
				(start 150.324312 -272.307304)
				(mid 150.294229 -272.316983)
				(end 150.275798 -272.34261)
			)
			(arc
				(start 150.275798 -272.34261)
				(mid 148.552755 -274.735363)
				(end 145.749772 -275.650452)
			)
			(arc
				(start 145.749772 -275.650452)
				(mid 142.390707 -274.259029)
				(end 140.999464 -270.89989)
			)
			(xy 141.00048 -270.796512) (xy 141.000734 -270.786098) (xy 140.993114 -270.767048)
			(arc
				(start 140.779246 -270.55318)
				(mid 140.762712 -270.542069)
				(end 140.743178 -270.538194)
			)
			(arc
				(start 132.70738 -270.538194)
				(mid 132.687857 -270.542095)
				(end 132.671312 -270.55318)
			)
			(arc
				(start 131.010152 -272.21434)
				(mid 130.90712 -272.283121)
				(end 130.785616 -272.307304)
			)
			(arc
				(start 94.224348 -272.307304)
				(mid 94.194265 -272.316983)
				(end 94.175834 -272.34261)
			)
			(arc
				(start 94.175834 -272.34261)
				(mid 89.649808 -275.650472)
				(end 85.123782 -272.34261)
			)
			(arc
				(start 85.123782 -272.34261)
				(mid 85.105284 -272.317076)
				(end 85.075268 -272.307304)
			)
			(arc
				(start 80.869282 -272.307304)
				(mid 80.845033 -272.313465)
				(end 80.82661 -272.330418)
			)
			(arc
				(start 80.82661 -272.330418)
				(mid 80.54975 -272.480262)
				(end 80.27289 -272.330418)
			)
			(arc
				(start 80.27289 -272.330418)
				(mid 80.254499 -272.313407)
				(end 80.230218 -272.307304)
			)
			(arc
				(start 78.969362 -272.307304)
				(mid 78.945113 -272.313465)
				(end 78.92669 -272.330418)
			)
			(arc
				(start 78.92669 -272.330418)
				(mid 78.64983 -272.480262)
				(end 78.37297 -272.330418)
			)
			(arc
				(start 78.37297 -272.330418)
				(mid 78.354579 -272.313407)
				(end 78.330298 -272.307304)
			)
			(arc
				(start 77.069442 -272.307304)
				(mid 77.045193 -272.313465)
				(end 77.02677 -272.330418)
			)
			(arc
				(start 77.02677 -272.330418)
				(mid 76.74991 -272.480262)
				(end 76.47305 -272.330418)
			)
			(arc
				(start 76.47305 -272.330418)
				(mid 76.454659 -272.313407)
				(end 76.430378 -272.307304)
			)
			(arc
				(start 75.169268 -272.307304)
				(mid 75.145019 -272.313465)
				(end 75.126596 -272.330418)
			)
			(arc
				(start 75.126596 -272.330418)
				(mid 74.849736 -272.480262)
				(end 74.572876 -272.330418)
			)
			(arc
				(start 74.572876 -272.330418)
				(mid 74.554485 -272.313407)
				(end 74.530204 -272.307304)
			)
			(arc
				(start 73.269094 -272.307304)
				(mid 73.244845 -272.313465)
				(end 73.226422 -272.330418)
			)
			(arc
				(start 73.226422 -272.330418)
				(mid 72.949562 -272.480262)
				(end 72.672702 -272.330418)
			)
			(arc
				(start 72.672702 -272.330418)
				(mid 72.654311 -272.313407)
				(end 72.63003 -272.307304)
			)
			(arc
				(start 71.369174 -272.307304)
				(mid 71.344925 -272.313465)
				(end 71.326502 -272.330418)
			)
			(arc
				(start 71.326502 -272.330418)
				(mid 71.049642 -272.480262)
				(end 70.772782 -272.330418)
			)
			(arc
				(start 70.772782 -272.330418)
				(mid 70.754391 -272.313407)
				(end 70.73011 -272.307304)
			)
			(arc
				(start 69.469254 -272.307304)
				(mid 69.445005 -272.313465)
				(end 69.426582 -272.330418)
			)
			(arc
				(start 69.426582 -272.330418)
				(mid 69.149722 -272.480262)
				(end 68.872862 -272.330418)
			)
			(arc
				(start 68.872862 -272.330418)
				(mid 68.854471 -272.313407)
				(end 68.83019 -272.307304)
			)
			(arc
				(start 67.56908 -272.307304)
				(mid 67.544831 -272.313465)
				(end 67.526408 -272.330418)
			)
			(arc
				(start 67.526408 -272.330418)
				(mid 67.249548 -272.480262)
				(end 66.972688 -272.330418)
			)
			(arc
				(start 66.972688 -272.330418)
				(mid 66.954297 -272.313407)
				(end 66.930016 -272.307304)
			)
			(arc
				(start 65.66916 -272.307304)
				(mid 65.644911 -272.313465)
				(end 65.626488 -272.330418)
			)
			(arc
				(start 65.626488 -272.330418)
				(mid 65.349628 -272.480262)
				(end 65.072768 -272.330418)
			)
			(arc
				(start 65.072768 -272.330418)
				(mid 65.054377 -272.313407)
				(end 65.030096 -272.307304)
			)
			(arc
				(start 63.76924 -272.307304)
				(mid 63.744991 -272.313465)
				(end 63.726568 -272.330418)
			)
			(arc
				(start 63.726568 -272.330418)
				(mid 63.449708 -272.480262)
				(end 63.172848 -272.330418)
			)
			(arc
				(start 63.172848 -272.330418)
				(mid 63.154457 -272.313407)
				(end 63.130176 -272.307304)
			)
			(arc
				(start 61.869066 -272.307304)
				(mid 61.844817 -272.313465)
				(end 61.826394 -272.330418)
			)
			(arc
				(start 61.826394 -272.330418)
				(mid 61.549534 -272.480262)
				(end 61.272674 -272.330418)
			)
			(arc
				(start 61.272674 -272.330418)
				(mid 61.254283 -272.313407)
				(end 61.230002 -272.307304)
			)
			(arc
				(start 59.968892 -272.307304)
				(mid 59.944785 -272.313525)
				(end 59.926474 -272.330418)
			)
			(arc
				(start 59.926474 -272.330418)
				(mid 59.649614 -272.480032)
				(end 59.372754 -272.330418)
			)
			(arc
				(start 59.372754 -272.330418)
				(mid 59.354475 -272.313467)
				(end 59.330336 -272.307304)
			)
			(arc
				(start 58.069226 -272.307304)
				(mid 58.044977 -272.313465)
				(end 58.026554 -272.330418)
			)
			(arc
				(start 58.026554 -272.330418)
				(mid 57.749694 -272.480262)
				(end 57.472834 -272.330418)
			)
			(arc
				(start 57.472834 -272.330418)
				(mid 57.454443 -272.313407)
				(end 57.430162 -272.307304)
			)
			(arc
				(start 56.169052 -272.307304)
				(mid 56.144803 -272.313465)
				(end 56.12638 -272.330418)
			)
			(arc
				(start 56.12638 -272.330418)
				(mid 55.84952 -272.480262)
				(end 55.57266 -272.330418)
			)
			(arc
				(start 55.57266 -272.330418)
				(mid 55.554269 -272.313407)
				(end 55.529988 -272.307304)
			)
			(arc
				(start 54.269132 -272.307304)
				(mid 54.244883 -272.313465)
				(end 54.22646 -272.330418)
			)
			(arc
				(start 54.22646 -272.330418)
				(mid 53.9496 -272.480262)
				(end 53.67274 -272.330418)
			)
			(arc
				(start 53.67274 -272.330418)
				(mid 53.654349 -272.313407)
				(end 53.630068 -272.307304)
			)
			(arc
				(start 52.369212 -272.307304)
				(mid 52.344963 -272.313465)
				(end 52.32654 -272.330418)
			)
			(arc
				(start 52.32654 -272.330418)
				(mid 52.04968 -272.480262)
				(end 51.77282 -272.330418)
			)
			(arc
				(start 51.77282 -272.330418)
				(mid 51.754429 -272.313407)
				(end 51.730148 -272.307304)
			)
			(arc
				(start 50.469038 -272.307304)
				(mid 50.444789 -272.313465)
				(end 50.426366 -272.330418)
			)
			(arc
				(start 50.426366 -272.330418)
				(mid 50.149506 -272.480262)
				(end 49.872646 -272.330418)
			)
			(arc
				(start 49.872646 -272.330418)
				(mid 49.854255 -272.313407)
				(end 49.829974 -272.307304)
			)
			(arc
				(start 48.569118 -272.307304)
				(mid 48.544869 -272.313465)
				(end 48.526446 -272.330418)
			)
			(arc
				(start 48.526446 -272.330418)
				(mid 48.249586 -272.480262)
				(end 47.972726 -272.330418)
			)
			(arc
				(start 47.972726 -272.330418)
				(mid 47.954335 -272.313407)
				(end 47.930054 -272.307304)
			)
			(arc
				(start 46.669198 -272.307304)
				(mid 46.644949 -272.313465)
				(end 46.626526 -272.330418)
			)
			(arc
				(start 46.626526 -272.330418)
				(mid 46.349666 -272.480262)
				(end 46.072806 -272.330418)
			)
			(arc
				(start 46.072806 -272.330418)
				(mid 46.054415 -272.313407)
				(end 46.030134 -272.307304)
			)
			(arc
				(start 44.769024 -272.307304)
				(mid 44.744775 -272.313465)
				(end 44.726352 -272.330418)
			)
			(arc
				(start 44.726352 -272.330418)
				(mid 44.449492 -272.480262)
				(end 44.172632 -272.330418)
			)
			(arc
				(start 44.172632 -272.330418)
				(mid 44.154241 -272.313407)
				(end 44.12996 -272.307304)
			)
			(arc
				(start 37.075618 -272.307304)
				(mid 37.056095 -272.311205)
				(end 37.03955 -272.32229)
			)
			(arc
				(start 36.707064 -272.654776)
				(mid 36.695953 -272.67131)
				(end 36.692078 -272.690844)
			)
			(xy 36.692078 -275.381212)
			(arc
				(start 36.693856 -275.387816)
				(mid 36.705538 -275.474938)
				(end 36.693856 -275.56206)
			)
			(xy 36.692078 -275.568664) (xy 36.692078 -276.331172)
			(arc
				(start 36.693856 -276.337776)
				(mid 36.705538 -276.424898)
				(end 36.693856 -276.51202)
			)
			(xy 36.692078 -276.518624) (xy 36.692078 -277.281132)
			(arc
				(start 36.693856 -277.287736)
				(mid 36.705538 -277.374858)
				(end 36.693856 -277.46198)
			)
			(xy 36.692078 -277.468584) (xy 36.692078 -278.231092)
			(arc
				(start 36.693856 -278.237696)
				(mid 36.705538 -278.324818)
				(end 36.693856 -278.41194)
			)
			(xy 36.692078 -278.418544) (xy 36.692078 -279.181052)
			(arc
				(start 36.693856 -279.187656)
				(mid 36.705538 -279.274778)
				(end 36.693856 -279.3619)
			)
			(xy 36.692078 -279.368504) (xy 36.692078 -280.131012)
			(arc
				(start 36.693856 -280.137616)
				(mid 36.705538 -280.224738)
				(end 36.693856 -280.31186)
			)
			(xy 36.692078 -280.318464) (xy 36.692078 -281.081226)
			(arc
				(start 36.693856 -281.08783)
				(mid 36.705538 -281.174952)
				(end 36.693856 -281.262074)
			)
			(xy 36.692078 -281.268678) (xy 36.692078 -282.031186)
			(arc
				(start 36.693856 -282.03779)
				(mid 36.705538 -282.124912)
				(end 36.693856 -282.212034)
			)
			(xy 36.692078 -282.218638) (xy 36.692078 -282.981146)
			(arc
				(start 36.693856 -282.98775)
				(mid 36.705538 -283.074872)
				(end 36.693856 -283.161994)
			)
			(xy 36.692078 -283.168598) (xy 36.692078 -283.931106)
			(arc
				(start 36.693856 -283.93771)
				(mid 36.705538 -284.024832)
				(end 36.693856 -284.111954)
			)
			(xy 36.692078 -284.118558) (xy 36.692078 -284.881066)
			(arc
				(start 36.693856 -284.88767)
				(mid 36.705538 -284.974792)
				(end 36.693856 -285.061914)
			)
			(xy 36.692078 -285.068518)
			(arc
				(start 36.692078 -285.56331)
				(mid 36.695979 -285.582833)
				(end 36.707064 -285.599378)
			)
			(arc
				(start 36.763452 -285.655766)
				(mid 36.779986 -285.666877)
				(end 36.79952 -285.670752)
			)
			(arc
				(start 37.09543 -285.670752)
				(mid 37.111494 -285.668145)
				(end 37.12591 -285.660592)
			)
			(arc
				(start 37.12591 -285.660592)
				(mid 37.324792 -285.594043)
				(end 37.523674 -285.660592)
			)
			(arc
				(start 37.523674 -285.660592)
				(mid 37.53809 -285.668145)
				(end 37.554154 -285.670752)
			)
			(arc
				(start 38.045644 -285.670752)
				(mid 38.061708 -285.668145)
				(end 38.076124 -285.660592)
			)
			(arc
				(start 38.076124 -285.660592)
				(mid 38.275006 -285.594043)
				(end 38.473888 -285.660592)
			)
			(arc
				(start 38.473888 -285.660592)
				(mid 38.488304 -285.668145)
				(end 38.504368 -285.670752)
			)
			(arc
				(start 38.995604 -285.670752)
				(mid 39.011668 -285.668145)
				(end 39.026084 -285.660592)
			)
			(arc
				(start 39.026084 -285.660592)
				(mid 39.224966 -285.594043)
				(end 39.423848 -285.660592)
			)
			(arc
				(start 39.423848 -285.660592)
				(mid 39.438264 -285.668145)
				(end 39.454328 -285.670752)
			)
			(arc
				(start 39.945564 -285.670752)
				(mid 39.961628 -285.668145)
				(end 39.976044 -285.660592)
			)
			(arc
				(start 39.976044 -285.660592)
				(mid 40.174926 -285.594043)
				(end 40.373808 -285.660592)
			)
			(arc
				(start 40.373808 -285.660592)
				(mid 40.388224 -285.668145)
				(end 40.404288 -285.670752)
			)
			(arc
				(start 40.895524 -285.670752)
				(mid 40.911588 -285.668145)
				(end 40.926004 -285.660592)
			)
			(arc
				(start 40.926004 -285.660592)
				(mid 41.124886 -285.594043)
				(end 41.323768 -285.660592)
			)
			(arc
				(start 41.323768 -285.660592)
				(mid 41.338184 -285.668145)
				(end 41.354248 -285.670752)
			)
			(arc
				(start 44.695618 -285.670752)
				(mid 44.711682 -285.668145)
				(end 44.726098 -285.660592)
			)
			(arc
				(start 44.726098 -285.660592)
				(mid 44.92498 -285.594043)
				(end 45.123862 -285.660592)
			)
			(arc
				(start 45.123862 -285.660592)
				(mid 45.138278 -285.668145)
				(end 45.154342 -285.670752)
			)
			(arc
				(start 45.645578 -285.670752)
				(mid 45.661642 -285.668145)
				(end 45.676058 -285.660592)
			)
			(arc
				(start 45.676058 -285.660592)
				(mid 45.87494 -285.594043)
				(end 46.073822 -285.660592)
			)
			(arc
				(start 46.073822 -285.660592)
				(mid 46.088238 -285.668145)
				(end 46.104302 -285.670752)
			)
			(arc
				(start 46.595538 -285.670752)
				(mid 46.611602 -285.668145)
				(end 46.626018 -285.660592)
			)
			(arc
				(start 46.626018 -285.660592)
				(mid 46.8249 -285.594043)
				(end 47.023782 -285.660592)
			)
			(arc
				(start 47.023782 -285.660592)
				(mid 47.038198 -285.668145)
				(end 47.054262 -285.670752)
			)
			(arc
				(start 47.545498 -285.670752)
				(mid 47.561562 -285.668145)
				(end 47.575978 -285.660592)
			)
			(arc
				(start 47.575978 -285.660592)
				(mid 47.77486 -285.594043)
				(end 47.973742 -285.660592)
			)
			(arc
				(start 47.973742 -285.660592)
				(mid 47.988158 -285.668145)
				(end 48.004222 -285.670752)
			)
			(arc
				(start 48.495458 -285.670752)
				(mid 48.511522 -285.668145)
				(end 48.525938 -285.660592)
			)
			(arc
				(start 48.525938 -285.660592)
				(mid 48.72482 -285.594043)
				(end 48.923702 -285.660592)
			)
			(arc
				(start 48.923702 -285.660592)
				(mid 48.938118 -285.668145)
				(end 48.954182 -285.670752)
			)
			(arc
				(start 49.445418 -285.670752)
				(mid 49.461482 -285.668145)
				(end 49.475898 -285.660592)
			)
			(arc
				(start 49.475898 -285.660592)
				(mid 49.67478 -285.594043)
				(end 49.873662 -285.660592)
			)
			(arc
				(start 49.873662 -285.660592)
				(mid 49.888078 -285.668145)
				(end 49.904142 -285.670752)
			)
			(arc
				(start 50.395632 -285.670752)
				(mid 50.411696 -285.668145)
				(end 50.426112 -285.660592)
			)
			(arc
				(start 50.426112 -285.660592)
				(mid 50.624994 -285.594043)
				(end 50.823876 -285.660592)
			)
			(arc
				(start 50.823876 -285.660592)
				(mid 50.838292 -285.668145)
				(end 50.854356 -285.670752)
			)
			(arc
				(start 51.345592 -285.670752)
				(mid 51.361656 -285.668145)
				(end 51.376072 -285.660592)
			)
			(arc
				(start 51.376072 -285.660592)
				(mid 51.574954 -285.594043)
				(end 51.773836 -285.660592)
			)
			(arc
				(start 51.773836 -285.660592)
				(mid 51.788252 -285.668145)
				(end 51.804316 -285.670752)
			)
			(arc
				(start 52.295552 -285.670752)
				(mid 52.311616 -285.668145)
				(end 52.326032 -285.660592)
			)
			(arc
				(start 52.326032 -285.660592)
				(mid 52.524914 -285.594043)
				(end 52.723796 -285.660592)
			)
			(arc
				(start 52.723796 -285.660592)
				(mid 52.738212 -285.668145)
				(end 52.754276 -285.670752)
			)
			(arc
				(start 53.245512 -285.670752)
				(mid 53.261576 -285.668145)
				(end 53.275992 -285.660592)
			)
			(arc
				(start 53.275992 -285.660592)
				(mid 53.474874 -285.594043)
				(end 53.673756 -285.660592)
			)
			(arc
				(start 53.673756 -285.660592)
				(mid 53.688172 -285.668145)
				(end 53.704236 -285.670752)
			)
			(arc
				(start 54.195472 -285.670752)
				(mid 54.211536 -285.668145)
				(end 54.225952 -285.660592)
			)
			(arc
				(start 54.225952 -285.660592)
				(mid 54.424834 -285.594043)
				(end 54.623716 -285.660592)
			)
			(arc
				(start 54.623716 -285.660592)
				(mid 54.638132 -285.668145)
				(end 54.654196 -285.670752)
			)
			(arc
				(start 55.145432 -285.670752)
				(mid 55.161496 -285.668145)
				(end 55.175912 -285.660592)
			)
			(arc
				(start 55.175912 -285.660592)
				(mid 55.374794 -285.594043)
				(end 55.573676 -285.660592)
			)
			(arc
				(start 55.573676 -285.660592)
				(mid 55.588092 -285.668145)
				(end 55.604156 -285.670752)
			)
			(arc
				(start 56.095392 -285.670752)
				(mid 56.111456 -285.668145)
				(end 56.125872 -285.660592)
			)
			(arc
				(start 56.125872 -285.660592)
				(mid 56.324754 -285.594043)
				(end 56.523636 -285.660592)
			)
			(arc
				(start 56.523636 -285.660592)
				(mid 56.538052 -285.668145)
				(end 56.554116 -285.670752)
			)
			(arc
				(start 57.045606 -285.670752)
				(mid 57.06167 -285.668145)
				(end 57.076086 -285.660592)
			)
			(arc
				(start 57.076086 -285.660592)
				(mid 57.274968 -285.594043)
				(end 57.47385 -285.660592)
			)
			(arc
				(start 57.47385 -285.660592)
				(mid 57.488266 -285.668145)
				(end 57.50433 -285.670752)
			)
			(arc
				(start 57.995566 -285.670752)
				(mid 58.01163 -285.668145)
				(end 58.026046 -285.660592)
			)
			(arc
				(start 58.026046 -285.660592)
				(mid 58.224928 -285.594043)
				(end 58.42381 -285.660592)
			)
			(arc
				(start 58.42381 -285.660592)
				(mid 58.438226 -285.668145)
				(end 58.45429 -285.670752)
			)
			(arc
				(start 59.895486 -285.670752)
				(mid 59.91155 -285.668145)
				(end 59.925966 -285.660592)
			)
			(arc
				(start 59.925966 -285.660592)
				(mid 60.124848 -285.594043)
				(end 60.32373 -285.660592)
			)
			(arc
				(start 60.32373 -285.660592)
				(mid 60.338146 -285.668145)
				(end 60.35421 -285.670752)
			)
			(arc
				(start 60.845446 -285.670752)
				(mid 60.86151 -285.668145)
				(end 60.875926 -285.660592)
			)
			(arc
				(start 60.875926 -285.660592)
				(mid 61.074808 -285.594043)
				(end 61.27369 -285.660592)
			)
			(arc
				(start 61.27369 -285.660592)
				(mid 61.288106 -285.668145)
				(end 61.30417 -285.670752)
			)
			(arc
				(start 61.795406 -285.670752)
				(mid 61.81147 -285.668145)
				(end 61.825886 -285.660592)
			)
			(arc
				(start 61.825886 -285.660592)
				(mid 62.024768 -285.594043)
				(end 62.22365 -285.660592)
			)
			(arc
				(start 62.22365 -285.660592)
				(mid 62.238066 -285.668145)
				(end 62.25413 -285.670752)
			)
			(arc
				(start 62.74562 -285.670752)
				(mid 62.761684 -285.668145)
				(end 62.7761 -285.660592)
			)
			(arc
				(start 62.7761 -285.660592)
				(mid 62.974982 -285.594043)
				(end 63.173864 -285.660592)
			)
			(arc
				(start 63.173864 -285.660592)
				(mid 63.18828 -285.668145)
				(end 63.204344 -285.670752)
			)
			(arc
				(start 63.69558 -285.670752)
				(mid 63.711644 -285.668145)
				(end 63.72606 -285.660592)
			)
			(arc
				(start 63.72606 -285.660592)
				(mid 63.924942 -285.594043)
				(end 64.123824 -285.660592)
			)
			(arc
				(start 64.123824 -285.660592)
				(mid 64.13824 -285.668145)
				(end 64.154304 -285.670752)
			)
			(arc
				(start 64.64554 -285.670752)
				(mid 64.661604 -285.668145)
				(end 64.67602 -285.660592)
			)
			(arc
				(start 64.67602 -285.660592)
				(mid 64.874902 -285.594043)
				(end 65.073784 -285.660592)
			)
			(arc
				(start 65.073784 -285.660592)
				(mid 65.0882 -285.668145)
				(end 65.104264 -285.670752)
			)
			(arc
				(start 65.5955 -285.670752)
				(mid 65.611564 -285.668145)
				(end 65.62598 -285.660592)
			)
			(arc
				(start 65.62598 -285.660592)
				(mid 65.824862 -285.594043)
				(end 66.023744 -285.660592)
			)
			(arc
				(start 66.023744 -285.660592)
				(mid 66.03816 -285.668145)
				(end 66.054224 -285.670752)
			)
			(arc
				(start 66.54546 -285.670752)
				(mid 66.561524 -285.668145)
				(end 66.57594 -285.660592)
			)
			(arc
				(start 66.57594 -285.660592)
				(mid 66.774822 -285.594043)
				(end 66.973704 -285.660592)
			)
			(arc
				(start 66.973704 -285.660592)
				(mid 66.98812 -285.668145)
				(end 67.004184 -285.670752)
			)
			(arc
				(start 67.49542 -285.670752)
				(mid 67.511484 -285.668145)
				(end 67.5259 -285.660592)
			)
			(arc
				(start 67.5259 -285.660592)
				(mid 67.724782 -285.594043)
				(end 67.923664 -285.660592)
			)
			(arc
				(start 67.923664 -285.660592)
				(mid 67.93808 -285.668145)
				(end 67.954144 -285.670752)
			)
			(arc
				(start 68.44538 -285.670752)
				(mid 68.461444 -285.668145)
				(end 68.47586 -285.660592)
			)
			(arc
				(start 68.47586 -285.660592)
				(mid 68.674742 -285.594043)
				(end 68.873624 -285.660592)
			)
			(arc
				(start 68.873624 -285.660592)
				(mid 68.88804 -285.668145)
				(end 68.904104 -285.670752)
			)
			(arc
				(start 69.395594 -285.670752)
				(mid 69.411658 -285.668145)
				(end 69.426074 -285.660592)
			)
			(arc
				(start 69.426074 -285.660592)
				(mid 69.624956 -285.594043)
				(end 69.823838 -285.660592)
			)
			(arc
				(start 69.823838 -285.660592)
				(mid 69.838254 -285.668145)
				(end 69.854318 -285.670752)
			)
			(arc
				(start 70.345554 -285.670752)
				(mid 70.361618 -285.668145)
				(end 70.376034 -285.660592)
			)
			(arc
				(start 70.376034 -285.660592)
				(mid 70.574916 -285.594043)
				(end 70.773798 -285.660592)
			)
			(arc
				(start 70.773798 -285.660592)
				(mid 70.788214 -285.668145)
				(end 70.804278 -285.670752)
			)
			(arc
				(start 99.788726 -285.670752)
				(mid 99.808249 -285.666851)
				(end 99.824794 -285.655766)
			)
			(arc
				(start 99.983544 -285.497016)
				(mid 99.994655 -285.480482)
				(end 99.99853 -285.460948)
			)
			(arc
				(start 99.99853 -279.197562)
				(mid 100.01788 -279.100375)
				(end 100.072952 -279.017984)
			)
			(xy 100.304092 -278.786844) (xy 100.311966 -278.764746)
			(arc
				(start 100.310442 -278.753062)
				(mid 100.308524 -278.730874)
				(end 100.307902 -278.708612)
			)
			(arc
				(start 100.307902 -278.708612)
				(mid 100.419643 -278.438845)
				(end 100.68941 -278.327104)
			)
			(arc
				(start 100.68941 -278.327104)
				(mid 100.711672 -278.327724)
				(end 100.73386 -278.329644)
			)
			(xy 100.745544 -278.331168) (xy 100.767642 -278.323294)
			(arc
				(start 100.823522 -278.267414)
				(mid 100.905899 -278.212308)
				(end 101.0031 -278.192992)
			)
			(arc
				(start 133.460744 -278.192992)
				(mid 133.487403 -278.185435)
				(end 133.50621 -278.165052)
			)
			(xy 133.553454 -278.070818) (xy 133.550914 -278.04237)
			(arc
				(start 133.542278 -278.030686)
				(mid 133.043543 -277.074624)
				(end 132.871464 -276.010116)
			)
			(arc
				(start 132.871464 -276.010116)
				(mid 138.639279 -273.621009)
				(end 136.250172 -279.388824)
			)
			(arc
				(start 136.250172 -279.388824)
				(mid 136.053111 -279.383013)
				(end 135.856726 -279.36571)
			)
			(xy 135.84555 -279.36444) (xy 135.82523 -279.371044)
			(arc
				(start 135.760206 -279.428702)
				(mid 135.747637 -279.44593)
				(end 135.743188 -279.466802)
			)
			(arc
				(start 135.743188 -285.960312)
				(mid 135.747089 -285.979835)
				(end 135.758174 -285.99638)
			)
			(arc
				(start 135.892794 -286.131)
				(mid 135.909328 -286.142111)
				(end 135.928862 -286.145986)
			)
		)
		(stroke
			(width 0)
			(type solid)
		)
		(fill yes)
		(layer "In2.Cu")
		(net "P1V8_PEX")
	)
	(gr_poly
		(pts
			(arc
				(start 374.13184 -286.145986)
				(mid 374.155935 -286.139908)
				(end 374.174258 -286.123126)
			)
			(arc
				(start 374.174258 -286.123126)
				(mid 374.493536 -285.950429)
				(end 374.812814 -286.123126)
			)
			(arc
				(start 374.812814 -286.123126)
				(mid 374.831141 -286.139902)
				(end 374.855232 -286.145986)
			)
			(arc
				(start 375.607326 -286.145986)
				(mid 375.631421 -286.139908)
				(end 375.649744 -286.123126)
			)
			(arc
				(start 375.649744 -286.123126)
				(mid 375.969022 -285.950429)
				(end 376.2883 -286.123126)
			)
			(arc
				(start 376.2883 -286.123126)
				(mid 376.306627 -286.139902)
				(end 376.330718 -286.145986)
			)
			(arc
				(start 376.496326 -286.145986)
				(mid 376.520421 -286.139908)
				(end 376.538744 -286.123126)
			)
			(arc
				(start 376.538744 -286.123126)
				(mid 376.858022 -285.950429)
				(end 377.1773 -286.123126)
			)
			(arc
				(start 377.1773 -286.123126)
				(mid 377.195627 -286.139902)
				(end 377.219718 -286.145986)
			)
			(arc
				(start 379.669294 -286.145986)
				(mid 379.693389 -286.139908)
				(end 379.711712 -286.123126)
			)
			(arc
				(start 379.711712 -286.123126)
				(mid 380.03099 -285.950429)
				(end 380.350268 -286.123126)
			)
			(arc
				(start 380.350268 -286.123126)
				(mid 380.368595 -286.139902)
				(end 380.392686 -286.145986)
			)
			(arc
				(start 421.969946 -286.145986)
				(mid 421.986144 -286.14342)
				(end 422.00068 -286.135826)
			)
			(arc
				(start 422.00068 -286.135826)
				(mid 422.0948 -286.08617)
				(end 422.199816 -286.069024)
			)
			(arc
				(start 422.199816 -286.069024)
				(mid 422.304815 -286.08622)
				(end 422.398952 -286.135826)
			)
			(arc
				(start 422.398952 -286.135826)
				(mid 422.413488 -286.143419)
				(end 422.429686 -286.145986)
			)
			(arc
				(start 422.92016 -286.145986)
				(mid 422.936358 -286.14342)
				(end 422.950894 -286.135826)
			)
			(arc
				(start 422.950894 -286.135826)
				(mid 423.045014 -286.08617)
				(end 423.15003 -286.069024)
			)
			(arc
				(start 423.15003 -286.069024)
				(mid 423.255029 -286.08622)
				(end 423.349166 -286.135826)
			)
			(arc
				(start 423.349166 -286.135826)
				(mid 423.363702 -286.143419)
				(end 423.3799 -286.145986)
			)
			(arc
				(start 423.87012 -286.145986)
				(mid 423.886318 -286.14342)
				(end 423.900854 -286.135826)
			)
			(arc
				(start 423.900854 -286.135826)
				(mid 423.994974 -286.08617)
				(end 424.09999 -286.069024)
			)
			(arc
				(start 424.09999 -286.069024)
				(mid 424.204989 -286.08622)
				(end 424.299126 -286.135826)
			)
			(arc
				(start 424.299126 -286.135826)
				(mid 424.313662 -286.143419)
				(end 424.32986 -286.145986)
			)
			(arc
				(start 424.820588 -286.145986)
				(mid 424.836652 -286.143379)
				(end 424.851068 -286.135826)
			)
			(arc
				(start 424.851068 -286.135826)
				(mid 425.04995 -286.069277)
				(end 425.248832 -286.135826)
			)
			(arc
				(start 425.248832 -286.135826)
				(mid 425.263248 -286.143379)
				(end 425.279312 -286.145986)
			)
			(arc
				(start 425.770548 -286.145986)
				(mid 425.786612 -286.143379)
				(end 425.801028 -286.135826)
			)
			(arc
				(start 425.801028 -286.135826)
				(mid 425.99991 -286.069277)
				(end 426.198792 -286.135826)
			)
			(arc
				(start 426.198792 -286.135826)
				(mid 426.213208 -286.143379)
				(end 426.229272 -286.145986)
			)
			(arc
				(start 426.72 -286.145986)
				(mid 426.736198 -286.14342)
				(end 426.750734 -286.135826)
			)
			(arc
				(start 426.750734 -286.135826)
				(mid 426.844854 -286.08617)
				(end 426.94987 -286.069024)
			)
			(arc
				(start 426.94987 -286.069024)
				(mid 427.054869 -286.08622)
				(end 427.149006 -286.135826)
			)
			(arc
				(start 427.149006 -286.135826)
				(mid 427.163542 -286.143419)
				(end 427.17974 -286.145986)
			)
			(arc
				(start 427.66996 -286.145986)
				(mid 427.686158 -286.14342)
				(end 427.700694 -286.135826)
			)
			(arc
				(start 427.700694 -286.135826)
				(mid 427.794814 -286.08617)
				(end 427.89983 -286.069024)
			)
			(arc
				(start 427.89983 -286.069024)
				(mid 428.004829 -286.08622)
				(end 428.098966 -286.135826)
			)
			(arc
				(start 428.098966 -286.135826)
				(mid 428.113502 -286.143419)
				(end 428.1297 -286.145986)
			)
			(arc
				(start 428.61992 -286.145986)
				(mid 428.636118 -286.14342)
				(end 428.650654 -286.135826)
			)
			(arc
				(start 428.650654 -286.135826)
				(mid 428.744774 -286.08617)
				(end 428.84979 -286.069024)
			)
			(arc
				(start 428.84979 -286.069024)
				(mid 428.954789 -286.08622)
				(end 429.048926 -286.135826)
			)
			(arc
				(start 429.048926 -286.135826)
				(mid 429.063462 -286.143419)
				(end 429.07966 -286.145986)
			)
			(arc
				(start 429.570134 -286.145986)
				(mid 429.586332 -286.14342)
				(end 429.600868 -286.135826)
			)
			(arc
				(start 429.600868 -286.135826)
				(mid 429.694988 -286.08617)
				(end 429.800004 -286.069024)
			)
			(arc
				(start 429.800004 -286.069024)
				(mid 429.905003 -286.08622)
				(end 429.99914 -286.135826)
			)
			(arc
				(start 429.99914 -286.135826)
				(mid 430.013676 -286.143419)
				(end 430.029874 -286.145986)
			)
			(arc
				(start 430.520094 -286.145986)
				(mid 430.536292 -286.14342)
				(end 430.550828 -286.135826)
			)
			(arc
				(start 430.550828 -286.135826)
				(mid 430.644948 -286.08617)
				(end 430.749964 -286.069024)
			)
			(arc
				(start 430.749964 -286.069024)
				(mid 430.768407 -286.069525)
				(end 430.786794 -286.071056)
			)
			(xy 430.798478 -286.072326) (xy 430.820068 -286.06496)
			(arc
				(start 430.892458 -285.99257)
				(mid 430.903569 -285.976036)
				(end 430.907444 -285.956502)
			)
			(arc
				(start 430.907444 -272.836894)
				(mid 430.903543 -272.817371)
				(end 430.892458 -272.800826)
			)
			(xy 430.416208 -272.324576) (xy 430.399698 -272.316956)
			(arc
				(start 430.390808 -272.316194)
				(mid 430.366274 -272.31334)
				(end 430.34204 -272.308574)
			)
			(xy 430.336198 -272.307304)
			(arc
				(start 429.169322 -272.307304)
				(mid 429.145073 -272.313465)
				(end 429.12665 -272.330418)
			)
			(arc
				(start 429.12665 -272.330418)
				(mid 428.84979 -272.480262)
				(end 428.57293 -272.330418)
			)
			(arc
				(start 428.57293 -272.330418)
				(mid 428.554539 -272.313407)
				(end 428.530258 -272.307304)
			)
			(arc
				(start 427.269402 -272.307304)
				(mid 427.245153 -272.313465)
				(end 427.22673 -272.330418)
			)
			(arc
				(start 427.22673 -272.330418)
				(mid 426.94987 -272.480262)
				(end 426.67301 -272.330418)
			)
			(arc
				(start 426.67301 -272.330418)
				(mid 426.654619 -272.313407)
				(end 426.630338 -272.307304)
			)
			(arc
				(start 425.369482 -272.307304)
				(mid 425.345233 -272.313465)
				(end 425.32681 -272.330418)
			)
			(arc
				(start 425.32681 -272.330418)
				(mid 425.04995 -272.480262)
				(end 424.77309 -272.330418)
			)
			(arc
				(start 424.77309 -272.330418)
				(mid 424.754699 -272.313407)
				(end 424.730418 -272.307304)
			)
			(arc
				(start 423.469308 -272.307304)
				(mid 423.445059 -272.313465)
				(end 423.426636 -272.330418)
			)
			(arc
				(start 423.426636 -272.330418)
				(mid 423.149776 -272.480262)
				(end 422.872916 -272.330418)
			)
			(arc
				(start 422.872916 -272.330418)
				(mid 422.854525 -272.313407)
				(end 422.830244 -272.307304)
			)
			(arc
				(start 421.569134 -272.307304)
				(mid 421.544885 -272.313465)
				(end 421.526462 -272.330418)
			)
			(arc
				(start 421.526462 -272.330418)
				(mid 421.249602 -272.480262)
				(end 420.972742 -272.330418)
			)
			(arc
				(start 420.972742 -272.330418)
				(mid 420.954351 -272.313407)
				(end 420.93007 -272.307304)
			)
			(arc
				(start 419.669214 -272.307304)
				(mid 419.644965 -272.313465)
				(end 419.626542 -272.330418)
			)
			(arc
				(start 419.626542 -272.330418)
				(mid 419.349682 -272.480262)
				(end 419.072822 -272.330418)
			)
			(arc
				(start 419.072822 -272.330418)
				(mid 419.054431 -272.313407)
				(end 419.03015 -272.307304)
			)
			(arc
				(start 417.769294 -272.307304)
				(mid 417.745045 -272.313465)
				(end 417.726622 -272.330418)
			)
			(arc
				(start 417.726622 -272.330418)
				(mid 417.449762 -272.480262)
				(end 417.172902 -272.330418)
			)
			(arc
				(start 417.172902 -272.330418)
				(mid 417.154511 -272.313407)
				(end 417.13023 -272.307304)
			)
			(arc
				(start 415.86912 -272.307304)
				(mid 415.844871 -272.313465)
				(end 415.826448 -272.330418)
			)
			(arc
				(start 415.826448 -272.330418)
				(mid 415.549588 -272.480262)
				(end 415.272728 -272.330418)
			)
			(arc
				(start 415.272728 -272.330418)
				(mid 415.254337 -272.313407)
				(end 415.230056 -272.307304)
			)
			(arc
				(start 413.9692 -272.307304)
				(mid 413.944951 -272.313465)
				(end 413.926528 -272.330418)
			)
			(arc
				(start 413.926528 -272.330418)
				(mid 413.649668 -272.480262)
				(end 413.372808 -272.330418)
			)
			(arc
				(start 413.372808 -272.330418)
				(mid 413.354417 -272.313407)
				(end 413.330136 -272.307304)
			)
			(arc
				(start 412.06928 -272.307304)
				(mid 412.045031 -272.313465)
				(end 412.026608 -272.330418)
			)
			(arc
				(start 412.026608 -272.330418)
				(mid 411.749748 -272.480262)
				(end 411.472888 -272.330418)
			)
			(arc
				(start 411.472888 -272.330418)
				(mid 411.454497 -272.313407)
				(end 411.430216 -272.307304)
			)
			(arc
				(start 410.169106 -272.307304)
				(mid 410.144857 -272.313465)
				(end 410.126434 -272.330418)
			)
			(arc
				(start 410.126434 -272.330418)
				(mid 409.849574 -272.480262)
				(end 409.572714 -272.330418)
			)
			(arc
				(start 409.572714 -272.330418)
				(mid 409.554323 -272.313407)
				(end 409.530042 -272.307304)
			)
			(arc
				(start 408.268932 -272.307304)
				(mid 408.244825 -272.313525)
				(end 408.226514 -272.330418)
			)
			(arc
				(start 408.226514 -272.330418)
				(mid 407.949654 -272.480032)
				(end 407.672794 -272.330418)
			)
			(arc
				(start 407.672794 -272.330418)
				(mid 407.654515 -272.313467)
				(end 407.630376 -272.307304)
			)
			(arc
				(start 406.369266 -272.307304)
				(mid 406.345017 -272.313465)
				(end 406.326594 -272.330418)
			)
			(arc
				(start 406.326594 -272.330418)
				(mid 406.049734 -272.480262)
				(end 405.772874 -272.330418)
			)
			(arc
				(start 405.772874 -272.330418)
				(mid 405.754483 -272.313407)
				(end 405.730202 -272.307304)
			)
			(arc
				(start 404.469092 -272.307304)
				(mid 404.444843 -272.313465)
				(end 404.42642 -272.330418)
			)
			(arc
				(start 404.42642 -272.330418)
				(mid 404.14956 -272.480262)
				(end 403.8727 -272.330418)
			)
			(arc
				(start 403.8727 -272.330418)
				(mid 403.854309 -272.313407)
				(end 403.830028 -272.307304)
			)
			(arc
				(start 402.569172 -272.307304)
				(mid 402.544923 -272.313465)
				(end 402.5265 -272.330418)
			)
			(arc
				(start 402.5265 -272.330418)
				(mid 402.24964 -272.480262)
				(end 401.97278 -272.330418)
			)
			(arc
				(start 401.97278 -272.330418)
				(mid 401.954389 -272.313407)
				(end 401.930108 -272.307304)
			)
			(arc
				(start 400.669252 -272.307304)
				(mid 400.645003 -272.313465)
				(end 400.62658 -272.330418)
			)
			(arc
				(start 400.62658 -272.330418)
				(mid 400.34972 -272.480262)
				(end 400.07286 -272.330418)
			)
			(arc
				(start 400.07286 -272.330418)
				(mid 400.054469 -272.313407)
				(end 400.030188 -272.307304)
			)
			(arc
				(start 398.769078 -272.307304)
				(mid 398.744829 -272.313465)
				(end 398.726406 -272.330418)
			)
			(arc
				(start 398.726406 -272.330418)
				(mid 398.449546 -272.480262)
				(end 398.172686 -272.330418)
			)
			(arc
				(start 398.172686 -272.330418)
				(mid 398.154295 -272.313407)
				(end 398.130014 -272.307304)
			)
			(arc
				(start 396.869158 -272.307304)
				(mid 396.844909 -272.313465)
				(end 396.826486 -272.330418)
			)
			(arc
				(start 396.826486 -272.330418)
				(mid 396.549626 -272.480262)
				(end 396.272766 -272.330418)
			)
			(arc
				(start 396.272766 -272.330418)
				(mid 396.254375 -272.313407)
				(end 396.230094 -272.307304)
			)
			(arc
				(start 394.969238 -272.307304)
				(mid 394.944989 -272.313465)
				(end 394.926566 -272.330418)
			)
			(arc
				(start 394.926566 -272.330418)
				(mid 394.649706 -272.480262)
				(end 394.372846 -272.330418)
			)
			(arc
				(start 394.372846 -272.330418)
				(mid 394.354455 -272.313407)
				(end 394.330174 -272.307304)
			)
			(arc
				(start 393.069064 -272.307304)
				(mid 393.044815 -272.313465)
				(end 393.026392 -272.330418)
			)
			(arc
				(start 393.026392 -272.330418)
				(mid 392.749532 -272.480262)
				(end 392.472672 -272.330418)
			)
			(arc
				(start 392.472672 -272.330418)
				(mid 392.454281 -272.313407)
				(end 392.43 -272.307304)
			)
			(arc
				(start 382.524254 -272.307304)
				(mid 382.494171 -272.316983)
				(end 382.47574 -272.34261)
			)
			(arc
				(start 382.47574 -272.34261)
				(mid 380.752697 -274.735363)
				(end 377.949714 -275.650452)
			)
			(arc
				(start 377.949714 -275.650452)
				(mid 374.590559 -274.259045)
				(end 373.199152 -270.89989)
			)
			(xy 373.200422 -270.796258) (xy 373.200676 -270.785844) (xy 373.193056 -270.766794)
			(arc
				(start 372.979442 -270.55318)
				(mid 372.962908 -270.542069)
				(end 372.943374 -270.538194)
			)
			(arc
				(start 364.907576 -270.538194)
				(mid 364.888053 -270.542095)
				(end 364.871508 -270.55318)
			)
			(arc
				(start 363.210348 -272.21434)
				(mid 363.107316 -272.283121)
				(end 362.985812 -272.307304)
			)
			(arc
				(start 326.42429 -272.307304)
				(mid 326.394207 -272.316983)
				(end 326.375776 -272.34261)
			)
			(arc
				(start 326.375776 -272.34261)
				(mid 321.84975 -275.650472)
				(end 317.323724 -272.34261)
			)
			(arc
				(start 317.323724 -272.34261)
				(mid 317.305226 -272.317076)
				(end 317.27521 -272.307304)
			)
			(arc
				(start 313.069224 -272.307304)
				(mid 313.044975 -272.313465)
				(end 313.026552 -272.330418)
			)
			(arc
				(start 313.026552 -272.330418)
				(mid 312.749692 -272.480262)
				(end 312.472832 -272.330418)
			)
			(arc
				(start 312.472832 -272.330418)
				(mid 312.454441 -272.313407)
				(end 312.43016 -272.307304)
			)
			(arc
				(start 311.169304 -272.307304)
				(mid 311.145055 -272.313465)
				(end 311.126632 -272.330418)
			)
			(arc
				(start 311.126632 -272.330418)
				(mid 310.849772 -272.480262)
				(end 310.572912 -272.330418)
			)
			(arc
				(start 310.572912 -272.330418)
				(mid 310.554521 -272.313407)
				(end 310.53024 -272.307304)
			)
			(arc
				(start 309.269384 -272.307304)
				(mid 309.245135 -272.313465)
				(end 309.226712 -272.330418)
			)
			(arc
				(start 309.226712 -272.330418)
				(mid 308.949852 -272.480262)
				(end 308.672992 -272.330418)
			)
			(arc
				(start 308.672992 -272.330418)
				(mid 308.654601 -272.313407)
				(end 308.63032 -272.307304)
			)
			(arc
				(start 307.36921 -272.307304)
				(mid 307.344961 -272.313465)
				(end 307.326538 -272.330418)
			)
			(arc
				(start 307.326538 -272.330418)
				(mid 307.049678 -272.480262)
				(end 306.772818 -272.330418)
			)
			(arc
				(start 306.772818 -272.330418)
				(mid 306.754427 -272.313407)
				(end 306.730146 -272.307304)
			)
			(arc
				(start 305.469036 -272.307304)
				(mid 305.444787 -272.313465)
				(end 305.426364 -272.330418)
			)
			(arc
				(start 305.426364 -272.330418)
				(mid 305.149504 -272.480262)
				(end 304.872644 -272.330418)
			)
			(arc
				(start 304.872644 -272.330418)
				(mid 304.854253 -272.313407)
				(end 304.829972 -272.307304)
			)
			(arc
				(start 303.569116 -272.307304)
				(mid 303.544867 -272.313465)
				(end 303.526444 -272.330418)
			)
			(arc
				(start 303.526444 -272.330418)
				(mid 303.249584 -272.480262)
				(end 302.972724 -272.330418)
			)
			(arc
				(start 302.972724 -272.330418)
				(mid 302.954333 -272.313407)
				(end 302.930052 -272.307304)
			)
			(arc
				(start 301.669196 -272.307304)
				(mid 301.644947 -272.313465)
				(end 301.626524 -272.330418)
			)
			(arc
				(start 301.626524 -272.330418)
				(mid 301.349664 -272.480262)
				(end 301.072804 -272.330418)
			)
			(arc
				(start 301.072804 -272.330418)
				(mid 301.054413 -272.313407)
				(end 301.030132 -272.307304)
			)
			(arc
				(start 299.769022 -272.307304)
				(mid 299.744773 -272.313465)
				(end 299.72635 -272.330418)
			)
			(arc
				(start 299.72635 -272.330418)
				(mid 299.44949 -272.480262)
				(end 299.17263 -272.330418)
			)
			(arc
				(start 299.17263 -272.330418)
				(mid 299.154239 -272.313407)
				(end 299.129958 -272.307304)
			)
			(arc
				(start 297.869102 -272.307304)
				(mid 297.844853 -272.313465)
				(end 297.82643 -272.330418)
			)
			(arc
				(start 297.82643 -272.330418)
				(mid 297.54957 -272.480262)
				(end 297.27271 -272.330418)
			)
			(arc
				(start 297.27271 -272.330418)
				(mid 297.254319 -272.313407)
				(end 297.230038 -272.307304)
			)
			(arc
				(start 295.969182 -272.307304)
				(mid 295.944933 -272.313465)
				(end 295.92651 -272.330418)
			)
			(arc
				(start 295.92651 -272.330418)
				(mid 295.64965 -272.480262)
				(end 295.37279 -272.330418)
			)
			(arc
				(start 295.37279 -272.330418)
				(mid 295.354399 -272.313407)
				(end 295.330118 -272.307304)
			)
			(arc
				(start 294.069008 -272.307304)
				(mid 294.044759 -272.313465)
				(end 294.026336 -272.330418)
			)
			(arc
				(start 294.026336 -272.330418)
				(mid 293.749476 -272.480262)
				(end 293.472616 -272.330418)
			)
			(arc
				(start 293.472616 -272.330418)
				(mid 293.454225 -272.313407)
				(end 293.429944 -272.307304)
			)
			(arc
				(start 292.168834 -272.307304)
				(mid 292.144727 -272.313525)
				(end 292.126416 -272.330418)
			)
			(arc
				(start 292.126416 -272.330418)
				(mid 291.849556 -272.480032)
				(end 291.572696 -272.330418)
			)
			(arc
				(start 291.572696 -272.330418)
				(mid 291.554417 -272.313467)
				(end 291.530278 -272.307304)
			)
			(arc
				(start 290.269168 -272.307304)
				(mid 290.244919 -272.313465)
				(end 290.226496 -272.330418)
			)
			(arc
				(start 290.226496 -272.330418)
				(mid 289.949636 -272.480262)
				(end 289.672776 -272.330418)
			)
			(arc
				(start 289.672776 -272.330418)
				(mid 289.654385 -272.313407)
				(end 289.630104 -272.307304)
			)
			(arc
				(start 288.368994 -272.307304)
				(mid 288.344745 -272.313465)
				(end 288.326322 -272.330418)
			)
			(arc
				(start 288.326322 -272.330418)
				(mid 288.049462 -272.480262)
				(end 287.772602 -272.330418)
			)
			(arc
				(start 287.772602 -272.330418)
				(mid 287.754211 -272.313407)
				(end 287.72993 -272.307304)
			)
			(arc
				(start 286.469074 -272.307304)
				(mid 286.444825 -272.313465)
				(end 286.426402 -272.330418)
			)
			(arc
				(start 286.426402 -272.330418)
				(mid 286.149542 -272.480262)
				(end 285.872682 -272.330418)
			)
			(arc
				(start 285.872682 -272.330418)
				(mid 285.854291 -272.313407)
				(end 285.83001 -272.307304)
			)
			(arc
				(start 284.569154 -272.307304)
				(mid 284.544905 -272.313465)
				(end 284.526482 -272.330418)
			)
			(arc
				(start 284.526482 -272.330418)
				(mid 284.249622 -272.480262)
				(end 283.972762 -272.330418)
			)
			(arc
				(start 283.972762 -272.330418)
				(mid 283.954371 -272.313407)
				(end 283.93009 -272.307304)
			)
			(arc
				(start 282.66898 -272.307304)
				(mid 282.644731 -272.313465)
				(end 282.626308 -272.330418)
			)
			(arc
				(start 282.626308 -272.330418)
				(mid 282.349448 -272.480262)
				(end 282.072588 -272.330418)
			)
			(arc
				(start 282.072588 -272.330418)
				(mid 282.054197 -272.313407)
				(end 282.029916 -272.307304)
			)
			(arc
				(start 280.76906 -272.307304)
				(mid 280.744811 -272.313465)
				(end 280.726388 -272.330418)
			)
			(arc
				(start 280.726388 -272.330418)
				(mid 280.449528 -272.480262)
				(end 280.172668 -272.330418)
			)
			(arc
				(start 280.172668 -272.330418)
				(mid 280.154277 -272.313407)
				(end 280.129996 -272.307304)
			)
			(arc
				(start 278.86914 -272.307304)
				(mid 278.844891 -272.313465)
				(end 278.826468 -272.330418)
			)
			(arc
				(start 278.826468 -272.330418)
				(mid 278.549608 -272.480262)
				(end 278.272748 -272.330418)
			)
			(arc
				(start 278.272748 -272.330418)
				(mid 278.254357 -272.313407)
				(end 278.230076 -272.307304)
			)
			(arc
				(start 276.968966 -272.307304)
				(mid 276.944717 -272.313465)
				(end 276.926294 -272.330418)
			)
			(arc
				(start 276.926294 -272.330418)
				(mid 276.649434 -272.480262)
				(end 276.372574 -272.330418)
			)
			(arc
				(start 276.372574 -272.330418)
				(mid 276.354183 -272.313407)
				(end 276.329902 -272.307304)
			)
			(arc
				(start 269.27556 -272.307304)
				(mid 269.256037 -272.311205)
				(end 269.239492 -272.32229)
			)
			(arc
				(start 268.907006 -272.654776)
				(mid 268.895895 -272.67131)
				(end 268.89202 -272.690844)
			)
			(xy 268.89202 -275.381212)
			(arc
				(start 268.893798 -275.387816)
				(mid 268.90548 -275.474938)
				(end 268.893798 -275.56206)
			)
			(xy 268.89202 -275.568664) (xy 268.89202 -276.331172)
			(arc
				(start 268.893798 -276.337776)
				(mid 268.90548 -276.424898)
				(end 268.893798 -276.51202)
			)
			(xy 268.89202 -276.518624) (xy 268.89202 -277.281132)
			(arc
				(start 268.893798 -277.287736)
				(mid 268.90548 -277.374858)
				(end 268.893798 -277.46198)
			)
			(xy 268.89202 -277.468584) (xy 268.89202 -278.231092)
			(arc
				(start 268.893798 -278.237696)
				(mid 268.90548 -278.324818)
				(end 268.893798 -278.41194)
			)
			(xy 268.89202 -278.418544) (xy 268.89202 -279.181052)
			(arc
				(start 268.893798 -279.187656)
				(mid 268.90548 -279.274778)
				(end 268.893798 -279.3619)
			)
			(xy 268.89202 -279.368504) (xy 268.89202 -280.131012)
			(arc
				(start 268.893798 -280.137616)
				(mid 268.90548 -280.224738)
				(end 268.893798 -280.31186)
			)
			(xy 268.89202 -280.318464) (xy 268.89202 -281.081226)
			(arc
				(start 268.893798 -281.08783)
				(mid 268.90548 -281.174952)
				(end 268.893798 -281.262074)
			)
			(xy 268.89202 -281.268678) (xy 268.89202 -282.031186)
			(arc
				(start 268.893798 -282.03779)
				(mid 268.90548 -282.124912)
				(end 268.893798 -282.212034)
			)
			(xy 268.89202 -282.218638) (xy 268.89202 -282.981146)
			(arc
				(start 268.893798 -282.98775)
				(mid 268.90548 -283.074872)
				(end 268.893798 -283.161994)
			)
			(xy 268.89202 -283.168598) (xy 268.89202 -283.931106)
			(arc
				(start 268.893798 -283.93771)
				(mid 268.90548 -284.024832)
				(end 268.893798 -284.111954)
			)
			(xy 268.89202 -284.118558) (xy 268.89202 -284.881066)
			(arc
				(start 268.893798 -284.88767)
				(mid 268.90548 -284.974792)
				(end 268.893798 -285.061914)
			)
			(xy 268.89202 -285.068518)
			(arc
				(start 268.89202 -285.56331)
				(mid 268.895921 -285.582833)
				(end 268.907006 -285.599378)
			)
			(arc
				(start 268.963394 -285.655766)
				(mid 268.979928 -285.666877)
				(end 268.999462 -285.670752)
			)
			(arc
				(start 269.295372 -285.670752)
				(mid 269.311436 -285.668145)
				(end 269.325852 -285.660592)
			)
			(arc
				(start 269.325852 -285.660592)
				(mid 269.524734 -285.594043)
				(end 269.723616 -285.660592)
			)
			(arc
				(start 269.723616 -285.660592)
				(mid 269.738032 -285.668145)
				(end 269.754096 -285.670752)
			)
			(arc
				(start 270.245586 -285.670752)
				(mid 270.26165 -285.668145)
				(end 270.276066 -285.660592)
			)
			(arc
				(start 270.276066 -285.660592)
				(mid 270.474948 -285.594043)
				(end 270.67383 -285.660592)
			)
			(arc
				(start 270.67383 -285.660592)
				(mid 270.688246 -285.668145)
				(end 270.70431 -285.670752)
			)
			(arc
				(start 271.195546 -285.670752)
				(mid 271.21161 -285.668145)
				(end 271.226026 -285.660592)
			)
			(arc
				(start 271.226026 -285.660592)
				(mid 271.424908 -285.594043)
				(end 271.62379 -285.660592)
			)
			(arc
				(start 271.62379 -285.660592)
				(mid 271.638206 -285.668145)
				(end 271.65427 -285.670752)
			)
			(arc
				(start 272.145506 -285.670752)
				(mid 272.16157 -285.668145)
				(end 272.175986 -285.660592)
			)
			(arc
				(start 272.175986 -285.660592)
				(mid 272.374868 -285.594043)
				(end 272.57375 -285.660592)
			)
			(arc
				(start 272.57375 -285.660592)
				(mid 272.588166 -285.668145)
				(end 272.60423 -285.670752)
			)
			(arc
				(start 273.095466 -285.670752)
				(mid 273.11153 -285.668145)
				(end 273.125946 -285.660592)
			)
			(arc
				(start 273.125946 -285.660592)
				(mid 273.324828 -285.594043)
				(end 273.52371 -285.660592)
			)
			(arc
				(start 273.52371 -285.660592)
				(mid 273.538126 -285.668145)
				(end 273.55419 -285.670752)
			)
			(arc
				(start 276.89556 -285.670752)
				(mid 276.911624 -285.668145)
				(end 276.92604 -285.660592)
			)
			(arc
				(start 276.92604 -285.660592)
				(mid 277.124922 -285.594043)
				(end 277.323804 -285.660592)
			)
			(arc
				(start 277.323804 -285.660592)
				(mid 277.33822 -285.668145)
				(end 277.354284 -285.670752)
			)
			(arc
				(start 277.84552 -285.670752)
				(mid 277.861584 -285.668145)
				(end 277.876 -285.660592)
			)
			(arc
				(start 277.876 -285.660592)
				(mid 278.074882 -285.594043)
				(end 278.273764 -285.660592)
			)
			(arc
				(start 278.273764 -285.660592)
				(mid 278.28818 -285.668145)
				(end 278.304244 -285.670752)
			)
			(arc
				(start 278.79548 -285.670752)
				(mid 278.811544 -285.668145)
				(end 278.82596 -285.660592)
			)
			(arc
				(start 278.82596 -285.660592)
				(mid 279.024842 -285.594043)
				(end 279.223724 -285.660592)
			)
			(arc
				(start 279.223724 -285.660592)
				(mid 279.23814 -285.668145)
				(end 279.254204 -285.670752)
			)
			(arc
				(start 279.74544 -285.670752)
				(mid 279.761504 -285.668145)
				(end 279.77592 -285.660592)
			)
			(arc
				(start 279.77592 -285.660592)
				(mid 279.974802 -285.594043)
				(end 280.173684 -285.660592)
			)
			(arc
				(start 280.173684 -285.660592)
				(mid 280.1881 -285.668145)
				(end 280.204164 -285.670752)
			)
			(arc
				(start 280.6954 -285.670752)
				(mid 280.711464 -285.668145)
				(end 280.72588 -285.660592)
			)
			(arc
				(start 280.72588 -285.660592)
				(mid 280.924762 -285.594043)
				(end 281.123644 -285.660592)
			)
			(arc
				(start 281.123644 -285.660592)
				(mid 281.13806 -285.668145)
				(end 281.154124 -285.670752)
			)
			(arc
				(start 281.64536 -285.670752)
				(mid 281.661424 -285.668145)
				(end 281.67584 -285.660592)
			)
			(arc
				(start 281.67584 -285.660592)
				(mid 281.874722 -285.594043)
				(end 282.073604 -285.660592)
			)
			(arc
				(start 282.073604 -285.660592)
				(mid 282.08802 -285.668145)
				(end 282.104084 -285.670752)
			)
			(arc
				(start 282.595574 -285.670752)
				(mid 282.611638 -285.668145)
				(end 282.626054 -285.660592)
			)
			(arc
				(start 282.626054 -285.660592)
				(mid 282.824936 -285.594043)
				(end 283.023818 -285.660592)
			)
			(arc
				(start 283.023818 -285.660592)
				(mid 283.038234 -285.668145)
				(end 283.054298 -285.670752)
			)
			(arc
				(start 283.545534 -285.670752)
				(mid 283.561598 -285.668145)
				(end 283.576014 -285.660592)
			)
			(arc
				(start 283.576014 -285.660592)
				(mid 283.774896 -285.594043)
				(end 283.973778 -285.660592)
			)
			(arc
				(start 283.973778 -285.660592)
				(mid 283.988194 -285.668145)
				(end 284.004258 -285.670752)
			)
			(arc
				(start 284.495494 -285.670752)
				(mid 284.511558 -285.668145)
				(end 284.525974 -285.660592)
			)
			(arc
				(start 284.525974 -285.660592)
				(mid 284.724856 -285.594043)
				(end 284.923738 -285.660592)
			)
			(arc
				(start 284.923738 -285.660592)
				(mid 284.938154 -285.668145)
				(end 284.954218 -285.670752)
			)
			(arc
				(start 285.445454 -285.670752)
				(mid 285.461518 -285.668145)
				(end 285.475934 -285.660592)
			)
			(arc
				(start 285.475934 -285.660592)
				(mid 285.674816 -285.594043)
				(end 285.873698 -285.660592)
			)
			(arc
				(start 285.873698 -285.660592)
				(mid 285.888114 -285.668145)
				(end 285.904178 -285.670752)
			)
			(arc
				(start 286.395414 -285.670752)
				(mid 286.411478 -285.668145)
				(end 286.425894 -285.660592)
			)
			(arc
				(start 286.425894 -285.660592)
				(mid 286.624776 -285.594043)
				(end 286.823658 -285.660592)
			)
			(arc
				(start 286.823658 -285.660592)
				(mid 286.838074 -285.668145)
				(end 286.854138 -285.670752)
			)
			(arc
				(start 287.345374 -285.670752)
				(mid 287.361438 -285.668145)
				(end 287.375854 -285.660592)
			)
			(arc
				(start 287.375854 -285.660592)
				(mid 287.574736 -285.594043)
				(end 287.773618 -285.660592)
			)
			(arc
				(start 287.773618 -285.660592)
				(mid 287.788034 -285.668145)
				(end 287.804098 -285.670752)
			)
			(arc
				(start 288.295334 -285.670752)
				(mid 288.311398 -285.668145)
				(end 288.325814 -285.660592)
			)
			(arc
				(start 288.325814 -285.660592)
				(mid 288.524696 -285.594043)
				(end 288.723578 -285.660592)
			)
			(arc
				(start 288.723578 -285.660592)
				(mid 288.737994 -285.668145)
				(end 288.754058 -285.670752)
			)
			(arc
				(start 289.245548 -285.670752)
				(mid 289.261612 -285.668145)
				(end 289.276028 -285.660592)
			)
			(arc
				(start 289.276028 -285.660592)
				(mid 289.47491 -285.594043)
				(end 289.673792 -285.660592)
			)
			(arc
				(start 289.673792 -285.660592)
				(mid 289.688208 -285.668145)
				(end 289.704272 -285.670752)
			)
			(arc
				(start 290.195508 -285.670752)
				(mid 290.211572 -285.668145)
				(end 290.225988 -285.660592)
			)
			(arc
				(start 290.225988 -285.660592)
				(mid 290.42487 -285.594043)
				(end 290.623752 -285.660592)
			)
			(arc
				(start 290.623752 -285.660592)
				(mid 290.638168 -285.668145)
				(end 290.654232 -285.670752)
			)
			(arc
				(start 292.095428 -285.670752)
				(mid 292.111492 -285.668145)
				(end 292.125908 -285.660592)
			)
			(arc
				(start 292.125908 -285.660592)
				(mid 292.32479 -285.594043)
				(end 292.523672 -285.660592)
			)
			(arc
				(start 292.523672 -285.660592)
				(mid 292.538088 -285.668145)
				(end 292.554152 -285.670752)
			)
			(arc
				(start 293.045388 -285.670752)
				(mid 293.061452 -285.668145)
				(end 293.075868 -285.660592)
			)
			(arc
				(start 293.075868 -285.660592)
				(mid 293.27475 -285.594043)
				(end 293.473632 -285.660592)
			)
			(arc
				(start 293.473632 -285.660592)
				(mid 293.488048 -285.668145)
				(end 293.504112 -285.670752)
			)
			(arc
				(start 293.995348 -285.670752)
				(mid 294.011412 -285.668145)
				(end 294.025828 -285.660592)
			)
			(arc
				(start 294.025828 -285.660592)
				(mid 294.22471 -285.594043)
				(end 294.423592 -285.660592)
			)
			(arc
				(start 294.423592 -285.660592)
				(mid 294.438008 -285.668145)
				(end 294.454072 -285.670752)
			)
			(arc
				(start 294.945562 -285.670752)
				(mid 294.961626 -285.668145)
				(end 294.976042 -285.660592)
			)
			(arc
				(start 294.976042 -285.660592)
				(mid 295.174924 -285.594043)
				(end 295.373806 -285.660592)
			)
			(arc
				(start 295.373806 -285.660592)
				(mid 295.388222 -285.668145)
				(end 295.404286 -285.670752)
			)
			(arc
				(start 295.895522 -285.670752)
				(mid 295.911586 -285.668145)
				(end 295.926002 -285.660592)
			)
			(arc
				(start 295.926002 -285.660592)
				(mid 296.124884 -285.594043)
				(end 296.323766 -285.660592)
			)
			(arc
				(start 296.323766 -285.660592)
				(mid 296.338182 -285.668145)
				(end 296.354246 -285.670752)
			)
			(arc
				(start 296.845482 -285.670752)
				(mid 296.861546 -285.668145)
				(end 296.875962 -285.660592)
			)
			(arc
				(start 296.875962 -285.660592)
				(mid 297.074844 -285.594043)
				(end 297.273726 -285.660592)
			)
			(arc
				(start 297.273726 -285.660592)
				(mid 297.288142 -285.668145)
				(end 297.304206 -285.670752)
			)
			(arc
				(start 297.795442 -285.670752)
				(mid 297.811506 -285.668145)
				(end 297.825922 -285.660592)
			)
			(arc
				(start 297.825922 -285.660592)
				(mid 298.024804 -285.594043)
				(end 298.223686 -285.660592)
			)
			(arc
				(start 298.223686 -285.660592)
				(mid 298.238102 -285.668145)
				(end 298.254166 -285.670752)
			)
			(arc
				(start 298.745402 -285.670752)
				(mid 298.761466 -285.668145)
				(end 298.775882 -285.660592)
			)
			(arc
				(start 298.775882 -285.660592)
				(mid 298.974764 -285.594043)
				(end 299.173646 -285.660592)
			)
			(arc
				(start 299.173646 -285.660592)
				(mid 299.188062 -285.668145)
				(end 299.204126 -285.670752)
			)
			(arc
				(start 299.695362 -285.670752)
				(mid 299.711426 -285.668145)
				(end 299.725842 -285.660592)
			)
			(arc
				(start 299.725842 -285.660592)
				(mid 299.924724 -285.594043)
				(end 300.123606 -285.660592)
			)
			(arc
				(start 300.123606 -285.660592)
				(mid 300.138022 -285.668145)
				(end 300.154086 -285.670752)
			)
			(arc
				(start 300.645322 -285.670752)
				(mid 300.661386 -285.668145)
				(end 300.675802 -285.660592)
			)
			(arc
				(start 300.675802 -285.660592)
				(mid 300.874684 -285.594043)
				(end 301.073566 -285.660592)
			)
			(arc
				(start 301.073566 -285.660592)
				(mid 301.087982 -285.668145)
				(end 301.104046 -285.670752)
			)
			(arc
				(start 301.595536 -285.670752)
				(mid 301.6116 -285.668145)
				(end 301.626016 -285.660592)
			)
			(arc
				(start 301.626016 -285.660592)
				(mid 301.824898 -285.594043)
				(end 302.02378 -285.660592)
			)
			(arc
				(start 302.02378 -285.660592)
				(mid 302.038196 -285.668145)
				(end 302.05426 -285.670752)
			)
			(arc
				(start 302.545496 -285.670752)
				(mid 302.56156 -285.668145)
				(end 302.575976 -285.660592)
			)
			(arc
				(start 302.575976 -285.660592)
				(mid 302.774858 -285.594043)
				(end 302.97374 -285.660592)
			)
			(arc
				(start 302.97374 -285.660592)
				(mid 302.988156 -285.668145)
				(end 303.00422 -285.670752)
			)
			(xy 328.737722 -285.670752) (xy 328.764646 -285.650178)
			(arc
				(start 328.769472 -285.633414)
				(mid 329.13701 -285.354064)
				(end 329.504548 -285.633414)
			)
			(xy 329.509374 -285.650178) (xy 329.536298 -285.670752)
			(arc
				(start 331.988668 -285.670752)
				(mid 332.008191 -285.666851)
				(end 332.024736 -285.655766)
			)
			(arc
				(start 332.183486 -285.497016)
				(mid 332.194597 -285.480482)
				(end 332.198472 -285.460948)
			)
			(arc
				(start 332.198472 -279.197562)
				(mid 332.217822 -279.100375)
				(end 332.272894 -279.017984)
			)
			(xy 332.504542 -278.786336) (xy 332.512162 -278.764746)
			(arc
				(start 332.510638 -278.752808)
				(mid 332.508727 -278.730747)
				(end 332.508098 -278.708612)
			)
			(arc
				(start 332.508098 -278.708612)
				(mid 332.619839 -278.438845)
				(end 332.889606 -278.327104)
			)
			(arc
				(start 332.889606 -278.327104)
				(mid 332.911741 -278.327732)
				(end 332.933802 -278.329644)
			)
			(xy 332.94574 -278.331168) (xy 332.96733 -278.323548)
			(arc
				(start 333.023464 -278.267414)
				(mid 333.105841 -278.212308)
				(end 333.203042 -278.192992)
			)
			(arc
				(start 365.660686 -278.192992)
				(mid 365.687345 -278.185435)
				(end 365.706152 -278.165052)
			)
			(xy 365.753396 -278.070818) (xy 365.750856 -278.04237)
			(arc
				(start 365.74222 -278.030686)
				(mid 365.243485 -277.074624)
				(end 365.071406 -276.010116)
			)
			(arc
				(start 365.071406 -276.010116)
				(mid 370.839221 -273.621009)
				(end 368.450114 -279.388824)
			)
			(arc
				(start 368.450114 -279.388824)
				(mid 368.253053 -279.383013)
				(end 368.056668 -279.36571)
			)
			(xy 368.045492 -279.36444) (xy 368.025172 -279.371044)
			(arc
				(start 367.960148 -279.428702)
				(mid 367.947579 -279.44593)
				(end 367.94313 -279.466802)
			)
			(arc
				(start 367.94313 -285.960312)
				(mid 367.947031 -285.979835)
				(end 367.958116 -285.99638)
			)
			(arc
				(start 368.092736 -286.131)
				(mid 368.10927 -286.142111)
				(end 368.128804 -286.145986)
			)
		)
		(stroke
			(width 0)
			(type solid)
		)
		(fill yes)
		(layer "In2.Cu")
		(net "P1V8_PEX")
	)
	(gr_poly
		(pts
			(xy 13.96492 -10.342118) (xy 14.020727 -10.341596) (xy 14.132028 -10.333253) (xy 14.242395 -10.316617)
			(xy 14.35121 -10.29178) (xy 14.457865 -10.25888) (xy 14.561763 -10.218102) (xy 14.662323 -10.169674)
			(xy 14.758983 -10.113867) (xy 14.851203 -10.050993) (xy 14.938466 -9.981402) (xy 15.020284 -9.905486)
			(xy 15.096201 -9.823667) (xy 15.165791 -9.736404) (xy 15.228666 -9.644185) (xy 15.284473 -9.547525)
			(xy 15.332901 -9.446965) (xy 15.373679 -9.343067) (xy 15.406579 -9.236412) (xy 15.431417 -9.127597)
			(xy 15.448053 -9.01723) (xy 15.456395 -8.905929) (xy 15.456916 -8.850122) (xy 15.456916 0) (xy 15.4574 0.070354)
			(xy 15.46529 0.21084) (xy 15.481044 0.350663) (xy 15.504614 0.489383) (xy 15.535924 0.626563) (xy 15.574877 0.761771)
			(xy 15.62135 0.894583) (xy 15.675197 1.02458) (xy 15.736248 1.151353) (xy 15.804311 1.274504) (xy 15.879172 1.393644)
			(xy 15.960596 1.5084) (xy 16.048326 1.618409) (xy 16.142086 1.723327) (xy 16.241582 1.822822) (xy 16.3465 1.916582)
			(xy 16.45651 2.004311) (xy 16.571266 2.085734) (xy 16.690407 2.160595) (xy 16.813558 2.228658) (xy 16.940331 2.289708)
			(xy 17.070328 2.343554) (xy 17.20314 2.390026) (xy 17.338349 2.428979) (xy 17.475529 2.460289) (xy 17.614249 2.483858)
			(xy 17.754072 2.499611) (xy 17.894558 2.5075) (xy 17.964912 2.507996) (xy 33.96488 2.507996) (xy 34.035234 2.507512)
			(xy 34.175722 2.499624) (xy 34.315546 2.48387) (xy 34.454267 2.460302) (xy 34.591448 2.428992) (xy 34.726657 2.39004)
			(xy 34.85947 2.343568) (xy 34.989468 2.289721) (xy 35.116243 2.228671) (xy 35.239395 2.160608) (xy 35.358537 2.085747)
			(xy 35.473294 2.004324) (xy 35.583304 1.916594) (xy 35.688223 1.822833) (xy 35.78772 1.723338) (xy 35.881481 1.61842)
			(xy 35.969212 1.50841) (xy 36.050636 1.393653) (xy 36.125498 1.274512) (xy 36.193562 1.151361) (xy 36.254613 1.024587)
			(xy 36.30846 0.894589) (xy 36.354934 0.761776) (xy 36.393887 0.626567) (xy 36.425198 0.489386) (xy 36.448768 0.350666)
			(xy 36.464522 0.210842) (xy 36.472412 0.070354) (xy 36.472876 0) (xy 36.472876 -8.850122) (xy 36.473399 -8.905929)
			(xy 36.481741 -9.01723) (xy 36.498377 -9.127597) (xy 36.523215 -9.236413) (xy 36.556114 -9.343067)
			(xy 36.596892 -9.446965) (xy 36.64532 -9.547526) (xy 36.701127 -9.644186) (xy 36.764002 -9.736405)
			(xy 36.833592 -9.823668) (xy 36.909508 -9.905487) (xy 36.991327 -9.981404) (xy 37.07859 -10.050995)
			(xy 37.170809 -10.113869) (xy 37.267469 -10.169677) (xy 37.368029 -10.218105) (xy 37.471927 -10.258884)
			(xy 37.578582 -10.291784) (xy 37.687397 -10.316622) (xy 37.797764 -10.333258) (xy 37.909065 -10.341601)
			(xy 37.964872 -10.342118) (xy 39.965122 -10.342118) (xy 40.020929 -10.341595) (xy 40.13223 -10.333253)
			(xy 40.242597 -10.316617) (xy 40.351412 -10.291779) (xy 40.458067 -10.258879) (xy 40.561964 -10.218102)
			(xy 40.662525 -10.169674) (xy 40.759184 -10.113866) (xy 40.851404 -10.050992) (xy 40.938667 -9.981402)
			(xy 41.020485 -9.905485) (xy 41.096402 -9.823667) (xy 41.165992 -9.736404) (xy 41.228866 -9.644184)
			(xy 41.284674 -9.547525) (xy 41.333102 -9.446964) (xy 41.373879 -9.343067) (xy 41.406779 -9.236412)
			(xy 41.431617 -9.127597) (xy 41.448253 -9.01723) (xy 41.456595 -8.905929) (xy 41.457118 -8.850122)
			(xy 41.457118 0) (xy 41.457602 0.070354) (xy 41.465492 0.21084) (xy 41.481246 0.350663) (xy 41.504816 0.489383)
			(xy 41.536126 0.626563) (xy 41.575079 0.761771) (xy 41.621552 0.894583) (xy 41.675399 1.02458) (xy 41.73645 1.151353)
			(xy 41.804513 1.274503) (xy 41.879374 1.393644) (xy 41.960798 1.508399) (xy 42.048528 1.618409) (xy 42.142288 1.723326)
			(xy 42.241784 1.822821) (xy 42.346702 1.916581) (xy 42.456712 2.00431) (xy 42.571468 2.085733) (xy 42.690609 2.160594)
			(xy 42.81376 2.228657) (xy 42.940533 2.289707) (xy 43.07053 2.343553) (xy 43.203342 2.390025) (xy 43.338551 2.428977)
			(xy 43.475731 2.460287) (xy 43.614451 2.483856) (xy 43.754274 2.499609) (xy 43.89476 2.507498) (xy 43.965114 2.507996)
			(xy 59.965082 2.507996) (xy 60.035436 2.507512) (xy 60.175924 2.499624) (xy 60.315748 2.48387) (xy 60.454468 2.460301)
			(xy 60.591649 2.428992) (xy 60.726859 2.390039) (xy 60.859672 2.343567) (xy 60.98967 2.289721) (xy 61.116444 2.22867)
			(xy 61.239596 2.160607) (xy 61.358738 2.085747) (xy 61.473495 2.004323) (xy 61.583505 1.916593) (xy 61.688424 1.822833)
			(xy 61.78792 1.723337) (xy 61.881681 1.618419) (xy 61.969412 1.508409) (xy 62.050837 1.393653) (xy 62.125698 1.274512)
			(xy 62.193762 1.15136) (xy 62.254813 1.024586) (xy 62.308661 0.894588) (xy 62.355134 0.761776) (xy 62.394087 0.626567)
			(xy 62.425398 0.489386) (xy 62.448968 0.350665) (xy 62.464722 0.210842) (xy 62.472612 0.070354) (xy 62.473078 0)
			(xy 62.473078 -8.850122) (xy 62.473601 -8.905929) (xy 62.481943 -9.01723) (xy 62.498579 -9.127597)
			(xy 62.523417 -9.236412) (xy 62.556316 -9.343067) (xy 62.597094 -9.446965) (xy 62.645522 -9.547525)
			(xy 62.701329 -9.644185) (xy 62.764204 -9.736405) (xy 62.833794 -9.823668) (xy 62.909711 -9.905487)
			(xy 62.991529 -9.981403) (xy 63.078792 -10.050994) (xy 63.171011 -10.113868) (xy 63.267671 -10.169676)
			(xy 63.368231 -10.218104) (xy 63.472129 -10.258882) (xy 63.578784 -10.291782) (xy 63.687599 -10.31662)
			(xy 63.797966 -10.333257) (xy 63.909267 -10.341599) (xy 63.965074 -10.342118) (xy 65.96507 -10.342118)
			(xy 66.020879 -10.34161) (xy 66.132184 -10.333271) (xy 66.242554 -10.316637) (xy 66.351373 -10.291802)
			(xy 66.458032 -10.258905) (xy 66.561934 -10.218128) (xy 66.662499 -10.169702) (xy 66.759163 -10.113895)
			(xy 66.851386 -10.05102) (xy 66.938653 -9.98143) (xy 67.020476 -9.905512) (xy 67.096396 -9.823693)
			(xy 67.165989 -9.736428) (xy 67.228867 -9.644207) (xy 67.284677 -9.547545) (xy 67.333108 -9.446982)
			(xy 67.373888 -9.343081) (xy 67.406789 -9.236424) (xy 67.431628 -9.127605) (xy 67.448265 -9.017235)
			(xy 67.456608 -8.905931) (xy 67.457066 -8.850122) (xy 67.457066 0) (xy 67.457559 0.070354) (xy 67.465449 0.210841)
			(xy 67.481203 0.350665) (xy 67.504772 0.489385) (xy 67.536082 0.626565) (xy 67.575035 0.761774) (xy 67.621508 0.894587)
			(xy 67.675354 1.024584) (xy 67.736404 1.151358) (xy 67.804467 1.27451) (xy 67.879328 1.393651) (xy 67.960751 1.508408)
			(xy 68.04848 1.618419) (xy 68.14224 1.723337) (xy 68.241735 1.822834) (xy 68.346652 1.916595) (xy 68.456662 2.004326)
			(xy 68.571417 2.085751) (xy 68.690557 2.160614) (xy 68.813708 2.228678) (xy 68.940481 2.289731) (xy 69.070478 2.343579)
			(xy 69.203289 2.390053) (xy 69.338498 2.429008) (xy 69.475678 2.46032) (xy 69.614398 2.483892) (xy 69.754221 2.499648)
			(xy 69.894708 2.50754) (xy 69.965062 2.507996) (xy 85.96503 2.507996) (xy 86.035383 2.507502) (xy 86.175868 2.499611)
			(xy 86.31569 2.483855) (xy 86.454408 2.460284) (xy 86.591586 2.428973) (xy 86.726793 2.390019) (xy 86.859603 2.343545)
			(xy 86.989598 2.289698) (xy 87.11637 2.228647) (xy 87.239519 2.160584) (xy 87.358658 2.085722) (xy 87.473412 2.004299)
			(xy 87.58342 1.916569) (xy 87.688336 1.822809) (xy 87.78783 1.723314) (xy 87.881588 1.618397) (xy 87.969317 1.508388)
			(xy 88.050739 1.393633) (xy 88.125599 1.274493) (xy 88.193661 1.151343) (xy 88.254711 1.024571) (xy 88.308556 0.894575)
			(xy 88.355028 0.761764) (xy 88.39398 0.626557) (xy 88.42529 0.489378) (xy 88.448859 0.35066) (xy 88.464613 0.210838)
			(xy 88.472503 0.070353) (xy 88.473026 0) (xy 88.473026 -8.850122) (xy 88.473549 -8.905928) (xy 88.481891 -9.017228)
			(xy 88.498528 -9.127594) (xy 88.523365 -9.236408) (xy 88.556265 -9.343061) (xy 88.597043 -9.446957)
			(xy 88.645472 -9.547516) (xy 88.701279 -9.644174) (xy 88.764154 -9.736392) (xy 88.833745 -9.823653)
			(xy 88.909662 -9.90547) (xy 88.99148 -9.981384) (xy 89.078743 -10.050972) (xy 89.170963 -10.113844)
			(xy 89.267623 -10.169649) (xy 89.368183 -10.218074) (xy 89.472081 -10.258849) (xy 89.578735 -10.291746)
			(xy 89.687549 -10.316581) (xy 89.797915 -10.333214) (xy 89.909216 -10.341553) (xy 89.965022 -10.342118)
			(xy 91.965018 -10.342118) (xy 92.020825 -10.341596) (xy 92.132127 -10.333254) (xy 92.242494 -10.316617)
			(xy 92.351309 -10.29178) (xy 92.457964 -10.258881) (xy 92.561862 -10.218103) (xy 92.662422 -10.169675)
			(xy 92.759082 -10.113868) (xy 92.851302 -10.050993) (xy 92.938565 -9.981403) (xy 93.020384 -9.905487)
			(xy 93.096301 -9.823668) (xy 93.165891 -9.736405) (xy 93.228766 -9.644186) (xy 93.284573 -9.547526)
			(xy 93.333001 -9.446965) (xy 93.373779 -9.343067) (xy 93.406679 -9.236413) (xy 93.431517 -9.127597)
			(xy 93.448153 -9.01723) (xy 93.456495 -8.905929) (xy 93.457014 -8.850122) (xy 93.457014 0) (xy 93.457498 0.070354)
			(xy 93.465388 0.21084) (xy 93.481142 0.350663) (xy 93.504712 0.489383) (xy 93.536022 0.626563) (xy 93.574975 0.761771)
			(xy 93.621448 0.894583) (xy 93.675295 1.02458) (xy 93.736346 1.151353) (xy 93.804409 1.274504) (xy 93.87927 1.393645)
			(xy 93.960694 1.5084) (xy 94.048424 1.61841) (xy 94.142184 1.723327) (xy 94.24168 1.822823) (xy 94.346598 1.916583)
			(xy 94.456608 2.004312) (xy 94.571364 2.085735) (xy 94.690505 2.160596) (xy 94.813655 2.228659) (xy 94.940429 2.289709)
			(xy 95.070426 2.343555) (xy 95.203238 2.390028) (xy 95.338447 2.42898) (xy 95.475627 2.46029) (xy 95.614347 2.483859)
			(xy 95.75417 2.499613) (xy 95.894656 2.507502) (xy 95.96501 2.507996) (xy 124.06503 2.507996) (xy 124.135383 2.507502)
			(xy 124.275868 2.499611) (xy 124.41569 2.483855) (xy 124.554408 2.460284) (xy 124.691586 2.428973)
			(xy 124.826793 2.390019) (xy 124.959603 2.343545) (xy 125.089598 2.289698) (xy 125.21637 2.228647)
			(xy 125.339519 2.160584) (xy 125.458658 2.085722) (xy 125.573412 2.004299) (xy 125.68342 1.916569)
			(xy 125.788336 1.822809) (xy 125.88783 1.723314) (xy 125.981588 1.618397) (xy 126.069317 1.508388)
			(xy 126.150739 1.393633) (xy 126.225599 1.274493) (xy 126.293661 1.151343) (xy 126.354711 1.024571)
			(xy 126.408556 0.894575) (xy 126.455028 0.761764) (xy 126.49398 0.626557) (xy 126.52529 0.489378)
			(xy 126.548859 0.35066) (xy 126.564613 0.210838) (xy 126.572503 0.070353) (xy 126.573026 0) (xy 126.573026 -8.850122)
			(xy 126.573549 -8.905928) (xy 126.581891 -9.017228) (xy 126.598528 -9.127594) (xy 126.623365 -9.236408)
			(xy 126.656265 -9.343061) (xy 126.697043 -9.446957) (xy 126.745472 -9.547516) (xy 126.801279 -9.644174)
			(xy 126.864154 -9.736392) (xy 126.933745 -9.823653) (xy 127.009662 -9.90547) (xy 127.09148 -9.981384)
			(xy 127.178743 -10.050972) (xy 127.270963 -10.113844) (xy 127.367623 -10.169649) (xy 127.468183 -10.218074)
			(xy 127.572081 -10.258849) (xy 127.678735 -10.291746) (xy 127.787549 -10.316581) (xy 127.897915 -10.333214)
			(xy 128.009216 -10.341553) (xy 128.065022 -10.342118) (xy 130.065018 -10.342118) (xy 130.120825 -10.341596)
			(xy 130.232127 -10.333254) (xy 130.342494 -10.316617) (xy 130.451309 -10.29178) (xy 130.557964 -10.258881)
			(xy 130.661862 -10.218103) (xy 130.762422 -10.169675) (xy 130.859082 -10.113868) (xy 130.951302 -10.050993)
			(xy 131.038565 -9.981403) (xy 131.120384 -9.905487) (xy 131.196301 -9.823668) (xy 131.265891 -9.736405)
			(xy 131.328766 -9.644186) (xy 131.384573 -9.547526) (xy 131.433001 -9.446965) (xy 131.473779 -9.343067)
			(xy 131.506679 -9.236413) (xy 131.531517 -9.127597) (xy 131.548153 -9.01723) (xy 131.556495 -8.905929)
			(xy 131.557014 -8.850122) (xy 131.557014 0) (xy 131.557498 0.070354) (xy 131.565388 0.21084) (xy 131.581142 0.350663)
			(xy 131.604712 0.489383) (xy 131.636022 0.626563) (xy 131.674975 0.761771) (xy 131.721448 0.894583)
			(xy 131.775295 1.02458) (xy 131.836346 1.151353) (xy 131.904409 1.274504) (xy 131.97927 1.393645)
			(xy 132.060694 1.5084) (xy 132.148424 1.61841) (xy 132.242184 1.723327) (xy 132.34168 1.822823) (xy 132.446598 1.916583)
			(xy 132.556608 2.004312) (xy 132.671364 2.085735) (xy 132.790505 2.160596) (xy 132.913655 2.228659)
			(xy 133.040429 2.289709) (xy 133.170426 2.343555) (xy 133.303238 2.390028) (xy 133.438447 2.42898)
			(xy 133.575627 2.46029) (xy 133.714347 2.483859) (xy 133.85417 2.499613) (xy 133.994656 2.507502)
			(xy 134.06501 2.507996) (xy 150.064978 2.507996) (xy 150.135332 2.507512) (xy 150.27582 2.499624)
			(xy 150.415644 2.483871) (xy 150.554365 2.460302) (xy 150.691546 2.428993) (xy 150.826756 2.39004)
			(xy 150.959569 2.343568) (xy 151.089567 2.289722) (xy 151.216342 2.228672) (xy 151.339494 2.160609)
			(xy 151.458636 2.085748) (xy 151.573393 2.004324) (xy 151.683404 1.916594) (xy 151.788322 1.822834)
			(xy 151.887819 1.723338) (xy 151.98158 1.61842) (xy 152.069311 1.50841) (xy 152.150736 1.393654)
			(xy 152.225598 1.274513) (xy 152.293661 1.151361) (xy 152.354713 1.024587) (xy 152.40856 0.894589)
			(xy 152.455034 0.761777) (xy 152.493987 0.626567) (xy 152.525298 0.489386) (xy 152.548868 0.350666)
			(xy 152.564622 0.210842) (xy 152.572512 0.070354) (xy 152.572974 0) (xy 152.572974 -8.850122) (xy 152.573497 -8.905929)
			(xy 152.581839 -9.017231) (xy 152.598475 -9.127598) (xy 152.623313 -9.236413) (xy 152.656212 -9.343068)
			(xy 152.69699 -9.446966) (xy 152.745418 -9.547526) (xy 152.801225 -9.644186) (xy 152.8641 -9.736406)
			(xy 152.93369 -9.823669) (xy 153.009606 -9.905488) (xy 153.091425 -9.981405) (xy 153.178688 -10.050995)
			(xy 153.270907 -10.11387) (xy 153.367567 -10.169678) (xy 153.468127 -10.218107) (xy 153.572025 -10.258885)
			(xy 153.67868 -10.291785) (xy 153.787495 -10.316623) (xy 153.897862 -10.33326) (xy 154.009163 -10.341603)
			(xy 154.06497 -10.342118) (xy 156.064966 -10.342118) (xy 156.120775 -10.34161) (xy 156.23208 -10.333271)
			(xy 156.342451 -10.316638) (xy 156.45127 -10.291803) (xy 156.557929 -10.258906) (xy 156.661832 -10.21813)
			(xy 156.762396 -10.169703) (xy 156.859061 -10.113896) (xy 156.951284 -10.051022) (xy 157.038552 -9.981431)
			(xy 157.120374 -9.905514) (xy 157.196295 -9.823694) (xy 157.265888 -9.736429) (xy 157.328766 -9.644208)
			(xy 157.384577 -9.547546) (xy 157.433007 -9.446983) (xy 157.473787 -9.343082) (xy 157.506689 -9.236424)
			(xy 157.531528 -9.127606) (xy 157.548165 -9.017236) (xy 157.556508 -8.905931) (xy 157.556962 -8.850122)
			(xy 157.556962 0) (xy 157.557455 0.070354) (xy 157.565345 0.210841) (xy 157.581099 0.350665) (xy 157.604668 0.489385)
			(xy 157.635978 0.626566) (xy 157.674931 0.761775) (xy 157.721404 0.894587) (xy 157.77525 1.024585)
			(xy 157.8363 1.151359) (xy 157.904363 1.274511) (xy 157.979224 1.393652) (xy 158.060647 1.508409)
			(xy 158.148376 1.61842) (xy 158.242136 1.723339) (xy 158.341631 1.822835) (xy 158.446548 1.916597)
			(xy 158.556557 2.004328) (xy 158.671313 2.085753) (xy 158.790453 2.160616) (xy 158.913604 2.22868)
			(xy 159.040377 2.289733) (xy 159.170374 2.343581) (xy 159.303185 2.390056) (xy 159.438394 2.429011)
			(xy 159.575574 2.460324) (xy 159.714294 2.483895) (xy 159.854117 2.499652) (xy 159.994604 2.507544)
			(xy 160.064958 2.507996) (xy 176.064926 2.507996) (xy 176.135279 2.507502) (xy 176.275764 2.499611)
			(xy 176.415586 2.483856) (xy 176.554304 2.460285) (xy 176.691483 2.428974) (xy 176.82669 2.39002)
			(xy 176.9595 2.343547) (xy 177.089496 2.289699) (xy 177.216267 2.228648) (xy 177.339416 2.160585)
			(xy 177.458556 2.085724) (xy 177.57331 2.0043) (xy 177.683318 1.91657) (xy 177.788234 1.822811) (xy 177.887728 1.723315)
			(xy 177.981487 1.618398) (xy 178.069216 1.508389) (xy 178.150638 1.393634) (xy 178.225498 1.274494)
			(xy 178.29356 1.151344) (xy 178.35461 1.024572) (xy 178.408456 0.894576) (xy 178.454928 0.761765)
			(xy 178.49388 0.626558) (xy 178.52519 0.489379) (xy 178.548759 0.35066) (xy 178.564513 0.210838)
			(xy 178.572403 0.070353) (xy 178.572922 0) (xy 178.572922 -8.850122) (xy 178.573445 -8.905928) (xy 178.581787 -9.017229)
			(xy 178.598424 -9.127594) (xy 178.623261 -9.236408) (xy 178.656161 -9.343061) (xy 178.696939 -9.446958)
			(xy 178.745367 -9.547517) (xy 178.801175 -9.644175) (xy 178.86405 -9.736393) (xy 178.93364 -9.823654)
			(xy 179.009557 -9.905471) (xy 179.091376 -9.981386) (xy 179.178639 -10.050974) (xy 179.270859 -10.113846)
			(xy 179.367519 -10.169651) (xy 179.468079 -10.218077) (xy 179.571976 -10.258852) (xy 179.678631 -10.291749)
			(xy 179.787445 -10.316584) (xy 179.897811 -10.333218) (xy 180.009112 -10.341557) (xy 180.064918 -10.342118)
			(xy 182.064914 -10.342118) (xy 182.120721 -10.341596) (xy 182.232023 -10.333254) (xy 182.34239 -10.316618)
			(xy 182.451206 -10.291781) (xy 182.557861 -10.258882) (xy 182.661759 -10.218104) (xy 182.76232 -10.169676)
			(xy 182.85898 -10.113869) (xy 182.9512 -10.050995) (xy 183.038463 -9.981405) (xy 183.120282 -9.905488)
			(xy 183.196199 -9.823669) (xy 183.26579 -9.736406) (xy 183.328665 -9.644187) (xy 183.384473 -9.547527)
			(xy 183.432901 -9.446966) (xy 183.473679 -9.343068) (xy 183.506579 -9.236413) (xy 183.531416 -9.127598)
			(xy 183.548053 -9.017231) (xy 183.556395 -8.905929) (xy 183.55691 -8.850122) (xy 183.55691 0) (xy 183.557394 0.070354)
			(xy 183.565284 0.21084) (xy 183.581038 0.350664) (xy 183.604608 0.489383) (xy 183.635918 0.626563)
			(xy 183.674871 0.761772) (xy 183.721344 0.894584) (xy 183.775191 1.024581) (xy 183.836242 1.151354)
			(xy 183.904305 1.274505) (xy 183.979166 1.393646) (xy 184.06059 1.508401) (xy 184.14832 1.618411)
			(xy 184.24208 1.723329) (xy 184.341576 1.822824) (xy 184.446493 1.916584) (xy 184.556503 2.004314)
			(xy 184.671259 2.085737) (xy 184.7904 2.160598) (xy 184.913551 2.228661) (xy 185.040325 2.289712)
			(xy 185.170322 2.343558) (xy 185.303134 2.390031) (xy 185.438342 2.428983) (xy 185.575523 2.460294)
			(xy 185.714242 2.483863) (xy 185.854066 2.499617) (xy 185.994552 2.507506) (xy 186.064906 2.507996)
			(xy 202.064874 2.507996) (xy 202.135228 2.507512) (xy 202.275716 2.499624) (xy 202.41554 2.483871)
			(xy 202.554261 2.460303) (xy 202.691443 2.428993) (xy 202.826653 2.390041) (xy 202.959466 2.343569)
			(xy 203.089464 2.289723) (xy 203.216239 2.228673) (xy 203.339391 2.16061) (xy 203.458534 2.085749)
			(xy 203.573291 2.004326) (xy 203.683302 1.916596) (xy 203.788221 1.822836) (xy 203.887718 1.72334)
			(xy 203.981479 1.618422) (xy 204.06921 1.508412) (xy 204.150635 1.393655) (xy 204.225497 1.274514)
			(xy 204.293561 1.151362) (xy 204.354613 1.024588) (xy 204.40846 0.89459) (xy 204.454933 0.761778)
			(xy 204.493887 0.626568) (xy 204.525198 0.489387) (xy 204.548768 0.350666) (xy 204.564522 0.210842)
			(xy 204.572412 0.070354) (xy 204.57287 0) (xy 204.57287 -8.850122) (xy 204.573393 -8.905929) (xy 204.581735 -9.017231)
			(xy 204.598371 -9.127598) (xy 204.623209 -9.236413) (xy 204.656108 -9.343068) (xy 204.696886 -9.446966)
			(xy 204.745314 -9.547527) (xy 204.801121 -9.644187) (xy 204.863996 -9.736407) (xy 204.933586 -9.82367)
			(xy 205.009502 -9.905489) (xy 205.091321 -9.981407) (xy 205.178583 -10.050997) (xy 205.270803 -10.113872)
			(xy 205.367463 -10.16968) (xy 205.468023 -10.218109) (xy 205.571921 -10.258888) (xy 205.678575 -10.291788)
			(xy 205.78739 -10.316626) (xy 205.897757 -10.333264) (xy 206.009059 -10.341607) (xy 206.064866 -10.342118)
			(xy 208.065116 -10.342118) (xy 208.120923 -10.341596) (xy 208.232225 -10.333254) (xy 208.342592 -10.316618)
			(xy 208.451407 -10.29178) (xy 208.558062 -10.258881) (xy 208.66196 -10.218103) (xy 208.762521 -10.169676)
			(xy 208.859181 -10.113868) (xy 208.951401 -10.050994) (xy 209.038664 -9.981404) (xy 209.120483 -9.905487)
			(xy 209.1964 -9.823669) (xy 209.26599 -9.736406) (xy 209.328865 -9.644186) (xy 209.384673 -9.547526)
			(xy 209.433101 -9.446966) (xy 209.473879 -9.343068) (xy 209.506779 -9.236413) (xy 209.531617 -9.127598)
			(xy 209.548253 -9.017231) (xy 209.556595 -8.905929) (xy 209.557112 -8.850122) (xy 209.557112 0) (xy 209.557596 0.070354)
			(xy 209.565486 0.21084) (xy 209.58124 0.350663) (xy 209.60481 0.489383) (xy 209.63612 0.626563) (xy 209.675073 0.761772)
			(xy 209.721546 0.894583) (xy 209.775393 1.02458) (xy 209.836444 1.151354) (xy 209.904507 1.274505)
			(xy 209.979368 1.393645) (xy 210.060792 1.508401) (xy 210.148522 1.618411) (xy 210.242282 1.723328)
			(xy 210.341778 1.822823) (xy 210.446696 1.916583) (xy 210.556706 2.004313) (xy 210.671462 2.085736)
			(xy 210.790602 2.160597) (xy 210.913753 2.22866) (xy 211.040527 2.289711) (xy 211.170524 2.343557)
			(xy 211.303336 2.390029) (xy 211.438545 2.428982) (xy 211.575725 2.460292) (xy 211.714444 2.483861)
			(xy 211.854268 2.499615) (xy 211.994754 2.507504) (xy 212.065108 2.507996) (xy 240.164874 2.507996)
			(xy 240.235228 2.507512) (xy 240.375716 2.499624) (xy 240.51554 2.483871) (xy 240.654261 2.460303)
			(xy 240.791443 2.428993) (xy 240.926653 2.390041) (xy 241.059466 2.343569) (xy 241.189464 2.289723)
			(xy 241.316239 2.228673) (xy 241.439391 2.16061) (xy 241.558534 2.085749) (xy 241.673291 2.004326)
			(xy 241.783302 1.916596) (xy 241.888221 1.822836) (xy 241.987718 1.72334) (xy 242.081479 1.618422)
			(xy 242.16921 1.508412) (xy 242.250635 1.393655) (xy 242.325497 1.274514) (xy 242.393561 1.151362)
			(xy 242.454613 1.024588) (xy 242.50846 0.89459) (xy 242.554933 0.761778) (xy 242.593887 0.626568)
			(xy 242.625198 0.489387) (xy 242.648768 0.350666) (xy 242.664522 0.210842) (xy 242.672412 0.070354)
			(xy 242.67287 0) (xy 242.67287 -8.850122) (xy 242.673393 -8.905929) (xy 242.681735 -9.017231) (xy 242.698371 -9.127598)
			(xy 242.723209 -9.236413) (xy 242.756108 -9.343068) (xy 242.796886 -9.446966) (xy 242.845314 -9.547527)
			(xy 242.901121 -9.644187) (xy 242.963996 -9.736407) (xy 243.033586 -9.82367) (xy 243.109502 -9.905489)
			(xy 243.191321 -9.981407) (xy 243.278583 -10.050997) (xy 243.370803 -10.113872) (xy 243.467463 -10.16968)
			(xy 243.568023 -10.218109) (xy 243.671921 -10.258888) (xy 243.778575 -10.291788) (xy 243.88739 -10.316626)
			(xy 243.997757 -10.333264) (xy 244.109059 -10.341607) (xy 244.164866 -10.342118) (xy 246.165116 -10.342118)
			(xy 246.220923 -10.341596) (xy 246.332225 -10.333254) (xy 246.442592 -10.316618) (xy 246.551407 -10.29178)
			(xy 246.658062 -10.258881) (xy 246.76196 -10.218103) (xy 246.862521 -10.169676) (xy 246.959181 -10.113868)
			(xy 247.051401 -10.050994) (xy 247.138664 -9.981404) (xy 247.220483 -9.905487) (xy 247.2964 -9.823669)
			(xy 247.36599 -9.736406) (xy 247.428865 -9.644186) (xy 247.484673 -9.547526) (xy 247.533101 -9.446966)
			(xy 247.573879 -9.343068) (xy 247.606779 -9.236413) (xy 247.631617 -9.127598) (xy 247.648253 -9.017231)
			(xy 247.656595 -8.905929) (xy 247.657112 -8.850122) (xy 247.657112 0) (xy 247.657596 0.070354) (xy 247.665486 0.21084)
			(xy 247.68124 0.350663) (xy 247.70481 0.489383) (xy 247.73612 0.626563) (xy 247.775073 0.761772)
			(xy 247.821546 0.894583) (xy 247.875393 1.02458) (xy 247.936444 1.151354) (xy 248.004507 1.274505)
			(xy 248.079368 1.393645) (xy 248.160792 1.508401) (xy 248.248522 1.618411) (xy 248.342282 1.723328)
			(xy 248.441778 1.822823) (xy 248.546696 1.916583) (xy 248.656706 2.004313) (xy 248.771462 2.085736)
			(xy 248.890602 2.160597) (xy 249.013753 2.22866) (xy 249.140527 2.289711) (xy 249.270524 2.343557)
			(xy 249.403336 2.390029) (xy 249.538545 2.428982) (xy 249.675725 2.460292) (xy 249.814444 2.483861)
			(xy 249.954268 2.499615) (xy 250.094754 2.507504) (xy 250.165108 2.507996) (xy 266.165076 2.507996)
			(xy 266.23543 2.507512) (xy 266.375918 2.499624) (xy 266.515742 2.483871) (xy 266.654463 2.460303)
			(xy 266.791644 2.428993) (xy 266.926854 2.390041) (xy 267.059667 2.343569) (xy 267.189666 2.289723)
			(xy 267.31644 2.228672) (xy 267.439593 2.160609) (xy 267.558735 2.085749) (xy 267.673492 2.004325)
			(xy 267.783503 1.916595) (xy 267.888422 1.822835) (xy 267.987918 1.723339) (xy 268.08168 1.618421)
			(xy 268.169411 1.508411) (xy 268.250835 1.393655) (xy 268.325697 1.274513) (xy 268.393761 1.151362)
			(xy 268.454813 1.024588) (xy 268.50866 0.89459) (xy 268.555134 0.761777) (xy 268.594087 0.626568)
			(xy 268.625398 0.489387) (xy 268.648968 0.350666) (xy 268.664722 0.210842) (xy 268.672612 0.070354)
			(xy 268.673072 0) (xy 268.673072 -8.850122) (xy 268.673595 -8.905929) (xy 268.681937 -9.017231) (xy 268.698573 -9.127598)
			(xy 268.723411 -9.236413) (xy 268.75631 -9.343068) (xy 268.797088 -9.446966) (xy 268.845516 -9.547526)
			(xy 268.901323 -9.644187) (xy 268.964198 -9.736406) (xy 269.033788 -9.82367) (xy 269.109704 -9.905489)
			(xy 269.191523 -9.981406) (xy 269.278786 -10.050996) (xy 269.371005 -10.113871) (xy 269.467665 -10.169679)
			(xy 269.568225 -10.218108) (xy 269.672123 -10.258886) (xy 269.778777 -10.291787) (xy 269.887592 -10.316625)
			(xy 269.997959 -10.333262) (xy 270.109261 -10.341605) (xy 270.165068 -10.342118) (xy 272.165064 -10.342118)
			(xy 272.220873 -10.34161) (xy 272.332178 -10.333272) (xy 272.442549 -10.316638) (xy 272.551368 -10.291804)
			(xy 272.658028 -10.258906) (xy 272.76193 -10.21813) (xy 272.862495 -10.169703) (xy 272.95916 -10.113897)
			(xy 273.051383 -10.051022) (xy 273.138651 -9.981432) (xy 273.220473 -9.905515) (xy 273.296394 -9.823695)
			(xy 273.365988 -9.73643) (xy 273.428866 -9.644209) (xy 273.484676 -9.547546) (xy 273.533107 -9.446983)
			(xy 273.573887 -9.343082) (xy 273.606789 -9.236425) (xy 273.631628 -9.127606) (xy 273.648265 -9.017236)
			(xy 273.656608 -8.905931) (xy 273.65706 -8.850122) (xy 273.65706 0) (xy 273.657553 0.070354) (xy 273.665443 0.210841)
			(xy 273.681197 0.350665) (xy 273.704766 0.489385) (xy 273.736076 0.626566) (xy 273.775029 0.761775)
			(xy 273.821502 0.894588) (xy 273.875348 1.024585) (xy 273.936398 1.15136) (xy 274.004461 1.274511)
			(xy 274.079321 1.393653) (xy 274.160745 1.50841) (xy 274.248474 1.618421) (xy 274.342234 1.723339)
			(xy 274.441729 1.822836) (xy 274.546646 1.916598) (xy 274.656655 2.004329) (xy 274.771411 2.085754)
			(xy 274.890551 2.160617) (xy 275.013701 2.228682) (xy 275.140474 2.289734) (xy 275.270471 2.343583)
			(xy 275.403283 2.390058) (xy 275.538492 2.429013) (xy 275.675672 2.460325) (xy 275.814392 2.483897)
			(xy 275.954215 2.499654) (xy 276.094702 2.507545) (xy 276.165056 2.507996) (xy 292.165024 2.507996)
			(xy 292.235377 2.507502) (xy 292.375862 2.499611) (xy 292.515684 2.483856) (xy 292.654403 2.460285)
			(xy 292.791581 2.428974) (xy 292.926788 2.390021) (xy 293.059599 2.343547) (xy 293.189594 2.2897)
			(xy 293.316366 2.228649) (xy 293.439515 2.160586) (xy 293.558655 2.085724) (xy 293.673409 2.004301)
			(xy 293.783417 1.916571) (xy 293.888334 1.822811) (xy 293.987828 1.723316) (xy 294.081587 1.618399)
			(xy 294.169315 1.50839) (xy 294.250738 1.393635) (xy 294.325598 1.274495) (xy 294.39366 1.151345)
			(xy 294.45471 1.024572) (xy 294.508556 0.894576) (xy 294.555028 0.761765) (xy 294.59398 0.626558)
			(xy 294.62529 0.489379) (xy 294.648859 0.35066) (xy 294.664613 0.210839) (xy 294.672503 0.070353)
			(xy 294.67302 0) (xy 294.67302 -8.850122) (xy 294.673543 -8.905928) (xy 294.681885 -9.017229) (xy 294.698522 -9.127594)
			(xy 294.723359 -9.236408) (xy 294.756259 -9.343062) (xy 294.797037 -9.446958) (xy 294.845465 -9.547517)
			(xy 294.901273 -9.644176) (xy 294.964148 -9.736394) (xy 295.033738 -9.823655) (xy 295.109655 -9.905472)
			(xy 295.191474 -9.981387) (xy 295.278737 -10.050975) (xy 295.370956 -10.113847) (xy 295.467616 -10.169652)
			(xy 295.568176 -10.218078) (xy 295.672074 -10.258853) (xy 295.778728 -10.291751) (xy 295.887543 -10.316586)
			(xy 295.997909 -10.333219) (xy 296.10921 -10.341559) (xy 296.165016 -10.342118) (xy 298.165012 -10.342118)
			(xy 298.220819 -10.341596) (xy 298.332121 -10.333254) (xy 298.442488 -10.316618) (xy 298.551304 -10.291781)
			(xy 298.657959 -10.258882) (xy 298.761858 -10.218105) (xy 298.862418 -10.169677) (xy 298.959079 -10.11387)
			(xy 299.051299 -10.050995) (xy 299.138562 -9.981405) (xy 299.220382 -9.905489) (xy 299.296299 -9.82367)
			(xy 299.365889 -9.736407) (xy 299.428764 -9.644188) (xy 299.484572 -9.547527) (xy 299.533001 -9.446967)
			(xy 299.573779 -9.343069) (xy 299.606679 -9.236414) (xy 299.631516 -9.127598) (xy 299.648153 -9.017231)
			(xy 299.656495 -8.905929) (xy 299.657008 -8.850122) (xy 299.657008 0) (xy 299.657492 0.070354) (xy 299.665382 0.21084)
			(xy 299.681136 0.350664) (xy 299.704706 0.489383) (xy 299.736016 0.626564) (xy 299.774969 0.761772)
			(xy 299.821442 0.894584) (xy 299.875289 1.024581) (xy 299.93634 1.151355) (xy 300.004403 1.274505)
			(xy 300.079264 1.393646) (xy 300.160688 1.508402) (xy 300.248418 1.618412) (xy 300.342178 1.723329)
			(xy 300.441673 1.822825) (xy 300.546591 1.916585) (xy 300.656601 2.004315) (xy 300.771357 2.085738)
			(xy 300.890498 2.160599) (xy 301.013649 2.228662) (xy 301.140423 2.289713) (xy 301.27042 2.343559)
			(xy 301.403232 2.390032) (xy 301.53844 2.428985) (xy 301.67562 2.460295) (xy 301.81434 2.483864)
			(xy 301.954163 2.499618) (xy 302.09465 2.507508) (xy 302.165004 2.507996) (xy 318.164972 2.507996)
			(xy 318.235326 2.507512) (xy 318.375814 2.499624) (xy 318.515639 2.483871) (xy 318.65436 2.460303)
			(xy 318.791541 2.428994) (xy 318.926751 2.390042) (xy 319.059564 2.34357) (xy 319.189563 2.289724)
			(xy 319.316338 2.228673) (xy 319.43949 2.160611) (xy 319.558633 2.08575) (xy 319.67339 2.004327)
			(xy 319.783401 1.916597) (xy 319.88832 1.822836) (xy 319.987817 1.723341) (xy 320.081579 1.618423)
			(xy 320.16931 1.508412) (xy 320.250734 1.393656) (xy 320.325597 1.274514) (xy 320.393661 1.151363)
			(xy 320.454712 1.024589) (xy 320.50856 0.894591) (xy 320.555033 0.761778) (xy 320.593987 0.626568)
			(xy 320.625298 0.489387) (xy 320.648868 0.350666) (xy 320.664622 0.210842) (xy 320.672512 0.070354)
			(xy 320.672968 0) (xy 320.672968 -8.850122) (xy 320.673491 -8.905929) (xy 320.681833 -9.017231) (xy 320.698469 -9.127598)
			(xy 320.723307 -9.236413) (xy 320.756206 -9.343068) (xy 320.796984 -9.446967) (xy 320.845412 -9.547527)
			(xy 320.901219 -9.644188) (xy 320.964093 -9.736408) (xy 321.033684 -9.823671) (xy 321.1096 -9.90549)
			(xy 321.191418 -9.981407) (xy 321.278681 -10.050998) (xy 321.3709 -10.113873) (xy 321.46756 -10.169682)
			(xy 321.56812 -10.21811) (xy 321.672018 -10.258889) (xy 321.778673 -10.29179) (xy 321.887488 -10.316628)
			(xy 321.997855 -10.333266) (xy 322.109157 -10.341609) (xy 322.164964 -10.342118) (xy 324.16496 -10.342118)
			(xy 324.220769 -10.34161) (xy 324.332074 -10.333272) (xy 324.442446 -10.316639) (xy 324.551265 -10.291805)
			(xy 324.657925 -10.258907) (xy 324.761827 -10.218131) (xy 324.862393 -10.169705) (xy 324.959057 -10.113898)
			(xy 325.051281 -10.051024) (xy 325.138549 -9.981433) (xy 325.220372 -9.905516) (xy 325.296293 -9.823696)
			(xy 325.365887 -9.736431) (xy 325.428765 -9.64421) (xy 325.484576 -9.547547) (xy 325.533007 -9.446984)
			(xy 325.573787 -9.343083) (xy 325.606689 -9.236425) (xy 325.631528 -9.127607) (xy 325.648165 -9.017236)
			(xy 325.656508 -8.905931) (xy 325.656956 -8.850122) (xy 325.656956 0) (xy 325.657449 0.070354) (xy 325.665339 0.210841)
			(xy 325.681093 0.350665) (xy 325.704662 0.489386) (xy 325.735972 0.626566) (xy 325.774925 0.761776)
			(xy 325.821398 0.894588) (xy 325.875244 1.024586) (xy 325.936294 1.15136) (xy 326.004357 1.274512)
			(xy 326.079217 1.393654) (xy 326.16064 1.508411) (xy 326.24837 1.618422) (xy 326.342129 1.723341)
			(xy 326.441624 1.822838) (xy 326.546542 1.916599) (xy 326.656551 2.004331) (xy 326.771306 2.085756)
			(xy 326.890447 2.160619) (xy 327.013597 2.228684) (xy 327.14037 2.289737) (xy 327.270367 2.343585)
			(xy 327.403179 2.39006) (xy 327.538387 2.429016) (xy 327.675567 2.460328) (xy 327.814287 2.4839)
			(xy 327.954111 2.499657) (xy 328.094598 2.507549) (xy 328.164952 2.507996) (xy 356.264972 2.507996)
			(xy 356.335326 2.507512) (xy 356.475814 2.499624) (xy 356.615639 2.483871) (xy 356.75436 2.460303)
			(xy 356.891541 2.428994) (xy 357.026751 2.390042) (xy 357.159564 2.34357) (xy 357.289563 2.289724)
			(xy 357.416338 2.228673) (xy 357.53949 2.160611) (xy 357.658633 2.08575) (xy 357.77339 2.004327)
			(xy 357.883401 1.916597) (xy 357.98832 1.822836) (xy 358.087817 1.723341) (xy 358.181579 1.618423)
			(xy 358.26931 1.508412) (xy 358.350734 1.393656) (xy 358.425597 1.274514) (xy 358.493661 1.151363)
			(xy 358.554712 1.024589) (xy 358.60856 0.894591) (xy 358.655033 0.761778) (xy 358.693987 0.626568)
			(xy 358.725298 0.489387) (xy 358.748868 0.350666) (xy 358.764622 0.210842) (xy 358.772512 0.070354)
			(xy 358.772968 0) (xy 358.772968 -8.850122) (xy 358.773491 -8.905929) (xy 358.781833 -9.017231) (xy 358.798469 -9.127598)
			(xy 358.823307 -9.236413) (xy 358.856206 -9.343068) (xy 358.896984 -9.446967) (xy 358.945412 -9.547527)
			(xy 359.001219 -9.644188) (xy 359.064093 -9.736408) (xy 359.133684 -9.823671) (xy 359.2096 -9.90549)
			(xy 359.291418 -9.981407) (xy 359.378681 -10.050998) (xy 359.4709 -10.113873) (xy 359.56756 -10.169682)
			(xy 359.66812 -10.21811) (xy 359.772018 -10.258889) (xy 359.878673 -10.29179) (xy 359.987488 -10.316628)
			(xy 360.097855 -10.333266) (xy 360.209157 -10.341609) (xy 360.264964 -10.342118) (xy 362.26496 -10.342118)
			(xy 362.320769 -10.34161) (xy 362.432074 -10.333272) (xy 362.542446 -10.316639) (xy 362.651265 -10.291805)
			(xy 362.757925 -10.258907) (xy 362.861827 -10.218131) (xy 362.962393 -10.169705) (xy 363.059057 -10.113898)
			(xy 363.151281 -10.051024) (xy 363.238549 -9.981433) (xy 363.320372 -9.905516) (xy 363.396293 -9.823696)
			(xy 363.465887 -9.736431) (xy 363.528765 -9.64421) (xy 363.584576 -9.547547) (xy 363.633007 -9.446984)
			(xy 363.673787 -9.343083) (xy 363.706689 -9.236425) (xy 363.731528 -9.127607) (xy 363.748165 -9.017236)
			(xy 363.756508 -8.905931) (xy 363.756956 -8.850122) (xy 363.756956 0) (xy 363.757449 0.070354) (xy 363.765339 0.210841)
			(xy 363.781093 0.350665) (xy 363.804662 0.489386) (xy 363.835972 0.626566) (xy 363.874925 0.761776)
			(xy 363.921398 0.894588) (xy 363.975244 1.024586) (xy 364.036294 1.15136) (xy 364.104357 1.274512)
			(xy 364.179217 1.393654) (xy 364.26064 1.508411) (xy 364.34837 1.618422) (xy 364.442129 1.723341)
			(xy 364.541624 1.822838) (xy 364.646542 1.916599) (xy 364.756551 2.004331) (xy 364.871306 2.085756)
			(xy 364.990447 2.160619) (xy 365.113597 2.228684) (xy 365.24037 2.289737) (xy 365.370367 2.343585)
			(xy 365.503179 2.39006) (xy 365.638387 2.429016) (xy 365.775567 2.460328) (xy 365.914287 2.4839)
			(xy 366.054111 2.499657) (xy 366.194598 2.507549) (xy 366.264952 2.507996) (xy 382.26492 2.507996)
			(xy 382.335273 2.507502) (xy 382.475759 2.499612) (xy 382.615581 2.483856) (xy 382.754299 2.460286)
			(xy 382.891478 2.428975) (xy 383.026685 2.390022) (xy 383.159496 2.343548) (xy 383.289491 2.289701)
			(xy 383.416264 2.22865) (xy 383.539413 2.160587) (xy 383.658552 2.085726) (xy 383.773307 2.004302)
			(xy 383.883316 1.916573) (xy 383.988232 1.822813) (xy 384.087726 1.723318) (xy 384.181485 1.6184)
			(xy 384.269214 1.508391) (xy 384.350637 1.393636) (xy 384.425497 1.274496) (xy 384.493559 1.151346)
			(xy 384.554609 1.024573) (xy 384.608455 0.894577) (xy 384.654928 0.761766) (xy 384.69388 0.626559)
			(xy 384.72519 0.48938) (xy 384.748759 0.350661) (xy 384.764513 0.210839) (xy 384.772403 0.070353)
			(xy 384.772916 0) (xy 384.772916 -8.850122) (xy 384.773439 -8.905928) (xy 384.781781 -9.017229) (xy 384.798418 -9.127595)
			(xy 384.823255 -9.236409) (xy 384.856155 -9.343062) (xy 384.896933 -9.446959) (xy 384.945361 -9.547518)
			(xy 385.001169 -9.644177) (xy 385.064044 -9.736395) (xy 385.133634 -9.823656) (xy 385.209551 -9.905473)
			(xy 385.29137 -9.981388) (xy 385.378633 -10.050977) (xy 385.470852 -10.113849) (xy 385.567512 -10.169655)
			(xy 385.668072 -10.218081) (xy 385.77197 -10.258856) (xy 385.878624 -10.291754) (xy 385.987439 -10.316589)
			(xy 386.097805 -10.333223) (xy 386.209106 -10.341563) (xy 386.264912 -10.342118) (xy 388.264908 -10.342118)
			(xy 388.320715 -10.341596) (xy 388.432017 -10.333255) (xy 388.542385 -10.316619) (xy 388.651201 -10.291782)
			(xy 388.757856 -10.258883) (xy 388.861755 -10.218106) (xy 388.962316 -10.169678) (xy 389.058977 -10.113871)
			(xy 389.151197 -10.050997) (xy 389.238461 -9.981407) (xy 389.32028 -9.90549) (xy 389.396198 -9.823671)
			(xy 389.465789 -9.736408) (xy 389.528664 -9.644189) (xy 389.584472 -9.547528) (xy 389.6329 -9.446968)
			(xy 389.673678 -9.343069) (xy 389.706579 -9.236414) (xy 389.731416 -9.127599) (xy 389.748053 -9.017231)
			(xy 389.756395 -8.905929) (xy 389.756904 -8.850122) (xy 389.756904 0) (xy 389.757397 0.070354) (xy 389.765287 0.21084)
			(xy 389.781041 0.350663) (xy 389.80461 0.489382) (xy 389.835921 0.626562) (xy 389.874874 0.76177)
			(xy 389.921346 0.894581) (xy 389.975193 1.024578) (xy 390.036243 1.151351) (xy 390.104306 1.274502)
			(xy 390.179167 1.393642) (xy 390.260591 1.508398) (xy 390.34832 1.618407) (xy 390.44208 1.723325)
			(xy 390.541575 1.82282) (xy 390.646493 1.91658) (xy 390.756502 2.004309) (xy 390.871258 2.085733)
			(xy 390.990398 2.160594) (xy 391.113549 2.228657) (xy 391.240322 2.289707) (xy 391.370319 2.343554)
			(xy 391.50313 2.390026) (xy 391.638338 2.428979) (xy 391.775518 2.46029) (xy 391.914237 2.483859)
			(xy 392.05406 2.499613) (xy 392.194546 2.507503) (xy 392.2649 2.507996) (xy 408.265122 2.507996)
			(xy 408.335475 2.507502) (xy 408.475961 2.499611) (xy 408.615782 2.483856) (xy 408.754501 2.460286)
			(xy 408.89168 2.428975) (xy 409.026887 2.390021) (xy 409.159697 2.343548) (xy 409.289693 2.289701)
			(xy 409.416465 2.22865) (xy 409.539614 2.160586) (xy 409.658754 2.085725) (xy 409.773508 2.004302)
			(xy 409.883516 1.916572) (xy 409.988433 1.822812) (xy 410.087927 1.723317) (xy 410.181686 1.6184)
			(xy 410.269415 1.50839) (xy 410.350837 1.393635) (xy 410.425697 1.274495) (xy 410.49376 1.151345)
			(xy 410.55481 1.024573) (xy 410.608655 0.894577) (xy 410.655128 0.761766) (xy 410.69408 0.626558)
			(xy 410.72539 0.489379) (xy 410.748959 0.350661) (xy 410.764713 0.210839) (xy 410.772603 0.070353)
			(xy 410.773118 0) (xy 410.773118 -8.850122) (xy 410.773641 -8.905928) (xy 410.781983 -9.017229) (xy 410.79862 -9.127595)
			(xy 410.823457 -9.236408) (xy 410.856357 -9.343062) (xy 410.897135 -9.446959) (xy 410.945563 -9.547518)
			(xy 411.001371 -9.644176) (xy 411.064246 -9.736394) (xy 411.133836 -9.823656) (xy 411.209753 -9.905472)
			(xy 411.291572 -9.981387) (xy 411.378835 -10.050976) (xy 411.471054 -10.113848) (xy 411.567714 -10.169653)
			(xy 411.668274 -10.218079) (xy 411.772172 -10.258855) (xy 411.878826 -10.291752) (xy 411.987641 -10.316587)
			(xy 412.098007 -10.333221) (xy 412.209308 -10.341561) (xy 412.265114 -10.342118) (xy 414.26511 -10.342118)
			(xy 414.320917 -10.341596) (xy 414.432219 -10.333254) (xy 414.542587 -10.316619) (xy 414.651402 -10.291782)
			(xy 414.758058 -10.258883) (xy 414.861956 -10.218105) (xy 414.962517 -10.169678) (xy 415.059178 -10.11387)
			(xy 415.151398 -10.050996) (xy 415.238662 -9.981406) (xy 415.320481 -9.905489) (xy 415.396398 -9.823671)
			(xy 415.465989 -9.736408) (xy 415.528864 -9.644188) (xy 415.584672 -9.547528) (xy 415.6331 -9.446967)
			(xy 415.673879 -9.343069) (xy 415.706779 -9.236414) (xy 415.731616 -9.127598) (xy 415.748253 -9.017231)
			(xy 415.756595 -8.905929) (xy 415.757106 -8.850122) (xy 415.757106 0) (xy 415.75759 0.070354) (xy 415.76548 0.210841)
			(xy 415.781234 0.350664) (xy 415.804804 0.489384) (xy 415.836114 0.626564) (xy 415.875067 0.761772)
			(xy 415.92154 0.894584) (xy 415.975387 1.024581) (xy 416.036438 1.151355) (xy 416.104501 1.274506)
			(xy 416.179362 1.393647) (xy 416.260785 1.508402) (xy 416.348515 1.618412) (xy 416.442276 1.72333)
			(xy 416.541771 1.822826) (xy 416.646689 1.916586) (xy 416.756699 2.004316) (xy 416.871455 2.085739)
			(xy 416.990596 2.1606) (xy 417.113747 2.228663) (xy 417.24052 2.289714) (xy 417.370518 2.343561)
			(xy 417.503329 2.390034) (xy 417.638538 2.428986) (xy 417.775718 2.460297) (xy 417.914438 2.483866)
			(xy 418.054261 2.49962) (xy 418.194748 2.50751) (xy 418.265102 2.507996) (xy 434.26507 2.507996)
			(xy 434.335425 2.507513) (xy 434.475912 2.499625) (xy 434.615737 2.483872) (xy 434.754458 2.460304)
			(xy 434.89164 2.428994) (xy 435.02685 2.390042) (xy 435.159663 2.34357) (xy 435.289662 2.289724)
			(xy 435.416437 2.228674) (xy 435.539589 2.160612) (xy 435.658732 2.085751) (xy 435.773489 2.004327)
			(xy 435.8835 1.916597) (xy 435.988419 1.822837) (xy 436.087916 1.723341) (xy 436.181678 1.618423)
			(xy 436.269409 1.508413) (xy 436.350834 1.393656) (xy 436.425696 1.274515) (xy 436.49376 1.151363)
			(xy 436.554812 1.024589) (xy 436.60866 0.894591) (xy 436.655133 0.761778) (xy 436.694087 0.626569)
			(xy 436.725398 0.489387) (xy 436.748967 0.350667) (xy 436.764722 0.210842) (xy 436.772612 0.070355)
			(xy 436.773066 0) (xy 436.773066 -8.850122) (xy 436.773589 -8.905929) (xy 436.781931 -9.017231) (xy 436.798567 -9.127598)
			(xy 436.823405 -9.236414) (xy 436.856304 -9.343069) (xy 436.897082 -9.446967) (xy 436.94551 -9.547528)
			(xy 437.001317 -9.644188) (xy 437.064191 -9.736408) (xy 437.133781 -9.823672) (xy 437.209698 -9.905491)
			(xy 437.291516 -9.981408) (xy 437.378779 -10.050999) (xy 437.470998 -10.113874) (xy 437.567658 -10.169683)
			(xy 437.668218 -10.218112) (xy 437.772116 -10.25889) (xy 437.878771 -10.291791) (xy 437.987586 -10.31663)
			(xy 438.097953 -10.333267) (xy 438.209255 -10.341611) (xy 438.265062 -10.342118) (xy 440.265058 -10.342118)
			(xy 440.320867 -10.34161) (xy 440.432173 -10.333272) (xy 440.542544 -10.316639) (xy 440.651364 -10.291805)
			(xy 440.758023 -10.258908) (xy 440.861926 -10.218132) (xy 440.962491 -10.169705) (xy 441.059156 -10.113899)
			(xy 441.151381 -10.051025) (xy 441.238648 -9.981434) (xy 441.320471 -9.905517) (xy 441.396392 -9.823697)
			(xy 441.465987 -9.736432) (xy 441.528865 -9.64421) (xy 441.584675 -9.547548) (xy 441.633106 -9.446985)
			(xy 441.673887 -9.343084) (xy 441.706788 -9.236425) (xy 441.731628 -9.127607) (xy 441.748265 -9.017236)
			(xy 441.756608 -8.905931) (xy 441.757054 -8.850122) (xy 441.757054 0) (xy 441.757538 0.070353) (xy 441.765428 0.210839)
			(xy 441.781182 0.350661) (xy 441.804752 0.48938) (xy 441.836062 0.626559) (xy 441.875016 0.761767)
			(xy 441.921489 0.894578) (xy 441.975336 1.024574) (xy 442.036387 1.151346) (xy 442.10445 1.274495)
			(xy 442.179312 1.393635) (xy 442.260736 1.508389) (xy 442.348466 1.618398) (xy 442.442227 1.723314)
			(xy 442.541722 1.822808) (xy 442.64664 1.916566) (xy 442.756651 2.004294) (xy 442.871407 2.085716)
			(xy 442.990548 2.160575) (xy 443.113699 2.228636) (xy 443.240472 2.289685) (xy 443.370469 2.343529)
			(xy 443.503281 2.39) (xy 443.638489 2.42895) (xy 443.775669 2.460258) (xy 443.914388 2.483825) (xy 444.054211 2.499576)
			(xy 444.194697 2.507463) (xy 444.26505 2.507996) (xy 465.600034 2.507996) (xy 465.65584 2.508519)
			(xy 465.767141 2.516862) (xy 465.877506 2.533499) (xy 465.98632 2.558338) (xy 466.092974 2.591238)
			(xy 466.19687 2.632016) (xy 466.297429 2.680445) (xy 466.394088 2.736252) (xy 466.486306 2.799127)
			(xy 466.573567 2.868717) (xy 466.655384 2.944634) (xy 466.7313 3.026452) (xy 466.800888 3.113715)
			(xy 466.863762 3.205934) (xy 466.919568 3.302594) (xy 466.967994 3.403154) (xy 467.008771 3.507051)
			(xy 467.041669 3.613705) (xy 467.066505 3.722519) (xy 467.083141 3.832885) (xy 467.091482 3.944186)
			(xy 467.09203 3.999992) (xy 467.09203 24.157686) (xy 467.091509 24.213494) (xy 467.083169 24.324797)
			(xy 467.066535 24.435167) (xy 467.041699 24.543984) (xy 467.008801 24.650641) (xy 466.968025 24.754542)
			(xy 466.919598 24.855105) (xy 466.863791 24.951768) (xy 466.800917 25.04399) (xy 466.731327 25.131255)
			(xy 466.655411 25.213077) (xy 466.573592 25.288996) (xy 466.486328 25.358589) (xy 466.394108 25.421466)
			(xy 466.297447 25.477275) (xy 466.196886 25.525705) (xy 466.092987 25.566485) (xy 465.986331 25.599387)
			(xy 465.877514 25.624226) (xy 465.767145 25.640863) (xy 465.655842 25.649207) (xy 465.600034 25.649682)
			(xy 160.11398 25.649682) (xy 160.058174 25.64916) (xy 159.946873 25.640817) (xy 159.836507 25.624181)
			(xy 159.727693 25.599343) (xy 159.62104 25.566443) (xy 159.517143 25.525665) (xy 159.416584 25.477237)
			(xy 159.319925 25.42143) (xy 159.227707 25.358555) (xy 159.140445 25.288965) (xy 159.058628 25.213048)
			(xy 158.982713 25.131229) (xy 158.913125 25.043966) (xy 158.850252 24.951746) (xy 158.794447 24.855086)
			(xy 158.746021 24.754526) (xy 158.705245 24.650628) (xy 158.672348 24.543974) (xy 158.647513 24.435159)
			(xy 158.630879 24.324793) (xy 158.622539 24.213492) (xy 158.621984 24.157686) (xy 158.621984 21.802649)
			(xy 269.304757 21.802649) (xy 269.304757 21.888399) (xy 269.312669 21.973782) (xy 269.328425 22.058072)
			(xy 269.351892 22.140548) (xy 269.382868 22.220507) (xy 269.42109 22.297267) (xy 269.466231 22.370173)
			(xy 269.517907 22.438602) (xy 269.575676 22.501972) (xy 269.639046 22.559741) (xy 269.707475 22.611417)
			(xy 269.780381 22.656558) (xy 269.857141 22.69478) (xy 269.9371 22.725756) (xy 270.019576 22.749223)
			(xy 270.103866 22.764979) (xy 270.189249 22.772891) (xy 270.274999 22.772891) (xy 270.360382 22.764979)
			(xy 270.444672 22.749223) (xy 270.527148 22.725756) (xy 270.607107 22.69478) (xy 270.683867 22.656558)
			(xy 270.756773 22.611417) (xy 270.825202 22.559741) (xy 270.888572 22.501972) (xy 270.946341 22.438602)
			(xy 270.998017 22.370173) (xy 271.043158 22.297267) (xy 271.08138 22.220507) (xy 271.112356 22.140548)
			(xy 271.135823 22.058072) (xy 271.151579 21.973782) (xy 271.159491 21.888399) (xy 271.159986 21.845524)
			(xy 271.159491 21.802649) (xy 275.654757 21.802649) (xy 275.654757 21.888399) (xy 275.662669 21.973782)
			(xy 275.678425 22.058072) (xy 275.701892 22.140548) (xy 275.732868 22.220507) (xy 275.77109 22.297267)
			(xy 275.816231 22.370173) (xy 275.867907 22.438602) (xy 275.925676 22.501972) (xy 275.989046 22.559741)
			(xy 276.057475 22.611417) (xy 276.130381 22.656558) (xy 276.207141 22.69478) (xy 276.2871 22.725756)
			(xy 276.369576 22.749223) (xy 276.453866 22.764979) (xy 276.539249 22.772891) (xy 276.624999 22.772891)
			(xy 276.710382 22.764979) (xy 276.794672 22.749223) (xy 276.877148 22.725756) (xy 276.957107 22.69478)
			(xy 277.033867 22.656558) (xy 277.106773 22.611417) (xy 277.175202 22.559741) (xy 277.238572 22.501972)
			(xy 277.296341 22.438602) (xy 277.348017 22.370173) (xy 277.393158 22.297267) (xy 277.43138 22.220507)
			(xy 277.462356 22.140548) (xy 277.485823 22.058072) (xy 277.501579 21.973782) (xy 277.509491 21.888399)
			(xy 277.509986 21.845524) (xy 277.509491 21.802649) (xy 277.508832 21.795537) (xy 308.364877 21.795537)
			(xy 308.364877 21.881287) (xy 308.372789 21.96667) (xy 308.388545 22.05096) (xy 308.412012 22.133436)
			(xy 308.442988 22.213395) (xy 308.48121 22.290155) (xy 308.526351 22.363061) (xy 308.578027 22.43149)
			(xy 308.635796 22.49486) (xy 308.699166 22.552629) (xy 308.767595 22.604305) (xy 308.840501 22.649446)
			(xy 308.917261 22.687668) (xy 308.99722 22.718644) (xy 309.079696 22.742111) (xy 309.163986 22.757867)
			(xy 309.249369 22.765779) (xy 309.335119 22.765779) (xy 309.420502 22.757867) (xy 309.504792 22.742111)
			(xy 309.587268 22.718644) (xy 309.667227 22.687668) (xy 309.743987 22.649446) (xy 309.816893 22.604305)
			(xy 309.885322 22.552629) (xy 309.948692 22.49486) (xy 310.006461 22.43149) (xy 310.058137 22.363061)
			(xy 310.103278 22.290155) (xy 310.1415 22.213395) (xy 310.172476 22.133436) (xy 310.195943 22.05096)
			(xy 310.211699 21.96667) (xy 310.219611 21.881287) (xy 310.220106 21.838412) (xy 310.219611 21.795537)
			(xy 314.714877 21.795537) (xy 314.714877 21.881287) (xy 314.722789 21.96667) (xy 314.738545 22.05096)
			(xy 314.762012 22.133436) (xy 314.792988 22.213395) (xy 314.83121 22.290155) (xy 314.876351 22.363061)
			(xy 314.928027 22.43149) (xy 314.985796 22.49486) (xy 315.049166 22.552629) (xy 315.117595 22.604305)
			(xy 315.190501 22.649446) (xy 315.267261 22.687668) (xy 315.34722 22.718644) (xy 315.429696 22.742111)
			(xy 315.513986 22.757867) (xy 315.599369 22.765779) (xy 315.685119 22.765779) (xy 315.770502 22.757867)
			(xy 315.854792 22.742111) (xy 315.937268 22.718644) (xy 316.017227 22.687668) (xy 316.093987 22.649446)
			(xy 316.166893 22.604305) (xy 316.235322 22.552629) (xy 316.298692 22.49486) (xy 316.356461 22.43149)
			(xy 316.408137 22.363061) (xy 316.453278 22.290155) (xy 316.4915 22.213395) (xy 316.522476 22.133436)
			(xy 316.545943 22.05096) (xy 316.561699 21.96667) (xy 316.569611 21.881287) (xy 316.570106 21.838412)
			(xy 316.569693 21.802649) (xy 334.455757 21.802649) (xy 334.455757 21.888399) (xy 334.463669 21.973782)
			(xy 334.479425 22.058072) (xy 334.502892 22.140548) (xy 334.533868 22.220507) (xy 334.57209 22.297267)
			(xy 334.617231 22.370173) (xy 334.668907 22.438602) (xy 334.726676 22.501972) (xy 334.790046 22.559741)
			(xy 334.858475 22.611417) (xy 334.931381 22.656558) (xy 335.008141 22.69478) (xy 335.0881 22.725756)
			(xy 335.170576 22.749223) (xy 335.254866 22.764979) (xy 335.340249 22.772891) (xy 335.425999 22.772891)
			(xy 335.511382 22.764979) (xy 335.595672 22.749223) (xy 335.678148 22.725756) (xy 335.758107 22.69478)
			(xy 335.834867 22.656558) (xy 335.907773 22.611417) (xy 335.976202 22.559741) (xy 336.039572 22.501972)
			(xy 336.097341 22.438602) (xy 336.149017 22.370173) (xy 336.194158 22.297267) (xy 336.23238 22.220507)
			(xy 336.263356 22.140548) (xy 336.286823 22.058072) (xy 336.302579 21.973782) (xy 336.310491 21.888399)
			(xy 336.310986 21.845524) (xy 336.310491 21.802649) (xy 340.805757 21.802649) (xy 340.805757 21.888399)
			(xy 340.813669 21.973782) (xy 340.829425 22.058072) (xy 340.852892 22.140548) (xy 340.883868 22.220507)
			(xy 340.92209 22.297267) (xy 340.967231 22.370173) (xy 341.018907 22.438602) (xy 341.076676 22.501972)
			(xy 341.140046 22.559741) (xy 341.208475 22.611417) (xy 341.281381 22.656558) (xy 341.358141 22.69478)
			(xy 341.4381 22.725756) (xy 341.520576 22.749223) (xy 341.604866 22.764979) (xy 341.690249 22.772891)
			(xy 341.775999 22.772891) (xy 341.861382 22.764979) (xy 341.945672 22.749223) (xy 342.028148 22.725756)
			(xy 342.108107 22.69478) (xy 342.184867 22.656558) (xy 342.257773 22.611417) (xy 342.326202 22.559741)
			(xy 342.389572 22.501972) (xy 342.447341 22.438602) (xy 342.499017 22.370173) (xy 342.544158 22.297267)
			(xy 342.58238 22.220507) (xy 342.613356 22.140548) (xy 342.636823 22.058072) (xy 342.652579 21.973782)
			(xy 342.660491 21.888399) (xy 342.660986 21.845524) (xy 342.660491 21.802649) (xy 342.659832 21.795537)
			(xy 373.515877 21.795537) (xy 373.515877 21.881287) (xy 373.523789 21.96667) (xy 373.539545 22.05096)
			(xy 373.563012 22.133436) (xy 373.593988 22.213395) (xy 373.63221 22.290155) (xy 373.677351 22.363061)
			(xy 373.729027 22.43149) (xy 373.786796 22.49486) (xy 373.850166 22.552629) (xy 373.918595 22.604305)
			(xy 373.991501 22.649446) (xy 374.068261 22.687668) (xy 374.14822 22.718644) (xy 374.230696 22.742111)
			(xy 374.314986 22.757867) (xy 374.400369 22.765779) (xy 374.486119 22.765779) (xy 374.571502 22.757867)
			(xy 374.655792 22.742111) (xy 374.738268 22.718644) (xy 374.818227 22.687668) (xy 374.894987 22.649446)
			(xy 374.967893 22.604305) (xy 375.036322 22.552629) (xy 375.099692 22.49486) (xy 375.157461 22.43149)
			(xy 375.209137 22.363061) (xy 375.254278 22.290155) (xy 375.2925 22.213395) (xy 375.323476 22.133436)
			(xy 375.346943 22.05096) (xy 375.362699 21.96667) (xy 375.370611 21.881287) (xy 375.371106 21.838412)
			(xy 375.370611 21.795537) (xy 379.865877 21.795537) (xy 379.865877 21.881287) (xy 379.873789 21.96667)
			(xy 379.889545 22.05096) (xy 379.913012 22.133436) (xy 379.943988 22.213395) (xy 379.98221 22.290155)
			(xy 380.027351 22.363061) (xy 380.079027 22.43149) (xy 380.136796 22.49486) (xy 380.200166 22.552629)
			(xy 380.268595 22.604305) (xy 380.341501 22.649446) (xy 380.418261 22.687668) (xy 380.49822 22.718644)
			(xy 380.580696 22.742111) (xy 380.664986 22.757867) (xy 380.750369 22.765779) (xy 380.836119 22.765779)
			(xy 380.921502 22.757867) (xy 381.005792 22.742111) (xy 381.088268 22.718644) (xy 381.168227 22.687668)
			(xy 381.244987 22.649446) (xy 381.317893 22.604305) (xy 381.386322 22.552629) (xy 381.449692 22.49486)
			(xy 381.507461 22.43149) (xy 381.559137 22.363061) (xy 381.604278 22.290155) (xy 381.6425 22.213395)
			(xy 381.673476 22.133436) (xy 381.696943 22.05096) (xy 381.712699 21.96667) (xy 381.720611 21.881287)
			(xy 381.721106 21.838412) (xy 381.720693 21.802649) (xy 399.098757 21.802649) (xy 399.098757 21.888399)
			(xy 399.106669 21.973782) (xy 399.122425 22.058072) (xy 399.145892 22.140548) (xy 399.176868 22.220507)
			(xy 399.21509 22.297267) (xy 399.260231 22.370173) (xy 399.311907 22.438602) (xy 399.369676 22.501972)
			(xy 399.433046 22.559741) (xy 399.501475 22.611417) (xy 399.574381 22.656558) (xy 399.651141 22.69478)
			(xy 399.7311 22.725756) (xy 399.813576 22.749223) (xy 399.897866 22.764979) (xy 399.983249 22.772891)
			(xy 400.068999 22.772891) (xy 400.154382 22.764979) (xy 400.238672 22.749223) (xy 400.321148 22.725756)
			(xy 400.401107 22.69478) (xy 400.477867 22.656558) (xy 400.550773 22.611417) (xy 400.619202 22.559741)
			(xy 400.682572 22.501972) (xy 400.740341 22.438602) (xy 400.792017 22.370173) (xy 400.837158 22.297267)
			(xy 400.87538 22.220507) (xy 400.906356 22.140548) (xy 400.929823 22.058072) (xy 400.945579 21.973782)
			(xy 400.953491 21.888399) (xy 400.953986 21.845524) (xy 400.953491 21.802649) (xy 405.448757 21.802649)
			(xy 405.448757 21.888399) (xy 405.456669 21.973782) (xy 405.472425 22.058072) (xy 405.495892 22.140548)
			(xy 405.526868 22.220507) (xy 405.56509 22.297267) (xy 405.610231 22.370173) (xy 405.661907 22.438602)
			(xy 405.719676 22.501972) (xy 405.783046 22.559741) (xy 405.851475 22.611417) (xy 405.924381 22.656558)
			(xy 406.001141 22.69478) (xy 406.0811 22.725756) (xy 406.163576 22.749223) (xy 406.247866 22.764979)
			(xy 406.333249 22.772891) (xy 406.418999 22.772891) (xy 406.504382 22.764979) (xy 406.588672 22.749223)
			(xy 406.671148 22.725756) (xy 406.751107 22.69478) (xy 406.827867 22.656558) (xy 406.900773 22.611417)
			(xy 406.969202 22.559741) (xy 407.032572 22.501972) (xy 407.090341 22.438602) (xy 407.142017 22.370173)
			(xy 407.187158 22.297267) (xy 407.22538 22.220507) (xy 407.256356 22.140548) (xy 407.279823 22.058072)
			(xy 407.295579 21.973782) (xy 407.303491 21.888399) (xy 407.303986 21.845524) (xy 407.303491 21.802649)
			(xy 407.302832 21.795537) (xy 438.158877 21.795537) (xy 438.158877 21.881287) (xy 438.166789 21.96667)
			(xy 438.182545 22.05096) (xy 438.206012 22.133436) (xy 438.236988 22.213395) (xy 438.27521 22.290155)
			(xy 438.320351 22.363061) (xy 438.372027 22.43149) (xy 438.429796 22.49486) (xy 438.493166 22.552629)
			(xy 438.561595 22.604305) (xy 438.634501 22.649446) (xy 438.711261 22.687668) (xy 438.79122 22.718644)
			(xy 438.873696 22.742111) (xy 438.957986 22.757867) (xy 439.043369 22.765779) (xy 439.129119 22.765779)
			(xy 439.214502 22.757867) (xy 439.298792 22.742111) (xy 439.381268 22.718644) (xy 439.461227 22.687668)
			(xy 439.537987 22.649446) (xy 439.610893 22.604305) (xy 439.679322 22.552629) (xy 439.742692 22.49486)
			(xy 439.800461 22.43149) (xy 439.852137 22.363061) (xy 439.897278 22.290155) (xy 439.9355 22.213395)
			(xy 439.966476 22.133436) (xy 439.989943 22.05096) (xy 440.005699 21.96667) (xy 440.013611 21.881287)
			(xy 440.014106 21.838412) (xy 440.013611 21.795537) (xy 444.508877 21.795537) (xy 444.508877 21.881287)
			(xy 444.516789 21.96667) (xy 444.532545 22.05096) (xy 444.556012 22.133436) (xy 444.586988 22.213395)
			(xy 444.62521 22.290155) (xy 444.670351 22.363061) (xy 444.722027 22.43149) (xy 444.779796 22.49486)
			(xy 444.843166 22.552629) (xy 444.911595 22.604305) (xy 444.984501 22.649446) (xy 445.061261 22.687668)
			(xy 445.14122 22.718644) (xy 445.223696 22.742111) (xy 445.307986 22.757867) (xy 445.393369 22.765779)
			(xy 445.479119 22.765779) (xy 445.564502 22.757867) (xy 445.648792 22.742111) (xy 445.731268 22.718644)
			(xy 445.811227 22.687668) (xy 445.887987 22.649446) (xy 445.960893 22.604305) (xy 446.029322 22.552629)
			(xy 446.092692 22.49486) (xy 446.150461 22.43149) (xy 446.202137 22.363061) (xy 446.247278 22.290155)
			(xy 446.2855 22.213395) (xy 446.316476 22.133436) (xy 446.339943 22.05096) (xy 446.355699 21.96667)
			(xy 446.363611 21.881287) (xy 446.364106 21.838412) (xy 446.363611 21.795537) (xy 446.355699 21.710154)
			(xy 446.339943 21.625864) (xy 446.316476 21.543388) (xy 446.2855 21.463429) (xy 446.247278 21.386669)
			(xy 446.202137 21.313763) (xy 446.150461 21.245334) (xy 446.092692 21.181964) (xy 446.029322 21.124195)
			(xy 445.988175 21.093122) (xy 460.504275 21.093122) (xy 460.504275 21.222262) (xy 460.512225 21.351157)
			(xy 460.528095 21.479317) (xy 460.551824 21.606258) (xy 460.583323 21.731497) (xy 460.622472 21.85456)
			(xy 460.669123 21.974979) (xy 460.723098 22.092298) (xy 460.784193 22.206072) (xy 460.852176 22.315869)
			(xy 460.92679 22.421272) (xy 461.007751 22.521882) (xy 461.094751 22.617317) (xy 461.187462 22.707216)
			(xy 461.285532 22.791237) (xy 461.388587 22.869061) (xy 461.496238 22.940393) (xy 461.608077 23.004963)
			(xy 461.723678 23.062525) (xy 461.842603 23.112862) (xy 461.964402 23.155782) (xy 462.088612 23.191123)
			(xy 462.214761 23.21875) (xy 462.342373 23.238559) (xy 462.470962 23.250475) (xy 462.60004 23.254452)
			(xy 462.729118 23.250475) (xy 462.857707 23.238559) (xy 462.985319 23.21875) (xy 463.111468 23.191123)
			(xy 463.235678 23.155782) (xy 463.357477 23.112862) (xy 463.476402 23.062525) (xy 463.592003 23.004963)
			(xy 463.703842 22.940393) (xy 463.811493 22.869061) (xy 463.914548 22.791237) (xy 464.012618 22.707216)
			(xy 464.105329 22.617317) (xy 464.192329 22.521882) (xy 464.27329 22.421272) (xy 464.347904 22.315869)
			(xy 464.415887 22.206072) (xy 464.476982 22.092298) (xy 464.530957 21.974979) (xy 464.577608 21.85456)
			(xy 464.616757 21.731497) (xy 464.648256 21.606258) (xy 464.671985 21.479317) (xy 464.687855 21.351157)
			(xy 464.695805 21.222262) (xy 464.696302 21.157692) (xy 464.695805 21.093122) (xy 464.687855 20.964227)
			(xy 464.671985 20.836067) (xy 464.648256 20.709126) (xy 464.616757 20.583887) (xy 464.577608 20.460824)
			(xy 464.530957 20.340405) (xy 464.476982 20.223086) (xy 464.415887 20.109312) (xy 464.347904 19.999515)
			(xy 464.27329 19.894112) (xy 464.192329 19.793502) (xy 464.105329 19.698067) (xy 464.012618 19.608168)
			(xy 463.914548 19.524147) (xy 463.811493 19.446323) (xy 463.703842 19.374991) (xy 463.592003 19.310421)
			(xy 463.476402 19.252859) (xy 463.357477 19.202522) (xy 463.235678 19.159602) (xy 463.111468 19.124261)
			(xy 462.985319 19.096634) (xy 462.857707 19.076825) (xy 462.729118 19.064909) (xy 462.60004 19.060933)
			(xy 462.470962 19.064909) (xy 462.342373 19.076825) (xy 462.214761 19.096634) (xy 462.088612 19.124261)
			(xy 461.964402 19.159602) (xy 461.842603 19.202522) (xy 461.723678 19.252859) (xy 461.608077 19.310421)
			(xy 461.496238 19.374991) (xy 461.388587 19.446323) (xy 461.285532 19.524147) (xy 461.187462 19.608168)
			(xy 461.094751 19.698067) (xy 461.007751 19.793502) (xy 460.92679 19.894112) (xy 460.852176 19.999515)
			(xy 460.784193 20.109312) (xy 460.723098 20.223086) (xy 460.669123 20.340405) (xy 460.622472 20.460824)
			(xy 460.583323 20.583887) (xy 460.551824 20.709126) (xy 460.528095 20.836067) (xy 460.512225 20.964227)
			(xy 460.504275 21.093122) (xy 445.988175 21.093122) (xy 445.960893 21.072519) (xy 445.887987 21.027378)
			(xy 445.811227 20.989156) (xy 445.731268 20.95818) (xy 445.648792 20.934713) (xy 445.564502 20.918957)
			(xy 445.479119 20.911045) (xy 445.393369 20.911045) (xy 445.307986 20.918957) (xy 445.223696 20.934713)
			(xy 445.14122 20.95818) (xy 445.061261 20.989156) (xy 444.984501 21.027378) (xy 444.911595 21.072519)
			(xy 444.843166 21.124195) (xy 444.779796 21.181964) (xy 444.722027 21.245334) (xy 444.670351 21.313763)
			(xy 444.62521 21.386669) (xy 444.586988 21.463429) (xy 444.556012 21.543388) (xy 444.532545 21.625864)
			(xy 444.516789 21.710154) (xy 444.508877 21.795537) (xy 440.013611 21.795537) (xy 440.005699 21.710154)
			(xy 439.989943 21.625864) (xy 439.966476 21.543388) (xy 439.9355 21.463429) (xy 439.897278 21.386669)
			(xy 439.852137 21.313763) (xy 439.800461 21.245334) (xy 439.742692 21.181964) (xy 439.679322 21.124195)
			(xy 439.610893 21.072519) (xy 439.537987 21.027378) (xy 439.461227 20.989156) (xy 439.381268 20.95818)
			(xy 439.298792 20.934713) (xy 439.214502 20.918957) (xy 439.129119 20.911045) (xy 439.043369 20.911045)
			(xy 438.957986 20.918957) (xy 438.873696 20.934713) (xy 438.79122 20.95818) (xy 438.711261 20.989156)
			(xy 438.634501 21.027378) (xy 438.561595 21.072519) (xy 438.493166 21.124195) (xy 438.429796 21.181964)
			(xy 438.372027 21.245334) (xy 438.320351 21.313763) (xy 438.27521 21.386669) (xy 438.236988 21.463429)
			(xy 438.206012 21.543388) (xy 438.182545 21.625864) (xy 438.166789 21.710154) (xy 438.158877 21.795537)
			(xy 407.302832 21.795537) (xy 407.295579 21.717266) (xy 407.279823 21.632976) (xy 407.256356 21.5505)
			(xy 407.22538 21.470541) (xy 407.187158 21.393781) (xy 407.142017 21.320875) (xy 407.090341 21.252446)
			(xy 407.032572 21.189076) (xy 406.969202 21.131307) (xy 406.900773 21.079631) (xy 406.827867 21.03449)
			(xy 406.751107 20.996268) (xy 406.671148 20.965292) (xy 406.588672 20.941825) (xy 406.504382 20.926069)
			(xy 406.418999 20.918157) (xy 406.333249 20.918157) (xy 406.247866 20.926069) (xy 406.163576 20.941825)
			(xy 406.0811 20.965292) (xy 406.001141 20.996268) (xy 405.924381 21.03449) (xy 405.851475 21.079631)
			(xy 405.783046 21.131307) (xy 405.719676 21.189076) (xy 405.661907 21.252446) (xy 405.610231 21.320875)
			(xy 405.56509 21.393781) (xy 405.526868 21.470541) (xy 405.495892 21.5505) (xy 405.472425 21.632976)
			(xy 405.456669 21.717266) (xy 405.448757 21.802649) (xy 400.953491 21.802649) (xy 400.945579 21.717266)
			(xy 400.929823 21.632976) (xy 400.906356 21.5505) (xy 400.87538 21.470541) (xy 400.837158 21.393781)
			(xy 400.792017 21.320875) (xy 400.740341 21.252446) (xy 400.682572 21.189076) (xy 400.619202 21.131307)
			(xy 400.550773 21.079631) (xy 400.477867 21.03449) (xy 400.401107 20.996268) (xy 400.321148 20.965292)
			(xy 400.238672 20.941825) (xy 400.154382 20.926069) (xy 400.068999 20.918157) (xy 399.983249 20.918157)
			(xy 399.897866 20.926069) (xy 399.813576 20.941825) (xy 399.7311 20.965292) (xy 399.651141 20.996268)
			(xy 399.574381 21.03449) (xy 399.501475 21.079631) (xy 399.433046 21.131307) (xy 399.369676 21.189076)
			(xy 399.311907 21.252446) (xy 399.260231 21.320875) (xy 399.21509 21.393781) (xy 399.176868 21.470541)
			(xy 399.145892 21.5505) (xy 399.122425 21.632976) (xy 399.106669 21.717266) (xy 399.098757 21.802649)
			(xy 381.720693 21.802649) (xy 381.720611 21.795537) (xy 381.712699 21.710154) (xy 381.696943 21.625864)
			(xy 381.673476 21.543388) (xy 381.6425 21.463429) (xy 381.604278 21.386669) (xy 381.559137 21.313763)
			(xy 381.507461 21.245334) (xy 381.449692 21.181964) (xy 381.386322 21.124195) (xy 381.317893 21.072519)
			(xy 381.244987 21.027378) (xy 381.168227 20.989156) (xy 381.088268 20.95818) (xy 381.005792 20.934713)
			(xy 380.921502 20.918957) (xy 380.836119 20.911045) (xy 380.750369 20.911045) (xy 380.664986 20.918957)
			(xy 380.580696 20.934713) (xy 380.49822 20.95818) (xy 380.418261 20.989156) (xy 380.341501 21.027378)
			(xy 380.268595 21.072519) (xy 380.200166 21.124195) (xy 380.136796 21.181964) (xy 380.079027 21.245334)
			(xy 380.027351 21.313763) (xy 379.98221 21.386669) (xy 379.943988 21.463429) (xy 379.913012 21.543388)
			(xy 379.889545 21.625864) (xy 379.873789 21.710154) (xy 379.865877 21.795537) (xy 375.370611 21.795537)
			(xy 375.362699 21.710154) (xy 375.346943 21.625864) (xy 375.323476 21.543388) (xy 375.2925 21.463429)
			(xy 375.254278 21.386669) (xy 375.209137 21.313763) (xy 375.157461 21.245334) (xy 375.099692 21.181964)
			(xy 375.036322 21.124195) (xy 374.967893 21.072519) (xy 374.894987 21.027378) (xy 374.818227 20.989156)
			(xy 374.738268 20.95818) (xy 374.655792 20.934713) (xy 374.571502 20.918957) (xy 374.486119 20.911045)
			(xy 374.400369 20.911045) (xy 374.314986 20.918957) (xy 374.230696 20.934713) (xy 374.14822 20.95818)
			(xy 374.068261 20.989156) (xy 373.991501 21.027378) (xy 373.918595 21.072519) (xy 373.850166 21.124195)
			(xy 373.786796 21.181964) (xy 373.729027 21.245334) (xy 373.677351 21.313763) (xy 373.63221 21.386669)
			(xy 373.593988 21.463429) (xy 373.563012 21.543388) (xy 373.539545 21.625864) (xy 373.523789 21.710154)
			(xy 373.515877 21.795537) (xy 342.659832 21.795537) (xy 342.652579 21.717266) (xy 342.636823 21.632976)
			(xy 342.613356 21.5505) (xy 342.58238 21.470541) (xy 342.544158 21.393781) (xy 342.499017 21.320875)
			(xy 342.447341 21.252446) (xy 342.389572 21.189076) (xy 342.326202 21.131307) (xy 342.257773 21.079631)
			(xy 342.184867 21.03449) (xy 342.108107 20.996268) (xy 342.028148 20.965292) (xy 341.945672 20.941825)
			(xy 341.861382 20.926069) (xy 341.775999 20.918157) (xy 341.690249 20.918157) (xy 341.604866 20.926069)
			(xy 341.520576 20.941825) (xy 341.4381 20.965292) (xy 341.358141 20.996268) (xy 341.281381 21.03449)
			(xy 341.208475 21.079631) (xy 341.140046 21.131307) (xy 341.076676 21.189076) (xy 341.018907 21.252446)
			(xy 340.967231 21.320875) (xy 340.92209 21.393781) (xy 340.883868 21.470541) (xy 340.852892 21.5505)
			(xy 340.829425 21.632976) (xy 340.813669 21.717266) (xy 340.805757 21.802649) (xy 336.310491 21.802649)
			(xy 336.302579 21.717266) (xy 336.286823 21.632976) (xy 336.263356 21.5505) (xy 336.23238 21.470541)
			(xy 336.194158 21.393781) (xy 336.149017 21.320875) (xy 336.097341 21.252446) (xy 336.039572 21.189076)
			(xy 335.976202 21.131307) (xy 335.907773 21.079631) (xy 335.834867 21.03449) (xy 335.758107 20.996268)
			(xy 335.678148 20.965292) (xy 335.595672 20.941825) (xy 335.511382 20.926069) (xy 335.425999 20.918157)
			(xy 335.340249 20.918157) (xy 335.254866 20.926069) (xy 335.170576 20.941825) (xy 335.0881 20.965292)
			(xy 335.008141 20.996268) (xy 334.931381 21.03449) (xy 334.858475 21.079631) (xy 334.790046 21.131307)
			(xy 334.726676 21.189076) (xy 334.668907 21.252446) (xy 334.617231 21.320875) (xy 334.57209 21.393781)
			(xy 334.533868 21.470541) (xy 334.502892 21.5505) (xy 334.479425 21.632976) (xy 334.463669 21.717266)
			(xy 334.455757 21.802649) (xy 316.569693 21.802649) (xy 316.569611 21.795537) (xy 316.561699 21.710154)
			(xy 316.545943 21.625864) (xy 316.522476 21.543388) (xy 316.4915 21.463429) (xy 316.453278 21.386669)
			(xy 316.408137 21.313763) (xy 316.356461 21.245334) (xy 316.298692 21.181964) (xy 316.235322 21.124195)
			(xy 316.166893 21.072519) (xy 316.093987 21.027378) (xy 316.017227 20.989156) (xy 315.937268 20.95818)
			(xy 315.854792 20.934713) (xy 315.770502 20.918957) (xy 315.685119 20.911045) (xy 315.599369 20.911045)
			(xy 315.513986 20.918957) (xy 315.429696 20.934713) (xy 315.34722 20.95818) (xy 315.267261 20.989156)
			(xy 315.190501 21.027378) (xy 315.117595 21.072519) (xy 315.049166 21.124195) (xy 314.985796 21.181964)
			(xy 314.928027 21.245334) (xy 314.876351 21.313763) (xy 314.83121 21.386669) (xy 314.792988 21.463429)
			(xy 314.762012 21.543388) (xy 314.738545 21.625864) (xy 314.722789 21.710154) (xy 314.714877 21.795537)
			(xy 310.219611 21.795537) (xy 310.211699 21.710154) (xy 310.195943 21.625864) (xy 310.172476 21.543388)
			(xy 310.1415 21.463429) (xy 310.103278 21.386669) (xy 310.058137 21.313763) (xy 310.006461 21.245334)
			(xy 309.948692 21.181964) (xy 309.885322 21.124195) (xy 309.816893 21.072519) (xy 309.743987 21.027378)
			(xy 309.667227 20.989156) (xy 309.587268 20.95818) (xy 309.504792 20.934713) (xy 309.420502 20.918957)
			(xy 309.335119 20.911045) (xy 309.249369 20.911045) (xy 309.163986 20.918957) (xy 309.079696 20.934713)
			(xy 308.99722 20.95818) (xy 308.917261 20.989156) (xy 308.840501 21.027378) (xy 308.767595 21.072519)
			(xy 308.699166 21.124195) (xy 308.635796 21.181964) (xy 308.578027 21.245334) (xy 308.526351 21.313763)
			(xy 308.48121 21.386669) (xy 308.442988 21.463429) (xy 308.412012 21.543388) (xy 308.388545 21.625864)
			(xy 308.372789 21.710154) (xy 308.364877 21.795537) (xy 277.508832 21.795537) (xy 277.501579 21.717266)
			(xy 277.485823 21.632976) (xy 277.462356 21.5505) (xy 277.43138 21.470541) (xy 277.393158 21.393781)
			(xy 277.348017 21.320875) (xy 277.296341 21.252446) (xy 277.238572 21.189076) (xy 277.175202 21.131307)
			(xy 277.106773 21.079631) (xy 277.033867 21.03449) (xy 276.957107 20.996268) (xy 276.877148 20.965292)
			(xy 276.794672 20.941825) (xy 276.710382 20.926069) (xy 276.624999 20.918157) (xy 276.539249 20.918157)
			(xy 276.453866 20.926069) (xy 276.369576 20.941825) (xy 276.2871 20.965292) (xy 276.207141 20.996268)
			(xy 276.130381 21.03449) (xy 276.057475 21.079631) (xy 275.989046 21.131307) (xy 275.925676 21.189076)
			(xy 275.867907 21.252446) (xy 275.816231 21.320875) (xy 275.77109 21.393781) (xy 275.732868 21.470541)
			(xy 275.701892 21.5505) (xy 275.678425 21.632976) (xy 275.662669 21.717266) (xy 275.654757 21.802649)
			(xy 271.159491 21.802649) (xy 271.151579 21.717266) (xy 271.135823 21.632976) (xy 271.112356 21.5505)
			(xy 271.08138 21.470541) (xy 271.043158 21.393781) (xy 270.998017 21.320875) (xy 270.946341 21.252446)
			(xy 270.888572 21.189076) (xy 270.825202 21.131307) (xy 270.756773 21.079631) (xy 270.683867 21.03449)
			(xy 270.607107 20.996268) (xy 270.527148 20.965292) (xy 270.444672 20.941825) (xy 270.360382 20.926069)
			(xy 270.274999 20.918157) (xy 270.189249 20.918157) (xy 270.103866 20.926069) (xy 270.019576 20.941825)
			(xy 269.9371 20.965292) (xy 269.857141 20.996268) (xy 269.780381 21.03449) (xy 269.707475 21.079631)
			(xy 269.639046 21.131307) (xy 269.575676 21.189076) (xy 269.517907 21.252446) (xy 269.466231 21.320875)
			(xy 269.42109 21.393781) (xy 269.382868 21.470541) (xy 269.351892 21.5505) (xy 269.328425 21.632976)
			(xy 269.312669 21.717266) (xy 269.304757 21.802649) (xy 158.621984 21.802649) (xy 158.621984 19.262649)
			(xy 209.995757 19.262649) (xy 209.995757 19.348399) (xy 210.003669 19.433782) (xy 210.019425 19.518072)
			(xy 210.042892 19.600548) (xy 210.073868 19.680507) (xy 210.11209 19.757267) (xy 210.157231 19.830173)
			(xy 210.208907 19.898602) (xy 210.266676 19.961972) (xy 210.330046 20.019741) (xy 210.398475 20.071417)
			(xy 210.471381 20.116558) (xy 210.548141 20.15478) (xy 210.6281 20.185756) (xy 210.710576 20.209223)
			(xy 210.794866 20.224979) (xy 210.880249 20.232891) (xy 210.965999 20.232891) (xy 211.051382 20.224979)
			(xy 211.135672 20.209223) (xy 211.218148 20.185756) (xy 211.298107 20.15478) (xy 211.374867 20.116558)
			(xy 211.447773 20.071417) (xy 211.516202 20.019741) (xy 211.579572 19.961972) (xy 211.637341 19.898602)
			(xy 211.689017 19.830173) (xy 211.734158 19.757267) (xy 211.77238 19.680507) (xy 211.803356 19.600548)
			(xy 211.826823 19.518072) (xy 211.842579 19.433782) (xy 211.850491 19.348399) (xy 211.850986 19.305524)
			(xy 211.850491 19.262649) (xy 216.345757 19.262649) (xy 216.345757 19.348399) (xy 216.353669 19.433782)
			(xy 216.369425 19.518072) (xy 216.392892 19.600548) (xy 216.423868 19.680507) (xy 216.46209 19.757267)
			(xy 216.507231 19.830173) (xy 216.558907 19.898602) (xy 216.616676 19.961972) (xy 216.680046 20.019741)
			(xy 216.748475 20.071417) (xy 216.821381 20.116558) (xy 216.898141 20.15478) (xy 216.9781 20.185756)
			(xy 217.060576 20.209223) (xy 217.144866 20.224979) (xy 217.230249 20.232891) (xy 217.315999 20.232891)
			(xy 217.401382 20.224979) (xy 217.485672 20.209223) (xy 217.568148 20.185756) (xy 217.648107 20.15478)
			(xy 217.724867 20.116558) (xy 217.797773 20.071417) (xy 217.866202 20.019741) (xy 217.929572 19.961972)
			(xy 217.987341 19.898602) (xy 218.039017 19.830173) (xy 218.084158 19.757267) (xy 218.12238 19.680507)
			(xy 218.153356 19.600548) (xy 218.176823 19.518072) (xy 218.192579 19.433782) (xy 218.200491 19.348399)
			(xy 218.200986 19.305524) (xy 218.200491 19.262649) (xy 218.199832 19.255537) (xy 244.026677 19.255537)
			(xy 244.026677 19.341287) (xy 244.034589 19.42667) (xy 244.050345 19.51096) (xy 244.073812 19.593436)
			(xy 244.104788 19.673395) (xy 244.14301 19.750155) (xy 244.188151 19.823061) (xy 244.239827 19.89149)
			(xy 244.297596 19.95486) (xy 244.360966 20.012629) (xy 244.429395 20.064305) (xy 244.502301 20.109446)
			(xy 244.579061 20.147668) (xy 244.65902 20.178644) (xy 244.741496 20.202111) (xy 244.825786 20.217867)
			(xy 244.911169 20.225779) (xy 244.996919 20.225779) (xy 245.082302 20.217867) (xy 245.166592 20.202111)
			(xy 245.249068 20.178644) (xy 245.329027 20.147668) (xy 245.405787 20.109446) (xy 245.478693 20.064305)
			(xy 245.547122 20.012629) (xy 245.610492 19.95486) (xy 245.668261 19.89149) (xy 245.719937 19.823061)
			(xy 245.765078 19.750155) (xy 245.8033 19.673395) (xy 245.834276 19.593436) (xy 245.857743 19.51096)
			(xy 245.873499 19.42667) (xy 245.881411 19.341287) (xy 245.881906 19.298412) (xy 245.881411 19.255537)
			(xy 250.376677 19.255537) (xy 250.376677 19.341287) (xy 250.384589 19.42667) (xy 250.400345 19.51096)
			(xy 250.423812 19.593436) (xy 250.454788 19.673395) (xy 250.49301 19.750155) (xy 250.538151 19.823061)
			(xy 250.589827 19.89149) (xy 250.647596 19.95486) (xy 250.710966 20.012629) (xy 250.779395 20.064305)
			(xy 250.852301 20.109446) (xy 250.929061 20.147668) (xy 251.00902 20.178644) (xy 251.091496 20.202111)
			(xy 251.175786 20.217867) (xy 251.261169 20.225779) (xy 251.346919 20.225779) (xy 251.432302 20.217867)
			(xy 251.516592 20.202111) (xy 251.599068 20.178644) (xy 251.679027 20.147668) (xy 251.755787 20.109446)
			(xy 251.828693 20.064305) (xy 251.897122 20.012629) (xy 251.960492 19.95486) (xy 252.018261 19.89149)
			(xy 252.069937 19.823061) (xy 252.115078 19.750155) (xy 252.1533 19.673395) (xy 252.184276 19.593436)
			(xy 252.207743 19.51096) (xy 252.223499 19.42667) (xy 252.231411 19.341287) (xy 252.231906 19.298412)
			(xy 252.231493 19.262649) (xy 269.304757 19.262649) (xy 269.304757 19.348399) (xy 269.312669 19.433782)
			(xy 269.328425 19.518072) (xy 269.351892 19.600548) (xy 269.382868 19.680507) (xy 269.42109 19.757267)
			(xy 269.466231 19.830173) (xy 269.517907 19.898602) (xy 269.575676 19.961972) (xy 269.639046 20.019741)
			(xy 269.707475 20.071417) (xy 269.780381 20.116558) (xy 269.857141 20.15478) (xy 269.9371 20.185756)
			(xy 270.019576 20.209223) (xy 270.103866 20.224979) (xy 270.189249 20.232891) (xy 270.274999 20.232891)
			(xy 270.360382 20.224979) (xy 270.444672 20.209223) (xy 270.527148 20.185756) (xy 270.607107 20.15478)
			(xy 270.62931 20.143724) (xy 274.239736 20.143724) (xy 274.239736 21.007324) (xy 274.240222 21.034593)
			(xy 274.247984 21.088577) (xy 274.263349 21.140907) (xy 274.286006 21.190517) (xy 274.315492 21.236398)
			(xy 274.351207 21.277615) (xy 274.392424 21.31333) (xy 274.438305 21.342816) (xy 274.487915 21.365473)
			(xy 274.540245 21.380838) (xy 274.594229 21.3886) (xy 274.648767 21.3886) (xy 274.702751 21.380838)
			(xy 274.755081 21.365473) (xy 274.804691 21.342816) (xy 274.850572 21.31333) (xy 274.891789 21.277615)
			(xy 274.927504 21.236398) (xy 274.95699 21.190517) (xy 274.979647 21.140907) (xy 274.995012 21.088577)
			(xy 275.002774 21.034593) (xy 275.00326 21.007324) (xy 275.00326 20.143724) (xy 275.002774 20.116455)
			(xy 274.995012 20.062471) (xy 274.979647 20.010141) (xy 274.95699 19.960531) (xy 274.927504 19.91465)
			(xy 274.891789 19.873433) (xy 274.850572 19.837718) (xy 274.804691 19.808232) (xy 274.755081 19.785575)
			(xy 274.702751 19.77021) (xy 274.648767 19.762448) (xy 274.594229 19.762448) (xy 274.540245 19.77021)
			(xy 274.487915 19.785575) (xy 274.438305 19.808232) (xy 274.392424 19.837718) (xy 274.351207 19.873433)
			(xy 274.315492 19.91465) (xy 274.286006 19.960531) (xy 274.263349 20.010141) (xy 274.247984 20.062471)
			(xy 274.240222 20.116455) (xy 274.239736 20.143724) (xy 270.62931 20.143724) (xy 270.683867 20.116558)
			(xy 270.756773 20.071417) (xy 270.825202 20.019741) (xy 270.888572 19.961972) (xy 270.946341 19.898602)
			(xy 270.998017 19.830173) (xy 271.043158 19.757267) (xy 271.08138 19.680507) (xy 271.112356 19.600548)
			(xy 271.135823 19.518072) (xy 271.151579 19.433782) (xy 271.159491 19.348399) (xy 271.159986 19.305524)
			(xy 271.159491 19.262649) (xy 275.654757 19.262649) (xy 275.654757 19.348399) (xy 275.662669 19.433782)
			(xy 275.678425 19.518072) (xy 275.701892 19.600548) (xy 275.732868 19.680507) (xy 275.77109 19.757267)
			(xy 275.816231 19.830173) (xy 275.867907 19.898602) (xy 275.925676 19.961972) (xy 275.989046 20.019741)
			(xy 276.057475 20.071417) (xy 276.130381 20.116558) (xy 276.207141 20.15478) (xy 276.2871 20.185756)
			(xy 276.369576 20.209223) (xy 276.453866 20.224979) (xy 276.539249 20.232891) (xy 276.624999 20.232891)
			(xy 276.710382 20.224979) (xy 276.794672 20.209223) (xy 276.877148 20.185756) (xy 276.957107 20.15478)
			(xy 277.033867 20.116558) (xy 277.106773 20.071417) (xy 277.175202 20.019741) (xy 277.238572 19.961972)
			(xy 277.296341 19.898602) (xy 277.348017 19.830173) (xy 277.393158 19.757267) (xy 277.43138 19.680507)
			(xy 277.462356 19.600548) (xy 277.485823 19.518072) (xy 277.501579 19.433782) (xy 277.509491 19.348399)
			(xy 277.509986 19.305524) (xy 277.509491 19.262649) (xy 277.508832 19.255537) (xy 308.364877 19.255537)
			(xy 308.364877 19.341287) (xy 308.372789 19.42667) (xy 308.388545 19.51096) (xy 308.412012 19.593436)
			(xy 308.442988 19.673395) (xy 308.48121 19.750155) (xy 308.526351 19.823061) (xy 308.578027 19.89149)
			(xy 308.635796 19.95486) (xy 308.699166 20.012629) (xy 308.767595 20.064305) (xy 308.840501 20.109446)
			(xy 308.917261 20.147668) (xy 308.99722 20.178644) (xy 309.079696 20.202111) (xy 309.163986 20.217867)
			(xy 309.249369 20.225779) (xy 309.335119 20.225779) (xy 309.420502 20.217867) (xy 309.504792 20.202111)
			(xy 309.587268 20.178644) (xy 309.667227 20.147668) (xy 309.68943 20.136612) (xy 310.871108 20.136612)
			(xy 310.871108 21.000212) (xy 310.871594 21.027481) (xy 310.879356 21.081465) (xy 310.894721 21.133795)
			(xy 310.917378 21.183405) (xy 310.946864 21.229286) (xy 310.982579 21.270503) (xy 311.023796 21.306218)
			(xy 311.069677 21.335704) (xy 311.119287 21.358361) (xy 311.171617 21.373726) (xy 311.225601 21.381488)
			(xy 311.280139 21.381488) (xy 311.334123 21.373726) (xy 311.386453 21.358361) (xy 311.436063 21.335704)
			(xy 311.481944 21.306218) (xy 311.523161 21.270503) (xy 311.558876 21.229286) (xy 311.588362 21.183405)
			(xy 311.611019 21.133795) (xy 311.626384 21.081465) (xy 311.634146 21.027481) (xy 311.634632 21.000212)
			(xy 311.634632 20.136612) (xy 311.634146 20.109343) (xy 311.626384 20.055359) (xy 311.611019 20.003029)
			(xy 311.588362 19.953419) (xy 311.558876 19.907538) (xy 311.523161 19.866321) (xy 311.481944 19.830606)
			(xy 311.436063 19.80112) (xy 311.386453 19.778463) (xy 311.334123 19.763098) (xy 311.280139 19.755336)
			(xy 311.225601 19.755336) (xy 311.171617 19.763098) (xy 311.119287 19.778463) (xy 311.069677 19.80112)
			(xy 311.023796 19.830606) (xy 310.982579 19.866321) (xy 310.946864 19.907538) (xy 310.917378 19.953419)
			(xy 310.894721 20.003029) (xy 310.879356 20.055359) (xy 310.871594 20.109343) (xy 310.871108 20.136612)
			(xy 309.68943 20.136612) (xy 309.743987 20.109446) (xy 309.816893 20.064305) (xy 309.885322 20.012629)
			(xy 309.948692 19.95486) (xy 310.006461 19.89149) (xy 310.058137 19.823061) (xy 310.103278 19.750155)
			(xy 310.1415 19.673395) (xy 310.172476 19.593436) (xy 310.195943 19.51096) (xy 310.211699 19.42667)
			(xy 310.219611 19.341287) (xy 310.220106 19.298412) (xy 310.219611 19.255537) (xy 314.714877 19.255537)
			(xy 314.714877 19.341287) (xy 314.722789 19.42667) (xy 314.738545 19.51096) (xy 314.762012 19.593436)
			(xy 314.792988 19.673395) (xy 314.83121 19.750155) (xy 314.876351 19.823061) (xy 314.928027 19.89149)
			(xy 314.985796 19.95486) (xy 315.049166 20.012629) (xy 315.117595 20.064305) (xy 315.190501 20.109446)
			(xy 315.267261 20.147668) (xy 315.34722 20.178644) (xy 315.429696 20.202111) (xy 315.513986 20.217867)
			(xy 315.599369 20.225779) (xy 315.685119 20.225779) (xy 315.770502 20.217867) (xy 315.854792 20.202111)
			(xy 315.937268 20.178644) (xy 316.017227 20.147668) (xy 316.093987 20.109446) (xy 316.166893 20.064305)
			(xy 316.235322 20.012629) (xy 316.298692 19.95486) (xy 316.356461 19.89149) (xy 316.408137 19.823061)
			(xy 316.453278 19.750155) (xy 316.4915 19.673395) (xy 316.522476 19.593436) (xy 316.545943 19.51096)
			(xy 316.561699 19.42667) (xy 316.569611 19.341287) (xy 316.570106 19.298412) (xy 316.569693 19.262649)
			(xy 334.455757 19.262649) (xy 334.455757 19.348399) (xy 334.463669 19.433782) (xy 334.479425 19.518072)
			(xy 334.502892 19.600548) (xy 334.533868 19.680507) (xy 334.57209 19.757267) (xy 334.617231 19.830173)
			(xy 334.668907 19.898602) (xy 334.726676 19.961972) (xy 334.790046 20.019741) (xy 334.858475 20.071417)
			(xy 334.931381 20.116558) (xy 335.008141 20.15478) (xy 335.0881 20.185756) (xy 335.170576 20.209223)
			(xy 335.254866 20.224979) (xy 335.340249 20.232891) (xy 335.425999 20.232891) (xy 335.511382 20.224979)
			(xy 335.595672 20.209223) (xy 335.678148 20.185756) (xy 335.758107 20.15478) (xy 335.78031 20.143724)
			(xy 339.390736 20.143724) (xy 339.390736 21.007324) (xy 339.391222 21.034593) (xy 339.398984 21.088577)
			(xy 339.414349 21.140907) (xy 339.437006 21.190517) (xy 339.466492 21.236398) (xy 339.502207 21.277615)
			(xy 339.543424 21.31333) (xy 339.589305 21.342816) (xy 339.638915 21.365473) (xy 339.691245 21.380838)
			(xy 339.745229 21.3886) (xy 339.799767 21.3886) (xy 339.853751 21.380838) (xy 339.906081 21.365473)
			(xy 339.955691 21.342816) (xy 340.001572 21.31333) (xy 340.042789 21.277615) (xy 340.078504 21.236398)
			(xy 340.10799 21.190517) (xy 340.130647 21.140907) (xy 340.146012 21.088577) (xy 340.153774 21.034593)
			(xy 340.15426 21.007324) (xy 340.15426 20.143724) (xy 340.153774 20.116455) (xy 340.146012 20.062471)
			(xy 340.130647 20.010141) (xy 340.10799 19.960531) (xy 340.078504 19.91465) (xy 340.042789 19.873433)
			(xy 340.001572 19.837718) (xy 339.955691 19.808232) (xy 339.906081 19.785575) (xy 339.853751 19.77021)
			(xy 339.799767 19.762448) (xy 339.745229 19.762448) (xy 339.691245 19.77021) (xy 339.638915 19.785575)
			(xy 339.589305 19.808232) (xy 339.543424 19.837718) (xy 339.502207 19.873433) (xy 339.466492 19.91465)
			(xy 339.437006 19.960531) (xy 339.414349 20.010141) (xy 339.398984 20.062471) (xy 339.391222 20.116455)
			(xy 339.390736 20.143724) (xy 335.78031 20.143724) (xy 335.834867 20.116558) (xy 335.907773 20.071417)
			(xy 335.976202 20.019741) (xy 336.039572 19.961972) (xy 336.097341 19.898602) (xy 336.149017 19.830173)
			(xy 336.194158 19.757267) (xy 336.23238 19.680507) (xy 336.263356 19.600548) (xy 336.286823 19.518072)
			(xy 336.302579 19.433782) (xy 336.310491 19.348399) (xy 336.310986 19.305524) (xy 336.310491 19.262649)
			(xy 340.805757 19.262649) (xy 340.805757 19.348399) (xy 340.813669 19.433782) (xy 340.829425 19.518072)
			(xy 340.852892 19.600548) (xy 340.883868 19.680507) (xy 340.92209 19.757267) (xy 340.967231 19.830173)
			(xy 341.018907 19.898602) (xy 341.076676 19.961972) (xy 341.140046 20.019741) (xy 341.208475 20.071417)
			(xy 341.281381 20.116558) (xy 341.358141 20.15478) (xy 341.4381 20.185756) (xy 341.520576 20.209223)
			(xy 341.604866 20.224979) (xy 341.690249 20.232891) (xy 341.775999 20.232891) (xy 341.861382 20.224979)
			(xy 341.945672 20.209223) (xy 342.028148 20.185756) (xy 342.108107 20.15478) (xy 342.184867 20.116558)
			(xy 342.257773 20.071417) (xy 342.326202 20.019741) (xy 342.389572 19.961972) (xy 342.447341 19.898602)
			(xy 342.499017 19.830173) (xy 342.544158 19.757267) (xy 342.58238 19.680507) (xy 342.613356 19.600548)
			(xy 342.636823 19.518072) (xy 342.652579 19.433782) (xy 342.660491 19.348399) (xy 342.660986 19.305524)
			(xy 342.660491 19.262649) (xy 342.659832 19.255537) (xy 373.515877 19.255537) (xy 373.515877 19.341287)
			(xy 373.523789 19.42667) (xy 373.539545 19.51096) (xy 373.563012 19.593436) (xy 373.593988 19.673395)
			(xy 373.63221 19.750155) (xy 373.677351 19.823061) (xy 373.729027 19.89149) (xy 373.786796 19.95486)
			(xy 373.850166 20.012629) (xy 373.918595 20.064305) (xy 373.991501 20.109446) (xy 374.068261 20.147668)
			(xy 374.14822 20.178644) (xy 374.230696 20.202111) (xy 374.314986 20.217867) (xy 374.400369 20.225779)
			(xy 374.486119 20.225779) (xy 374.571502 20.217867) (xy 374.655792 20.202111) (xy 374.738268 20.178644)
			(xy 374.818227 20.147668) (xy 374.84043 20.136612) (xy 376.022108 20.136612) (xy 376.022108 21.000212)
			(xy 376.022594 21.027481) (xy 376.030356 21.081465) (xy 376.045721 21.133795) (xy 376.068378 21.183405)
			(xy 376.097864 21.229286) (xy 376.133579 21.270503) (xy 376.174796 21.306218) (xy 376.220677 21.335704)
			(xy 376.270287 21.358361) (xy 376.322617 21.373726) (xy 376.376601 21.381488) (xy 376.431139 21.381488)
			(xy 376.485123 21.373726) (xy 376.537453 21.358361) (xy 376.587063 21.335704) (xy 376.632944 21.306218)
			(xy 376.674161 21.270503) (xy 376.709876 21.229286) (xy 376.739362 21.183405) (xy 376.762019 21.133795)
			(xy 376.777384 21.081465) (xy 376.785146 21.027481) (xy 376.785632 21.000212) (xy 376.785632 20.136612)
			(xy 376.785146 20.109343) (xy 376.777384 20.055359) (xy 376.762019 20.003029) (xy 376.739362 19.953419)
			(xy 376.709876 19.907538) (xy 376.674161 19.866321) (xy 376.632944 19.830606) (xy 376.587063 19.80112)
			(xy 376.537453 19.778463) (xy 376.485123 19.763098) (xy 376.431139 19.755336) (xy 376.376601 19.755336)
			(xy 376.322617 19.763098) (xy 376.270287 19.778463) (xy 376.220677 19.80112) (xy 376.174796 19.830606)
			(xy 376.133579 19.866321) (xy 376.097864 19.907538) (xy 376.068378 19.953419) (xy 376.045721 20.003029)
			(xy 376.030356 20.055359) (xy 376.022594 20.109343) (xy 376.022108 20.136612) (xy 374.84043 20.136612)
			(xy 374.894987 20.109446) (xy 374.967893 20.064305) (xy 375.036322 20.012629) (xy 375.099692 19.95486)
			(xy 375.157461 19.89149) (xy 375.209137 19.823061) (xy 375.254278 19.750155) (xy 375.2925 19.673395)
			(xy 375.323476 19.593436) (xy 375.346943 19.51096) (xy 375.362699 19.42667) (xy 375.370611 19.341287)
			(xy 375.371106 19.298412) (xy 375.370611 19.255537) (xy 379.865877 19.255537) (xy 379.865877 19.341287)
			(xy 379.873789 19.42667) (xy 379.889545 19.51096) (xy 379.913012 19.593436) (xy 379.943988 19.673395)
			(xy 379.98221 19.750155) (xy 380.027351 19.823061) (xy 380.079027 19.89149) (xy 380.136796 19.95486)
			(xy 380.200166 20.012629) (xy 380.268595 20.064305) (xy 380.341501 20.109446) (xy 380.418261 20.147668)
			(xy 380.49822 20.178644) (xy 380.580696 20.202111) (xy 380.664986 20.217867) (xy 380.750369 20.225779)
			(xy 380.836119 20.225779) (xy 380.921502 20.217867) (xy 381.005792 20.202111) (xy 381.088268 20.178644)
			(xy 381.168227 20.147668) (xy 381.244987 20.109446) (xy 381.317893 20.064305) (xy 381.386322 20.012629)
			(xy 381.449692 19.95486) (xy 381.507461 19.89149) (xy 381.559137 19.823061) (xy 381.604278 19.750155)
			(xy 381.6425 19.673395) (xy 381.673476 19.593436) (xy 381.696943 19.51096) (xy 381.712699 19.42667)
			(xy 381.720611 19.341287) (xy 381.721106 19.298412) (xy 381.720693 19.262649) (xy 399.098757 19.262649)
			(xy 399.098757 19.348399) (xy 399.106669 19.433782) (xy 399.122425 19.518072) (xy 399.145892 19.600548)
			(xy 399.176868 19.680507) (xy 399.21509 19.757267) (xy 399.260231 19.830173) (xy 399.311907 19.898602)
			(xy 399.369676 19.961972) (xy 399.433046 20.019741) (xy 399.501475 20.071417) (xy 399.574381 20.116558)
			(xy 399.651141 20.15478) (xy 399.7311 20.185756) (xy 399.813576 20.209223) (xy 399.897866 20.224979)
			(xy 399.983249 20.232891) (xy 400.068999 20.232891) (xy 400.154382 20.224979) (xy 400.238672 20.209223)
			(xy 400.321148 20.185756) (xy 400.401107 20.15478) (xy 400.42331 20.143724) (xy 404.033736 20.143724)
			(xy 404.033736 21.007324) (xy 404.034222 21.034593) (xy 404.041984 21.088577) (xy 404.057349 21.140907)
			(xy 404.080006 21.190517) (xy 404.109492 21.236398) (xy 404.145207 21.277615) (xy 404.186424 21.31333)
			(xy 404.232305 21.342816) (xy 404.281915 21.365473) (xy 404.334245 21.380838) (xy 404.388229 21.3886)
			(xy 404.442767 21.3886) (xy 404.496751 21.380838) (xy 404.549081 21.365473) (xy 404.598691 21.342816)
			(xy 404.644572 21.31333) (xy 404.685789 21.277615) (xy 404.721504 21.236398) (xy 404.75099 21.190517)
			(xy 404.773647 21.140907) (xy 404.789012 21.088577) (xy 404.796774 21.034593) (xy 404.79726 21.007324)
			(xy 404.79726 20.143724) (xy 404.796774 20.116455) (xy 404.789012 20.062471) (xy 404.773647 20.010141)
			(xy 404.75099 19.960531) (xy 404.721504 19.91465) (xy 404.685789 19.873433) (xy 404.644572 19.837718)
			(xy 404.598691 19.808232) (xy 404.549081 19.785575) (xy 404.496751 19.77021) (xy 404.442767 19.762448)
			(xy 404.388229 19.762448) (xy 404.334245 19.77021) (xy 404.281915 19.785575) (xy 404.232305 19.808232)
			(xy 404.186424 19.837718) (xy 404.145207 19.873433) (xy 404.109492 19.91465) (xy 404.080006 19.960531)
			(xy 404.057349 20.010141) (xy 404.041984 20.062471) (xy 404.034222 20.116455) (xy 404.033736 20.143724)
			(xy 400.42331 20.143724) (xy 400.477867 20.116558) (xy 400.550773 20.071417) (xy 400.619202 20.019741)
			(xy 400.682572 19.961972) (xy 400.740341 19.898602) (xy 400.792017 19.830173) (xy 400.837158 19.757267)
			(xy 400.87538 19.680507) (xy 400.906356 19.600548) (xy 400.929823 19.518072) (xy 400.945579 19.433782)
			(xy 400.953491 19.348399) (xy 400.953986 19.305524) (xy 400.953491 19.262649) (xy 405.448757 19.262649)
			(xy 405.448757 19.348399) (xy 405.456669 19.433782) (xy 405.472425 19.518072) (xy 405.495892 19.600548)
			(xy 405.526868 19.680507) (xy 405.56509 19.757267) (xy 405.610231 19.830173) (xy 405.661907 19.898602)
			(xy 405.719676 19.961972) (xy 405.783046 20.019741) (xy 405.851475 20.071417) (xy 405.924381 20.116558)
			(xy 406.001141 20.15478) (xy 406.0811 20.185756) (xy 406.163576 20.209223) (xy 406.247866 20.224979)
			(xy 406.333249 20.232891) (xy 406.418999 20.232891) (xy 406.504382 20.224979) (xy 406.588672 20.209223)
			(xy 406.671148 20.185756) (xy 406.751107 20.15478) (xy 406.827867 20.116558) (xy 406.900773 20.071417)
			(xy 406.969202 20.019741) (xy 407.032572 19.961972) (xy 407.090341 19.898602) (xy 407.142017 19.830173)
			(xy 407.187158 19.757267) (xy 407.22538 19.680507) (xy 407.256356 19.600548) (xy 407.279823 19.518072)
			(xy 407.295579 19.433782) (xy 407.303491 19.348399) (xy 407.303986 19.305524) (xy 407.303491 19.262649)
			(xy 407.302832 19.255537) (xy 438.158877 19.255537) (xy 438.158877 19.341287) (xy 438.166789 19.42667)
			(xy 438.182545 19.51096) (xy 438.206012 19.593436) (xy 438.236988 19.673395) (xy 438.27521 19.750155)
			(xy 438.320351 19.823061) (xy 438.372027 19.89149) (xy 438.429796 19.95486) (xy 438.493166 20.012629)
			(xy 438.561595 20.064305) (xy 438.634501 20.109446) (xy 438.711261 20.147668) (xy 438.79122 20.178644)
			(xy 438.873696 20.202111) (xy 438.957986 20.217867) (xy 439.043369 20.225779) (xy 439.129119 20.225779)
			(xy 439.214502 20.217867) (xy 439.298792 20.202111) (xy 439.381268 20.178644) (xy 439.461227 20.147668)
			(xy 439.48343 20.136612) (xy 440.665108 20.136612) (xy 440.665108 21.000212) (xy 440.665594 21.027481)
			(xy 440.673356 21.081465) (xy 440.688721 21.133795) (xy 440.711378 21.183405) (xy 440.740864 21.229286)
			(xy 440.776579 21.270503) (xy 440.817796 21.306218) (xy 440.863677 21.335704) (xy 440.913287 21.358361)
			(xy 440.965617 21.373726) (xy 441.019601 21.381488) (xy 441.074139 21.381488) (xy 441.128123 21.373726)
			(xy 441.180453 21.358361) (xy 441.230063 21.335704) (xy 441.275944 21.306218) (xy 441.317161 21.270503)
			(xy 441.352876 21.229286) (xy 441.382362 21.183405) (xy 441.405019 21.133795) (xy 441.420384 21.081465)
			(xy 441.428146 21.027481) (xy 441.428632 21.000212) (xy 441.428632 20.136612) (xy 441.428146 20.109343)
			(xy 441.420384 20.055359) (xy 441.405019 20.003029) (xy 441.382362 19.953419) (xy 441.352876 19.907538)
			(xy 441.317161 19.866321) (xy 441.275944 19.830606) (xy 441.230063 19.80112) (xy 441.180453 19.778463)
			(xy 441.128123 19.763098) (xy 441.074139 19.755336) (xy 441.019601 19.755336) (xy 440.965617 19.763098)
			(xy 440.913287 19.778463) (xy 440.863677 19.80112) (xy 440.817796 19.830606) (xy 440.776579 19.866321)
			(xy 440.740864 19.907538) (xy 440.711378 19.953419) (xy 440.688721 20.003029) (xy 440.673356 20.055359)
			(xy 440.665594 20.109343) (xy 440.665108 20.136612) (xy 439.48343 20.136612) (xy 439.537987 20.109446)
			(xy 439.610893 20.064305) (xy 439.679322 20.012629) (xy 439.742692 19.95486) (xy 439.800461 19.89149)
			(xy 439.852137 19.823061) (xy 439.897278 19.750155) (xy 439.9355 19.673395) (xy 439.966476 19.593436)
			(xy 439.989943 19.51096) (xy 440.005699 19.42667) (xy 440.013611 19.341287) (xy 440.014106 19.298412)
			(xy 440.013611 19.255537) (xy 444.508877 19.255537) (xy 444.508877 19.341287) (xy 444.516789 19.42667)
			(xy 444.532545 19.51096) (xy 444.556012 19.593436) (xy 444.586988 19.673395) (xy 444.62521 19.750155)
			(xy 444.670351 19.823061) (xy 444.722027 19.89149) (xy 444.779796 19.95486) (xy 444.843166 20.012629)
			(xy 444.911595 20.064305) (xy 444.984501 20.109446) (xy 445.061261 20.147668) (xy 445.14122 20.178644)
			(xy 445.223696 20.202111) (xy 445.307986 20.217867) (xy 445.393369 20.225779) (xy 445.479119 20.225779)
			(xy 445.564502 20.217867) (xy 445.648792 20.202111) (xy 445.731268 20.178644) (xy 445.811227 20.147668)
			(xy 445.887987 20.109446) (xy 445.960893 20.064305) (xy 446.029322 20.012629) (xy 446.092692 19.95486)
			(xy 446.150461 19.89149) (xy 446.202137 19.823061) (xy 446.247278 19.750155) (xy 446.2855 19.673395)
			(xy 446.316476 19.593436) (xy 446.339943 19.51096) (xy 446.355699 19.42667) (xy 446.363611 19.341287)
			(xy 446.364106 19.298412) (xy 446.363611 19.255537) (xy 446.355699 19.170154) (xy 446.339943 19.085864)
			(xy 446.316476 19.003388) (xy 446.2855 18.923429) (xy 446.247278 18.846669) (xy 446.202137 18.773763)
			(xy 446.150461 18.705334) (xy 446.092692 18.641964) (xy 446.029322 18.584195) (xy 445.960893 18.532519)
			(xy 445.887987 18.487378) (xy 445.811227 18.449156) (xy 445.731268 18.41818) (xy 445.648792 18.394713)
			(xy 445.564502 18.378957) (xy 445.479119 18.371045) (xy 445.393369 18.371045) (xy 445.307986 18.378957)
			(xy 445.223696 18.394713) (xy 445.14122 18.41818) (xy 445.061261 18.449156) (xy 444.984501 18.487378)
			(xy 444.911595 18.532519) (xy 444.843166 18.584195) (xy 444.779796 18.641964) (xy 444.722027 18.705334)
			(xy 444.670351 18.773763) (xy 444.62521 18.846669) (xy 444.586988 18.923429) (xy 444.556012 19.003388)
			(xy 444.532545 19.085864) (xy 444.516789 19.170154) (xy 444.508877 19.255537) (xy 440.013611 19.255537)
			(xy 440.005699 19.170154) (xy 439.989943 19.085864) (xy 439.966476 19.003388) (xy 439.9355 18.923429)
			(xy 439.897278 18.846669) (xy 439.852137 18.773763) (xy 439.800461 18.705334) (xy 439.742692 18.641964)
			(xy 439.679322 18.584195) (xy 439.610893 18.532519) (xy 439.537987 18.487378) (xy 439.461227 18.449156)
			(xy 439.381268 18.41818) (xy 439.298792 18.394713) (xy 439.214502 18.378957) (xy 439.129119 18.371045)
			(xy 439.043369 18.371045) (xy 438.957986 18.378957) (xy 438.873696 18.394713) (xy 438.79122 18.41818)
			(xy 438.711261 18.449156) (xy 438.634501 18.487378) (xy 438.561595 18.532519) (xy 438.493166 18.584195)
			(xy 438.429796 18.641964) (xy 438.372027 18.705334) (xy 438.320351 18.773763) (xy 438.27521 18.846669)
			(xy 438.236988 18.923429) (xy 438.206012 19.003388) (xy 438.182545 19.085864) (xy 438.166789 19.170154)
			(xy 438.158877 19.255537) (xy 407.302832 19.255537) (xy 407.295579 19.177266) (xy 407.279823 19.092976)
			(xy 407.256356 19.0105) (xy 407.22538 18.930541) (xy 407.187158 18.853781) (xy 407.142017 18.780875)
			(xy 407.090341 18.712446) (xy 407.032572 18.649076) (xy 406.969202 18.591307) (xy 406.900773 18.539631)
			(xy 406.827867 18.49449) (xy 406.751107 18.456268) (xy 406.671148 18.425292) (xy 406.588672 18.401825)
			(xy 406.504382 18.386069) (xy 406.418999 18.378157) (xy 406.333249 18.378157) (xy 406.247866 18.386069)
			(xy 406.163576 18.401825) (xy 406.0811 18.425292) (xy 406.001141 18.456268) (xy 405.924381 18.49449)
			(xy 405.851475 18.539631) (xy 405.783046 18.591307) (xy 405.719676 18.649076) (xy 405.661907 18.712446)
			(xy 405.610231 18.780875) (xy 405.56509 18.853781) (xy 405.526868 18.930541) (xy 405.495892 19.0105)
			(xy 405.472425 19.092976) (xy 405.456669 19.177266) (xy 405.448757 19.262649) (xy 400.953491 19.262649)
			(xy 400.945579 19.177266) (xy 400.929823 19.092976) (xy 400.906356 19.0105) (xy 400.87538 18.930541)
			(xy 400.837158 18.853781) (xy 400.792017 18.780875) (xy 400.740341 18.712446) (xy 400.682572 18.649076)
			(xy 400.619202 18.591307) (xy 400.550773 18.539631) (xy 400.477867 18.49449) (xy 400.401107 18.456268)
			(xy 400.321148 18.425292) (xy 400.238672 18.401825) (xy 400.154382 18.386069) (xy 400.068999 18.378157)
			(xy 399.983249 18.378157) (xy 399.897866 18.386069) (xy 399.813576 18.401825) (xy 399.7311 18.425292)
			(xy 399.651141 18.456268) (xy 399.574381 18.49449) (xy 399.501475 18.539631) (xy 399.433046 18.591307)
			(xy 399.369676 18.649076) (xy 399.311907 18.712446) (xy 399.260231 18.780875) (xy 399.21509 18.853781)
			(xy 399.176868 18.930541) (xy 399.145892 19.0105) (xy 399.122425 19.092976) (xy 399.106669 19.177266)
			(xy 399.098757 19.262649) (xy 381.720693 19.262649) (xy 381.720611 19.255537) (xy 381.712699 19.170154)
			(xy 381.696943 19.085864) (xy 381.673476 19.003388) (xy 381.6425 18.923429) (xy 381.604278 18.846669)
			(xy 381.559137 18.773763) (xy 381.507461 18.705334) (xy 381.449692 18.641964) (xy 381.386322 18.584195)
			(xy 381.317893 18.532519) (xy 381.244987 18.487378) (xy 381.168227 18.449156) (xy 381.088268 18.41818)
			(xy 381.005792 18.394713) (xy 380.921502 18.378957) (xy 380.836119 18.371045) (xy 380.750369 18.371045)
			(xy 380.664986 18.378957) (xy 380.580696 18.394713) (xy 380.49822 18.41818) (xy 380.418261 18.449156)
			(xy 380.341501 18.487378) (xy 380.268595 18.532519) (xy 380.200166 18.584195) (xy 380.136796 18.641964)
			(xy 380.079027 18.705334) (xy 380.027351 18.773763) (xy 379.98221 18.846669) (xy 379.943988 18.923429)
			(xy 379.913012 19.003388) (xy 379.889545 19.085864) (xy 379.873789 19.170154) (xy 379.865877 19.255537)
			(xy 375.370611 19.255537) (xy 375.362699 19.170154) (xy 375.346943 19.085864) (xy 375.323476 19.003388)
			(xy 375.2925 18.923429) (xy 375.254278 18.846669) (xy 375.209137 18.773763) (xy 375.157461 18.705334)
			(xy 375.099692 18.641964) (xy 375.036322 18.584195) (xy 374.967893 18.532519) (xy 374.894987 18.487378)
			(xy 374.818227 18.449156) (xy 374.738268 18.41818) (xy 374.655792 18.394713) (xy 374.571502 18.378957)
			(xy 374.486119 18.371045) (xy 374.400369 18.371045) (xy 374.314986 18.378957) (xy 374.230696 18.394713)
			(xy 374.14822 18.41818) (xy 374.068261 18.449156) (xy 373.991501 18.487378) (xy 373.918595 18.532519)
			(xy 373.850166 18.584195) (xy 373.786796 18.641964) (xy 373.729027 18.705334) (xy 373.677351 18.773763)
			(xy 373.63221 18.846669) (xy 373.593988 18.923429) (xy 373.563012 19.003388) (xy 373.539545 19.085864)
			(xy 373.523789 19.170154) (xy 373.515877 19.255537) (xy 342.659832 19.255537) (xy 342.652579 19.177266)
			(xy 342.636823 19.092976) (xy 342.613356 19.0105) (xy 342.58238 18.930541) (xy 342.544158 18.853781)
			(xy 342.499017 18.780875) (xy 342.447341 18.712446) (xy 342.389572 18.649076) (xy 342.326202 18.591307)
			(xy 342.257773 18.539631) (xy 342.184867 18.49449) (xy 342.108107 18.456268) (xy 342.028148 18.425292)
			(xy 341.945672 18.401825) (xy 341.861382 18.386069) (xy 341.775999 18.378157) (xy 341.690249 18.378157)
			(xy 341.604866 18.386069) (xy 341.520576 18.401825) (xy 341.4381 18.425292) (xy 341.358141 18.456268)
			(xy 341.281381 18.49449) (xy 341.208475 18.539631) (xy 341.140046 18.591307) (xy 341.076676 18.649076)
			(xy 341.018907 18.712446) (xy 340.967231 18.780875) (xy 340.92209 18.853781) (xy 340.883868 18.930541)
			(xy 340.852892 19.0105) (xy 340.829425 19.092976) (xy 340.813669 19.177266) (xy 340.805757 19.262649)
			(xy 336.310491 19.262649) (xy 336.302579 19.177266) (xy 336.286823 19.092976) (xy 336.263356 19.0105)
			(xy 336.23238 18.930541) (xy 336.194158 18.853781) (xy 336.149017 18.780875) (xy 336.097341 18.712446)
			(xy 336.039572 18.649076) (xy 335.976202 18.591307) (xy 335.907773 18.539631) (xy 335.834867 18.49449)
			(xy 335.758107 18.456268) (xy 335.678148 18.425292) (xy 335.595672 18.401825) (xy 335.511382 18.386069)
			(xy 335.425999 18.378157) (xy 335.340249 18.378157) (xy 335.254866 18.386069) (xy 335.170576 18.401825)
			(xy 335.0881 18.425292) (xy 335.008141 18.456268) (xy 334.931381 18.49449) (xy 334.858475 18.539631)
			(xy 334.790046 18.591307) (xy 334.726676 18.649076) (xy 334.668907 18.712446) (xy 334.617231 18.780875)
			(xy 334.57209 18.853781) (xy 334.533868 18.930541) (xy 334.502892 19.0105) (xy 334.479425 19.092976)
			(xy 334.463669 19.177266) (xy 334.455757 19.262649) (xy 316.569693 19.262649) (xy 316.569611 19.255537)
			(xy 316.561699 19.170154) (xy 316.545943 19.085864) (xy 316.522476 19.003388) (xy 316.4915 18.923429)
			(xy 316.453278 18.846669) (xy 316.408137 18.773763) (xy 316.356461 18.705334) (xy 316.298692 18.641964)
			(xy 316.235322 18.584195) (xy 316.166893 18.532519) (xy 316.093987 18.487378) (xy 316.017227 18.449156)
			(xy 315.937268 18.41818) (xy 315.854792 18.394713) (xy 315.770502 18.378957) (xy 315.685119 18.371045)
			(xy 315.599369 18.371045) (xy 315.513986 18.378957) (xy 315.429696 18.394713) (xy 315.34722 18.41818)
			(xy 315.267261 18.449156) (xy 315.190501 18.487378) (xy 315.117595 18.532519) (xy 315.049166 18.584195)
			(xy 314.985796 18.641964) (xy 314.928027 18.705334) (xy 314.876351 18.773763) (xy 314.83121 18.846669)
			(xy 314.792988 18.923429) (xy 314.762012 19.003388) (xy 314.738545 19.085864) (xy 314.722789 19.170154)
			(xy 314.714877 19.255537) (xy 310.219611 19.255537) (xy 310.211699 19.170154) (xy 310.195943 19.085864)
			(xy 310.172476 19.003388) (xy 310.1415 18.923429) (xy 310.103278 18.846669) (xy 310.058137 18.773763)
			(xy 310.006461 18.705334) (xy 309.948692 18.641964) (xy 309.885322 18.584195) (xy 309.816893 18.532519)
			(xy 309.743987 18.487378) (xy 309.667227 18.449156) (xy 309.587268 18.41818) (xy 309.504792 18.394713)
			(xy 309.420502 18.378957) (xy 309.335119 18.371045) (xy 309.249369 18.371045) (xy 309.163986 18.378957)
			(xy 309.079696 18.394713) (xy 308.99722 18.41818) (xy 308.917261 18.449156) (xy 308.840501 18.487378)
			(xy 308.767595 18.532519) (xy 308.699166 18.584195) (xy 308.635796 18.641964) (xy 308.578027 18.705334)
			(xy 308.526351 18.773763) (xy 308.48121 18.846669) (xy 308.442988 18.923429) (xy 308.412012 19.003388)
			(xy 308.388545 19.085864) (xy 308.372789 19.170154) (xy 308.364877 19.255537) (xy 277.508832 19.255537)
			(xy 277.501579 19.177266) (xy 277.485823 19.092976) (xy 277.462356 19.0105) (xy 277.43138 18.930541)
			(xy 277.393158 18.853781) (xy 277.348017 18.780875) (xy 277.296341 18.712446) (xy 277.238572 18.649076)
			(xy 277.175202 18.591307) (xy 277.106773 18.539631) (xy 277.033867 18.49449) (xy 276.957107 18.456268)
			(xy 276.877148 18.425292) (xy 276.794672 18.401825) (xy 276.710382 18.386069) (xy 276.624999 18.378157)
			(xy 276.539249 18.378157) (xy 276.453866 18.386069) (xy 276.369576 18.401825) (xy 276.2871 18.425292)
			(xy 276.207141 18.456268) (xy 276.130381 18.49449) (xy 276.057475 18.539631) (xy 275.989046 18.591307)
			(xy 275.925676 18.649076) (xy 275.867907 18.712446) (xy 275.816231 18.780875) (xy 275.77109 18.853781)
			(xy 275.732868 18.930541) (xy 275.701892 19.0105) (xy 275.678425 19.092976) (xy 275.662669 19.177266)
			(xy 275.654757 19.262649) (xy 271.159491 19.262649) (xy 271.151579 19.177266) (xy 271.135823 19.092976)
			(xy 271.112356 19.0105) (xy 271.08138 18.930541) (xy 271.043158 18.853781) (xy 270.998017 18.780875)
			(xy 270.946341 18.712446) (xy 270.888572 18.649076) (xy 270.825202 18.591307) (xy 270.756773 18.539631)
			(xy 270.683867 18.49449) (xy 270.607107 18.456268) (xy 270.527148 18.425292) (xy 270.444672 18.401825)
			(xy 270.360382 18.386069) (xy 270.274999 18.378157) (xy 270.189249 18.378157) (xy 270.103866 18.386069)
			(xy 270.019576 18.401825) (xy 269.9371 18.425292) (xy 269.857141 18.456268) (xy 269.780381 18.49449)
			(xy 269.707475 18.539631) (xy 269.639046 18.591307) (xy 269.575676 18.649076) (xy 269.517907 18.712446)
			(xy 269.466231 18.780875) (xy 269.42109 18.853781) (xy 269.382868 18.930541) (xy 269.351892 19.0105)
			(xy 269.328425 19.092976) (xy 269.312669 19.177266) (xy 269.304757 19.262649) (xy 252.231493 19.262649)
			(xy 252.231411 19.255537) (xy 252.223499 19.170154) (xy 252.207743 19.085864) (xy 252.184276 19.003388)
			(xy 252.1533 18.923429) (xy 252.115078 18.846669) (xy 252.069937 18.773763) (xy 252.018261 18.705334)
			(xy 251.960492 18.641964) (xy 251.897122 18.584195) (xy 251.828693 18.532519) (xy 251.755787 18.487378)
			(xy 251.679027 18.449156) (xy 251.599068 18.41818) (xy 251.516592 18.394713) (xy 251.432302 18.378957)
			(xy 251.346919 18.371045) (xy 251.261169 18.371045) (xy 251.175786 18.378957) (xy 251.091496 18.394713)
			(xy 251.00902 18.41818) (xy 250.929061 18.449156) (xy 250.852301 18.487378) (xy 250.779395 18.532519)
			(xy 250.710966 18.584195) (xy 250.647596 18.641964) (xy 250.589827 18.705334) (xy 250.538151 18.773763)
			(xy 250.49301 18.846669) (xy 250.454788 18.923429) (xy 250.423812 19.003388) (xy 250.400345 19.085864)
			(xy 250.384589 19.170154) (xy 250.376677 19.255537) (xy 245.881411 19.255537) (xy 245.873499 19.170154)
			(xy 245.857743 19.085864) (xy 245.834276 19.003388) (xy 245.8033 18.923429) (xy 245.765078 18.846669)
			(xy 245.719937 18.773763) (xy 245.668261 18.705334) (xy 245.610492 18.641964) (xy 245.547122 18.584195)
			(xy 245.478693 18.532519) (xy 245.405787 18.487378) (xy 245.329027 18.449156) (xy 245.249068 18.41818)
			(xy 245.166592 18.394713) (xy 245.082302 18.378957) (xy 244.996919 18.371045) (xy 244.911169 18.371045)
			(xy 244.825786 18.378957) (xy 244.741496 18.394713) (xy 244.65902 18.41818) (xy 244.579061 18.449156)
			(xy 244.502301 18.487378) (xy 244.429395 18.532519) (xy 244.360966 18.584195) (xy 244.297596 18.641964)
			(xy 244.239827 18.705334) (xy 244.188151 18.773763) (xy 244.14301 18.846669) (xy 244.104788 18.923429)
			(xy 244.073812 19.003388) (xy 244.050345 19.085864) (xy 244.034589 19.170154) (xy 244.026677 19.255537)
			(xy 218.199832 19.255537) (xy 218.192579 19.177266) (xy 218.176823 19.092976) (xy 218.153356 19.0105)
			(xy 218.12238 18.930541) (xy 218.084158 18.853781) (xy 218.039017 18.780875) (xy 217.987341 18.712446)
			(xy 217.929572 18.649076) (xy 217.866202 18.591307) (xy 217.797773 18.539631) (xy 217.724867 18.49449)
			(xy 217.648107 18.456268) (xy 217.568148 18.425292) (xy 217.485672 18.401825) (xy 217.401382 18.386069)
			(xy 217.315999 18.378157) (xy 217.230249 18.378157) (xy 217.144866 18.386069) (xy 217.060576 18.401825)
			(xy 216.9781 18.425292) (xy 216.898141 18.456268) (xy 216.821381 18.49449) (xy 216.748475 18.539631)
			(xy 216.680046 18.591307) (xy 216.616676 18.649076) (xy 216.558907 18.712446) (xy 216.507231 18.780875)
			(xy 216.46209 18.853781) (xy 216.423868 18.930541) (xy 216.392892 19.0105) (xy 216.369425 19.092976)
			(xy 216.353669 19.177266) (xy 216.345757 19.262649) (xy 211.850491 19.262649) (xy 211.842579 19.177266)
			(xy 211.826823 19.092976) (xy 211.803356 19.0105) (xy 211.77238 18.930541) (xy 211.734158 18.853781)
			(xy 211.689017 18.780875) (xy 211.637341 18.712446) (xy 211.579572 18.649076) (xy 211.516202 18.591307)
			(xy 211.447773 18.539631) (xy 211.374867 18.49449) (xy 211.298107 18.456268) (xy 211.218148 18.425292)
			(xy 211.135672 18.401825) (xy 211.051382 18.386069) (xy 210.965999 18.378157) (xy 210.880249 18.378157)
			(xy 210.794866 18.386069) (xy 210.710576 18.401825) (xy 210.6281 18.425292) (xy 210.548141 18.456268)
			(xy 210.471381 18.49449) (xy 210.398475 18.539631) (xy 210.330046 18.591307) (xy 210.266676 18.649076)
			(xy 210.208907 18.712446) (xy 210.157231 18.780875) (xy 210.11209 18.853781) (xy 210.073868 18.930541)
			(xy 210.042892 19.0105) (xy 210.019425 19.092976) (xy 210.003669 19.177266) (xy 209.995757 19.262649)
			(xy 158.621984 19.262649) (xy 158.621984 16.722649) (xy 209.995757 16.722649) (xy 209.995757 16.808399)
			(xy 210.003669 16.893782) (xy 210.019425 16.978072) (xy 210.042892 17.060548) (xy 210.073868 17.140507)
			(xy 210.11209 17.217267) (xy 210.157231 17.290173) (xy 210.208907 17.358602) (xy 210.266676 17.421972)
			(xy 210.330046 17.479741) (xy 210.398475 17.531417) (xy 210.471381 17.576558) (xy 210.548141 17.61478)
			(xy 210.6281 17.645756) (xy 210.710576 17.669223) (xy 210.794866 17.684979) (xy 210.880249 17.692891)
			(xy 210.965999 17.692891) (xy 211.051382 17.684979) (xy 211.135672 17.669223) (xy 211.218148 17.645756)
			(xy 211.298107 17.61478) (xy 211.374867 17.576558) (xy 211.447773 17.531417) (xy 211.516202 17.479741)
			(xy 211.579572 17.421972) (xy 211.637341 17.358602) (xy 211.689017 17.290173) (xy 211.734158 17.217267)
			(xy 211.77238 17.140507) (xy 211.803356 17.060548) (xy 211.826823 16.978072) (xy 211.842579 16.893782)
			(xy 211.850491 16.808399) (xy 211.850986 16.765524) (xy 211.850491 16.722649) (xy 216.345757 16.722649)
			(xy 216.345757 16.808399) (xy 216.353669 16.893782) (xy 216.369425 16.978072) (xy 216.392892 17.060548)
			(xy 216.423868 17.140507) (xy 216.46209 17.217267) (xy 216.507231 17.290173) (xy 216.558907 17.358602)
			(xy 216.616676 17.421972) (xy 216.680046 17.479741) (xy 216.748475 17.531417) (xy 216.821381 17.576558)
			(xy 216.898141 17.61478) (xy 216.9781 17.645756) (xy 217.060576 17.669223) (xy 217.144866 17.684979)
			(xy 217.230249 17.692891) (xy 217.315999 17.692891) (xy 217.401382 17.684979) (xy 217.485672 17.669223)
			(xy 217.568148 17.645756) (xy 217.648107 17.61478) (xy 217.724867 17.576558) (xy 217.797773 17.531417)
			(xy 217.866202 17.479741) (xy 217.929572 17.421972) (xy 217.987341 17.358602) (xy 218.039017 17.290173)
			(xy 218.084158 17.217267) (xy 218.12238 17.140507) (xy 218.153356 17.060548) (xy 218.176823 16.978072)
			(xy 218.192579 16.893782) (xy 218.200491 16.808399) (xy 218.200986 16.765524) (xy 218.200491 16.722649)
			(xy 218.199832 16.715537) (xy 244.026677 16.715537) (xy 244.026677 16.801287) (xy 244.034589 16.88667)
			(xy 244.050345 16.97096) (xy 244.073812 17.053436) (xy 244.104788 17.133395) (xy 244.14301 17.210155)
			(xy 244.188151 17.283061) (xy 244.239827 17.35149) (xy 244.297596 17.41486) (xy 244.360966 17.472629)
			(xy 244.429395 17.524305) (xy 244.502301 17.569446) (xy 244.579061 17.607668) (xy 244.65902 17.638644)
			(xy 244.741496 17.662111) (xy 244.825786 17.677867) (xy 244.911169 17.685779) (xy 244.996919 17.685779)
			(xy 245.082302 17.677867) (xy 245.166592 17.662111) (xy 245.249068 17.638644) (xy 245.329027 17.607668)
			(xy 245.405787 17.569446) (xy 245.478693 17.524305) (xy 245.547122 17.472629) (xy 245.610492 17.41486)
			(xy 245.668261 17.35149) (xy 245.719937 17.283061) (xy 245.765078 17.210155) (xy 245.8033 17.133395)
			(xy 245.834276 17.053436) (xy 245.857743 16.97096) (xy 245.873499 16.88667) (xy 245.881411 16.801287)
			(xy 245.881906 16.758412) (xy 245.881411 16.715537) (xy 250.376677 16.715537) (xy 250.376677 16.801287)
			(xy 250.384589 16.88667) (xy 250.400345 16.97096) (xy 250.423812 17.053436) (xy 250.454788 17.133395)
			(xy 250.49301 17.210155) (xy 250.538151 17.283061) (xy 250.589827 17.35149) (xy 250.647596 17.41486)
			(xy 250.710966 17.472629) (xy 250.779395 17.524305) (xy 250.852301 17.569446) (xy 250.929061 17.607668)
			(xy 251.00902 17.638644) (xy 251.091496 17.662111) (xy 251.175786 17.677867) (xy 251.261169 17.685779)
			(xy 251.346919 17.685779) (xy 251.432302 17.677867) (xy 251.516592 17.662111) (xy 251.599068 17.638644)
			(xy 251.679027 17.607668) (xy 251.755787 17.569446) (xy 251.828693 17.524305) (xy 251.897122 17.472629)
			(xy 251.960492 17.41486) (xy 252.018261 17.35149) (xy 252.069937 17.283061) (xy 252.115078 17.210155)
			(xy 252.1533 17.133395) (xy 252.184276 17.053436) (xy 252.207743 16.97096) (xy 252.223499 16.88667)
			(xy 252.231411 16.801287) (xy 252.231906 16.758412) (xy 252.231493 16.722649) (xy 269.304757 16.722649)
			(xy 269.304757 16.808399) (xy 269.312669 16.893782) (xy 269.328425 16.978072) (xy 269.351892 17.060548)
			(xy 269.382868 17.140507) (xy 269.42109 17.217267) (xy 269.466231 17.290173) (xy 269.517907 17.358602)
			(xy 269.575676 17.421972) (xy 269.639046 17.479741) (xy 269.707475 17.531417) (xy 269.780381 17.576558)
			(xy 269.857141 17.61478) (xy 269.9371 17.645756) (xy 270.019576 17.669223) (xy 270.103866 17.684979)
			(xy 270.189249 17.692891) (xy 270.274999 17.692891) (xy 270.360382 17.684979) (xy 270.444672 17.669223)
			(xy 270.527148 17.645756) (xy 270.607107 17.61478) (xy 270.62931 17.603724) (xy 274.239736 17.603724)
			(xy 274.239736 18.467324) (xy 274.240222 18.494593) (xy 274.247984 18.548577) (xy 274.263349 18.600907)
			(xy 274.286006 18.650517) (xy 274.315492 18.696398) (xy 274.351207 18.737615) (xy 274.392424 18.77333)
			(xy 274.438305 18.802816) (xy 274.487915 18.825473) (xy 274.540245 18.840838) (xy 274.594229 18.8486)
			(xy 274.648767 18.8486) (xy 274.702751 18.840838) (xy 274.755081 18.825473) (xy 274.804691 18.802816)
			(xy 274.850572 18.77333) (xy 274.891789 18.737615) (xy 274.927504 18.696398) (xy 274.95699 18.650517)
			(xy 274.979647 18.600907) (xy 274.995012 18.548577) (xy 275.002774 18.494593) (xy 275.00326 18.467324)
			(xy 275.00326 17.603724) (xy 275.002774 17.576455) (xy 274.995012 17.522471) (xy 274.979647 17.470141)
			(xy 274.95699 17.420531) (xy 274.927504 17.37465) (xy 274.891789 17.333433) (xy 274.850572 17.297718)
			(xy 274.804691 17.268232) (xy 274.755081 17.245575) (xy 274.702751 17.23021) (xy 274.648767 17.222448)
			(xy 274.594229 17.222448) (xy 274.540245 17.23021) (xy 274.487915 17.245575) (xy 274.438305 17.268232)
			(xy 274.392424 17.297718) (xy 274.351207 17.333433) (xy 274.315492 17.37465) (xy 274.286006 17.420531)
			(xy 274.263349 17.470141) (xy 274.247984 17.522471) (xy 274.240222 17.576455) (xy 274.239736 17.603724)
			(xy 270.62931 17.603724) (xy 270.683867 17.576558) (xy 270.756773 17.531417) (xy 270.825202 17.479741)
			(xy 270.888572 17.421972) (xy 270.946341 17.358602) (xy 270.998017 17.290173) (xy 271.043158 17.217267)
			(xy 271.08138 17.140507) (xy 271.112356 17.060548) (xy 271.135823 16.978072) (xy 271.151579 16.893782)
			(xy 271.159491 16.808399) (xy 271.159986 16.765524) (xy 271.159491 16.722649) (xy 275.654757 16.722649)
			(xy 275.654757 16.808399) (xy 275.662669 16.893782) (xy 275.678425 16.978072) (xy 275.701892 17.060548)
			(xy 275.732868 17.140507) (xy 275.77109 17.217267) (xy 275.816231 17.290173) (xy 275.867907 17.358602)
			(xy 275.925676 17.421972) (xy 275.989046 17.479741) (xy 276.057475 17.531417) (xy 276.130381 17.576558)
			(xy 276.207141 17.61478) (xy 276.2871 17.645756) (xy 276.369576 17.669223) (xy 276.453866 17.684979)
			(xy 276.539249 17.692891) (xy 276.624999 17.692891) (xy 276.710382 17.684979) (xy 276.794672 17.669223)
			(xy 276.877148 17.645756) (xy 276.957107 17.61478) (xy 277.033867 17.576558) (xy 277.106773 17.531417)
			(xy 277.175202 17.479741) (xy 277.238572 17.421972) (xy 277.296341 17.358602) (xy 277.348017 17.290173)
			(xy 277.393158 17.217267) (xy 277.43138 17.140507) (xy 277.462356 17.060548) (xy 277.485823 16.978072)
			(xy 277.501579 16.893782) (xy 277.509491 16.808399) (xy 277.509986 16.765524) (xy 277.509491 16.722649)
			(xy 277.508832 16.715537) (xy 308.364877 16.715537) (xy 308.364877 16.801287) (xy 308.372789 16.88667)
			(xy 308.388545 16.97096) (xy 308.412012 17.053436) (xy 308.442988 17.133395) (xy 308.48121 17.210155)
			(xy 308.526351 17.283061) (xy 308.578027 17.35149) (xy 308.635796 17.41486) (xy 308.699166 17.472629)
			(xy 308.767595 17.524305) (xy 308.840501 17.569446) (xy 308.917261 17.607668) (xy 308.99722 17.638644)
			(xy 309.079696 17.662111) (xy 309.163986 17.677867) (xy 309.249369 17.685779) (xy 309.335119 17.685779)
			(xy 309.420502 17.677867) (xy 309.504792 17.662111) (xy 309.587268 17.638644) (xy 309.667227 17.607668)
			(xy 309.68943 17.596612) (xy 310.871108 17.596612) (xy 310.871108 18.460212) (xy 310.871594 18.487481)
			(xy 310.879356 18.541465) (xy 310.894721 18.593795) (xy 310.917378 18.643405) (xy 310.946864 18.689286)
			(xy 310.982579 18.730503) (xy 311.023796 18.766218) (xy 311.069677 18.795704) (xy 311.119287 18.818361)
			(xy 311.171617 18.833726) (xy 311.225601 18.841488) (xy 311.280139 18.841488) (xy 311.334123 18.833726)
			(xy 311.386453 18.818361) (xy 311.436063 18.795704) (xy 311.481944 18.766218) (xy 311.523161 18.730503)
			(xy 311.558876 18.689286) (xy 311.588362 18.643405) (xy 311.611019 18.593795) (xy 311.626384 18.541465)
			(xy 311.634146 18.487481) (xy 311.634632 18.460212) (xy 311.634632 17.596612) (xy 311.634146 17.569343)
			(xy 311.626384 17.515359) (xy 311.611019 17.463029) (xy 311.588362 17.413419) (xy 311.558876 17.367538)
			(xy 311.523161 17.326321) (xy 311.481944 17.290606) (xy 311.436063 17.26112) (xy 311.386453 17.238463)
			(xy 311.334123 17.223098) (xy 311.280139 17.215336) (xy 311.225601 17.215336) (xy 311.171617 17.223098)
			(xy 311.119287 17.238463) (xy 311.069677 17.26112) (xy 311.023796 17.290606) (xy 310.982579 17.326321)
			(xy 310.946864 17.367538) (xy 310.917378 17.413419) (xy 310.894721 17.463029) (xy 310.879356 17.515359)
			(xy 310.871594 17.569343) (xy 310.871108 17.596612) (xy 309.68943 17.596612) (xy 309.743987 17.569446)
			(xy 309.816893 17.524305) (xy 309.885322 17.472629) (xy 309.948692 17.41486) (xy 310.006461 17.35149)
			(xy 310.058137 17.283061) (xy 310.103278 17.210155) (xy 310.1415 17.133395) (xy 310.172476 17.053436)
			(xy 310.195943 16.97096) (xy 310.211699 16.88667) (xy 310.219611 16.801287) (xy 310.220106 16.758412)
			(xy 310.219611 16.715537) (xy 314.714877 16.715537) (xy 314.714877 16.801287) (xy 314.722789 16.88667)
			(xy 314.738545 16.97096) (xy 314.762012 17.053436) (xy 314.792988 17.133395) (xy 314.83121 17.210155)
			(xy 314.876351 17.283061) (xy 314.928027 17.35149) (xy 314.985796 17.41486) (xy 315.049166 17.472629)
			(xy 315.117595 17.524305) (xy 315.190501 17.569446) (xy 315.267261 17.607668) (xy 315.34722 17.638644)
			(xy 315.429696 17.662111) (xy 315.513986 17.677867) (xy 315.599369 17.685779) (xy 315.685119 17.685779)
			(xy 315.770502 17.677867) (xy 315.854792 17.662111) (xy 315.937268 17.638644) (xy 316.017227 17.607668)
			(xy 316.093987 17.569446) (xy 316.166893 17.524305) (xy 316.235322 17.472629) (xy 316.298692 17.41486)
			(xy 316.356461 17.35149) (xy 316.408137 17.283061) (xy 316.453278 17.210155) (xy 316.4915 17.133395)
			(xy 316.522476 17.053436) (xy 316.545943 16.97096) (xy 316.561699 16.88667) (xy 316.569611 16.801287)
			(xy 316.570106 16.758412) (xy 316.569693 16.722649) (xy 334.455757 16.722649) (xy 334.455757 16.808399)
			(xy 334.463669 16.893782) (xy 334.479425 16.978072) (xy 334.502892 17.060548) (xy 334.533868 17.140507)
			(xy 334.57209 17.217267) (xy 334.617231 17.290173) (xy 334.668907 17.358602) (xy 334.726676 17.421972)
			(xy 334.790046 17.479741) (xy 334.858475 17.531417) (xy 334.931381 17.576558) (xy 335.008141 17.61478)
			(xy 335.0881 17.645756) (xy 335.170576 17.669223) (xy 335.254866 17.684979) (xy 335.340249 17.692891)
			(xy 335.425999 17.692891) (xy 335.511382 17.684979) (xy 335.595672 17.669223) (xy 335.678148 17.645756)
			(xy 335.758107 17.61478) (xy 335.78031 17.603724) (xy 339.390736 17.603724) (xy 339.390736 18.467324)
			(xy 339.391222 18.494593) (xy 339.398984 18.548577) (xy 339.414349 18.600907) (xy 339.437006 18.650517)
			(xy 339.466492 18.696398) (xy 339.502207 18.737615) (xy 339.543424 18.77333) (xy 339.589305 18.802816)
			(xy 339.638915 18.825473) (xy 339.691245 18.840838) (xy 339.745229 18.8486) (xy 339.799767 18.8486)
			(xy 339.853751 18.840838) (xy 339.906081 18.825473) (xy 339.955691 18.802816) (xy 340.001572 18.77333)
			(xy 340.042789 18.737615) (xy 340.078504 18.696398) (xy 340.10799 18.650517) (xy 340.130647 18.600907)
			(xy 340.146012 18.548577) (xy 340.153774 18.494593) (xy 340.15426 18.467324) (xy 340.15426 17.603724)
			(xy 340.153774 17.576455) (xy 340.146012 17.522471) (xy 340.130647 17.470141) (xy 340.10799 17.420531)
			(xy 340.078504 17.37465) (xy 340.042789 17.333433) (xy 340.001572 17.297718) (xy 339.955691 17.268232)
			(xy 339.906081 17.245575) (xy 339.853751 17.23021) (xy 339.799767 17.222448) (xy 339.745229 17.222448)
			(xy 339.691245 17.23021) (xy 339.638915 17.245575) (xy 339.589305 17.268232) (xy 339.543424 17.297718)
			(xy 339.502207 17.333433) (xy 339.466492 17.37465) (xy 339.437006 17.420531) (xy 339.414349 17.470141)
			(xy 339.398984 17.522471) (xy 339.391222 17.576455) (xy 339.390736 17.603724) (xy 335.78031 17.603724)
			(xy 335.834867 17.576558) (xy 335.907773 17.531417) (xy 335.976202 17.479741) (xy 336.039572 17.421972)
			(xy 336.097341 17.358602) (xy 336.149017 17.290173) (xy 336.194158 17.217267) (xy 336.23238 17.140507)
			(xy 336.263356 17.060548) (xy 336.286823 16.978072) (xy 336.302579 16.893782) (xy 336.310491 16.808399)
			(xy 336.310986 16.765524) (xy 336.310491 16.722649) (xy 340.805757 16.722649) (xy 340.805757 16.808399)
			(xy 340.813669 16.893782) (xy 340.829425 16.978072) (xy 340.852892 17.060548) (xy 340.883868 17.140507)
			(xy 340.92209 17.217267) (xy 340.967231 17.290173) (xy 341.018907 17.358602) (xy 341.076676 17.421972)
			(xy 341.140046 17.479741) (xy 341.208475 17.531417) (xy 341.281381 17.576558) (xy 341.358141 17.61478)
			(xy 341.4381 17.645756) (xy 341.520576 17.669223) (xy 341.604866 17.684979) (xy 341.690249 17.692891)
			(xy 341.775999 17.692891) (xy 341.861382 17.684979) (xy 341.945672 17.669223) (xy 342.028148 17.645756)
			(xy 342.108107 17.61478) (xy 342.184867 17.576558) (xy 342.257773 17.531417) (xy 342.326202 17.479741)
			(xy 342.389572 17.421972) (xy 342.447341 17.358602) (xy 342.499017 17.290173) (xy 342.544158 17.217267)
			(xy 342.58238 17.140507) (xy 342.613356 17.060548) (xy 342.636823 16.978072) (xy 342.652579 16.893782)
			(xy 342.660491 16.808399) (xy 342.660986 16.765524) (xy 342.660491 16.722649) (xy 342.659832 16.715537)
			(xy 373.515877 16.715537) (xy 373.515877 16.801287) (xy 373.523789 16.88667) (xy 373.539545 16.97096)
			(xy 373.563012 17.053436) (xy 373.593988 17.133395) (xy 373.63221 17.210155) (xy 373.677351 17.283061)
			(xy 373.729027 17.35149) (xy 373.786796 17.41486) (xy 373.850166 17.472629) (xy 373.918595 17.524305)
			(xy 373.991501 17.569446) (xy 374.068261 17.607668) (xy 374.14822 17.638644) (xy 374.230696 17.662111)
			(xy 374.314986 17.677867) (xy 374.400369 17.685779) (xy 374.486119 17.685779) (xy 374.571502 17.677867)
			(xy 374.655792 17.662111) (xy 374.738268 17.638644) (xy 374.818227 17.607668) (xy 374.84043 17.596612)
			(xy 376.022108 17.596612) (xy 376.022108 18.460212) (xy 376.022594 18.487481) (xy 376.030356 18.541465)
			(xy 376.045721 18.593795) (xy 376.068378 18.643405) (xy 376.097864 18.689286) (xy 376.133579 18.730503)
			(xy 376.174796 18.766218) (xy 376.220677 18.795704) (xy 376.270287 18.818361) (xy 376.322617 18.833726)
			(xy 376.376601 18.841488) (xy 376.431139 18.841488) (xy 376.485123 18.833726) (xy 376.537453 18.818361)
			(xy 376.587063 18.795704) (xy 376.632944 18.766218) (xy 376.674161 18.730503) (xy 376.709876 18.689286)
			(xy 376.739362 18.643405) (xy 376.762019 18.593795) (xy 376.777384 18.541465) (xy 376.785146 18.487481)
			(xy 376.785632 18.460212) (xy 376.785632 17.596612) (xy 376.785146 17.569343) (xy 376.777384 17.515359)
			(xy 376.762019 17.463029) (xy 376.739362 17.413419) (xy 376.709876 17.367538) (xy 376.674161 17.326321)
			(xy 376.632944 17.290606) (xy 376.587063 17.26112) (xy 376.537453 17.238463) (xy 376.485123 17.223098)
			(xy 376.431139 17.215336) (xy 376.376601 17.215336) (xy 376.322617 17.223098) (xy 376.270287 17.238463)
			(xy 376.220677 17.26112) (xy 376.174796 17.290606) (xy 376.133579 17.326321) (xy 376.097864 17.367538)
			(xy 376.068378 17.413419) (xy 376.045721 17.463029) (xy 376.030356 17.515359) (xy 376.022594 17.569343)
			(xy 376.022108 17.596612) (xy 374.84043 17.596612) (xy 374.894987 17.569446) (xy 374.967893 17.524305)
			(xy 375.036322 17.472629) (xy 375.099692 17.41486) (xy 375.157461 17.35149) (xy 375.209137 17.283061)
			(xy 375.254278 17.210155) (xy 375.2925 17.133395) (xy 375.323476 17.053436) (xy 375.346943 16.97096)
			(xy 375.362699 16.88667) (xy 375.370611 16.801287) (xy 375.371106 16.758412) (xy 375.370611 16.715537)
			(xy 379.865877 16.715537) (xy 379.865877 16.801287) (xy 379.873789 16.88667) (xy 379.889545 16.97096)
			(xy 379.913012 17.053436) (xy 379.943988 17.133395) (xy 379.98221 17.210155) (xy 380.027351 17.283061)
			(xy 380.079027 17.35149) (xy 380.136796 17.41486) (xy 380.200166 17.472629) (xy 380.268595 17.524305)
			(xy 380.341501 17.569446) (xy 380.418261 17.607668) (xy 380.49822 17.638644) (xy 380.580696 17.662111)
			(xy 380.664986 17.677867) (xy 380.750369 17.685779) (xy 380.836119 17.685779) (xy 380.921502 17.677867)
			(xy 381.005792 17.662111) (xy 381.088268 17.638644) (xy 381.168227 17.607668) (xy 381.244987 17.569446)
			(xy 381.317893 17.524305) (xy 381.386322 17.472629) (xy 381.449692 17.41486) (xy 381.507461 17.35149)
			(xy 381.559137 17.283061) (xy 381.604278 17.210155) (xy 381.6425 17.133395) (xy 381.673476 17.053436)
			(xy 381.696943 16.97096) (xy 381.712699 16.88667) (xy 381.720611 16.801287) (xy 381.721106 16.758412)
			(xy 381.720693 16.722649) (xy 399.098757 16.722649) (xy 399.098757 16.808399) (xy 399.106669 16.893782)
			(xy 399.122425 16.978072) (xy 399.145892 17.060548) (xy 399.176868 17.140507) (xy 399.21509 17.217267)
			(xy 399.260231 17.290173) (xy 399.311907 17.358602) (xy 399.369676 17.421972) (xy 399.433046 17.479741)
			(xy 399.501475 17.531417) (xy 399.574381 17.576558) (xy 399.651141 17.61478) (xy 399.7311 17.645756)
			(xy 399.813576 17.669223) (xy 399.897866 17.684979) (xy 399.983249 17.692891) (xy 400.068999 17.692891)
			(xy 400.154382 17.684979) (xy 400.238672 17.669223) (xy 400.321148 17.645756) (xy 400.401107 17.61478)
			(xy 400.42331 17.603724) (xy 404.033736 17.603724) (xy 404.033736 18.467324) (xy 404.034222 18.494593)
			(xy 404.041984 18.548577) (xy 404.057349 18.600907) (xy 404.080006 18.650517) (xy 404.109492 18.696398)
			(xy 404.145207 18.737615) (xy 404.186424 18.77333) (xy 404.232305 18.802816) (xy 404.281915 18.825473)
			(xy 404.334245 18.840838) (xy 404.388229 18.8486) (xy 404.442767 18.8486) (xy 404.496751 18.840838)
			(xy 404.549081 18.825473) (xy 404.598691 18.802816) (xy 404.644572 18.77333) (xy 404.685789 18.737615)
			(xy 404.721504 18.696398) (xy 404.75099 18.650517) (xy 404.773647 18.600907) (xy 404.789012 18.548577)
			(xy 404.796774 18.494593) (xy 404.79726 18.467324) (xy 404.79726 17.603724) (xy 404.796774 17.576455)
			(xy 404.789012 17.522471) (xy 404.773647 17.470141) (xy 404.75099 17.420531) (xy 404.721504 17.37465)
			(xy 404.685789 17.333433) (xy 404.644572 17.297718) (xy 404.598691 17.268232) (xy 404.549081 17.245575)
			(xy 404.496751 17.23021) (xy 404.442767 17.222448) (xy 404.388229 17.222448) (xy 404.334245 17.23021)
			(xy 404.281915 17.245575) (xy 404.232305 17.268232) (xy 404.186424 17.297718) (xy 404.145207 17.333433)
			(xy 404.109492 17.37465) (xy 404.080006 17.420531) (xy 404.057349 17.470141) (xy 404.041984 17.522471)
			(xy 404.034222 17.576455) (xy 404.033736 17.603724) (xy 400.42331 17.603724) (xy 400.477867 17.576558)
			(xy 400.550773 17.531417) (xy 400.619202 17.479741) (xy 400.682572 17.421972) (xy 400.740341 17.358602)
			(xy 400.792017 17.290173) (xy 400.837158 17.217267) (xy 400.87538 17.140507) (xy 400.906356 17.060548)
			(xy 400.929823 16.978072) (xy 400.945579 16.893782) (xy 400.953491 16.808399) (xy 400.953986 16.765524)
			(xy 400.953491 16.722649) (xy 405.448757 16.722649) (xy 405.448757 16.808399) (xy 405.456669 16.893782)
			(xy 405.472425 16.978072) (xy 405.495892 17.060548) (xy 405.526868 17.140507) (xy 405.56509 17.217267)
			(xy 405.610231 17.290173) (xy 405.661907 17.358602) (xy 405.719676 17.421972) (xy 405.783046 17.479741)
			(xy 405.851475 17.531417) (xy 405.924381 17.576558) (xy 406.001141 17.61478) (xy 406.0811 17.645756)
			(xy 406.163576 17.669223) (xy 406.247866 17.684979) (xy 406.333249 17.692891) (xy 406.418999 17.692891)
			(xy 406.504382 17.684979) (xy 406.588672 17.669223) (xy 406.671148 17.645756) (xy 406.751107 17.61478)
			(xy 406.827867 17.576558) (xy 406.900773 17.531417) (xy 406.969202 17.479741) (xy 407.032572 17.421972)
			(xy 407.090341 17.358602) (xy 407.142017 17.290173) (xy 407.187158 17.217267) (xy 407.22538 17.140507)
			(xy 407.256356 17.060548) (xy 407.279823 16.978072) (xy 407.295579 16.893782) (xy 407.303491 16.808399)
			(xy 407.303986 16.765524) (xy 407.303491 16.722649) (xy 407.302832 16.715537) (xy 438.158877 16.715537)
			(xy 438.158877 16.801287) (xy 438.166789 16.88667) (xy 438.182545 16.97096) (xy 438.206012 17.053436)
			(xy 438.236988 17.133395) (xy 438.27521 17.210155) (xy 438.320351 17.283061) (xy 438.372027 17.35149)
			(xy 438.429796 17.41486) (xy 438.493166 17.472629) (xy 438.561595 17.524305) (xy 438.634501 17.569446)
			(xy 438.711261 17.607668) (xy 438.79122 17.638644) (xy 438.873696 17.662111) (xy 438.957986 17.677867)
			(xy 439.043369 17.685779) (xy 439.129119 17.685779) (xy 439.214502 17.677867) (xy 439.298792 17.662111)
			(xy 439.381268 17.638644) (xy 439.461227 17.607668) (xy 439.48343 17.596612) (xy 440.665108 17.596612)
			(xy 440.665108 18.460212) (xy 440.665594 18.487481) (xy 440.673356 18.541465) (xy 440.688721 18.593795)
			(xy 440.711378 18.643405) (xy 440.740864 18.689286) (xy 440.776579 18.730503) (xy 440.817796 18.766218)
			(xy 440.863677 18.795704) (xy 440.913287 18.818361) (xy 440.965617 18.833726) (xy 441.019601 18.841488)
			(xy 441.074139 18.841488) (xy 441.128123 18.833726) (xy 441.180453 18.818361) (xy 441.230063 18.795704)
			(xy 441.275944 18.766218) (xy 441.317161 18.730503) (xy 441.352876 18.689286) (xy 441.382362 18.643405)
			(xy 441.405019 18.593795) (xy 441.420384 18.541465) (xy 441.428146 18.487481) (xy 441.428632 18.460212)
			(xy 441.428632 17.596612) (xy 441.428146 17.569343) (xy 441.420384 17.515359) (xy 441.405019 17.463029)
			(xy 441.382362 17.413419) (xy 441.352876 17.367538) (xy 441.317161 17.326321) (xy 441.275944 17.290606)
			(xy 441.230063 17.26112) (xy 441.180453 17.238463) (xy 441.128123 17.223098) (xy 441.074139 17.215336)
			(xy 441.019601 17.215336) (xy 440.965617 17.223098) (xy 440.913287 17.238463) (xy 440.863677 17.26112)
			(xy 440.817796 17.290606) (xy 440.776579 17.326321) (xy 440.740864 17.367538) (xy 440.711378 17.413419)
			(xy 440.688721 17.463029) (xy 440.673356 17.515359) (xy 440.665594 17.569343) (xy 440.665108 17.596612)
			(xy 439.48343 17.596612) (xy 439.537987 17.569446) (xy 439.610893 17.524305) (xy 439.679322 17.472629)
			(xy 439.742692 17.41486) (xy 439.800461 17.35149) (xy 439.852137 17.283061) (xy 439.897278 17.210155)
			(xy 439.9355 17.133395) (xy 439.966476 17.053436) (xy 439.989943 16.97096) (xy 440.005699 16.88667)
			(xy 440.013611 16.801287) (xy 440.014106 16.758412) (xy 440.013611 16.715537) (xy 444.508877 16.715537)
			(xy 444.508877 16.801287) (xy 444.516789 16.88667) (xy 444.532545 16.97096) (xy 444.556012 17.053436)
			(xy 444.586988 17.133395) (xy 444.62521 17.210155) (xy 444.670351 17.283061) (xy 444.722027 17.35149)
			(xy 444.779796 17.41486) (xy 444.843166 17.472629) (xy 444.911595 17.524305) (xy 444.984501 17.569446)
			(xy 445.061261 17.607668) (xy 445.14122 17.638644) (xy 445.223696 17.662111) (xy 445.307986 17.677867)
			(xy 445.393369 17.685779) (xy 445.479119 17.685779) (xy 445.564502 17.677867) (xy 445.648792 17.662111)
			(xy 445.731268 17.638644) (xy 445.811227 17.607668) (xy 445.887987 17.569446) (xy 445.960893 17.524305)
			(xy 446.029322 17.472629) (xy 446.092692 17.41486) (xy 446.150461 17.35149) (xy 446.202137 17.283061)
			(xy 446.247278 17.210155) (xy 446.2855 17.133395) (xy 446.316476 17.053436) (xy 446.339943 16.97096)
			(xy 446.355699 16.88667) (xy 446.363611 16.801287) (xy 446.364106 16.758412) (xy 446.363611 16.715537)
			(xy 446.355699 16.630154) (xy 446.339943 16.545864) (xy 446.316476 16.463388) (xy 446.2855 16.383429)
			(xy 446.247278 16.306669) (xy 446.202137 16.233763) (xy 446.150461 16.165334) (xy 446.092692 16.101964)
			(xy 446.029322 16.044195) (xy 445.960893 15.992519) (xy 445.887987 15.947378) (xy 445.811227 15.909156)
			(xy 445.731268 15.87818) (xy 445.648792 15.854713) (xy 445.564502 15.838957) (xy 445.479119 15.831045)
			(xy 445.393369 15.831045) (xy 445.307986 15.838957) (xy 445.223696 15.854713) (xy 445.14122 15.87818)
			(xy 445.061261 15.909156) (xy 444.984501 15.947378) (xy 444.911595 15.992519) (xy 444.843166 16.044195)
			(xy 444.779796 16.101964) (xy 444.722027 16.165334) (xy 444.670351 16.233763) (xy 444.62521 16.306669)
			(xy 444.586988 16.383429) (xy 444.556012 16.463388) (xy 444.532545 16.545864) (xy 444.516789 16.630154)
			(xy 444.508877 16.715537) (xy 440.013611 16.715537) (xy 440.005699 16.630154) (xy 439.989943 16.545864)
			(xy 439.966476 16.463388) (xy 439.9355 16.383429) (xy 439.897278 16.306669) (xy 439.852137 16.233763)
			(xy 439.800461 16.165334) (xy 439.742692 16.101964) (xy 439.679322 16.044195) (xy 439.610893 15.992519)
			(xy 439.537987 15.947378) (xy 439.461227 15.909156) (xy 439.381268 15.87818) (xy 439.298792 15.854713)
			(xy 439.214502 15.838957) (xy 439.129119 15.831045) (xy 439.043369 15.831045) (xy 438.957986 15.838957)
			(xy 438.873696 15.854713) (xy 438.79122 15.87818) (xy 438.711261 15.909156) (xy 438.634501 15.947378)
			(xy 438.561595 15.992519) (xy 438.493166 16.044195) (xy 438.429796 16.101964) (xy 438.372027 16.165334)
			(xy 438.320351 16.233763) (xy 438.27521 16.306669) (xy 438.236988 16.383429) (xy 438.206012 16.463388)
			(xy 438.182545 16.545864) (xy 438.166789 16.630154) (xy 438.158877 16.715537) (xy 407.302832 16.715537)
			(xy 407.295579 16.637266) (xy 407.279823 16.552976) (xy 407.256356 16.4705) (xy 407.22538 16.390541)
			(xy 407.187158 16.313781) (xy 407.142017 16.240875) (xy 407.090341 16.172446) (xy 407.032572 16.109076)
			(xy 406.969202 16.051307) (xy 406.900773 15.999631) (xy 406.827867 15.95449) (xy 406.751107 15.916268)
			(xy 406.671148 15.885292) (xy 406.588672 15.861825) (xy 406.504382 15.846069) (xy 406.418999 15.838157)
			(xy 406.333249 15.838157) (xy 406.247866 15.846069) (xy 406.163576 15.861825) (xy 406.0811 15.885292)
			(xy 406.001141 15.916268) (xy 405.924381 15.95449) (xy 405.851475 15.999631) (xy 405.783046 16.051307)
			(xy 405.719676 16.109076) (xy 405.661907 16.172446) (xy 405.610231 16.240875) (xy 405.56509 16.313781)
			(xy 405.526868 16.390541) (xy 405.495892 16.4705) (xy 405.472425 16.552976) (xy 405.456669 16.637266)
			(xy 405.448757 16.722649) (xy 400.953491 16.722649) (xy 400.945579 16.637266) (xy 400.929823 16.552976)
			(xy 400.906356 16.4705) (xy 400.87538 16.390541) (xy 400.837158 16.313781) (xy 400.792017 16.240875)
			(xy 400.740341 16.172446) (xy 400.682572 16.109076) (xy 400.619202 16.051307) (xy 400.550773 15.999631)
			(xy 400.477867 15.95449) (xy 400.401107 15.916268) (xy 400.321148 15.885292) (xy 400.238672 15.861825)
			(xy 400.154382 15.846069) (xy 400.068999 15.838157) (xy 399.983249 15.838157) (xy 399.897866 15.846069)
			(xy 399.813576 15.861825) (xy 399.7311 15.885292) (xy 399.651141 15.916268) (xy 399.574381 15.95449)
			(xy 399.501475 15.999631) (xy 399.433046 16.051307) (xy 399.369676 16.109076) (xy 399.311907 16.172446)
			(xy 399.260231 16.240875) (xy 399.21509 16.313781) (xy 399.176868 16.390541) (xy 399.145892 16.4705)
			(xy 399.122425 16.552976) (xy 399.106669 16.637266) (xy 399.098757 16.722649) (xy 381.720693 16.722649)
			(xy 381.720611 16.715537) (xy 381.712699 16.630154) (xy 381.696943 16.545864) (xy 381.673476 16.463388)
			(xy 381.6425 16.383429) (xy 381.604278 16.306669) (xy 381.559137 16.233763) (xy 381.507461 16.165334)
			(xy 381.449692 16.101964) (xy 381.386322 16.044195) (xy 381.317893 15.992519) (xy 381.244987 15.947378)
			(xy 381.168227 15.909156) (xy 381.088268 15.87818) (xy 381.005792 15.854713) (xy 380.921502 15.838957)
			(xy 380.836119 15.831045) (xy 380.750369 15.831045) (xy 380.664986 15.838957) (xy 380.580696 15.854713)
			(xy 380.49822 15.87818) (xy 380.418261 15.909156) (xy 380.341501 15.947378) (xy 380.268595 15.992519)
			(xy 380.200166 16.044195) (xy 380.136796 16.101964) (xy 380.079027 16.165334) (xy 380.027351 16.233763)
			(xy 379.98221 16.306669) (xy 379.943988 16.383429) (xy 379.913012 16.463388) (xy 379.889545 16.545864)
			(xy 379.873789 16.630154) (xy 379.865877 16.715537) (xy 375.370611 16.715537) (xy 375.362699 16.630154)
			(xy 375.346943 16.545864) (xy 375.323476 16.463388) (xy 375.2925 16.383429) (xy 375.254278 16.306669)
			(xy 375.209137 16.233763) (xy 375.157461 16.165334) (xy 375.099692 16.101964) (xy 375.036322 16.044195)
			(xy 374.967893 15.992519) (xy 374.894987 15.947378) (xy 374.818227 15.909156) (xy 374.738268 15.87818)
			(xy 374.655792 15.854713) (xy 374.571502 15.838957) (xy 374.486119 15.831045) (xy 374.400369 15.831045)
			(xy 374.314986 15.838957) (xy 374.230696 15.854713) (xy 374.14822 15.87818) (xy 374.068261 15.909156)
			(xy 373.991501 15.947378) (xy 373.918595 15.992519) (xy 373.850166 16.044195) (xy 373.786796 16.101964)
			(xy 373.729027 16.165334) (xy 373.677351 16.233763) (xy 373.63221 16.306669) (xy 373.593988 16.383429)
			(xy 373.563012 16.463388) (xy 373.539545 16.545864) (xy 373.523789 16.630154) (xy 373.515877 16.715537)
			(xy 342.659832 16.715537) (xy 342.652579 16.637266) (xy 342.636823 16.552976) (xy 342.613356 16.4705)
			(xy 342.58238 16.390541) (xy 342.544158 16.313781) (xy 342.499017 16.240875) (xy 342.447341 16.172446)
			(xy 342.389572 16.109076) (xy 342.326202 16.051307) (xy 342.257773 15.999631) (xy 342.184867 15.95449)
			(xy 342.108107 15.916268) (xy 342.028148 15.885292) (xy 341.945672 15.861825) (xy 341.861382 15.846069)
			(xy 341.775999 15.838157) (xy 341.690249 15.838157) (xy 341.604866 15.846069) (xy 341.520576 15.861825)
			(xy 341.4381 15.885292) (xy 341.358141 15.916268) (xy 341.281381 15.95449) (xy 341.208475 15.999631)
			(xy 341.140046 16.051307) (xy 341.076676 16.109076) (xy 341.018907 16.172446) (xy 340.967231 16.240875)
			(xy 340.92209 16.313781) (xy 340.883868 16.390541) (xy 340.852892 16.4705) (xy 340.829425 16.552976)
			(xy 340.813669 16.637266) (xy 340.805757 16.722649) (xy 336.310491 16.722649) (xy 336.302579 16.637266)
			(xy 336.286823 16.552976) (xy 336.263356 16.4705) (xy 336.23238 16.390541) (xy 336.194158 16.313781)
			(xy 336.149017 16.240875) (xy 336.097341 16.172446) (xy 336.039572 16.109076) (xy 335.976202 16.051307)
			(xy 335.907773 15.999631) (xy 335.834867 15.95449) (xy 335.758107 15.916268) (xy 335.678148 15.885292)
			(xy 335.595672 15.861825) (xy 335.511382 15.846069) (xy 335.425999 15.838157) (xy 335.340249 15.838157)
			(xy 335.254866 15.846069) (xy 335.170576 15.861825) (xy 335.0881 15.885292) (xy 335.008141 15.916268)
			(xy 334.931381 15.95449) (xy 334.858475 15.999631) (xy 334.790046 16.051307) (xy 334.726676 16.109076)
			(xy 334.668907 16.172446) (xy 334.617231 16.240875) (xy 334.57209 16.313781) (xy 334.533868 16.390541)
			(xy 334.502892 16.4705) (xy 334.479425 16.552976) (xy 334.463669 16.637266) (xy 334.455757 16.722649)
			(xy 316.569693 16.722649) (xy 316.569611 16.715537) (xy 316.561699 16.630154) (xy 316.545943 16.545864)
			(xy 316.522476 16.463388) (xy 316.4915 16.383429) (xy 316.453278 16.306669) (xy 316.408137 16.233763)
			(xy 316.356461 16.165334) (xy 316.298692 16.101964) (xy 316.235322 16.044195) (xy 316.166893 15.992519)
			(xy 316.093987 15.947378) (xy 316.017227 15.909156) (xy 315.937268 15.87818) (xy 315.854792 15.854713)
			(xy 315.770502 15.838957) (xy 315.685119 15.831045) (xy 315.599369 15.831045) (xy 315.513986 15.838957)
			(xy 315.429696 15.854713) (xy 315.34722 15.87818) (xy 315.267261 15.909156) (xy 315.190501 15.947378)
			(xy 315.117595 15.992519) (xy 315.049166 16.044195) (xy 314.985796 16.101964) (xy 314.928027 16.165334)
			(xy 314.876351 16.233763) (xy 314.83121 16.306669) (xy 314.792988 16.383429) (xy 314.762012 16.463388)
			(xy 314.738545 16.545864) (xy 314.722789 16.630154) (xy 314.714877 16.715537) (xy 310.219611 16.715537)
			(xy 310.211699 16.630154) (xy 310.195943 16.545864) (xy 310.172476 16.463388) (xy 310.1415 16.383429)
			(xy 310.103278 16.306669) (xy 310.058137 16.233763) (xy 310.006461 16.165334) (xy 309.948692 16.101964)
			(xy 309.885322 16.044195) (xy 309.816893 15.992519) (xy 309.743987 15.947378) (xy 309.667227 15.909156)
			(xy 309.587268 15.87818) (xy 309.504792 15.854713) (xy 309.420502 15.838957) (xy 309.335119 15.831045)
			(xy 309.249369 15.831045) (xy 309.163986 15.838957) (xy 309.079696 15.854713) (xy 308.99722 15.87818)
			(xy 308.917261 15.909156) (xy 308.840501 15.947378) (xy 308.767595 15.992519) (xy 308.699166 16.044195)
			(xy 308.635796 16.101964) (xy 308.578027 16.165334) (xy 308.526351 16.233763) (xy 308.48121 16.306669)
			(xy 308.442988 16.383429) (xy 308.412012 16.463388) (xy 308.388545 16.545864) (xy 308.372789 16.630154)
			(xy 308.364877 16.715537) (xy 277.508832 16.715537) (xy 277.501579 16.637266) (xy 277.485823 16.552976)
			(xy 277.462356 16.4705) (xy 277.43138 16.390541) (xy 277.393158 16.313781) (xy 277.348017 16.240875)
			(xy 277.296341 16.172446) (xy 277.238572 16.109076) (xy 277.175202 16.051307) (xy 277.106773 15.999631)
			(xy 277.033867 15.95449) (xy 276.957107 15.916268) (xy 276.877148 15.885292) (xy 276.794672 15.861825)
			(xy 276.710382 15.846069) (xy 276.624999 15.838157) (xy 276.539249 15.838157) (xy 276.453866 15.846069)
			(xy 276.369576 15.861825) (xy 276.2871 15.885292) (xy 276.207141 15.916268) (xy 276.130381 15.95449)
			(xy 276.057475 15.999631) (xy 275.989046 16.051307) (xy 275.925676 16.109076) (xy 275.867907 16.172446)
			(xy 275.816231 16.240875) (xy 275.77109 16.313781) (xy 275.732868 16.390541) (xy 275.701892 16.4705)
			(xy 275.678425 16.552976) (xy 275.662669 16.637266) (xy 275.654757 16.722649) (xy 271.159491 16.722649)
			(xy 271.151579 16.637266) (xy 271.135823 16.552976) (xy 271.112356 16.4705) (xy 271.08138 16.390541)
			(xy 271.043158 16.313781) (xy 270.998017 16.240875) (xy 270.946341 16.172446) (xy 270.888572 16.109076)
			(xy 270.825202 16.051307) (xy 270.756773 15.999631) (xy 270.683867 15.95449) (xy 270.607107 15.916268)
			(xy 270.527148 15.885292) (xy 270.444672 15.861825) (xy 270.360382 15.846069) (xy 270.274999 15.838157)
			(xy 270.189249 15.838157) (xy 270.103866 15.846069) (xy 270.019576 15.861825) (xy 269.9371 15.885292)
			(xy 269.857141 15.916268) (xy 269.780381 15.95449) (xy 269.707475 15.999631) (xy 269.639046 16.051307)
			(xy 269.575676 16.109076) (xy 269.517907 16.172446) (xy 269.466231 16.240875) (xy 269.42109 16.313781)
			(xy 269.382868 16.390541) (xy 269.351892 16.4705) (xy 269.328425 16.552976) (xy 269.312669 16.637266)
			(xy 269.304757 16.722649) (xy 252.231493 16.722649) (xy 252.231411 16.715537) (xy 252.223499 16.630154)
			(xy 252.207743 16.545864) (xy 252.184276 16.463388) (xy 252.1533 16.383429) (xy 252.115078 16.306669)
			(xy 252.069937 16.233763) (xy 252.018261 16.165334) (xy 251.960492 16.101964) (xy 251.897122 16.044195)
			(xy 251.828693 15.992519) (xy 251.755787 15.947378) (xy 251.679027 15.909156) (xy 251.599068 15.87818)
			(xy 251.516592 15.854713) (xy 251.432302 15.838957) (xy 251.346919 15.831045) (xy 251.261169 15.831045)
			(xy 251.175786 15.838957) (xy 251.091496 15.854713) (xy 251.00902 15.87818) (xy 250.929061 15.909156)
			(xy 250.852301 15.947378) (xy 250.779395 15.992519) (xy 250.710966 16.044195) (xy 250.647596 16.101964)
			(xy 250.589827 16.165334) (xy 250.538151 16.233763) (xy 250.49301 16.306669) (xy 250.454788 16.383429)
			(xy 250.423812 16.463388) (xy 250.400345 16.545864) (xy 250.384589 16.630154) (xy 250.376677 16.715537)
			(xy 245.881411 16.715537) (xy 245.873499 16.630154) (xy 245.857743 16.545864) (xy 245.834276 16.463388)
			(xy 245.8033 16.383429) (xy 245.765078 16.306669) (xy 245.719937 16.233763) (xy 245.668261 16.165334)
			(xy 245.610492 16.101964) (xy 245.547122 16.044195) (xy 245.478693 15.992519) (xy 245.405787 15.947378)
			(xy 245.329027 15.909156) (xy 245.249068 15.87818) (xy 245.166592 15.854713) (xy 245.082302 15.838957)
			(xy 244.996919 15.831045) (xy 244.911169 15.831045) (xy 244.825786 15.838957) (xy 244.741496 15.854713)
			(xy 244.65902 15.87818) (xy 244.579061 15.909156) (xy 244.502301 15.947378) (xy 244.429395 15.992519)
			(xy 244.360966 16.044195) (xy 244.297596 16.101964) (xy 244.239827 16.165334) (xy 244.188151 16.233763)
			(xy 244.14301 16.306669) (xy 244.104788 16.383429) (xy 244.073812 16.463388) (xy 244.050345 16.545864)
			(xy 244.034589 16.630154) (xy 244.026677 16.715537) (xy 218.199832 16.715537) (xy 218.192579 16.637266)
			(xy 218.176823 16.552976) (xy 218.153356 16.4705) (xy 218.12238 16.390541) (xy 218.084158 16.313781)
			(xy 218.039017 16.240875) (xy 217.987341 16.172446) (xy 217.929572 16.109076) (xy 217.866202 16.051307)
			(xy 217.797773 15.999631) (xy 217.724867 15.95449) (xy 217.648107 15.916268) (xy 217.568148 15.885292)
			(xy 217.485672 15.861825) (xy 217.401382 15.846069) (xy 217.315999 15.838157) (xy 217.230249 15.838157)
			(xy 217.144866 15.846069) (xy 217.060576 15.861825) (xy 216.9781 15.885292) (xy 216.898141 15.916268)
			(xy 216.821381 15.95449) (xy 216.748475 15.999631) (xy 216.680046 16.051307) (xy 216.616676 16.109076)
			(xy 216.558907 16.172446) (xy 216.507231 16.240875) (xy 216.46209 16.313781) (xy 216.423868 16.390541)
			(xy 216.392892 16.4705) (xy 216.369425 16.552976) (xy 216.353669 16.637266) (xy 216.345757 16.722649)
			(xy 211.850491 16.722649) (xy 211.842579 16.637266) (xy 211.826823 16.552976) (xy 211.803356 16.4705)
			(xy 211.77238 16.390541) (xy 211.734158 16.313781) (xy 211.689017 16.240875) (xy 211.637341 16.172446)
			(xy 211.579572 16.109076) (xy 211.516202 16.051307) (xy 211.447773 15.999631) (xy 211.374867 15.95449)
			(xy 211.298107 15.916268) (xy 211.218148 15.885292) (xy 211.135672 15.861825) (xy 211.051382 15.846069)
			(xy 210.965999 15.838157) (xy 210.880249 15.838157) (xy 210.794866 15.846069) (xy 210.710576 15.861825)
			(xy 210.6281 15.885292) (xy 210.548141 15.916268) (xy 210.471381 15.95449) (xy 210.398475 15.999631)
			(xy 210.330046 16.051307) (xy 210.266676 16.109076) (xy 210.208907 16.172446) (xy 210.157231 16.240875)
			(xy 210.11209 16.313781) (xy 210.073868 16.390541) (xy 210.042892 16.4705) (xy 210.019425 16.552976)
			(xy 210.003669 16.637266) (xy 209.995757 16.722649) (xy 158.621984 16.722649) (xy 158.621984 11.850929)
			(xy 251.524757 11.850929) (xy 251.524757 11.936679) (xy 251.532669 12.022062) (xy 251.548425 12.106352)
			(xy 251.571892 12.188828) (xy 251.602868 12.268787) (xy 251.64109 12.345547) (xy 251.686231 12.418453)
			(xy 251.737907 12.486882) (xy 251.795676 12.550252) (xy 251.859046 12.608021) (xy 251.927475 12.659697)
			(xy 252.000381 12.704838) (xy 252.077141 12.74306) (xy 252.1571 12.774036) (xy 252.239576 12.797503)
			(xy 252.323866 12.813259) (xy 252.409249 12.821171) (xy 252.494999 12.821171) (xy 252.580382 12.813259)
			(xy 252.664672 12.797503) (xy 252.747148 12.774036) (xy 252.827107 12.74306) (xy 252.903867 12.704838)
			(xy 252.976773 12.659697) (xy 253.045202 12.608021) (xy 253.108572 12.550252) (xy 253.166341 12.486882)
			(xy 253.218017 12.418453) (xy 253.263158 12.345547) (xy 253.30138 12.268787) (xy 253.332356 12.188828)
			(xy 253.355823 12.106352) (xy 253.371579 12.022062) (xy 253.379491 11.936679) (xy 253.379986 11.893804)
			(xy 253.379491 11.850929) (xy 257.874757 11.850929) (xy 257.874757 11.936679) (xy 257.882669 12.022062)
			(xy 257.898425 12.106352) (xy 257.921892 12.188828) (xy 257.952868 12.268787) (xy 257.99109 12.345547)
			(xy 258.036231 12.418453) (xy 258.087907 12.486882) (xy 258.145676 12.550252) (xy 258.209046 12.608021)
			(xy 258.277475 12.659697) (xy 258.350381 12.704838) (xy 258.427141 12.74306) (xy 258.5071 12.774036)
			(xy 258.589576 12.797503) (xy 258.673866 12.813259) (xy 258.759249 12.821171) (xy 258.844999 12.821171)
			(xy 258.930382 12.813259) (xy 259.014672 12.797503) (xy 259.097148 12.774036) (xy 259.177107 12.74306)
			(xy 259.253867 12.704838) (xy 259.326773 12.659697) (xy 259.395202 12.608021) (xy 259.458572 12.550252)
			(xy 259.516341 12.486882) (xy 259.568017 12.418453) (xy 259.613158 12.345547) (xy 259.65138 12.268787)
			(xy 259.682356 12.188828) (xy 259.705823 12.106352) (xy 259.721579 12.022062) (xy 259.729491 11.936679)
			(xy 259.729986 11.893804) (xy 259.72979 11.876837) (xy 309.725301 11.876837) (xy 309.725301 11.962587)
			(xy 309.733213 12.04797) (xy 309.748969 12.13226) (xy 309.772436 12.214736) (xy 309.803412 12.294695)
			(xy 309.841634 12.371455) (xy 309.886775 12.444361) (xy 309.938451 12.51279) (xy 309.99622 12.57616)
			(xy 310.05959 12.633929) (xy 310.128019 12.685605) (xy 310.200925 12.730746) (xy 310.277685 12.768968)
			(xy 310.357644 12.799944) (xy 310.44012 12.823411) (xy 310.52441 12.839167) (xy 310.609793 12.847079)
			(xy 310.695543 12.847079) (xy 310.780926 12.839167) (xy 310.865216 12.823411) (xy 310.947692 12.799944)
			(xy 311.027651 12.768968) (xy 311.104411 12.730746) (xy 311.177317 12.685605) (xy 311.245746 12.633929)
			(xy 311.309116 12.57616) (xy 311.366885 12.51279) (xy 311.418561 12.444361) (xy 311.463702 12.371455)
			(xy 311.501924 12.294695) (xy 311.5329 12.214736) (xy 311.556367 12.13226) (xy 311.572123 12.04797)
			(xy 311.580035 11.962587) (xy 311.58053 11.919712) (xy 311.580035 11.876837) (xy 316.075301 11.876837)
			(xy 316.075301 11.962587) (xy 316.083213 12.04797) (xy 316.098969 12.13226) (xy 316.122436 12.214736)
			(xy 316.153412 12.294695) (xy 316.191634 12.371455) (xy 316.236775 12.444361) (xy 316.288451 12.51279)
			(xy 316.34622 12.57616) (xy 316.40959 12.633929) (xy 316.478019 12.685605) (xy 316.550925 12.730746)
			(xy 316.627685 12.768968) (xy 316.707644 12.799944) (xy 316.79012 12.823411) (xy 316.87441 12.839167)
			(xy 316.959793 12.847079) (xy 317.045543 12.847079) (xy 317.130926 12.839167) (xy 317.215216 12.823411)
			(xy 317.297692 12.799944) (xy 317.377651 12.768968) (xy 317.454411 12.730746) (xy 317.527317 12.685605)
			(xy 317.595746 12.633929) (xy 317.659116 12.57616) (xy 317.716885 12.51279) (xy 317.768561 12.444361)
			(xy 317.813702 12.371455) (xy 317.851924 12.294695) (xy 317.8829 12.214736) (xy 317.906367 12.13226)
			(xy 317.922123 12.04797) (xy 317.930035 11.962587) (xy 317.93053 11.919712) (xy 317.930117 11.883949)
			(xy 324.295757 11.883949) (xy 324.295757 11.969699) (xy 324.303669 12.055082) (xy 324.319425 12.139372)
			(xy 324.342892 12.221848) (xy 324.373868 12.301807) (xy 324.41209 12.378567) (xy 324.457231 12.451473)
			(xy 324.508907 12.519902) (xy 324.566676 12.583272) (xy 324.630046 12.641041) (xy 324.698475 12.692717)
			(xy 324.771381 12.737858) (xy 324.848141 12.77608) (xy 324.9281 12.807056) (xy 325.010576 12.830523)
			(xy 325.094866 12.846279) (xy 325.180249 12.854191) (xy 325.265999 12.854191) (xy 325.351382 12.846279)
			(xy 325.435672 12.830523) (xy 325.518148 12.807056) (xy 325.598107 12.77608) (xy 325.674867 12.737858)
			(xy 325.747773 12.692717) (xy 325.816202 12.641041) (xy 325.879572 12.583272) (xy 325.937341 12.519902)
			(xy 325.989017 12.451473) (xy 326.034158 12.378567) (xy 326.07238 12.301807) (xy 326.103356 12.221848)
			(xy 326.126823 12.139372) (xy 326.142579 12.055082) (xy 326.150491 11.969699) (xy 326.150986 11.926824)
			(xy 326.150491 11.883949) (xy 330.645757 11.883949) (xy 330.645757 11.969699) (xy 330.653669 12.055082)
			(xy 330.669425 12.139372) (xy 330.692892 12.221848) (xy 330.723868 12.301807) (xy 330.76209 12.378567)
			(xy 330.807231 12.451473) (xy 330.858907 12.519902) (xy 330.916676 12.583272) (xy 330.980046 12.641041)
			(xy 331.048475 12.692717) (xy 331.121381 12.737858) (xy 331.198141 12.77608) (xy 331.2781 12.807056)
			(xy 331.360576 12.830523) (xy 331.444866 12.846279) (xy 331.530249 12.854191) (xy 331.615999 12.854191)
			(xy 331.701382 12.846279) (xy 331.785672 12.830523) (xy 331.868148 12.807056) (xy 331.948107 12.77608)
			(xy 332.024867 12.737858) (xy 332.097773 12.692717) (xy 332.166202 12.641041) (xy 332.229572 12.583272)
			(xy 332.287341 12.519902) (xy 332.339017 12.451473) (xy 332.384158 12.378567) (xy 332.42238 12.301807)
			(xy 332.453356 12.221848) (xy 332.476823 12.139372) (xy 332.492579 12.055082) (xy 332.500491 11.969699)
			(xy 332.500986 11.926824) (xy 332.50079 11.909857) (xy 382.496301 11.909857) (xy 382.496301 11.995607)
			(xy 382.504213 12.08099) (xy 382.519969 12.16528) (xy 382.543436 12.247756) (xy 382.574412 12.327715)
			(xy 382.612634 12.404475) (xy 382.657775 12.477381) (xy 382.709451 12.54581) (xy 382.76722 12.60918)
			(xy 382.83059 12.666949) (xy 382.899019 12.718625) (xy 382.971925 12.763766) (xy 383.048685 12.801988)
			(xy 383.128644 12.832964) (xy 383.21112 12.856431) (xy 383.29541 12.872187) (xy 383.380793 12.880099)
			(xy 383.466543 12.880099) (xy 383.551926 12.872187) (xy 383.636216 12.856431) (xy 383.718692 12.832964)
			(xy 383.798651 12.801988) (xy 383.875411 12.763766) (xy 383.948317 12.718625) (xy 384.016746 12.666949)
			(xy 384.080116 12.60918) (xy 384.137885 12.54581) (xy 384.189561 12.477381) (xy 384.234702 12.404475)
			(xy 384.272924 12.327715) (xy 384.3039 12.247756) (xy 384.327367 12.16528) (xy 384.343123 12.08099)
			(xy 384.351035 11.995607) (xy 384.35153 11.952732) (xy 384.351035 11.909857) (xy 388.846301 11.909857)
			(xy 388.846301 11.995607) (xy 388.854213 12.08099) (xy 388.869969 12.16528) (xy 388.893436 12.247756)
			(xy 388.924412 12.327715) (xy 388.962634 12.404475) (xy 389.007775 12.477381) (xy 389.059451 12.54581)
			(xy 389.11722 12.60918) (xy 389.18059 12.666949) (xy 389.249019 12.718625) (xy 389.321925 12.763766)
			(xy 389.398685 12.801988) (xy 389.478644 12.832964) (xy 389.56112 12.856431) (xy 389.64541 12.872187)
			(xy 389.730793 12.880099) (xy 389.816543 12.880099) (xy 389.901926 12.872187) (xy 389.986216 12.856431)
			(xy 390.068692 12.832964) (xy 390.148651 12.801988) (xy 390.225411 12.763766) (xy 390.298317 12.718625)
			(xy 390.366746 12.666949) (xy 390.430116 12.60918) (xy 390.487885 12.54581) (xy 390.539561 12.477381)
			(xy 390.584702 12.404475) (xy 390.622924 12.327715) (xy 390.6539 12.247756) (xy 390.677367 12.16528)
			(xy 390.693123 12.08099) (xy 390.701035 11.995607) (xy 390.70153 11.952732) (xy 390.701117 11.916969)
			(xy 396.558757 11.916969) (xy 396.558757 12.002719) (xy 396.566669 12.088102) (xy 396.582425 12.172392)
			(xy 396.605892 12.254868) (xy 396.636868 12.334827) (xy 396.67509 12.411587) (xy 396.720231 12.484493)
			(xy 396.771907 12.552922) (xy 396.829676 12.616292) (xy 396.893046 12.674061) (xy 396.961475 12.725737)
			(xy 397.034381 12.770878) (xy 397.111141 12.8091) (xy 397.1911 12.840076) (xy 397.273576 12.863543)
			(xy 397.357866 12.879299) (xy 397.443249 12.887211) (xy 397.528999 12.887211) (xy 397.614382 12.879299)
			(xy 397.698672 12.863543) (xy 397.781148 12.840076) (xy 397.861107 12.8091) (xy 397.937867 12.770878)
			(xy 398.010773 12.725737) (xy 398.079202 12.674061) (xy 398.142572 12.616292) (xy 398.200341 12.552922)
			(xy 398.252017 12.484493) (xy 398.297158 12.411587) (xy 398.33538 12.334827) (xy 398.366356 12.254868)
			(xy 398.389823 12.172392) (xy 398.405579 12.088102) (xy 398.413491 12.002719) (xy 398.413986 11.959844)
			(xy 398.413491 11.916969) (xy 402.908757 11.916969) (xy 402.908757 12.002719) (xy 402.916669 12.088102)
			(xy 402.932425 12.172392) (xy 402.955892 12.254868) (xy 402.986868 12.334827) (xy 403.02509 12.411587)
			(xy 403.070231 12.484493) (xy 403.121907 12.552922) (xy 403.179676 12.616292) (xy 403.243046 12.674061)
			(xy 403.311475 12.725737) (xy 403.384381 12.770878) (xy 403.461141 12.8091) (xy 403.5411 12.840076)
			(xy 403.623576 12.863543) (xy 403.707866 12.879299) (xy 403.793249 12.887211) (xy 403.878999 12.887211)
			(xy 403.964382 12.879299) (xy 404.048672 12.863543) (xy 404.131148 12.840076) (xy 404.211107 12.8091)
			(xy 404.287867 12.770878) (xy 404.360773 12.725737) (xy 404.429202 12.674061) (xy 404.492572 12.616292)
			(xy 404.550341 12.552922) (xy 404.602017 12.484493) (xy 404.647158 12.411587) (xy 404.68538 12.334827)
			(xy 404.716356 12.254868) (xy 404.739823 12.172392) (xy 404.755579 12.088102) (xy 404.763491 12.002719)
			(xy 404.763986 11.959844) (xy 404.76379 11.942877) (xy 454.759301 11.942877) (xy 454.759301 12.028627)
			(xy 454.767213 12.11401) (xy 454.782969 12.1983) (xy 454.806436 12.280776) (xy 454.837412 12.360735)
			(xy 454.875634 12.437495) (xy 454.920775 12.510401) (xy 454.972451 12.57883) (xy 455.03022 12.6422)
			(xy 455.09359 12.699969) (xy 455.162019 12.751645) (xy 455.234925 12.796786) (xy 455.311685 12.835008)
			(xy 455.391644 12.865984) (xy 455.47412 12.889451) (xy 455.55841 12.905207) (xy 455.643793 12.913119)
			(xy 455.729543 12.913119) (xy 455.814926 12.905207) (xy 455.899216 12.889451) (xy 455.981692 12.865984)
			(xy 456.061651 12.835008) (xy 456.138411 12.796786) (xy 456.211317 12.751645) (xy 456.279746 12.699969)
			(xy 456.343116 12.6422) (xy 456.400885 12.57883) (xy 456.452561 12.510401) (xy 456.497702 12.437495)
			(xy 456.535924 12.360735) (xy 456.5669 12.280776) (xy 456.590367 12.1983) (xy 456.606123 12.11401)
			(xy 456.614035 12.028627) (xy 456.61453 11.985752) (xy 456.614035 11.942877) (xy 461.109301 11.942877)
			(xy 461.109301 12.028627) (xy 461.117213 12.11401) (xy 461.132969 12.1983) (xy 461.156436 12.280776)
			(xy 461.187412 12.360735) (xy 461.225634 12.437495) (xy 461.270775 12.510401) (xy 461.322451 12.57883)
			(xy 461.38022 12.6422) (xy 461.44359 12.699969) (xy 461.512019 12.751645) (xy 461.584925 12.796786)
			(xy 461.661685 12.835008) (xy 461.741644 12.865984) (xy 461.82412 12.889451) (xy 461.90841 12.905207)
			(xy 461.993793 12.913119) (xy 462.079543 12.913119) (xy 462.164926 12.905207) (xy 462.249216 12.889451)
			(xy 462.331692 12.865984) (xy 462.411651 12.835008) (xy 462.488411 12.796786) (xy 462.561317 12.751645)
			(xy 462.629746 12.699969) (xy 462.693116 12.6422) (xy 462.750885 12.57883) (xy 462.802561 12.510401)
			(xy 462.847702 12.437495) (xy 462.885924 12.360735) (xy 462.9169 12.280776) (xy 462.940367 12.1983)
			(xy 462.956123 12.11401) (xy 462.964035 12.028627) (xy 462.96453 11.985752) (xy 462.964035 11.942877)
			(xy 462.956123 11.857494) (xy 462.940367 11.773204) (xy 462.9169 11.690728) (xy 462.885924 11.610769)
			(xy 462.847702 11.534009) (xy 462.802561 11.461103) (xy 462.750885 11.392674) (xy 462.693116 11.329304)
			(xy 462.629746 11.271535) (xy 462.561317 11.219859) (xy 462.488411 11.174718) (xy 462.411651 11.136496)
			(xy 462.331692 11.10552) (xy 462.249216 11.082053) (xy 462.164926 11.066297) (xy 462.079543 11.058385)
			(xy 461.993793 11.058385) (xy 461.90841 11.066297) (xy 461.82412 11.082053) (xy 461.741644 11.10552)
			(xy 461.661685 11.136496) (xy 461.584925 11.174718) (xy 461.512019 11.219859) (xy 461.44359 11.271535)
			(xy 461.38022 11.329304) (xy 461.322451 11.392674) (xy 461.270775 11.461103) (xy 461.225634 11.534009)
			(xy 461.187412 11.610769) (xy 461.156436 11.690728) (xy 461.132969 11.773204) (xy 461.117213 11.857494)
			(xy 461.109301 11.942877) (xy 456.614035 11.942877) (xy 456.606123 11.857494) (xy 456.590367 11.773204)
			(xy 456.5669 11.690728) (xy 456.535924 11.610769) (xy 456.497702 11.534009) (xy 456.452561 11.461103)
			(xy 456.400885 11.392674) (xy 456.343116 11.329304) (xy 456.279746 11.271535) (xy 456.211317 11.219859)
			(xy 456.138411 11.174718) (xy 456.061651 11.136496) (xy 455.981692 11.10552) (xy 455.899216 11.082053)
			(xy 455.814926 11.066297) (xy 455.729543 11.058385) (xy 455.643793 11.058385) (xy 455.55841 11.066297)
			(xy 455.47412 11.082053) (xy 455.391644 11.10552) (xy 455.311685 11.136496) (xy 455.234925 11.174718)
			(xy 455.162019 11.219859) (xy 455.09359 11.271535) (xy 455.03022 11.329304) (xy 454.972451 11.392674)
			(xy 454.920775 11.461103) (xy 454.875634 11.534009) (xy 454.837412 11.610769) (xy 454.806436 11.690728)
			(xy 454.782969 11.773204) (xy 454.767213 11.857494) (xy 454.759301 11.942877) (xy 404.76379 11.942877)
			(xy 404.763491 11.916969) (xy 404.755579 11.831586) (xy 404.739823 11.747296) (xy 404.716356 11.66482)
			(xy 404.68538 11.584861) (xy 404.647158 11.508101) (xy 404.602017 11.435195) (xy 404.550341 11.366766)
			(xy 404.492572 11.303396) (xy 404.429202 11.245627) (xy 404.360773 11.193951) (xy 404.287867 11.14881)
			(xy 404.211107 11.110588) (xy 404.131148 11.079612) (xy 404.048672 11.056145) (xy 403.964382 11.040389)
			(xy 403.878999 11.032477) (xy 403.793249 11.032477) (xy 403.707866 11.040389) (xy 403.623576 11.056145)
			(xy 403.5411 11.079612) (xy 403.461141 11.110588) (xy 403.384381 11.14881) (xy 403.311475 11.193951)
			(xy 403.243046 11.245627) (xy 403.179676 11.303396) (xy 403.121907 11.366766) (xy 403.070231 11.435195)
			(xy 403.02509 11.508101) (xy 402.986868 11.584861) (xy 402.955892 11.66482) (xy 402.932425 11.747296)
			(xy 402.916669 11.831586) (xy 402.908757 11.916969) (xy 398.413491 11.916969) (xy 398.405579 11.831586)
			(xy 398.389823 11.747296) (xy 398.366356 11.66482) (xy 398.33538 11.584861) (xy 398.297158 11.508101)
			(xy 398.252017 11.435195) (xy 398.200341 11.366766) (xy 398.142572 11.303396) (xy 398.079202 11.245627)
			(xy 398.010773 11.193951) (xy 397.937867 11.14881) (xy 397.861107 11.110588) (xy 397.781148 11.079612)
			(xy 397.698672 11.056145) (xy 397.614382 11.040389) (xy 397.528999 11.032477) (xy 397.443249 11.032477)
			(xy 397.357866 11.040389) (xy 397.273576 11.056145) (xy 397.1911 11.079612) (xy 397.111141 11.110588)
			(xy 397.034381 11.14881) (xy 396.961475 11.193951) (xy 396.893046 11.245627) (xy 396.829676 11.303396)
			(xy 396.771907 11.366766) (xy 396.720231 11.435195) (xy 396.67509 11.508101) (xy 396.636868 11.584861)
			(xy 396.605892 11.66482) (xy 396.582425 11.747296) (xy 396.566669 11.831586) (xy 396.558757 11.916969)
			(xy 390.701117 11.916969) (xy 390.701035 11.909857) (xy 390.693123 11.824474) (xy 390.677367 11.740184)
			(xy 390.6539 11.657708) (xy 390.622924 11.577749) (xy 390.584702 11.500989) (xy 390.539561 11.428083)
			(xy 390.487885 11.359654) (xy 390.430116 11.296284) (xy 390.366746 11.238515) (xy 390.298317 11.186839)
			(xy 390.225411 11.141698) (xy 390.148651 11.103476) (xy 390.068692 11.0725) (xy 389.986216 11.049033)
			(xy 389.901926 11.033277) (xy 389.816543 11.025365) (xy 389.730793 11.025365) (xy 389.64541 11.033277)
			(xy 389.56112 11.049033) (xy 389.478644 11.0725) (xy 389.398685 11.103476) (xy 389.321925 11.141698)
			(xy 389.249019 11.186839) (xy 389.18059 11.238515) (xy 389.11722 11.296284) (xy 389.059451 11.359654)
			(xy 389.007775 11.428083) (xy 388.962634 11.500989) (xy 388.924412 11.577749) (xy 388.893436 11.657708)
			(xy 388.869969 11.740184) (xy 388.854213 11.824474) (xy 388.846301 11.909857) (xy 384.351035 11.909857)
			(xy 384.343123 11.824474) (xy 384.327367 11.740184) (xy 384.3039 11.657708) (xy 384.272924 11.577749)
			(xy 384.234702 11.500989) (xy 384.189561 11.428083) (xy 384.137885 11.359654) (xy 384.080116 11.296284)
			(xy 384.016746 11.238515) (xy 383.948317 11.186839) (xy 383.875411 11.141698) (xy 383.798651 11.103476)
			(xy 383.718692 11.0725) (xy 383.636216 11.049033) (xy 383.551926 11.033277) (xy 383.466543 11.025365)
			(xy 383.380793 11.025365) (xy 383.29541 11.033277) (xy 383.21112 11.049033) (xy 383.128644 11.0725)
			(xy 383.048685 11.103476) (xy 382.971925 11.141698) (xy 382.899019 11.186839) (xy 382.83059 11.238515)
			(xy 382.76722 11.296284) (xy 382.709451 11.359654) (xy 382.657775 11.428083) (xy 382.612634 11.500989)
			(xy 382.574412 11.577749) (xy 382.543436 11.657708) (xy 382.519969 11.740184) (xy 382.504213 11.824474)
			(xy 382.496301 11.909857) (xy 332.50079 11.909857) (xy 332.500491 11.883949) (xy 332.492579 11.798566)
			(xy 332.476823 11.714276) (xy 332.453356 11.6318) (xy 332.42238 11.551841) (xy 332.384158 11.475081)
			(xy 332.339017 11.402175) (xy 332.287341 11.333746) (xy 332.229572 11.270376) (xy 332.166202 11.212607)
			(xy 332.097773 11.160931) (xy 332.024867 11.11579) (xy 331.948107 11.077568) (xy 331.868148 11.046592)
			(xy 331.785672 11.023125) (xy 331.701382 11.007369) (xy 331.615999 10.999457) (xy 331.530249 10.999457)
			(xy 331.444866 11.007369) (xy 331.360576 11.023125) (xy 331.2781 11.046592) (xy 331.198141 11.077568)
			(xy 331.121381 11.11579) (xy 331.048475 11.160931) (xy 330.980046 11.212607) (xy 330.916676 11.270376)
			(xy 330.858907 11.333746) (xy 330.807231 11.402175) (xy 330.76209 11.475081) (xy 330.723868 11.551841)
			(xy 330.692892 11.6318) (xy 330.669425 11.714276) (xy 330.653669 11.798566) (xy 330.645757 11.883949)
			(xy 326.150491 11.883949) (xy 326.142579 11.798566) (xy 326.126823 11.714276) (xy 326.103356 11.6318)
			(xy 326.07238 11.551841) (xy 326.034158 11.475081) (xy 325.989017 11.402175) (xy 325.937341 11.333746)
			(xy 325.879572 11.270376) (xy 325.816202 11.212607) (xy 325.747773 11.160931) (xy 325.674867 11.11579)
			(xy 325.598107 11.077568) (xy 325.518148 11.046592) (xy 325.435672 11.023125) (xy 325.351382 11.007369)
			(xy 325.265999 10.999457) (xy 325.180249 10.999457) (xy 325.094866 11.007369) (xy 325.010576 11.023125)
			(xy 324.9281 11.046592) (xy 324.848141 11.077568) (xy 324.771381 11.11579) (xy 324.698475 11.160931)
			(xy 324.630046 11.212607) (xy 324.566676 11.270376) (xy 324.508907 11.333746) (xy 324.457231 11.402175)
			(xy 324.41209 11.475081) (xy 324.373868 11.551841) (xy 324.342892 11.6318) (xy 324.319425 11.714276)
			(xy 324.303669 11.798566) (xy 324.295757 11.883949) (xy 317.930117 11.883949) (xy 317.930035 11.876837)
			(xy 317.922123 11.791454) (xy 317.906367 11.707164) (xy 317.8829 11.624688) (xy 317.851924 11.544729)
			(xy 317.813702 11.467969) (xy 317.768561 11.395063) (xy 317.716885 11.326634) (xy 317.659116 11.263264)
			(xy 317.595746 11.205495) (xy 317.527317 11.153819) (xy 317.454411 11.108678) (xy 317.377651 11.070456)
			(xy 317.297692 11.03948) (xy 317.215216 11.016013) (xy 317.130926 11.000257) (xy 317.045543 10.992345)
			(xy 316.959793 10.992345) (xy 316.87441 11.000257) (xy 316.79012 11.016013) (xy 316.707644 11.03948)
			(xy 316.627685 11.070456) (xy 316.550925 11.108678) (xy 316.478019 11.153819) (xy 316.40959 11.205495)
			(xy 316.34622 11.263264) (xy 316.288451 11.326634) (xy 316.236775 11.395063) (xy 316.191634 11.467969)
			(xy 316.153412 11.544729) (xy 316.122436 11.624688) (xy 316.098969 11.707164) (xy 316.083213 11.791454)
			(xy 316.075301 11.876837) (xy 311.580035 11.876837) (xy 311.572123 11.791454) (xy 311.556367 11.707164)
			(xy 311.5329 11.624688) (xy 311.501924 11.544729) (xy 311.463702 11.467969) (xy 311.418561 11.395063)
			(xy 311.366885 11.326634) (xy 311.309116 11.263264) (xy 311.245746 11.205495) (xy 311.177317 11.153819)
			(xy 311.104411 11.108678) (xy 311.027651 11.070456) (xy 310.947692 11.03948) (xy 310.865216 11.016013)
			(xy 310.780926 11.000257) (xy 310.695543 10.992345) (xy 310.609793 10.992345) (xy 310.52441 11.000257)
			(xy 310.44012 11.016013) (xy 310.357644 11.03948) (xy 310.277685 11.070456) (xy 310.200925 11.108678)
			(xy 310.128019 11.153819) (xy 310.05959 11.205495) (xy 309.99622 11.263264) (xy 309.938451 11.326634)
			(xy 309.886775 11.395063) (xy 309.841634 11.467969) (xy 309.803412 11.544729) (xy 309.772436 11.624688)
			(xy 309.748969 11.707164) (xy 309.733213 11.791454) (xy 309.725301 11.876837) (xy 259.72979 11.876837)
			(xy 259.729491 11.850929) (xy 259.721579 11.765546) (xy 259.705823 11.681256) (xy 259.682356 11.59878)
			(xy 259.65138 11.518821) (xy 259.613158 11.442061) (xy 259.568017 11.369155) (xy 259.516341 11.300726)
			(xy 259.458572 11.237356) (xy 259.395202 11.179587) (xy 259.326773 11.127911) (xy 259.253867 11.08277)
			(xy 259.177107 11.044548) (xy 259.097148 11.013572) (xy 259.014672 10.990105) (xy 258.930382 10.974349)
			(xy 258.844999 10.966437) (xy 258.759249 10.966437) (xy 258.673866 10.974349) (xy 258.589576 10.990105)
			(xy 258.5071 11.013572) (xy 258.427141 11.044548) (xy 258.350381 11.08277) (xy 258.277475 11.127911)
			(xy 258.209046 11.179587) (xy 258.145676 11.237356) (xy 258.087907 11.300726) (xy 258.036231 11.369155)
			(xy 257.99109 11.442061) (xy 257.952868 11.518821) (xy 257.921892 11.59878) (xy 257.898425 11.681256)
			(xy 257.882669 11.765546) (xy 257.874757 11.850929) (xy 253.379491 11.850929) (xy 253.371579 11.765546)
			(xy 253.355823 11.681256) (xy 253.332356 11.59878) (xy 253.30138 11.518821) (xy 253.263158 11.442061)
			(xy 253.218017 11.369155) (xy 253.166341 11.300726) (xy 253.108572 11.237356) (xy 253.045202 11.179587)
			(xy 252.976773 11.127911) (xy 252.903867 11.08277) (xy 252.827107 11.044548) (xy 252.747148 11.013572)
			(xy 252.664672 10.990105) (xy 252.580382 10.974349) (xy 252.494999 10.966437) (xy 252.409249 10.966437)
			(xy 252.323866 10.974349) (xy 252.239576 10.990105) (xy 252.1571 11.013572) (xy 252.077141 11.044548)
			(xy 252.000381 11.08277) (xy 251.927475 11.127911) (xy 251.859046 11.179587) (xy 251.795676 11.237356)
			(xy 251.737907 11.300726) (xy 251.686231 11.369155) (xy 251.64109 11.442061) (xy 251.602868 11.518821)
			(xy 251.571892 11.59878) (xy 251.548425 11.681256) (xy 251.532669 11.765546) (xy 251.524757 11.850929)
			(xy 158.621984 11.850929) (xy 158.621984 9.310929) (xy 179.515757 9.310929) (xy 179.515757 9.396679)
			(xy 179.523669 9.482062) (xy 179.539425 9.566352) (xy 179.562892 9.648828) (xy 179.593868 9.728787)
			(xy 179.63209 9.805547) (xy 179.677231 9.878453) (xy 179.728907 9.946882) (xy 179.786676 10.010252)
			(xy 179.850046 10.068021) (xy 179.918475 10.119697) (xy 179.991381 10.164838) (xy 180.068141 10.20306)
			(xy 180.1481 10.234036) (xy 180.230576 10.257503) (xy 180.314866 10.273259) (xy 180.400249 10.281171)
			(xy 180.485999 10.281171) (xy 180.571382 10.273259) (xy 180.655672 10.257503) (xy 180.738148 10.234036)
			(xy 180.818107 10.20306) (xy 180.894867 10.164838) (xy 180.967773 10.119697) (xy 181.036202 10.068021)
			(xy 181.099572 10.010252) (xy 181.157341 9.946882) (xy 181.209017 9.878453) (xy 181.254158 9.805547)
			(xy 181.29238 9.728787) (xy 181.323356 9.648828) (xy 181.346823 9.566352) (xy 181.362579 9.482062)
			(xy 181.370491 9.396679) (xy 181.370986 9.353804) (xy 181.370491 9.310929) (xy 185.865757 9.310929)
			(xy 185.865757 9.396679) (xy 185.873669 9.482062) (xy 185.889425 9.566352) (xy 185.912892 9.648828)
			(xy 185.943868 9.728787) (xy 185.98209 9.805547) (xy 186.027231 9.878453) (xy 186.078907 9.946882)
			(xy 186.136676 10.010252) (xy 186.200046 10.068021) (xy 186.268475 10.119697) (xy 186.341381 10.164838)
			(xy 186.418141 10.20306) (xy 186.4981 10.234036) (xy 186.580576 10.257503) (xy 186.664866 10.273259)
			(xy 186.750249 10.281171) (xy 186.835999 10.281171) (xy 186.921382 10.273259) (xy 187.005672 10.257503)
			(xy 187.088148 10.234036) (xy 187.168107 10.20306) (xy 187.244867 10.164838) (xy 187.317773 10.119697)
			(xy 187.386202 10.068021) (xy 187.449572 10.010252) (xy 187.507341 9.946882) (xy 187.559017 9.878453)
			(xy 187.604158 9.805547) (xy 187.64238 9.728787) (xy 187.673356 9.648828) (xy 187.696823 9.566352)
			(xy 187.712579 9.482062) (xy 187.720491 9.396679) (xy 187.720986 9.353804) (xy 187.720491 9.310929)
			(xy 187.719832 9.303817) (xy 237.716301 9.303817) (xy 237.716301 9.389567) (xy 237.724213 9.47495)
			(xy 237.739969 9.55924) (xy 237.763436 9.641716) (xy 237.794412 9.721675) (xy 237.832634 9.798435)
			(xy 237.877775 9.871341) (xy 237.929451 9.93977) (xy 237.98722 10.00314) (xy 238.05059 10.060909)
			(xy 238.119019 10.112585) (xy 238.191925 10.157726) (xy 238.268685 10.195948) (xy 238.348644 10.226924)
			(xy 238.43112 10.250391) (xy 238.51541 10.266147) (xy 238.600793 10.274059) (xy 238.686543 10.274059)
			(xy 238.771926 10.266147) (xy 238.856216 10.250391) (xy 238.938692 10.226924) (xy 239.018651 10.195948)
			(xy 239.095411 10.157726) (xy 239.168317 10.112585) (xy 239.236746 10.060909) (xy 239.300116 10.00314)
			(xy 239.357885 9.93977) (xy 239.409561 9.871341) (xy 239.454702 9.798435) (xy 239.492924 9.721675)
			(xy 239.5239 9.641716) (xy 239.547367 9.55924) (xy 239.563123 9.47495) (xy 239.571035 9.389567) (xy 239.57153 9.346692)
			(xy 239.571035 9.303817) (xy 244.066301 9.303817) (xy 244.066301 9.389567) (xy 244.074213 9.47495)
			(xy 244.089969 9.55924) (xy 244.113436 9.641716) (xy 244.144412 9.721675) (xy 244.182634 9.798435)
			(xy 244.227775 9.871341) (xy 244.279451 9.93977) (xy 244.33722 10.00314) (xy 244.40059 10.060909)
			(xy 244.469019 10.112585) (xy 244.541925 10.157726) (xy 244.618685 10.195948) (xy 244.698644 10.226924)
			(xy 244.78112 10.250391) (xy 244.86541 10.266147) (xy 244.950793 10.274059) (xy 245.036543 10.274059)
			(xy 245.121926 10.266147) (xy 245.206216 10.250391) (xy 245.288692 10.226924) (xy 245.368651 10.195948)
			(xy 245.445411 10.157726) (xy 245.518317 10.112585) (xy 245.586746 10.060909) (xy 245.650116 10.00314)
			(xy 245.707885 9.93977) (xy 245.759561 9.871341) (xy 245.804702 9.798435) (xy 245.842924 9.721675)
			(xy 245.8739 9.641716) (xy 245.897367 9.55924) (xy 245.913123 9.47495) (xy 245.921035 9.389567) (xy 245.92153 9.346692)
			(xy 245.921117 9.310929) (xy 251.524757 9.310929) (xy 251.524757 9.396679) (xy 251.532669 9.482062)
			(xy 251.548425 9.566352) (xy 251.571892 9.648828) (xy 251.602868 9.728787) (xy 251.64109 9.805547)
			(xy 251.686231 9.878453) (xy 251.737907 9.946882) (xy 251.795676 10.010252) (xy 251.859046 10.068021)
			(xy 251.927475 10.119697) (xy 252.000381 10.164838) (xy 252.077141 10.20306) (xy 252.1571 10.234036)
			(xy 252.239576 10.257503) (xy 252.323866 10.273259) (xy 252.409249 10.281171) (xy 252.494999 10.281171)
			(xy 252.580382 10.273259) (xy 252.664672 10.257503) (xy 252.747148 10.234036) (xy 252.827107 10.20306)
			(xy 252.84931 10.192004) (xy 256.459736 10.192004) (xy 256.459736 11.055604) (xy 256.460222 11.082873)
			(xy 256.467984 11.136857) (xy 256.483349 11.189187) (xy 256.506006 11.238797) (xy 256.535492 11.284678)
			(xy 256.571207 11.325895) (xy 256.612424 11.36161) (xy 256.658305 11.391096) (xy 256.707915 11.413753)
			(xy 256.760245 11.429118) (xy 256.814229 11.43688) (xy 256.868767 11.43688) (xy 256.922751 11.429118)
			(xy 256.975081 11.413753) (xy 257.024691 11.391096) (xy 257.070572 11.36161) (xy 257.111789 11.325895)
			(xy 257.147504 11.284678) (xy 257.17699 11.238797) (xy 257.199647 11.189187) (xy 257.215012 11.136857)
			(xy 257.222774 11.082873) (xy 257.22326 11.055604) (xy 257.22326 10.192004) (xy 257.222774 10.164735)
			(xy 257.215012 10.110751) (xy 257.199647 10.058421) (xy 257.17699 10.008811) (xy 257.147504 9.96293)
			(xy 257.111789 9.921713) (xy 257.070572 9.885998) (xy 257.024691 9.856512) (xy 256.975081 9.833855)
			(xy 256.922751 9.81849) (xy 256.868767 9.810728) (xy 256.814229 9.810728) (xy 256.760245 9.81849)
			(xy 256.707915 9.833855) (xy 256.658305 9.856512) (xy 256.612424 9.885998) (xy 256.571207 9.921713)
			(xy 256.535492 9.96293) (xy 256.506006 10.008811) (xy 256.483349 10.058421) (xy 256.467984 10.110751)
			(xy 256.460222 10.164735) (xy 256.459736 10.192004) (xy 252.84931 10.192004) (xy 252.903867 10.164838)
			(xy 252.976773 10.119697) (xy 253.045202 10.068021) (xy 253.108572 10.010252) (xy 253.166341 9.946882)
			(xy 253.218017 9.878453) (xy 253.263158 9.805547) (xy 253.30138 9.728787) (xy 253.332356 9.648828)
			(xy 253.355823 9.566352) (xy 253.371579 9.482062) (xy 253.379491 9.396679) (xy 253.379986 9.353804)
			(xy 253.379491 9.310929) (xy 257.874757 9.310929) (xy 257.874757 9.396679) (xy 257.882669 9.482062)
			(xy 257.898425 9.566352) (xy 257.921892 9.648828) (xy 257.952868 9.728787) (xy 257.99109 9.805547)
			(xy 258.036231 9.878453) (xy 258.087907 9.946882) (xy 258.145676 10.010252) (xy 258.209046 10.068021)
			(xy 258.277475 10.119697) (xy 258.350381 10.164838) (xy 258.427141 10.20306) (xy 258.5071 10.234036)
			(xy 258.589576 10.257503) (xy 258.673866 10.273259) (xy 258.759249 10.281171) (xy 258.844999 10.281171)
			(xy 258.930382 10.273259) (xy 259.014672 10.257503) (xy 259.097148 10.234036) (xy 259.177107 10.20306)
			(xy 259.253867 10.164838) (xy 259.326773 10.119697) (xy 259.395202 10.068021) (xy 259.458572 10.010252)
			(xy 259.516341 9.946882) (xy 259.568017 9.878453) (xy 259.613158 9.805547) (xy 259.65138 9.728787)
			(xy 259.682356 9.648828) (xy 259.705823 9.566352) (xy 259.721579 9.482062) (xy 259.729491 9.396679)
			(xy 259.729986 9.353804) (xy 259.72979 9.336837) (xy 309.725301 9.336837) (xy 309.725301 9.422587)
			(xy 309.733213 9.50797) (xy 309.748969 9.59226) (xy 309.772436 9.674736) (xy 309.803412 9.754695)
			(xy 309.841634 9.831455) (xy 309.886775 9.904361) (xy 309.938451 9.97279) (xy 309.99622 10.03616)
			(xy 310.05959 10.093929) (xy 310.128019 10.145605) (xy 310.200925 10.190746) (xy 310.277685 10.228968)
			(xy 310.357644 10.259944) (xy 310.44012 10.283411) (xy 310.52441 10.299167) (xy 310.609793 10.307079)
			(xy 310.695543 10.307079) (xy 310.780926 10.299167) (xy 310.865216 10.283411) (xy 310.947692 10.259944)
			(xy 311.027651 10.228968) (xy 311.049854 10.217912) (xy 312.231532 10.217912) (xy 312.231532 11.081512)
			(xy 312.232018 11.108781) (xy 312.23978 11.162765) (xy 312.255145 11.215095) (xy 312.277802 11.264705)
			(xy 312.307288 11.310586) (xy 312.343003 11.351803) (xy 312.38422 11.387518) (xy 312.430101 11.417004)
			(xy 312.479711 11.439661) (xy 312.532041 11.455026) (xy 312.586025 11.462788) (xy 312.640563 11.462788)
			(xy 312.694547 11.455026) (xy 312.746877 11.439661) (xy 312.796487 11.417004) (xy 312.842368 11.387518)
			(xy 312.883585 11.351803) (xy 312.9193 11.310586) (xy 312.948786 11.264705) (xy 312.971443 11.215095)
			(xy 312.986808 11.162765) (xy 312.99457 11.108781) (xy 312.995056 11.081512) (xy 312.995056 10.217912)
			(xy 312.99457 10.190643) (xy 312.986808 10.136659) (xy 312.971443 10.084329) (xy 312.948786 10.034719)
			(xy 312.9193 9.988838) (xy 312.883585 9.947621) (xy 312.842368 9.911906) (xy 312.796487 9.88242)
			(xy 312.746877 9.859763) (xy 312.694547 9.844398) (xy 312.640563 9.836636) (xy 312.586025 9.836636)
			(xy 312.532041 9.844398) (xy 312.479711 9.859763) (xy 312.430101 9.88242) (xy 312.38422 9.911906)
			(xy 312.343003 9.947621) (xy 312.307288 9.988838) (xy 312.277802 10.034719) (xy 312.255145 10.084329)
			(xy 312.23978 10.136659) (xy 312.232018 10.190643) (xy 312.231532 10.217912) (xy 311.049854 10.217912)
			(xy 311.104411 10.190746) (xy 311.177317 10.145605) (xy 311.245746 10.093929) (xy 311.309116 10.03616)
			(xy 311.366885 9.97279) (xy 311.418561 9.904361) (xy 311.463702 9.831455) (xy 311.501924 9.754695)
			(xy 311.5329 9.674736) (xy 311.556367 9.59226) (xy 311.572123 9.50797) (xy 311.580035 9.422587) (xy 311.58053 9.379712)
			(xy 311.580035 9.336837) (xy 316.075301 9.336837) (xy 316.075301 9.422587) (xy 316.083213 9.50797)
			(xy 316.098969 9.59226) (xy 316.122436 9.674736) (xy 316.153412 9.754695) (xy 316.191634 9.831455)
			(xy 316.236775 9.904361) (xy 316.288451 9.97279) (xy 316.34622 10.03616) (xy 316.40959 10.093929)
			(xy 316.478019 10.145605) (xy 316.550925 10.190746) (xy 316.627685 10.228968) (xy 316.707644 10.259944)
			(xy 316.79012 10.283411) (xy 316.87441 10.299167) (xy 316.959793 10.307079) (xy 317.045543 10.307079)
			(xy 317.130926 10.299167) (xy 317.215216 10.283411) (xy 317.297692 10.259944) (xy 317.377651 10.228968)
			(xy 317.454411 10.190746) (xy 317.527317 10.145605) (xy 317.595746 10.093929) (xy 317.659116 10.03616)
			(xy 317.716885 9.97279) (xy 317.768561 9.904361) (xy 317.813702 9.831455) (xy 317.851924 9.754695)
			(xy 317.8829 9.674736) (xy 317.906367 9.59226) (xy 317.922123 9.50797) (xy 317.930035 9.422587) (xy 317.93053 9.379712)
			(xy 317.930117 9.343949) (xy 324.295757 9.343949) (xy 324.295757 9.429699) (xy 324.303669 9.515082)
			(xy 324.319425 9.599372) (xy 324.342892 9.681848) (xy 324.373868 9.761807) (xy 324.41209 9.838567)
			(xy 324.457231 9.911473) (xy 324.508907 9.979902) (xy 324.566676 10.043272) (xy 324.630046 10.101041)
			(xy 324.698475 10.152717) (xy 324.771381 10.197858) (xy 324.848141 10.23608) (xy 324.9281 10.267056)
			(xy 325.010576 10.290523) (xy 325.094866 10.306279) (xy 325.180249 10.314191) (xy 325.265999 10.314191)
			(xy 325.351382 10.306279) (xy 325.435672 10.290523) (xy 325.518148 10.267056) (xy 325.598107 10.23608)
			(xy 325.62031 10.225024) (xy 329.230736 10.225024) (xy 329.230736 11.088624) (xy 329.231222 11.115893)
			(xy 329.238984 11.169877) (xy 329.254349 11.222207) (xy 329.277006 11.271817) (xy 329.306492 11.317698)
			(xy 329.342207 11.358915) (xy 329.383424 11.39463) (xy 329.429305 11.424116) (xy 329.478915 11.446773)
			(xy 329.531245 11.462138) (xy 329.585229 11.4699) (xy 329.639767 11.4699) (xy 329.693751 11.462138)
			(xy 329.746081 11.446773) (xy 329.795691 11.424116) (xy 329.841572 11.39463) (xy 329.882789 11.358915)
			(xy 329.918504 11.317698) (xy 329.94799 11.271817) (xy 329.970647 11.222207) (xy 329.986012 11.169877)
			(xy 329.993774 11.115893) (xy 329.99426 11.088624) (xy 329.99426 10.225024) (xy 329.993774 10.197755)
			(xy 329.986012 10.143771) (xy 329.970647 10.091441) (xy 329.94799 10.041831) (xy 329.918504 9.99595)
			(xy 329.882789 9.954733) (xy 329.841572 9.919018) (xy 329.795691 9.889532) (xy 329.746081 9.866875)
			(xy 329.693751 9.85151) (xy 329.639767 9.843748) (xy 329.585229 9.843748) (xy 329.531245 9.85151)
			(xy 329.478915 9.866875) (xy 329.429305 9.889532) (xy 329.383424 9.919018) (xy 329.342207 9.954733)
			(xy 329.306492 9.99595) (xy 329.277006 10.041831) (xy 329.254349 10.091441) (xy 329.238984 10.143771)
			(xy 329.231222 10.197755) (xy 329.230736 10.225024) (xy 325.62031 10.225024) (xy 325.674867 10.197858)
			(xy 325.747773 10.152717) (xy 325.816202 10.101041) (xy 325.879572 10.043272) (xy 325.937341 9.979902)
			(xy 325.989017 9.911473) (xy 326.034158 9.838567) (xy 326.07238 9.761807) (xy 326.103356 9.681848)
			(xy 326.126823 9.599372) (xy 326.142579 9.515082) (xy 326.150491 9.429699) (xy 326.150986 9.386824)
			(xy 326.150491 9.343949) (xy 330.645757 9.343949) (xy 330.645757 9.429699) (xy 330.653669 9.515082)
			(xy 330.669425 9.599372) (xy 330.692892 9.681848) (xy 330.723868 9.761807) (xy 330.76209 9.838567)
			(xy 330.807231 9.911473) (xy 330.858907 9.979902) (xy 330.916676 10.043272) (xy 330.980046 10.101041)
			(xy 331.048475 10.152717) (xy 331.121381 10.197858) (xy 331.198141 10.23608) (xy 331.2781 10.267056)
			(xy 331.360576 10.290523) (xy 331.444866 10.306279) (xy 331.530249 10.314191) (xy 331.615999 10.314191)
			(xy 331.701382 10.306279) (xy 331.785672 10.290523) (xy 331.868148 10.267056) (xy 331.948107 10.23608)
			(xy 332.024867 10.197858) (xy 332.097773 10.152717) (xy 332.166202 10.101041) (xy 332.229572 10.043272)
			(xy 332.287341 9.979902) (xy 332.339017 9.911473) (xy 332.384158 9.838567) (xy 332.42238 9.761807)
			(xy 332.453356 9.681848) (xy 332.476823 9.599372) (xy 332.492579 9.515082) (xy 332.500491 9.429699)
			(xy 332.500986 9.386824) (xy 332.50079 9.369857) (xy 382.496301 9.369857) (xy 382.496301 9.455607)
			(xy 382.504213 9.54099) (xy 382.519969 9.62528) (xy 382.543436 9.707756) (xy 382.574412 9.787715)
			(xy 382.612634 9.864475) (xy 382.657775 9.937381) (xy 382.709451 10.00581) (xy 382.76722 10.06918)
			(xy 382.83059 10.126949) (xy 382.899019 10.178625) (xy 382.971925 10.223766) (xy 383.048685 10.261988)
			(xy 383.128644 10.292964) (xy 383.21112 10.316431) (xy 383.29541 10.332187) (xy 383.380793 10.340099)
			(xy 383.466543 10.340099) (xy 383.551926 10.332187) (xy 383.636216 10.316431) (xy 383.718692 10.292964)
			(xy 383.798651 10.261988) (xy 383.820854 10.250932) (xy 385.002532 10.250932) (xy 385.002532 11.114532)
			(xy 385.003018 11.141801) (xy 385.01078 11.195785) (xy 385.026145 11.248115) (xy 385.048802 11.297725)
			(xy 385.078288 11.343606) (xy 385.114003 11.384823) (xy 385.15522 11.420538) (xy 385.201101 11.450024)
			(xy 385.250711 11.472681) (xy 385.303041 11.488046) (xy 385.357025 11.495808) (xy 385.411563 11.495808)
			(xy 385.465547 11.488046) (xy 385.517877 11.472681) (xy 385.567487 11.450024) (xy 385.613368 11.420538)
			(xy 385.654585 11.384823) (xy 385.6903 11.343606) (xy 385.719786 11.297725) (xy 385.742443 11.248115)
			(xy 385.757808 11.195785) (xy 385.76557 11.141801) (xy 385.766056 11.114532) (xy 385.766056 10.250932)
			(xy 385.76557 10.223663) (xy 385.757808 10.169679) (xy 385.742443 10.117349) (xy 385.719786 10.067739)
			(xy 385.6903 10.021858) (xy 385.654585 9.980641) (xy 385.613368 9.944926) (xy 385.567487 9.91544)
			(xy 385.517877 9.892783) (xy 385.465547 9.877418) (xy 385.411563 9.869656) (xy 385.357025 9.869656)
			(xy 385.303041 9.877418) (xy 385.250711 9.892783) (xy 385.201101 9.91544) (xy 385.15522 9.944926)
			(xy 385.114003 9.980641) (xy 385.078288 10.021858) (xy 385.048802 10.067739) (xy 385.026145 10.117349)
			(xy 385.01078 10.169679) (xy 385.003018 10.223663) (xy 385.002532 10.250932) (xy 383.820854 10.250932)
			(xy 383.875411 10.223766) (xy 383.948317 10.178625) (xy 384.016746 10.126949) (xy 384.080116 10.06918)
			(xy 384.137885 10.00581) (xy 384.189561 9.937381) (xy 384.234702 9.864475) (xy 384.272924 9.787715)
			(xy 384.3039 9.707756) (xy 384.327367 9.62528) (xy 384.343123 9.54099) (xy 384.351035 9.455607) (xy 384.35153 9.412732)
			(xy 384.351035 9.369857) (xy 388.846301 9.369857) (xy 388.846301 9.455607) (xy 388.854213 9.54099)
			(xy 388.869969 9.62528) (xy 388.893436 9.707756) (xy 388.924412 9.787715) (xy 388.962634 9.864475)
			(xy 389.007775 9.937381) (xy 389.059451 10.00581) (xy 389.11722 10.06918) (xy 389.18059 10.126949)
			(xy 389.249019 10.178625) (xy 389.321925 10.223766) (xy 389.398685 10.261988) (xy 389.478644 10.292964)
			(xy 389.56112 10.316431) (xy 389.64541 10.332187) (xy 389.730793 10.340099) (xy 389.816543 10.340099)
			(xy 389.901926 10.332187) (xy 389.986216 10.316431) (xy 390.068692 10.292964) (xy 390.148651 10.261988)
			(xy 390.225411 10.223766) (xy 390.298317 10.178625) (xy 390.366746 10.126949) (xy 390.430116 10.06918)
			(xy 390.487885 10.00581) (xy 390.539561 9.937381) (xy 390.584702 9.864475) (xy 390.622924 9.787715)
			(xy 390.6539 9.707756) (xy 390.677367 9.62528) (xy 390.693123 9.54099) (xy 390.701035 9.455607) (xy 390.70153 9.412732)
			(xy 390.701117 9.376969) (xy 396.558757 9.376969) (xy 396.558757 9.462719) (xy 396.566669 9.548102)
			(xy 396.582425 9.632392) (xy 396.605892 9.714868) (xy 396.636868 9.794827) (xy 396.67509 9.871587)
			(xy 396.720231 9.944493) (xy 396.771907 10.012922) (xy 396.829676 10.076292) (xy 396.893046 10.134061)
			(xy 396.961475 10.185737) (xy 397.034381 10.230878) (xy 397.111141 10.2691) (xy 397.1911 10.300076)
			(xy 397.273576 10.323543) (xy 397.357866 10.339299) (xy 397.443249 10.347211) (xy 397.528999 10.347211)
			(xy 397.614382 10.339299) (xy 397.698672 10.323543) (xy 397.781148 10.300076) (xy 397.861107 10.2691)
			(xy 397.88331 10.258044) (xy 401.493736 10.258044) (xy 401.493736 11.121644) (xy 401.494222 11.148913)
			(xy 401.501984 11.202897) (xy 401.517349 11.255227) (xy 401.540006 11.304837) (xy 401.569492 11.350718)
			(xy 401.605207 11.391935) (xy 401.646424 11.42765) (xy 401.692305 11.457136) (xy 401.741915 11.479793)
			(xy 401.794245 11.495158) (xy 401.848229 11.50292) (xy 401.902767 11.50292) (xy 401.956751 11.495158)
			(xy 402.009081 11.479793) (xy 402.058691 11.457136) (xy 402.104572 11.42765) (xy 402.145789 11.391935)
			(xy 402.181504 11.350718) (xy 402.21099 11.304837) (xy 402.233647 11.255227) (xy 402.249012 11.202897)
			(xy 402.256774 11.148913) (xy 402.25726 11.121644) (xy 402.25726 10.258044) (xy 402.256774 10.230775)
			(xy 402.249012 10.176791) (xy 402.233647 10.124461) (xy 402.21099 10.074851) (xy 402.181504 10.02897)
			(xy 402.145789 9.987753) (xy 402.104572 9.952038) (xy 402.058691 9.922552) (xy 402.009081 9.899895)
			(xy 401.956751 9.88453) (xy 401.902767 9.876768) (xy 401.848229 9.876768) (xy 401.794245 9.88453)
			(xy 401.741915 9.899895) (xy 401.692305 9.922552) (xy 401.646424 9.952038) (xy 401.605207 9.987753)
			(xy 401.569492 10.02897) (xy 401.540006 10.074851) (xy 401.517349 10.124461) (xy 401.501984 10.176791)
			(xy 401.494222 10.230775) (xy 401.493736 10.258044) (xy 397.88331 10.258044) (xy 397.937867 10.230878)
			(xy 398.010773 10.185737) (xy 398.079202 10.134061) (xy 398.142572 10.076292) (xy 398.200341 10.012922)
			(xy 398.252017 9.944493) (xy 398.297158 9.871587) (xy 398.33538 9.794827) (xy 398.366356 9.714868)
			(xy 398.389823 9.632392) (xy 398.405579 9.548102) (xy 398.413491 9.462719) (xy 398.413986 9.419844)
			(xy 398.413491 9.376969) (xy 402.908757 9.376969) (xy 402.908757 9.462719) (xy 402.916669 9.548102)
			(xy 402.932425 9.632392) (xy 402.955892 9.714868) (xy 402.986868 9.794827) (xy 403.02509 9.871587)
			(xy 403.070231 9.944493) (xy 403.121907 10.012922) (xy 403.179676 10.076292) (xy 403.243046 10.134061)
			(xy 403.311475 10.185737) (xy 403.384381 10.230878) (xy 403.461141 10.2691) (xy 403.5411 10.300076)
			(xy 403.623576 10.323543) (xy 403.707866 10.339299) (xy 403.793249 10.347211) (xy 403.878999 10.347211)
			(xy 403.964382 10.339299) (xy 404.048672 10.323543) (xy 404.131148 10.300076) (xy 404.211107 10.2691)
			(xy 404.287867 10.230878) (xy 404.360773 10.185737) (xy 404.429202 10.134061) (xy 404.492572 10.076292)
			(xy 404.550341 10.012922) (xy 404.602017 9.944493) (xy 404.647158 9.871587) (xy 404.68538 9.794827)
			(xy 404.716356 9.714868) (xy 404.739823 9.632392) (xy 404.755579 9.548102) (xy 404.763491 9.462719)
			(xy 404.763986 9.419844) (xy 404.76379 9.402877) (xy 454.759301 9.402877) (xy 454.759301 9.488627)
			(xy 454.767213 9.57401) (xy 454.782969 9.6583) (xy 454.806436 9.740776) (xy 454.837412 9.820735)
			(xy 454.875634 9.897495) (xy 454.920775 9.970401) (xy 454.972451 10.03883) (xy 455.03022 10.1022)
			(xy 455.09359 10.159969) (xy 455.162019 10.211645) (xy 455.234925 10.256786) (xy 455.311685 10.295008)
			(xy 455.391644 10.325984) (xy 455.47412 10.349451) (xy 455.55841 10.365207) (xy 455.643793 10.373119)
			(xy 455.729543 10.373119) (xy 455.814926 10.365207) (xy 455.899216 10.349451) (xy 455.981692 10.325984)
			(xy 456.061651 10.295008) (xy 456.083854 10.283952) (xy 457.265532 10.283952) (xy 457.265532 11.147552)
			(xy 457.266018 11.174821) (xy 457.27378 11.228805) (xy 457.289145 11.281135) (xy 457.311802 11.330745)
			(xy 457.341288 11.376626) (xy 457.377003 11.417843) (xy 457.41822 11.453558) (xy 457.464101 11.483044)
			(xy 457.513711 11.505701) (xy 457.566041 11.521066) (xy 457.620025 11.528828) (xy 457.674563 11.528828)
			(xy 457.728547 11.521066) (xy 457.780877 11.505701) (xy 457.830487 11.483044) (xy 457.876368 11.453558)
			(xy 457.917585 11.417843) (xy 457.9533 11.376626) (xy 457.982786 11.330745) (xy 458.005443 11.281135)
			(xy 458.020808 11.228805) (xy 458.02857 11.174821) (xy 458.029056 11.147552) (xy 458.029056 10.283952)
			(xy 458.02857 10.256683) (xy 458.020808 10.202699) (xy 458.005443 10.150369) (xy 457.982786 10.100759)
			(xy 457.9533 10.054878) (xy 457.917585 10.013661) (xy 457.876368 9.977946) (xy 457.830487 9.94846)
			(xy 457.780877 9.925803) (xy 457.728547 9.910438) (xy 457.674563 9.902676) (xy 457.620025 9.902676)
			(xy 457.566041 9.910438) (xy 457.513711 9.925803) (xy 457.464101 9.94846) (xy 457.41822 9.977946)
			(xy 457.377003 10.013661) (xy 457.341288 10.054878) (xy 457.311802 10.100759) (xy 457.289145 10.150369)
			(xy 457.27378 10.202699) (xy 457.266018 10.256683) (xy 457.265532 10.283952) (xy 456.083854 10.283952)
			(xy 456.138411 10.256786) (xy 456.211317 10.211645) (xy 456.279746 10.159969) (xy 456.343116 10.1022)
			(xy 456.400885 10.03883) (xy 456.452561 9.970401) (xy 456.497702 9.897495) (xy 456.535924 9.820735)
			(xy 456.5669 9.740776) (xy 456.590367 9.6583) (xy 456.606123 9.57401) (xy 456.614035 9.488627) (xy 456.61453 9.445752)
			(xy 456.614035 9.402877) (xy 461.109301 9.402877) (xy 461.109301 9.488627) (xy 461.117213 9.57401)
			(xy 461.132969 9.6583) (xy 461.156436 9.740776) (xy 461.187412 9.820735) (xy 461.225634 9.897495)
			(xy 461.270775 9.970401) (xy 461.322451 10.03883) (xy 461.38022 10.1022) (xy 461.44359 10.159969)
			(xy 461.512019 10.211645) (xy 461.584925 10.256786) (xy 461.661685 10.295008) (xy 461.741644 10.325984)
			(xy 461.82412 10.349451) (xy 461.90841 10.365207) (xy 461.993793 10.373119) (xy 462.079543 10.373119)
			(xy 462.164926 10.365207) (xy 462.249216 10.349451) (xy 462.331692 10.325984) (xy 462.411651 10.295008)
			(xy 462.488411 10.256786) (xy 462.561317 10.211645) (xy 462.629746 10.159969) (xy 462.693116 10.1022)
			(xy 462.750885 10.03883) (xy 462.802561 9.970401) (xy 462.847702 9.897495) (xy 462.885924 9.820735)
			(xy 462.9169 9.740776) (xy 462.940367 9.6583) (xy 462.956123 9.57401) (xy 462.964035 9.488627) (xy 462.96453 9.445752)
			(xy 462.964035 9.402877) (xy 462.956123 9.317494) (xy 462.940367 9.233204) (xy 462.9169 9.150728)
			(xy 462.885924 9.070769) (xy 462.847702 8.994009) (xy 462.802561 8.921103) (xy 462.750885 8.852674)
			(xy 462.693116 8.789304) (xy 462.629746 8.731535) (xy 462.561317 8.679859) (xy 462.488411 8.634718)
			(xy 462.411651 8.596496) (xy 462.331692 8.56552) (xy 462.249216 8.542053) (xy 462.164926 8.526297)
			(xy 462.079543 8.518385) (xy 461.993793 8.518385) (xy 461.90841 8.526297) (xy 461.82412 8.542053)
			(xy 461.741644 8.56552) (xy 461.661685 8.596496) (xy 461.584925 8.634718) (xy 461.512019 8.679859)
			(xy 461.44359 8.731535) (xy 461.38022 8.789304) (xy 461.322451 8.852674) (xy 461.270775 8.921103)
			(xy 461.225634 8.994009) (xy 461.187412 9.070769) (xy 461.156436 9.150728) (xy 461.132969 9.233204)
			(xy 461.117213 9.317494) (xy 461.109301 9.402877) (xy 456.614035 9.402877) (xy 456.606123 9.317494)
			(xy 456.590367 9.233204) (xy 456.5669 9.150728) (xy 456.535924 9.070769) (xy 456.497702 8.994009)
			(xy 456.452561 8.921103) (xy 456.400885 8.852674) (xy 456.343116 8.789304) (xy 456.279746 8.731535)
			(xy 456.211317 8.679859) (xy 456.138411 8.634718) (xy 456.061651 8.596496) (xy 455.981692 8.56552)
			(xy 455.899216 8.542053) (xy 455.814926 8.526297) (xy 455.729543 8.518385) (xy 455.643793 8.518385)
			(xy 455.55841 8.526297) (xy 455.47412 8.542053) (xy 455.391644 8.56552) (xy 455.311685 8.596496)
			(xy 455.234925 8.634718) (xy 455.162019 8.679859) (xy 455.09359 8.731535) (xy 455.03022 8.789304)
			(xy 454.972451 8.852674) (xy 454.920775 8.921103) (xy 454.875634 8.994009) (xy 454.837412 9.070769)
			(xy 454.806436 9.150728) (xy 454.782969 9.233204) (xy 454.767213 9.317494) (xy 454.759301 9.402877)
			(xy 404.76379 9.402877) (xy 404.763491 9.376969) (xy 404.755579 9.291586) (xy 404.739823 9.207296)
			(xy 404.716356 9.12482) (xy 404.68538 9.044861) (xy 404.647158 8.968101) (xy 404.602017 8.895195)
			(xy 404.550341 8.826766) (xy 404.492572 8.763396) (xy 404.429202 8.705627) (xy 404.360773 8.653951)
			(xy 404.287867 8.60881) (xy 404.211107 8.570588) (xy 404.131148 8.539612) (xy 404.048672 8.516145)
			(xy 403.964382 8.500389) (xy 403.878999 8.492477) (xy 403.793249 8.492477) (xy 403.707866 8.500389)
			(xy 403.623576 8.516145) (xy 403.5411 8.539612) (xy 403.461141 8.570588) (xy 403.384381 8.60881)
			(xy 403.311475 8.653951) (xy 403.243046 8.705627) (xy 403.179676 8.763396) (xy 403.121907 8.826766)
			(xy 403.070231 8.895195) (xy 403.02509 8.968101) (xy 402.986868 9.044861) (xy 402.955892 9.12482)
			(xy 402.932425 9.207296) (xy 402.916669 9.291586) (xy 402.908757 9.376969) (xy 398.413491 9.376969)
			(xy 398.405579 9.291586) (xy 398.389823 9.207296) (xy 398.366356 9.12482) (xy 398.33538 9.044861)
			(xy 398.297158 8.968101) (xy 398.252017 8.895195) (xy 398.200341 8.826766) (xy 398.142572 8.763396)
			(xy 398.079202 8.705627) (xy 398.010773 8.653951) (xy 397.937867 8.60881) (xy 397.861107 8.570588)
			(xy 397.781148 8.539612) (xy 397.698672 8.516145) (xy 397.614382 8.500389) (xy 397.528999 8.492477)
			(xy 397.443249 8.492477) (xy 397.357866 8.500389) (xy 397.273576 8.516145) (xy 397.1911 8.539612)
			(xy 397.111141 8.570588) (xy 397.034381 8.60881) (xy 396.961475 8.653951) (xy 396.893046 8.705627)
			(xy 396.829676 8.763396) (xy 396.771907 8.826766) (xy 396.720231 8.895195) (xy 396.67509 8.968101)
			(xy 396.636868 9.044861) (xy 396.605892 9.12482) (xy 396.582425 9.207296) (xy 396.566669 9.291586)
			(xy 396.558757 9.376969) (xy 390.701117 9.376969) (xy 390.701035 9.369857) (xy 390.693123 9.284474)
			(xy 390.677367 9.200184) (xy 390.6539 9.117708) (xy 390.622924 9.037749) (xy 390.584702 8.960989)
			(xy 390.539561 8.888083) (xy 390.487885 8.819654) (xy 390.430116 8.756284) (xy 390.366746 8.698515)
			(xy 390.298317 8.646839) (xy 390.225411 8.601698) (xy 390.148651 8.563476) (xy 390.068692 8.5325)
			(xy 389.986216 8.509033) (xy 389.901926 8.493277) (xy 389.816543 8.485365) (xy 389.730793 8.485365)
			(xy 389.64541 8.493277) (xy 389.56112 8.509033) (xy 389.478644 8.5325) (xy 389.398685 8.563476) (xy 389.321925 8.601698)
			(xy 389.249019 8.646839) (xy 389.18059 8.698515) (xy 389.11722 8.756284) (xy 389.059451 8.819654)
			(xy 389.007775 8.888083) (xy 388.962634 8.960989) (xy 388.924412 9.037749) (xy 388.893436 9.117708)
			(xy 388.869969 9.200184) (xy 388.854213 9.284474) (xy 388.846301 9.369857) (xy 384.351035 9.369857)
			(xy 384.343123 9.284474) (xy 384.327367 9.200184) (xy 384.3039 9.117708) (xy 384.272924 9.037749)
			(xy 384.234702 8.960989) (xy 384.189561 8.888083) (xy 384.137885 8.819654) (xy 384.080116 8.756284)
			(xy 384.016746 8.698515) (xy 383.948317 8.646839) (xy 383.875411 8.601698) (xy 383.798651 8.563476)
			(xy 383.718692 8.5325) (xy 383.636216 8.509033) (xy 383.551926 8.493277) (xy 383.466543 8.485365)
			(xy 383.380793 8.485365) (xy 383.29541 8.493277) (xy 383.21112 8.509033) (xy 383.128644 8.5325) (xy 383.048685 8.563476)
			(xy 382.971925 8.601698) (xy 382.899019 8.646839) (xy 382.83059 8.698515) (xy 382.76722 8.756284)
			(xy 382.709451 8.819654) (xy 382.657775 8.888083) (xy 382.612634 8.960989) (xy 382.574412 9.037749)
			(xy 382.543436 9.117708) (xy 382.519969 9.200184) (xy 382.504213 9.284474) (xy 382.496301 9.369857)
			(xy 332.50079 9.369857) (xy 332.500491 9.343949) (xy 332.492579 9.258566) (xy 332.476823 9.174276)
			(xy 332.453356 9.0918) (xy 332.42238 9.011841) (xy 332.384158 8.935081) (xy 332.339017 8.862175)
			(xy 332.287341 8.793746) (xy 332.229572 8.730376) (xy 332.166202 8.672607) (xy 332.097773 8.620931)
			(xy 332.024867 8.57579) (xy 331.948107 8.537568) (xy 331.868148 8.506592) (xy 331.785672 8.483125)
			(xy 331.701382 8.467369) (xy 331.615999 8.459457) (xy 331.530249 8.459457) (xy 331.444866 8.467369)
			(xy 331.360576 8.483125) (xy 331.2781 8.506592) (xy 331.198141 8.537568) (xy 331.121381 8.57579)
			(xy 331.048475 8.620931) (xy 330.980046 8.672607) (xy 330.916676 8.730376) (xy 330.858907 8.793746)
			(xy 330.807231 8.862175) (xy 330.76209 8.935081) (xy 330.723868 9.011841) (xy 330.692892 9.0918)
			(xy 330.669425 9.174276) (xy 330.653669 9.258566) (xy 330.645757 9.343949) (xy 326.150491 9.343949)
			(xy 326.142579 9.258566) (xy 326.126823 9.174276) (xy 326.103356 9.0918) (xy 326.07238 9.011841)
			(xy 326.034158 8.935081) (xy 325.989017 8.862175) (xy 325.937341 8.793746) (xy 325.879572 8.730376)
			(xy 325.816202 8.672607) (xy 325.747773 8.620931) (xy 325.674867 8.57579) (xy 325.598107 8.537568)
			(xy 325.518148 8.506592) (xy 325.435672 8.483125) (xy 325.351382 8.467369) (xy 325.265999 8.459457)
			(xy 325.180249 8.459457) (xy 325.094866 8.467369) (xy 325.010576 8.483125) (xy 324.9281 8.506592)
			(xy 324.848141 8.537568) (xy 324.771381 8.57579) (xy 324.698475 8.620931) (xy 324.630046 8.672607)
			(xy 324.566676 8.730376) (xy 324.508907 8.793746) (xy 324.457231 8.862175) (xy 324.41209 8.935081)
			(xy 324.373868 9.011841) (xy 324.342892 9.0918) (xy 324.319425 9.174276) (xy 324.303669 9.258566)
			(xy 324.295757 9.343949) (xy 317.930117 9.343949) (xy 317.930035 9.336837) (xy 317.922123 9.251454)
			(xy 317.906367 9.167164) (xy 317.8829 9.084688) (xy 317.851924 9.004729) (xy 317.813702 8.927969)
			(xy 317.768561 8.855063) (xy 317.716885 8.786634) (xy 317.659116 8.723264) (xy 317.595746 8.665495)
			(xy 317.527317 8.613819) (xy 317.454411 8.568678) (xy 317.377651 8.530456) (xy 317.297692 8.49948)
			(xy 317.215216 8.476013) (xy 317.130926 8.460257) (xy 317.045543 8.452345) (xy 316.959793 8.452345)
			(xy 316.87441 8.460257) (xy 316.79012 8.476013) (xy 316.707644 8.49948) (xy 316.627685 8.530456)
			(xy 316.550925 8.568678) (xy 316.478019 8.613819) (xy 316.40959 8.665495) (xy 316.34622 8.723264)
			(xy 316.288451 8.786634) (xy 316.236775 8.855063) (xy 316.191634 8.927969) (xy 316.153412 9.004729)
			(xy 316.122436 9.084688) (xy 316.098969 9.167164) (xy 316.083213 9.251454) (xy 316.075301 9.336837)
			(xy 311.580035 9.336837) (xy 311.572123 9.251454) (xy 311.556367 9.167164) (xy 311.5329 9.084688)
			(xy 311.501924 9.004729) (xy 311.463702 8.927969) (xy 311.418561 8.855063) (xy 311.366885 8.786634)
			(xy 311.309116 8.723264) (xy 311.245746 8.665495) (xy 311.177317 8.613819) (xy 311.104411 8.568678)
			(xy 311.027651 8.530456) (xy 310.947692 8.49948) (xy 310.865216 8.476013) (xy 310.780926 8.460257)
			(xy 310.695543 8.452345) (xy 310.609793 8.452345) (xy 310.52441 8.460257) (xy 310.44012 8.476013)
			(xy 310.357644 8.49948) (xy 310.277685 8.530456) (xy 310.200925 8.568678) (xy 310.128019 8.613819)
			(xy 310.05959 8.665495) (xy 309.99622 8.723264) (xy 309.938451 8.786634) (xy 309.886775 8.855063)
			(xy 309.841634 8.927969) (xy 309.803412 9.004729) (xy 309.772436 9.084688) (xy 309.748969 9.167164)
			(xy 309.733213 9.251454) (xy 309.725301 9.336837) (xy 259.72979 9.336837) (xy 259.729491 9.310929)
			(xy 259.721579 9.225546) (xy 259.705823 9.141256) (xy 259.682356 9.05878) (xy 259.65138 8.978821)
			(xy 259.613158 8.902061) (xy 259.568017 8.829155) (xy 259.516341 8.760726) (xy 259.458572 8.697356)
			(xy 259.395202 8.639587) (xy 259.326773 8.587911) (xy 259.253867 8.54277) (xy 259.177107 8.504548)
			(xy 259.097148 8.473572) (xy 259.014672 8.450105) (xy 258.930382 8.434349) (xy 258.844999 8.426437)
			(xy 258.759249 8.426437) (xy 258.673866 8.434349) (xy 258.589576 8.450105) (xy 258.5071 8.473572)
			(xy 258.427141 8.504548) (xy 258.350381 8.54277) (xy 258.277475 8.587911) (xy 258.209046 8.639587)
			(xy 258.145676 8.697356) (xy 258.087907 8.760726) (xy 258.036231 8.829155) (xy 257.99109 8.902061)
			(xy 257.952868 8.978821) (xy 257.921892 9.05878) (xy 257.898425 9.141256) (xy 257.882669 9.225546)
			(xy 257.874757 9.310929) (xy 253.379491 9.310929) (xy 253.371579 9.225546) (xy 253.355823 9.141256)
			(xy 253.332356 9.05878) (xy 253.30138 8.978821) (xy 253.263158 8.902061) (xy 253.218017 8.829155)
			(xy 253.166341 8.760726) (xy 253.108572 8.697356) (xy 253.045202 8.639587) (xy 252.976773 8.587911)
			(xy 252.903867 8.54277) (xy 252.827107 8.504548) (xy 252.747148 8.473572) (xy 252.664672 8.450105)
			(xy 252.580382 8.434349) (xy 252.494999 8.426437) (xy 252.409249 8.426437) (xy 252.323866 8.434349)
			(xy 252.239576 8.450105) (xy 252.1571 8.473572) (xy 252.077141 8.504548) (xy 252.000381 8.54277)
			(xy 251.927475 8.587911) (xy 251.859046 8.639587) (xy 251.795676 8.697356) (xy 251.737907 8.760726)
			(xy 251.686231 8.829155) (xy 251.64109 8.902061) (xy 251.602868 8.978821) (xy 251.571892 9.05878)
			(xy 251.548425 9.141256) (xy 251.532669 9.225546) (xy 251.524757 9.310929) (xy 245.921117 9.310929)
			(xy 245.921035 9.303817) (xy 245.913123 9.218434) (xy 245.897367 9.134144) (xy 245.8739 9.051668)
			(xy 245.842924 8.971709) (xy 245.804702 8.894949) (xy 245.759561 8.822043) (xy 245.707885 8.753614)
			(xy 245.650116 8.690244) (xy 245.586746 8.632475) (xy 245.518317 8.580799) (xy 245.445411 8.535658)
			(xy 245.368651 8.497436) (xy 245.288692 8.46646) (xy 245.206216 8.442993) (xy 245.121926 8.427237)
			(xy 245.036543 8.419325) (xy 244.950793 8.419325) (xy 244.86541 8.427237) (xy 244.78112 8.442993)
			(xy 244.698644 8.46646) (xy 244.618685 8.497436) (xy 244.541925 8.535658) (xy 244.469019 8.580799)
			(xy 244.40059 8.632475) (xy 244.33722 8.690244) (xy 244.279451 8.753614) (xy 244.227775 8.822043)
			(xy 244.182634 8.894949) (xy 244.144412 8.971709) (xy 244.113436 9.051668) (xy 244.089969 9.134144)
			(xy 244.074213 9.218434) (xy 244.066301 9.303817) (xy 239.571035 9.303817) (xy 239.563123 9.218434)
			(xy 239.547367 9.134144) (xy 239.5239 9.051668) (xy 239.492924 8.971709) (xy 239.454702 8.894949)
			(xy 239.409561 8.822043) (xy 239.357885 8.753614) (xy 239.300116 8.690244) (xy 239.236746 8.632475)
			(xy 239.168317 8.580799) (xy 239.095411 8.535658) (xy 239.018651 8.497436) (xy 238.938692 8.46646)
			(xy 238.856216 8.442993) (xy 238.771926 8.427237) (xy 238.686543 8.419325) (xy 238.600793 8.419325)
			(xy 238.51541 8.427237) (xy 238.43112 8.442993) (xy 238.348644 8.46646) (xy 238.268685 8.497436)
			(xy 238.191925 8.535658) (xy 238.119019 8.580799) (xy 238.05059 8.632475) (xy 237.98722 8.690244)
			(xy 237.929451 8.753614) (xy 237.877775 8.822043) (xy 237.832634 8.894949) (xy 237.794412 8.971709)
			(xy 237.763436 9.051668) (xy 237.739969 9.134144) (xy 237.724213 9.218434) (xy 237.716301 9.303817)
			(xy 187.719832 9.303817) (xy 187.712579 9.225546) (xy 187.696823 9.141256) (xy 187.673356 9.05878)
			(xy 187.64238 8.978821) (xy 187.604158 8.902061) (xy 187.559017 8.829155) (xy 187.507341 8.760726)
			(xy 187.449572 8.697356) (xy 187.386202 8.639587) (xy 187.317773 8.587911) (xy 187.244867 8.54277)
			(xy 187.168107 8.504548) (xy 187.088148 8.473572) (xy 187.005672 8.450105) (xy 186.921382 8.434349)
			(xy 186.835999 8.426437) (xy 186.750249 8.426437) (xy 186.664866 8.434349) (xy 186.580576 8.450105)
			(xy 186.4981 8.473572) (xy 186.418141 8.504548) (xy 186.341381 8.54277) (xy 186.268475 8.587911)
			(xy 186.200046 8.639587) (xy 186.136676 8.697356) (xy 186.078907 8.760726) (xy 186.027231 8.829155)
			(xy 185.98209 8.902061) (xy 185.943868 8.978821) (xy 185.912892 9.05878) (xy 185.889425 9.141256)
			(xy 185.873669 9.225546) (xy 185.865757 9.310929) (xy 181.370491 9.310929) (xy 181.362579 9.225546)
			(xy 181.346823 9.141256) (xy 181.323356 9.05878) (xy 181.29238 8.978821) (xy 181.254158 8.902061)
			(xy 181.209017 8.829155) (xy 181.157341 8.760726) (xy 181.099572 8.697356) (xy 181.036202 8.639587)
			(xy 180.967773 8.587911) (xy 180.894867 8.54277) (xy 180.818107 8.504548) (xy 180.738148 8.473572)
			(xy 180.655672 8.450105) (xy 180.571382 8.434349) (xy 180.485999 8.426437) (xy 180.400249 8.426437)
			(xy 180.314866 8.434349) (xy 180.230576 8.450105) (xy 180.1481 8.473572) (xy 180.068141 8.504548)
			(xy 179.991381 8.54277) (xy 179.918475 8.587911) (xy 179.850046 8.639587) (xy 179.786676 8.697356)
			(xy 179.728907 8.760726) (xy 179.677231 8.829155) (xy 179.63209 8.902061) (xy 179.593868 8.978821)
			(xy 179.562892 9.05878) (xy 179.539425 9.141256) (xy 179.523669 9.225546) (xy 179.515757 9.310929)
			(xy 158.621984 9.310929) (xy 158.621984 8.377682) (xy 158.62149 8.307329) (xy 158.6136 8.166844)
			(xy 158.597845 8.027022) (xy 158.574274 7.888303) (xy 158.542963 7.751125) (xy 158.50401 7.615918)
			(xy 158.457537 7.483107) (xy 158.40369 7.353112) (xy 158.342638 7.22634) (xy 158.274575 7.103191)
			(xy 158.199714 6.984051) (xy 158.11829 6.869297) (xy 158.039844 6.770929) (xy 179.515757 6.770929)
			(xy 179.515757 6.856679) (xy 179.523669 6.942062) (xy 179.539425 7.026352) (xy 179.562892 7.108828)
			(xy 179.593868 7.188787) (xy 179.63209 7.265547) (xy 179.677231 7.338453) (xy 179.728907 7.406882)
			(xy 179.786676 7.470252) (xy 179.850046 7.528021) (xy 179.918475 7.579697) (xy 179.991381 7.624838)
			(xy 180.068141 7.66306) (xy 180.1481 7.694036) (xy 180.230576 7.717503) (xy 180.314866 7.733259)
			(xy 180.400249 7.741171) (xy 180.485999 7.741171) (xy 180.571382 7.733259) (xy 180.655672 7.717503)
			(xy 180.738148 7.694036) (xy 180.818107 7.66306) (xy 180.894867 7.624838) (xy 180.967773 7.579697)
			(xy 181.036202 7.528021) (xy 181.099572 7.470252) (xy 181.157341 7.406882) (xy 181.209017 7.338453)
			(xy 181.254158 7.265547) (xy 181.29238 7.188787) (xy 181.323356 7.108828) (xy 181.346823 7.026352)
			(xy 181.362579 6.942062) (xy 181.370491 6.856679) (xy 181.370986 6.813804) (xy 181.370491 6.770929)
			(xy 185.865757 6.770929) (xy 185.865757 6.856679) (xy 185.873669 6.942062) (xy 185.889425 7.026352)
			(xy 185.912892 7.108828) (xy 185.943868 7.188787) (xy 185.98209 7.265547) (xy 186.027231 7.338453)
			(xy 186.078907 7.406882) (xy 186.136676 7.470252) (xy 186.200046 7.528021) (xy 186.268475 7.579697)
			(xy 186.341381 7.624838) (xy 186.418141 7.66306) (xy 186.4981 7.694036) (xy 186.580576 7.717503)
			(xy 186.664866 7.733259) (xy 186.750249 7.741171) (xy 186.835999 7.741171) (xy 186.921382 7.733259)
			(xy 187.005672 7.717503) (xy 187.088148 7.694036) (xy 187.168107 7.66306) (xy 187.244867 7.624838)
			(xy 187.317773 7.579697) (xy 187.386202 7.528021) (xy 187.449572 7.470252) (xy 187.507341 7.406882)
			(xy 187.559017 7.338453) (xy 187.604158 7.265547) (xy 187.64238 7.188787) (xy 187.673356 7.108828)
			(xy 187.696823 7.026352) (xy 187.712579 6.942062) (xy 187.720491 6.856679) (xy 187.720986 6.813804)
			(xy 187.720491 6.770929) (xy 187.719832 6.763817) (xy 237.716301 6.763817) (xy 237.716301 6.849567)
			(xy 237.724213 6.93495) (xy 237.739969 7.01924) (xy 237.763436 7.101716) (xy 237.794412 7.181675)
			(xy 237.832634 7.258435) (xy 237.877775 7.331341) (xy 237.929451 7.39977) (xy 237.98722 7.46314)
			(xy 238.05059 7.520909) (xy 238.119019 7.572585) (xy 238.191925 7.617726) (xy 238.268685 7.655948)
			(xy 238.348644 7.686924) (xy 238.43112 7.710391) (xy 238.51541 7.726147) (xy 238.600793 7.734059)
			(xy 238.686543 7.734059) (xy 238.771926 7.726147) (xy 238.856216 7.710391) (xy 238.938692 7.686924)
			(xy 239.018651 7.655948) (xy 239.095411 7.617726) (xy 239.168317 7.572585) (xy 239.236746 7.520909)
			(xy 239.300116 7.46314) (xy 239.357885 7.39977) (xy 239.409561 7.331341) (xy 239.454702 7.258435)
			(xy 239.492924 7.181675) (xy 239.5239 7.101716) (xy 239.547367 7.01924) (xy 239.563123 6.93495) (xy 239.571035 6.849567)
			(xy 239.57153 6.806692) (xy 239.571035 6.763817) (xy 244.066301 6.763817) (xy 244.066301 6.849567)
			(xy 244.074213 6.93495) (xy 244.089969 7.01924) (xy 244.113436 7.101716) (xy 244.144412 7.181675)
			(xy 244.182634 7.258435) (xy 244.227775 7.331341) (xy 244.279451 7.39977) (xy 244.33722 7.46314)
			(xy 244.40059 7.520909) (xy 244.469019 7.572585) (xy 244.541925 7.617726) (xy 244.618685 7.655948)
			(xy 244.698644 7.686924) (xy 244.78112 7.710391) (xy 244.86541 7.726147) (xy 244.950793 7.734059)
			(xy 245.036543 7.734059) (xy 245.121926 7.726147) (xy 245.206216 7.710391) (xy 245.288692 7.686924)
			(xy 245.368651 7.655948) (xy 245.445411 7.617726) (xy 245.518317 7.572585) (xy 245.586746 7.520909)
			(xy 245.650116 7.46314) (xy 245.707885 7.39977) (xy 245.759561 7.331341) (xy 245.804702 7.258435)
			(xy 245.842924 7.181675) (xy 245.8739 7.101716) (xy 245.897367 7.01924) (xy 245.913123 6.93495) (xy 245.921035 6.849567)
			(xy 245.92153 6.806692) (xy 245.921117 6.770929) (xy 251.524757 6.770929) (xy 251.524757 6.856679)
			(xy 251.532669 6.942062) (xy 251.548425 7.026352) (xy 251.571892 7.108828) (xy 251.602868 7.188787)
			(xy 251.64109 7.265547) (xy 251.686231 7.338453) (xy 251.737907 7.406882) (xy 251.795676 7.470252)
			(xy 251.859046 7.528021) (xy 251.927475 7.579697) (xy 252.000381 7.624838) (xy 252.077141 7.66306)
			(xy 252.1571 7.694036) (xy 252.239576 7.717503) (xy 252.323866 7.733259) (xy 252.409249 7.741171)
			(xy 252.494999 7.741171) (xy 252.580382 7.733259) (xy 252.664672 7.717503) (xy 252.747148 7.694036)
			(xy 252.827107 7.66306) (xy 252.84931 7.652004) (xy 256.459736 7.652004) (xy 256.459736 8.515604)
			(xy 256.460222 8.542873) (xy 256.467984 8.596857) (xy 256.483349 8.649187) (xy 256.506006 8.698797)
			(xy 256.535492 8.744678) (xy 256.571207 8.785895) (xy 256.612424 8.82161) (xy 256.658305 8.851096)
			(xy 256.707915 8.873753) (xy 256.760245 8.889118) (xy 256.814229 8.89688) (xy 256.868767 8.89688)
			(xy 256.922751 8.889118) (xy 256.975081 8.873753) (xy 257.024691 8.851096) (xy 257.070572 8.82161)
			(xy 257.111789 8.785895) (xy 257.147504 8.744678) (xy 257.17699 8.698797) (xy 257.199647 8.649187)
			(xy 257.215012 8.596857) (xy 257.222774 8.542873) (xy 257.22326 8.515604) (xy 257.22326 7.652004)
			(xy 257.222774 7.624735) (xy 257.215012 7.570751) (xy 257.199647 7.518421) (xy 257.17699 7.468811)
			(xy 257.147504 7.42293) (xy 257.111789 7.381713) (xy 257.070572 7.345998) (xy 257.024691 7.316512)
			(xy 256.975081 7.293855) (xy 256.922751 7.27849) (xy 256.868767 7.270728) (xy 256.814229 7.270728)
			(xy 256.760245 7.27849) (xy 256.707915 7.293855) (xy 256.658305 7.316512) (xy 256.612424 7.345998)
			(xy 256.571207 7.381713) (xy 256.535492 7.42293) (xy 256.506006 7.468811) (xy 256.483349 7.518421)
			(xy 256.467984 7.570751) (xy 256.460222 7.624735) (xy 256.459736 7.652004) (xy 252.84931 7.652004)
			(xy 252.903867 7.624838) (xy 252.976773 7.579697) (xy 253.045202 7.528021) (xy 253.108572 7.470252)
			(xy 253.166341 7.406882) (xy 253.218017 7.338453) (xy 253.263158 7.265547) (xy 253.30138 7.188787)
			(xy 253.332356 7.108828) (xy 253.355823 7.026352) (xy 253.371579 6.942062) (xy 253.379491 6.856679)
			(xy 253.379986 6.813804) (xy 253.379491 6.770929) (xy 257.874757 6.770929) (xy 257.874757 6.856679)
			(xy 257.882669 6.942062) (xy 257.898425 7.026352) (xy 257.921892 7.108828) (xy 257.952868 7.188787)
			(xy 257.99109 7.265547) (xy 258.036231 7.338453) (xy 258.087907 7.406882) (xy 258.145676 7.470252)
			(xy 258.209046 7.528021) (xy 258.277475 7.579697) (xy 258.350381 7.624838) (xy 258.427141 7.66306)
			(xy 258.5071 7.694036) (xy 258.589576 7.717503) (xy 258.673866 7.733259) (xy 258.759249 7.741171)
			(xy 258.844999 7.741171) (xy 258.930382 7.733259) (xy 259.014672 7.717503) (xy 259.097148 7.694036)
			(xy 259.177107 7.66306) (xy 259.253867 7.624838) (xy 259.326773 7.579697) (xy 259.395202 7.528021)
			(xy 259.458572 7.470252) (xy 259.516341 7.406882) (xy 259.568017 7.338453) (xy 259.613158 7.265547)
			(xy 259.65138 7.188787) (xy 259.682356 7.108828) (xy 259.705823 7.026352) (xy 259.721579 6.942062)
			(xy 259.729491 6.856679) (xy 259.729986 6.813804) (xy 259.72979 6.796837) (xy 309.725301 6.796837)
			(xy 309.725301 6.882587) (xy 309.733213 6.96797) (xy 309.748969 7.05226) (xy 309.772436 7.134736)
			(xy 309.803412 7.214695) (xy 309.841634 7.291455) (xy 309.886775 7.364361) (xy 309.938451 7.43279)
			(xy 309.99622 7.49616) (xy 310.05959 7.553929) (xy 310.128019 7.605605) (xy 310.200925 7.650746)
			(xy 310.277685 7.688968) (xy 310.357644 7.719944) (xy 310.44012 7.743411) (xy 310.52441 7.759167)
			(xy 310.609793 7.767079) (xy 310.695543 7.767079) (xy 310.780926 7.759167) (xy 310.865216 7.743411)
			(xy 310.947692 7.719944) (xy 311.027651 7.688968) (xy 311.049854 7.677912) (xy 312.231532 7.677912)
			(xy 312.231532 8.541512) (xy 312.232018 8.568781) (xy 312.23978 8.622765) (xy 312.255145 8.675095)
			(xy 312.277802 8.724705) (xy 312.307288 8.770586) (xy 312.343003 8.811803) (xy 312.38422 8.847518)
			(xy 312.430101 8.877004) (xy 312.479711 8.899661) (xy 312.532041 8.915026) (xy 312.586025 8.922788)
			(xy 312.640563 8.922788) (xy 312.694547 8.915026) (xy 312.746877 8.899661) (xy 312.796487 8.877004)
			(xy 312.842368 8.847518) (xy 312.883585 8.811803) (xy 312.9193 8.770586) (xy 312.948786 8.724705)
			(xy 312.971443 8.675095) (xy 312.986808 8.622765) (xy 312.99457 8.568781) (xy 312.995056 8.541512)
			(xy 312.995056 7.677912) (xy 312.99457 7.650643) (xy 312.986808 7.596659) (xy 312.971443 7.544329)
			(xy 312.948786 7.494719) (xy 312.9193 7.448838) (xy 312.883585 7.407621) (xy 312.842368 7.371906)
			(xy 312.796487 7.34242) (xy 312.746877 7.319763) (xy 312.694547 7.304398) (xy 312.640563 7.296636)
			(xy 312.586025 7.296636) (xy 312.532041 7.304398) (xy 312.479711 7.319763) (xy 312.430101 7.34242)
			(xy 312.38422 7.371906) (xy 312.343003 7.407621) (xy 312.307288 7.448838) (xy 312.277802 7.494719)
			(xy 312.255145 7.544329) (xy 312.23978 7.596659) (xy 312.232018 7.650643) (xy 312.231532 7.677912)
			(xy 311.049854 7.677912) (xy 311.104411 7.650746) (xy 311.177317 7.605605) (xy 311.245746 7.553929)
			(xy 311.309116 7.49616) (xy 311.366885 7.43279) (xy 311.418561 7.364361) (xy 311.463702 7.291455)
			(xy 311.501924 7.214695) (xy 311.5329 7.134736) (xy 311.556367 7.05226) (xy 311.572123 6.96797) (xy 311.580035 6.882587)
			(xy 311.58053 6.839712) (xy 311.580035 6.796837) (xy 316.075301 6.796837) (xy 316.075301 6.882587)
			(xy 316.083213 6.96797) (xy 316.098969 7.05226) (xy 316.122436 7.134736) (xy 316.153412 7.214695)
			(xy 316.191634 7.291455) (xy 316.236775 7.364361) (xy 316.288451 7.43279) (xy 316.34622 7.49616)
			(xy 316.40959 7.553929) (xy 316.478019 7.605605) (xy 316.550925 7.650746) (xy 316.627685 7.688968)
			(xy 316.707644 7.719944) (xy 316.79012 7.743411) (xy 316.87441 7.759167) (xy 316.959793 7.767079)
			(xy 317.045543 7.767079) (xy 317.130926 7.759167) (xy 317.215216 7.743411) (xy 317.297692 7.719944)
			(xy 317.377651 7.688968) (xy 317.454411 7.650746) (xy 317.527317 7.605605) (xy 317.595746 7.553929)
			(xy 317.659116 7.49616) (xy 317.716885 7.43279) (xy 317.768561 7.364361) (xy 317.813702 7.291455)
			(xy 317.851924 7.214695) (xy 317.8829 7.134736) (xy 317.906367 7.05226) (xy 317.922123 6.96797) (xy 317.930035 6.882587)
			(xy 317.93053 6.839712) (xy 317.930117 6.803949) (xy 324.295757 6.803949) (xy 324.295757 6.889699)
			(xy 324.303669 6.975082) (xy 324.319425 7.059372) (xy 324.342892 7.141848) (xy 324.373868 7.221807)
			(xy 324.41209 7.298567) (xy 324.457231 7.371473) (xy 324.508907 7.439902) (xy 324.566676 7.503272)
			(xy 324.630046 7.561041) (xy 324.698475 7.612717) (xy 324.771381 7.657858) (xy 324.848141 7.69608)
			(xy 324.9281 7.727056) (xy 325.010576 7.750523) (xy 325.094866 7.766279) (xy 325.180249 7.774191)
			(xy 325.265999 7.774191) (xy 325.351382 7.766279) (xy 325.435672 7.750523) (xy 325.518148 7.727056)
			(xy 325.598107 7.69608) (xy 325.62031 7.685024) (xy 329.230736 7.685024) (xy 329.230736 8.548624)
			(xy 329.231222 8.575893) (xy 329.238984 8.629877) (xy 329.254349 8.682207) (xy 329.277006 8.731817)
			(xy 329.306492 8.777698) (xy 329.342207 8.818915) (xy 329.383424 8.85463) (xy 329.429305 8.884116)
			(xy 329.478915 8.906773) (xy 329.531245 8.922138) (xy 329.585229 8.9299) (xy 329.639767 8.9299) (xy 329.693751 8.922138)
			(xy 329.746081 8.906773) (xy 329.795691 8.884116) (xy 329.841572 8.85463) (xy 329.882789 8.818915)
			(xy 329.918504 8.777698) (xy 329.94799 8.731817) (xy 329.970647 8.682207) (xy 329.986012 8.629877)
			(xy 329.993774 8.575893) (xy 329.99426 8.548624) (xy 329.99426 7.685024) (xy 329.993774 7.657755)
			(xy 329.986012 7.603771) (xy 329.970647 7.551441) (xy 329.94799 7.501831) (xy 329.918504 7.45595)
			(xy 329.882789 7.414733) (xy 329.841572 7.379018) (xy 329.795691 7.349532) (xy 329.746081 7.326875)
			(xy 329.693751 7.31151) (xy 329.639767 7.303748) (xy 329.585229 7.303748) (xy 329.531245 7.31151)
			(xy 329.478915 7.326875) (xy 329.429305 7.349532) (xy 329.383424 7.379018) (xy 329.342207 7.414733)
			(xy 329.306492 7.45595) (xy 329.277006 7.501831) (xy 329.254349 7.551441) (xy 329.238984 7.603771)
			(xy 329.231222 7.657755) (xy 329.230736 7.685024) (xy 325.62031 7.685024) (xy 325.674867 7.657858)
			(xy 325.747773 7.612717) (xy 325.816202 7.561041) (xy 325.879572 7.503272) (xy 325.937341 7.439902)
			(xy 325.989017 7.371473) (xy 326.034158 7.298567) (xy 326.07238 7.221807) (xy 326.103356 7.141848)
			(xy 326.126823 7.059372) (xy 326.142579 6.975082) (xy 326.150491 6.889699) (xy 326.150986 6.846824)
			(xy 326.150491 6.803949) (xy 330.645757 6.803949) (xy 330.645757 6.889699) (xy 330.653669 6.975082)
			(xy 330.669425 7.059372) (xy 330.692892 7.141848) (xy 330.723868 7.221807) (xy 330.76209 7.298567)
			(xy 330.807231 7.371473) (xy 330.858907 7.439902) (xy 330.916676 7.503272) (xy 330.980046 7.561041)
			(xy 331.048475 7.612717) (xy 331.121381 7.657858) (xy 331.198141 7.69608) (xy 331.2781 7.727056)
			(xy 331.360576 7.750523) (xy 331.444866 7.766279) (xy 331.530249 7.774191) (xy 331.615999 7.774191)
			(xy 331.701382 7.766279) (xy 331.785672 7.750523) (xy 331.868148 7.727056) (xy 331.948107 7.69608)
			(xy 332.024867 7.657858) (xy 332.097773 7.612717) (xy 332.166202 7.561041) (xy 332.229572 7.503272)
			(xy 332.287341 7.439902) (xy 332.339017 7.371473) (xy 332.384158 7.298567) (xy 332.42238 7.221807)
			(xy 332.453356 7.141848) (xy 332.476823 7.059372) (xy 332.492579 6.975082) (xy 332.500491 6.889699)
			(xy 332.500986 6.846824) (xy 332.50079 6.829857) (xy 382.496301 6.829857) (xy 382.496301 6.915607)
			(xy 382.504213 7.00099) (xy 382.519969 7.08528) (xy 382.543436 7.167756) (xy 382.574412 7.247715)
			(xy 382.612634 7.324475) (xy 382.657775 7.397381) (xy 382.709451 7.46581) (xy 382.76722 7.52918)
			(xy 382.83059 7.586949) (xy 382.899019 7.638625) (xy 382.971925 7.683766) (xy 383.048685 7.721988)
			(xy 383.128644 7.752964) (xy 383.21112 7.776431) (xy 383.29541 7.792187) (xy 383.380793 7.800099)
			(xy 383.466543 7.800099) (xy 383.551926 7.792187) (xy 383.636216 7.776431) (xy 383.718692 7.752964)
			(xy 383.798651 7.721988) (xy 383.820854 7.710932) (xy 385.002532 7.710932) (xy 385.002532 8.574532)
			(xy 385.003018 8.601801) (xy 385.01078 8.655785) (xy 385.026145 8.708115) (xy 385.048802 8.757725)
			(xy 385.078288 8.803606) (xy 385.114003 8.844823) (xy 385.15522 8.880538) (xy 385.201101 8.910024)
			(xy 385.250711 8.932681) (xy 385.303041 8.948046) (xy 385.357025 8.955808) (xy 385.411563 8.955808)
			(xy 385.465547 8.948046) (xy 385.517877 8.932681) (xy 385.567487 8.910024) (xy 385.613368 8.880538)
			(xy 385.654585 8.844823) (xy 385.6903 8.803606) (xy 385.719786 8.757725) (xy 385.742443 8.708115)
			(xy 385.757808 8.655785) (xy 385.76557 8.601801) (xy 385.766056 8.574532) (xy 385.766056 7.710932)
			(xy 385.76557 7.683663) (xy 385.757808 7.629679) (xy 385.742443 7.577349) (xy 385.719786 7.527739)
			(xy 385.6903 7.481858) (xy 385.654585 7.440641) (xy 385.613368 7.404926) (xy 385.567487 7.37544)
			(xy 385.517877 7.352783) (xy 385.465547 7.337418) (xy 385.411563 7.329656) (xy 385.357025 7.329656)
			(xy 385.303041 7.337418) (xy 385.250711 7.352783) (xy 385.201101 7.37544) (xy 385.15522 7.404926)
			(xy 385.114003 7.440641) (xy 385.078288 7.481858) (xy 385.048802 7.527739) (xy 385.026145 7.577349)
			(xy 385.01078 7.629679) (xy 385.003018 7.683663) (xy 385.002532 7.710932) (xy 383.820854 7.710932)
			(xy 383.875411 7.683766) (xy 383.948317 7.638625) (xy 384.016746 7.586949) (xy 384.080116 7.52918)
			(xy 384.137885 7.46581) (xy 384.189561 7.397381) (xy 384.234702 7.324475) (xy 384.272924 7.247715)
			(xy 384.3039 7.167756) (xy 384.327367 7.08528) (xy 384.343123 7.00099) (xy 384.351035 6.915607) (xy 384.35153 6.872732)
			(xy 384.351035 6.829857) (xy 388.846301 6.829857) (xy 388.846301 6.915607) (xy 388.854213 7.00099)
			(xy 388.869969 7.08528) (xy 388.893436 7.167756) (xy 388.924412 7.247715) (xy 388.962634 7.324475)
			(xy 389.007775 7.397381) (xy 389.059451 7.46581) (xy 389.11722 7.52918) (xy 389.18059 7.586949) (xy 389.249019 7.638625)
			(xy 389.321925 7.683766) (xy 389.398685 7.721988) (xy 389.478644 7.752964) (xy 389.56112 7.776431)
			(xy 389.64541 7.792187) (xy 389.730793 7.800099) (xy 389.816543 7.800099) (xy 389.901926 7.792187)
			(xy 389.986216 7.776431) (xy 390.068692 7.752964) (xy 390.148651 7.721988) (xy 390.225411 7.683766)
			(xy 390.298317 7.638625) (xy 390.366746 7.586949) (xy 390.430116 7.52918) (xy 390.487885 7.46581)
			(xy 390.539561 7.397381) (xy 390.584702 7.324475) (xy 390.622924 7.247715) (xy 390.6539 7.167756)
			(xy 390.677367 7.08528) (xy 390.693123 7.00099) (xy 390.701035 6.915607) (xy 390.70153 6.872732)
			(xy 390.701117 6.836969) (xy 396.558757 6.836969) (xy 396.558757 6.922719) (xy 396.566669 7.008102)
			(xy 396.582425 7.092392) (xy 396.605892 7.174868) (xy 396.636868 7.254827) (xy 396.67509 7.331587)
			(xy 396.720231 7.404493) (xy 396.771907 7.472922) (xy 396.829676 7.536292) (xy 396.893046 7.594061)
			(xy 396.961475 7.645737) (xy 397.034381 7.690878) (xy 397.111141 7.7291) (xy 397.1911 7.760076) (xy 397.273576 7.783543)
			(xy 397.357866 7.799299) (xy 397.443249 7.807211) (xy 397.528999 7.807211) (xy 397.614382 7.799299)
			(xy 397.698672 7.783543) (xy 397.781148 7.760076) (xy 397.861107 7.7291) (xy 397.88331 7.718044)
			(xy 401.493736 7.718044) (xy 401.493736 8.581644) (xy 401.494222 8.608913) (xy 401.501984 8.662897)
			(xy 401.517349 8.715227) (xy 401.540006 8.764837) (xy 401.569492 8.810718) (xy 401.605207 8.851935)
			(xy 401.646424 8.88765) (xy 401.692305 8.917136) (xy 401.741915 8.939793) (xy 401.794245 8.955158)
			(xy 401.848229 8.96292) (xy 401.902767 8.96292) (xy 401.956751 8.955158) (xy 402.009081 8.939793)
			(xy 402.058691 8.917136) (xy 402.104572 8.88765) (xy 402.145789 8.851935) (xy 402.181504 8.810718)
			(xy 402.21099 8.764837) (xy 402.233647 8.715227) (xy 402.249012 8.662897) (xy 402.256774 8.608913)
			(xy 402.25726 8.581644) (xy 402.25726 7.718044) (xy 402.256774 7.690775) (xy 402.249012 7.636791)
			(xy 402.233647 7.584461) (xy 402.21099 7.534851) (xy 402.181504 7.48897) (xy 402.145789 7.447753)
			(xy 402.104572 7.412038) (xy 402.058691 7.382552) (xy 402.009081 7.359895) (xy 401.956751 7.34453)
			(xy 401.902767 7.336768) (xy 401.848229 7.336768) (xy 401.794245 7.34453) (xy 401.741915 7.359895)
			(xy 401.692305 7.382552) (xy 401.646424 7.412038) (xy 401.605207 7.447753) (xy 401.569492 7.48897)
			(xy 401.540006 7.534851) (xy 401.517349 7.584461) (xy 401.501984 7.636791) (xy 401.494222 7.690775)
			(xy 401.493736 7.718044) (xy 397.88331 7.718044) (xy 397.937867 7.690878) (xy 398.010773 7.645737)
			(xy 398.079202 7.594061) (xy 398.142572 7.536292) (xy 398.200341 7.472922) (xy 398.252017 7.404493)
			(xy 398.297158 7.331587) (xy 398.33538 7.254827) (xy 398.366356 7.174868) (xy 398.389823 7.092392)
			(xy 398.405579 7.008102) (xy 398.413491 6.922719) (xy 398.413986 6.879844) (xy 398.413491 6.836969)
			(xy 402.908757 6.836969) (xy 402.908757 6.922719) (xy 402.916669 7.008102) (xy 402.932425 7.092392)
			(xy 402.955892 7.174868) (xy 402.986868 7.254827) (xy 403.02509 7.331587) (xy 403.070231 7.404493)
			(xy 403.121907 7.472922) (xy 403.179676 7.536292) (xy 403.243046 7.594061) (xy 403.311475 7.645737)
			(xy 403.384381 7.690878) (xy 403.461141 7.7291) (xy 403.5411 7.760076) (xy 403.623576 7.783543) (xy 403.707866 7.799299)
			(xy 403.793249 7.807211) (xy 403.878999 7.807211) (xy 403.964382 7.799299) (xy 404.048672 7.783543)
			(xy 404.131148 7.760076) (xy 404.211107 7.7291) (xy 404.287867 7.690878) (xy 404.360773 7.645737)
			(xy 404.429202 7.594061) (xy 404.492572 7.536292) (xy 404.550341 7.472922) (xy 404.602017 7.404493)
			(xy 404.647158 7.331587) (xy 404.68538 7.254827) (xy 404.716356 7.174868) (xy 404.739823 7.092392)
			(xy 404.755579 7.008102) (xy 404.763491 6.922719) (xy 404.763986 6.879844) (xy 404.76379 6.862877)
			(xy 454.759301 6.862877) (xy 454.759301 6.948627) (xy 454.767213 7.03401) (xy 454.782969 7.1183)
			(xy 454.806436 7.200776) (xy 454.837412 7.280735) (xy 454.875634 7.357495) (xy 454.920775 7.430401)
			(xy 454.972451 7.49883) (xy 455.03022 7.5622) (xy 455.09359 7.619969) (xy 455.162019 7.671645) (xy 455.234925 7.716786)
			(xy 455.311685 7.755008) (xy 455.391644 7.785984) (xy 455.47412 7.809451) (xy 455.55841 7.825207)
			(xy 455.643793 7.833119) (xy 455.729543 7.833119) (xy 455.814926 7.825207) (xy 455.899216 7.809451)
			(xy 455.981692 7.785984) (xy 456.061651 7.755008) (xy 456.083854 7.743952) (xy 457.265532 7.743952)
			(xy 457.265532 8.607552) (xy 457.266018 8.634821) (xy 457.27378 8.688805) (xy 457.289145 8.741135)
			(xy 457.311802 8.790745) (xy 457.341288 8.836626) (xy 457.377003 8.877843) (xy 457.41822 8.913558)
			(xy 457.464101 8.943044) (xy 457.513711 8.965701) (xy 457.566041 8.981066) (xy 457.620025 8.988828)
			(xy 457.674563 8.988828) (xy 457.728547 8.981066) (xy 457.780877 8.965701) (xy 457.830487 8.943044)
			(xy 457.876368 8.913558) (xy 457.917585 8.877843) (xy 457.9533 8.836626) (xy 457.982786 8.790745)
			(xy 458.005443 8.741135) (xy 458.020808 8.688805) (xy 458.02857 8.634821) (xy 458.029056 8.607552)
			(xy 458.029056 7.743952) (xy 458.02857 7.716683) (xy 458.020808 7.662699) (xy 458.005443 7.610369)
			(xy 457.982786 7.560759) (xy 457.9533 7.514878) (xy 457.917585 7.473661) (xy 457.876368 7.437946)
			(xy 457.830487 7.40846) (xy 457.780877 7.385803) (xy 457.728547 7.370438) (xy 457.674563 7.362676)
			(xy 457.620025 7.362676) (xy 457.566041 7.370438) (xy 457.513711 7.385803) (xy 457.464101 7.40846)
			(xy 457.41822 7.437946) (xy 457.377003 7.473661) (xy 457.341288 7.514878) (xy 457.311802 7.560759)
			(xy 457.289145 7.610369) (xy 457.27378 7.662699) (xy 457.266018 7.716683) (xy 457.265532 7.743952)
			(xy 456.083854 7.743952) (xy 456.138411 7.716786) (xy 456.211317 7.671645) (xy 456.279746 7.619969)
			(xy 456.343116 7.5622) (xy 456.400885 7.49883) (xy 456.452561 7.430401) (xy 456.497702 7.357495)
			(xy 456.535924 7.280735) (xy 456.5669 7.200776) (xy 456.590367 7.1183) (xy 456.606123 7.03401) (xy 456.614035 6.948627)
			(xy 456.61453 6.905752) (xy 456.614035 6.862877) (xy 461.109301 6.862877) (xy 461.109301 6.948627)
			(xy 461.117213 7.03401) (xy 461.132969 7.1183) (xy 461.156436 7.200776) (xy 461.187412 7.280735)
			(xy 461.225634 7.357495) (xy 461.270775 7.430401) (xy 461.322451 7.49883) (xy 461.38022 7.5622) (xy 461.44359 7.619969)
			(xy 461.512019 7.671645) (xy 461.584925 7.716786) (xy 461.661685 7.755008) (xy 461.741644 7.785984)
			(xy 461.82412 7.809451) (xy 461.90841 7.825207) (xy 461.993793 7.833119) (xy 462.079543 7.833119)
			(xy 462.164926 7.825207) (xy 462.249216 7.809451) (xy 462.331692 7.785984) (xy 462.411651 7.755008)
			(xy 462.488411 7.716786) (xy 462.561317 7.671645) (xy 462.629746 7.619969) (xy 462.693116 7.5622)
			(xy 462.750885 7.49883) (xy 462.802561 7.430401) (xy 462.847702 7.357495) (xy 462.885924 7.280735)
			(xy 462.9169 7.200776) (xy 462.940367 7.1183) (xy 462.956123 7.03401) (xy 462.964035 6.948627) (xy 462.96453 6.905752)
			(xy 462.964035 6.862877) (xy 462.956123 6.777494) (xy 462.940367 6.693204) (xy 462.9169 6.610728)
			(xy 462.885924 6.530769) (xy 462.847702 6.454009) (xy 462.802561 6.381103) (xy 462.750885 6.312674)
			(xy 462.693116 6.249304) (xy 462.629746 6.191535) (xy 462.561317 6.139859) (xy 462.488411 6.094718)
			(xy 462.411651 6.056496) (xy 462.331692 6.02552) (xy 462.249216 6.002053) (xy 462.164926 5.986297)
			(xy 462.079543 5.978385) (xy 461.993793 5.978385) (xy 461.90841 5.986297) (xy 461.82412 6.002053)
			(xy 461.741644 6.02552) (xy 461.661685 6.056496) (xy 461.584925 6.094718) (xy 461.512019 6.139859)
			(xy 461.44359 6.191535) (xy 461.38022 6.249304) (xy 461.322451 6.312674) (xy 461.270775 6.381103)
			(xy 461.225634 6.454009) (xy 461.187412 6.530769) (xy 461.156436 6.610728) (xy 461.132969 6.693204)
			(xy 461.117213 6.777494) (xy 461.109301 6.862877) (xy 456.614035 6.862877) (xy 456.606123 6.777494)
			(xy 456.590367 6.693204) (xy 456.5669 6.610728) (xy 456.535924 6.530769) (xy 456.497702 6.454009)
			(xy 456.452561 6.381103) (xy 456.400885 6.312674) (xy 456.343116 6.249304) (xy 456.279746 6.191535)
			(xy 456.211317 6.139859) (xy 456.138411 6.094718) (xy 456.061651 6.056496) (xy 455.981692 6.02552)
			(xy 455.899216 6.002053) (xy 455.814926 5.986297) (xy 455.729543 5.978385) (xy 455.643793 5.978385)
			(xy 455.55841 5.986297) (xy 455.47412 6.002053) (xy 455.391644 6.02552) (xy 455.311685 6.056496)
			(xy 455.234925 6.094718) (xy 455.162019 6.139859) (xy 455.09359 6.191535) (xy 455.03022 6.249304)
			(xy 454.972451 6.312674) (xy 454.920775 6.381103) (xy 454.875634 6.454009) (xy 454.837412 6.530769)
			(xy 454.806436 6.610728) (xy 454.782969 6.693204) (xy 454.767213 6.777494) (xy 454.759301 6.862877)
			(xy 404.76379 6.862877) (xy 404.763491 6.836969) (xy 404.755579 6.751586) (xy 404.739823 6.667296)
			(xy 404.716356 6.58482) (xy 404.68538 6.504861) (xy 404.647158 6.428101) (xy 404.602017 6.355195)
			(xy 404.550341 6.286766) (xy 404.492572 6.223396) (xy 404.429202 6.165627) (xy 404.360773 6.113951)
			(xy 404.287867 6.06881) (xy 404.211107 6.030588) (xy 404.131148 5.999612) (xy 404.048672 5.976145)
			(xy 403.964382 5.960389) (xy 403.878999 5.952477) (xy 403.793249 5.952477) (xy 403.707866 5.960389)
			(xy 403.623576 5.976145) (xy 403.5411 5.999612) (xy 403.461141 6.030588) (xy 403.384381 6.06881)
			(xy 403.311475 6.113951) (xy 403.243046 6.165627) (xy 403.179676 6.223396) (xy 403.121907 6.286766)
			(xy 403.070231 6.355195) (xy 403.02509 6.428101) (xy 402.986868 6.504861) (xy 402.955892 6.58482)
			(xy 402.932425 6.667296) (xy 402.916669 6.751586) (xy 402.908757 6.836969) (xy 398.413491 6.836969)
			(xy 398.405579 6.751586) (xy 398.389823 6.667296) (xy 398.366356 6.58482) (xy 398.33538 6.504861)
			(xy 398.297158 6.428101) (xy 398.252017 6.355195) (xy 398.200341 6.286766) (xy 398.142572 6.223396)
			(xy 398.079202 6.165627) (xy 398.010773 6.113951) (xy 397.937867 6.06881) (xy 397.861107 6.030588)
			(xy 397.781148 5.999612) (xy 397.698672 5.976145) (xy 397.614382 5.960389) (xy 397.528999 5.952477)
			(xy 397.443249 5.952477) (xy 397.357866 5.960389) (xy 397.273576 5.976145) (xy 397.1911 5.999612)
			(xy 397.111141 6.030588) (xy 397.034381 6.06881) (xy 396.961475 6.113951) (xy 396.893046 6.165627)
			(xy 396.829676 6.223396) (xy 396.771907 6.286766) (xy 396.720231 6.355195) (xy 396.67509 6.428101)
			(xy 396.636868 6.504861) (xy 396.605892 6.58482) (xy 396.582425 6.667296) (xy 396.566669 6.751586)
			(xy 396.558757 6.836969) (xy 390.701117 6.836969) (xy 390.701035 6.829857) (xy 390.693123 6.744474)
			(xy 390.677367 6.660184) (xy 390.6539 6.577708) (xy 390.622924 6.497749) (xy 390.584702 6.420989)
			(xy 390.539561 6.348083) (xy 390.487885 6.279654) (xy 390.430116 6.216284) (xy 390.366746 6.158515)
			(xy 390.298317 6.106839) (xy 390.225411 6.061698) (xy 390.148651 6.023476) (xy 390.068692 5.9925)
			(xy 389.986216 5.969033) (xy 389.901926 5.953277) (xy 389.816543 5.945365) (xy 389.730793 5.945365)
			(xy 389.64541 5.953277) (xy 389.56112 5.969033) (xy 389.478644 5.9925) (xy 389.398685 6.023476) (xy 389.321925 6.061698)
			(xy 389.249019 6.106839) (xy 389.18059 6.158515) (xy 389.11722 6.216284) (xy 389.059451 6.279654)
			(xy 389.007775 6.348083) (xy 388.962634 6.420989) (xy 388.924412 6.497749) (xy 388.893436 6.577708)
			(xy 388.869969 6.660184) (xy 388.854213 6.744474) (xy 388.846301 6.829857) (xy 384.351035 6.829857)
			(xy 384.343123 6.744474) (xy 384.327367 6.660184) (xy 384.3039 6.577708) (xy 384.272924 6.497749)
			(xy 384.234702 6.420989) (xy 384.189561 6.348083) (xy 384.137885 6.279654) (xy 384.080116 6.216284)
			(xy 384.016746 6.158515) (xy 383.948317 6.106839) (xy 383.875411 6.061698) (xy 383.798651 6.023476)
			(xy 383.718692 5.9925) (xy 383.636216 5.969033) (xy 383.551926 5.953277) (xy 383.466543 5.945365)
			(xy 383.380793 5.945365) (xy 383.29541 5.953277) (xy 383.21112 5.969033) (xy 383.128644 5.9925) (xy 383.048685 6.023476)
			(xy 382.971925 6.061698) (xy 382.899019 6.106839) (xy 382.83059 6.158515) (xy 382.76722 6.216284)
			(xy 382.709451 6.279654) (xy 382.657775 6.348083) (xy 382.612634 6.420989) (xy 382.574412 6.497749)
			(xy 382.543436 6.577708) (xy 382.519969 6.660184) (xy 382.504213 6.744474) (xy 382.496301 6.829857)
			(xy 332.50079 6.829857) (xy 332.500491 6.803949) (xy 332.492579 6.718566) (xy 332.476823 6.634276)
			(xy 332.453356 6.5518) (xy 332.42238 6.471841) (xy 332.384158 6.395081) (xy 332.339017 6.322175)
			(xy 332.287341 6.253746) (xy 332.229572 6.190376) (xy 332.166202 6.132607) (xy 332.097773 6.080931)
			(xy 332.024867 6.03579) (xy 331.948107 5.997568) (xy 331.868148 5.966592) (xy 331.785672 5.943125)
			(xy 331.701382 5.927369) (xy 331.615999 5.919457) (xy 331.530249 5.919457) (xy 331.444866 5.927369)
			(xy 331.360576 5.943125) (xy 331.2781 5.966592) (xy 331.198141 5.997568) (xy 331.121381 6.03579)
			(xy 331.048475 6.080931) (xy 330.980046 6.132607) (xy 330.916676 6.190376) (xy 330.858907 6.253746)
			(xy 330.807231 6.322175) (xy 330.76209 6.395081) (xy 330.723868 6.471841) (xy 330.692892 6.5518)
			(xy 330.669425 6.634276) (xy 330.653669 6.718566) (xy 330.645757 6.803949) (xy 326.150491 6.803949)
			(xy 326.142579 6.718566) (xy 326.126823 6.634276) (xy 326.103356 6.5518) (xy 326.07238 6.471841)
			(xy 326.034158 6.395081) (xy 325.989017 6.322175) (xy 325.937341 6.253746) (xy 325.879572 6.190376)
			(xy 325.816202 6.132607) (xy 325.747773 6.080931) (xy 325.674867 6.03579) (xy 325.598107 5.997568)
			(xy 325.518148 5.966592) (xy 325.435672 5.943125) (xy 325.351382 5.927369) (xy 325.265999 5.919457)
			(xy 325.180249 5.919457) (xy 325.094866 5.927369) (xy 325.010576 5.943125) (xy 324.9281 5.966592)
			(xy 324.848141 5.997568) (xy 324.771381 6.03579) (xy 324.698475 6.080931) (xy 324.630046 6.132607)
			(xy 324.566676 6.190376) (xy 324.508907 6.253746) (xy 324.457231 6.322175) (xy 324.41209 6.395081)
			(xy 324.373868 6.471841) (xy 324.342892 6.5518) (xy 324.319425 6.634276) (xy 324.303669 6.718566)
			(xy 324.295757 6.803949) (xy 317.930117 6.803949) (xy 317.930035 6.796837) (xy 317.922123 6.711454)
			(xy 317.906367 6.627164) (xy 317.8829 6.544688) (xy 317.851924 6.464729) (xy 317.813702 6.387969)
			(xy 317.768561 6.315063) (xy 317.716885 6.246634) (xy 317.659116 6.183264) (xy 317.595746 6.125495)
			(xy 317.527317 6.073819) (xy 317.454411 6.028678) (xy 317.377651 5.990456) (xy 317.297692 5.95948)
			(xy 317.215216 5.936013) (xy 317.130926 5.920257) (xy 317.045543 5.912345) (xy 316.959793 5.912345)
			(xy 316.87441 5.920257) (xy 316.79012 5.936013) (xy 316.707644 5.95948) (xy 316.627685 5.990456)
			(xy 316.550925 6.028678) (xy 316.478019 6.073819) (xy 316.40959 6.125495) (xy 316.34622 6.183264)
			(xy 316.288451 6.246634) (xy 316.236775 6.315063) (xy 316.191634 6.387969) (xy 316.153412 6.464729)
			(xy 316.122436 6.544688) (xy 316.098969 6.627164) (xy 316.083213 6.711454) (xy 316.075301 6.796837)
			(xy 311.580035 6.796837) (xy 311.572123 6.711454) (xy 311.556367 6.627164) (xy 311.5329 6.544688)
			(xy 311.501924 6.464729) (xy 311.463702 6.387969) (xy 311.418561 6.315063) (xy 311.366885 6.246634)
			(xy 311.309116 6.183264) (xy 311.245746 6.125495) (xy 311.177317 6.073819) (xy 311.104411 6.028678)
			(xy 311.027651 5.990456) (xy 310.947692 5.95948) (xy 310.865216 5.936013) (xy 310.780926 5.920257)
			(xy 310.695543 5.912345) (xy 310.609793 5.912345) (xy 310.52441 5.920257) (xy 310.44012 5.936013)
			(xy 310.357644 5.95948) (xy 310.277685 5.990456) (xy 310.200925 6.028678) (xy 310.128019 6.073819)
			(xy 310.05959 6.125495) (xy 309.99622 6.183264) (xy 309.938451 6.246634) (xy 309.886775 6.315063)
			(xy 309.841634 6.387969) (xy 309.803412 6.464729) (xy 309.772436 6.544688) (xy 309.748969 6.627164)
			(xy 309.733213 6.711454) (xy 309.725301 6.796837) (xy 259.72979 6.796837) (xy 259.729491 6.770929)
			(xy 259.721579 6.685546) (xy 259.705823 6.601256) (xy 259.682356 6.51878) (xy 259.65138 6.438821)
			(xy 259.613158 6.362061) (xy 259.568017 6.289155) (xy 259.516341 6.220726) (xy 259.458572 6.157356)
			(xy 259.395202 6.099587) (xy 259.326773 6.047911) (xy 259.253867 6.00277) (xy 259.177107 5.964548)
			(xy 259.097148 5.933572) (xy 259.014672 5.910105) (xy 258.930382 5.894349) (xy 258.844999 5.886437)
			(xy 258.759249 5.886437) (xy 258.673866 5.894349) (xy 258.589576 5.910105) (xy 258.5071 5.933572)
			(xy 258.427141 5.964548) (xy 258.350381 6.00277) (xy 258.277475 6.047911) (xy 258.209046 6.099587)
			(xy 258.145676 6.157356) (xy 258.087907 6.220726) (xy 258.036231 6.289155) (xy 257.99109 6.362061)
			(xy 257.952868 6.438821) (xy 257.921892 6.51878) (xy 257.898425 6.601256) (xy 257.882669 6.685546)
			(xy 257.874757 6.770929) (xy 253.379491 6.770929) (xy 253.371579 6.685546) (xy 253.355823 6.601256)
			(xy 253.332356 6.51878) (xy 253.30138 6.438821) (xy 253.263158 6.362061) (xy 253.218017 6.289155)
			(xy 253.166341 6.220726) (xy 253.108572 6.157356) (xy 253.045202 6.099587) (xy 252.976773 6.047911)
			(xy 252.903867 6.00277) (xy 252.827107 5.964548) (xy 252.747148 5.933572) (xy 252.664672 5.910105)
			(xy 252.580382 5.894349) (xy 252.494999 5.886437) (xy 252.409249 5.886437) (xy 252.323866 5.894349)
			(xy 252.239576 5.910105) (xy 252.1571 5.933572) (xy 252.077141 5.964548) (xy 252.000381 6.00277)
			(xy 251.927475 6.047911) (xy 251.859046 6.099587) (xy 251.795676 6.157356) (xy 251.737907 6.220726)
			(xy 251.686231 6.289155) (xy 251.64109 6.362061) (xy 251.602868 6.438821) (xy 251.571892 6.51878)
			(xy 251.548425 6.601256) (xy 251.532669 6.685546) (xy 251.524757 6.770929) (xy 245.921117 6.770929)
			(xy 245.921035 6.763817) (xy 245.913123 6.678434) (xy 245.897367 6.594144) (xy 245.8739 6.511668)
			(xy 245.842924 6.431709) (xy 245.804702 6.354949) (xy 245.759561 6.282043) (xy 245.707885 6.213614)
			(xy 245.650116 6.150244) (xy 245.586746 6.092475) (xy 245.518317 6.040799) (xy 245.445411 5.995658)
			(xy 245.368651 5.957436) (xy 245.288692 5.92646) (xy 245.206216 5.902993) (xy 245.121926 5.887237)
			(xy 245.036543 5.879325) (xy 244.950793 5.879325) (xy 244.86541 5.887237) (xy 244.78112 5.902993)
			(xy 244.698644 5.92646) (xy 244.618685 5.957436) (xy 244.541925 5.995658) (xy 244.469019 6.040799)
			(xy 244.40059 6.092475) (xy 244.33722 6.150244) (xy 244.279451 6.213614) (xy 244.227775 6.282043)
			(xy 244.182634 6.354949) (xy 244.144412 6.431709) (xy 244.113436 6.511668) (xy 244.089969 6.594144)
			(xy 244.074213 6.678434) (xy 244.066301 6.763817) (xy 239.571035 6.763817) (xy 239.563123 6.678434)
			(xy 239.547367 6.594144) (xy 239.5239 6.511668) (xy 239.492924 6.431709) (xy 239.454702 6.354949)
			(xy 239.409561 6.282043) (xy 239.357885 6.213614) (xy 239.300116 6.150244) (xy 239.236746 6.092475)
			(xy 239.168317 6.040799) (xy 239.095411 5.995658) (xy 239.018651 5.957436) (xy 238.938692 5.92646)
			(xy 238.856216 5.902993) (xy 238.771926 5.887237) (xy 238.686543 5.879325) (xy 238.600793 5.879325)
			(xy 238.51541 5.887237) (xy 238.43112 5.902993) (xy 238.348644 5.92646) (xy 238.268685 5.957436)
			(xy 238.191925 5.995658) (xy 238.119019 6.040799) (xy 238.05059 6.092475) (xy 237.98722 6.150244)
			(xy 237.929451 6.213614) (xy 237.877775 6.282043) (xy 237.832634 6.354949) (xy 237.794412 6.431709)
			(xy 237.763436 6.511668) (xy 237.739969 6.594144) (xy 237.724213 6.678434) (xy 237.716301 6.763817)
			(xy 187.719832 6.763817) (xy 187.712579 6.685546) (xy 187.696823 6.601256) (xy 187.673356 6.51878)
			(xy 187.64238 6.438821) (xy 187.604158 6.362061) (xy 187.559017 6.289155) (xy 187.507341 6.220726)
			(xy 187.449572 6.157356) (xy 187.386202 6.099587) (xy 187.317773 6.047911) (xy 187.244867 6.00277)
			(xy 187.168107 5.964548) (xy 187.088148 5.933572) (xy 187.005672 5.910105) (xy 186.921382 5.894349)
			(xy 186.835999 5.886437) (xy 186.750249 5.886437) (xy 186.664866 5.894349) (xy 186.580576 5.910105)
			(xy 186.4981 5.933572) (xy 186.418141 5.964548) (xy 186.341381 6.00277) (xy 186.268475 6.047911)
			(xy 186.200046 6.099587) (xy 186.136676 6.157356) (xy 186.078907 6.220726) (xy 186.027231 6.289155)
			(xy 185.98209 6.362061) (xy 185.943868 6.438821) (xy 185.912892 6.51878) (xy 185.889425 6.601256)
			(xy 185.873669 6.685546) (xy 185.865757 6.770929) (xy 181.370491 6.770929) (xy 181.362579 6.685546)
			(xy 181.346823 6.601256) (xy 181.323356 6.51878) (xy 181.29238 6.438821) (xy 181.254158 6.362061)
			(xy 181.209017 6.289155) (xy 181.157341 6.220726) (xy 181.099572 6.157356) (xy 181.036202 6.099587)
			(xy 180.967773 6.047911) (xy 180.894867 6.00277) (xy 180.818107 5.964548) (xy 180.738148 5.933572)
			(xy 180.655672 5.910105) (xy 180.571382 5.894349) (xy 180.485999 5.886437) (xy 180.400249 5.886437)
			(xy 180.314866 5.894349) (xy 180.230576 5.910105) (xy 180.1481 5.933572) (xy 180.068141 5.964548)
			(xy 179.991381 6.00277) (xy 179.918475 6.047911) (xy 179.850046 6.099587) (xy 179.786676 6.157356)
			(xy 179.728907 6.220726) (xy 179.677231 6.289155) (xy 179.63209 6.362061) (xy 179.593868 6.438821)
			(xy 179.562892 6.51878) (xy 179.539425 6.601256) (xy 179.523669 6.685546) (xy 179.515757 6.770929)
			(xy 158.039844 6.770929) (xy 158.030561 6.759289) (xy 157.936801 6.654373) (xy 157.837306 6.554879)
			(xy 157.732388 6.46112) (xy 157.622379 6.373391) (xy 157.507624 6.291969) (xy 157.388483 6.21711)
			(xy 157.265333 6.149048) (xy 157.138561 6.087998) (xy 157.008565 6.034153) (xy 156.875754 5.987681)
			(xy 156.740546 5.948729) (xy 156.603367 5.91742) (xy 156.464649 5.893851) (xy 156.324827 5.878098)
			(xy 156.184341 5.870209) (xy 156.113988 5.869686) (xy 17.493996 5.869686) (xy 17.423642 5.870179)
			(xy 17.283156 5.878069) (xy 17.143333 5.893824) (xy 17.004613 5.917393) (xy 16.867433 5.948703) (xy 16.732225 5.987656)
			(xy 16.599413 6.034129) (xy 16.469416 6.087976) (xy 16.342643 6.149026) (xy 16.219492 6.217089) (xy 16.100351 6.29195)
			(xy 15.985596 6.373373) (xy 15.875586 6.461103) (xy 15.770668 6.554863) (xy 15.671172 6.654358) (xy 15.577412 6.759275)
			(xy 15.489682 6.869284) (xy 15.408258 6.98404) (xy 15.333396 7.10318) (xy 15.265333 7.22633) (xy 15.204281 7.353103)
			(xy 15.150434 7.4831) (xy 15.103961 7.615912) (xy 15.065007 7.75112) (xy 15.033696 7.8883) (xy 15.010125 8.027019)
			(xy 14.99437 8.166842) (xy 14.98648 8.307328) (xy 14.986 8.377682) (xy 14.986 24.157686) (xy 14.985478 24.213493)
			(xy 14.977137 24.324795) (xy 14.960501 24.435162) (xy 14.935664 24.543977) (xy 14.902765 24.650632)
			(xy 14.861988 24.754531) (xy 14.81356 24.855091) (xy 14.757753 24.951752) (xy 14.694879 25.043971)
			(xy 14.625289 25.131234) (xy 14.549372 25.213053) (xy 14.467553 25.28897) (xy 14.38029 25.35856)
			(xy 14.28807 25.421434) (xy 14.19141 25.477241) (xy 14.090849 25.525669) (xy 13.986951 25.566446)
			(xy 13.880295 25.599345) (xy 13.77148 25.624182) (xy 13.661113 25.640817) (xy 13.549811 25.649158)
			(xy 13.494004 25.649682) (xy 1.999996 25.649682) (xy 1.944189 25.64916) (xy 1.832887 25.640819) (xy 1.72252 25.624184)
			(xy 1.613704 25.599347) (xy 1.507049 25.566448) (xy 1.40315 25.525671) (xy 1.30259 25.477243) (xy 1.205929 25.421436)
			(xy 1.113709 25.358562) (xy 1.026446 25.288971) (xy 0.944627 25.213055) (xy 0.86871 25.131236) (xy 0.79912 25.043972)
			(xy 0.736245 24.951753) (xy 0.680438 24.855092) (xy 0.63201 24.754532) (xy 0.591233 24.650633) (xy 0.558334 24.543978)
			(xy 0.533497 24.435162) (xy 0.516861 24.324795) (xy 0.50852 24.213493) (xy 0.508 24.157686) (xy 0.508 21.093122)
			(xy 2.904225 21.093122) (xy 2.904225 21.222262) (xy 2.912175 21.351157) (xy 2.928045 21.479317) (xy 2.951774 21.606258)
			(xy 2.983273 21.731497) (xy 3.022422 21.85456) (xy 3.069073 21.974979) (xy 3.123048 22.092298) (xy 3.184143 22.206072)
			(xy 3.252126 22.315869) (xy 3.32674 22.421272) (xy 3.407701 22.521882) (xy 3.494701 22.617317) (xy 3.587412 22.707216)
			(xy 3.685482 22.791237) (xy 3.788537 22.869061) (xy 3.896188 22.940393) (xy 4.008027 23.004963) (xy 4.123628 23.062525)
			(xy 4.242553 23.112862) (xy 4.364352 23.155782) (xy 4.488562 23.191123) (xy 4.614711 23.21875) (xy 4.742323 23.238559)
			(xy 4.870912 23.250475) (xy 4.99999 23.254452) (xy 5.129068 23.250475) (xy 5.257657 23.238559) (xy 5.385269 23.21875)
			(xy 5.511418 23.191123) (xy 5.635628 23.155782) (xy 5.757427 23.112862) (xy 5.876352 23.062525) (xy 5.991953 23.004963)
			(xy 6.103792 22.940393) (xy 6.211443 22.869061) (xy 6.314498 22.791237) (xy 6.412568 22.707216) (xy 6.505279 22.617317)
			(xy 6.592279 22.521882) (xy 6.67324 22.421272) (xy 6.747854 22.315869) (xy 6.815837 22.206072) (xy 6.876932 22.092298)
			(xy 6.930907 21.974979) (xy 6.977558 21.85456) (xy 7.016707 21.731497) (xy 7.048206 21.606258) (xy 7.071935 21.479317)
			(xy 7.087805 21.351157) (xy 7.095755 21.222262) (xy 7.096252 21.157692) (xy 7.095755 21.093122) (xy 7.087805 20.964227)
			(xy 7.071935 20.836067) (xy 7.048206 20.709126) (xy 7.016707 20.583887) (xy 6.977558 20.460824) (xy 6.930907 20.340405)
			(xy 6.876932 20.223086) (xy 6.815837 20.109312) (xy 6.747854 19.999515) (xy 6.67324 19.894112) (xy 6.592279 19.793502)
			(xy 6.505279 19.698067) (xy 6.412568 19.608168) (xy 6.314498 19.524147) (xy 6.211443 19.446323) (xy 6.103792 19.374991)
			(xy 5.991953 19.310421) (xy 5.876352 19.252859) (xy 5.757427 19.202522) (xy 5.635628 19.159602) (xy 5.511418 19.124261)
			(xy 5.385269 19.096634) (xy 5.257657 19.076825) (xy 5.129068 19.064909) (xy 4.99999 19.060933) (xy 4.870912 19.064909)
			(xy 4.742323 19.076825) (xy 4.614711 19.096634) (xy 4.488562 19.124261) (xy 4.364352 19.159602) (xy 4.242553 19.202522)
			(xy 4.123628 19.252859) (xy 4.008027 19.310421) (xy 3.896188 19.374991) (xy 3.788537 19.446323) (xy 3.685482 19.524147)
			(xy 3.587412 19.608168) (xy 3.494701 19.698067) (xy 3.407701 19.793502) (xy 3.32674 19.894112) (xy 3.252126 19.999515)
			(xy 3.184143 20.109312) (xy 3.123048 20.223086) (xy 3.069073 20.340405) (xy 3.022422 20.460824) (xy 2.983273 20.583887)
			(xy 2.951774 20.709126) (xy 2.928045 20.836067) (xy 2.912175 20.964227) (xy 2.904225 21.093122) (xy 0.508 21.093122)
			(xy 0.508 3.999992) (xy 0.508522 3.944185) (xy 0.516863 3.832883) (xy 0.533498 3.722516) (xy 0.558335 3.6137)
			(xy 0.591234 3.507045) (xy 0.632011 3.403146) (xy 0.680438 3.302586) (xy 0.736246 3.205925) (xy 0.79912 3.113705)
			(xy 0.86871 3.026442) (xy 0.944627 2.944623) (xy 1.026446 2.868706) (xy 1.113709 2.799116) (xy 1.205929 2.736242)
			(xy 1.30259 2.680434) (xy 1.40315 2.632007) (xy 1.507049 2.59123) (xy 1.613704 2.558331) (xy 1.72252 2.533494)
			(xy 1.832887 2.516859) (xy 1.944189 2.508518) (xy 1.999996 2.507996) (xy 7.964932 2.507996) (xy 8.035286 2.507503)
			(xy 8.175772 2.499613) (xy 8.315594 2.483859) (xy 8.454314 2.460289) (xy 8.591493 2.428979) (xy 8.726701 2.390026)
			(xy 8.859513 2.343553) (xy 8.989509 2.289707) (xy 9.116282 2.228656) (xy 9.239433 2.160593) (xy 9.358573 2.085732)
			(xy 9.473329 2.004309) (xy 9.583338 1.916579) (xy 9.688255 1.822819) (xy 9.78775 1.723324) (xy 9.88151 1.618406)
			(xy 9.96924 1.508397) (xy 10.050663 1.393641) (xy 10.125524 1.274501) (xy 10.193587 1.151351) (xy 10.254637 1.024578)
			(xy 10.308484 0.894581) (xy 10.354957 0.76177) (xy 10.393909 0.626561) (xy 10.42522 0.489382) (xy 10.448789 0.350662)
			(xy 10.464543 0.21084) (xy 10.472433 0.070354) (xy 10.472928 0) (xy 10.472928 -8.850122) (xy 10.47345 -8.905929)
			(xy 10.481791 -9.017231) (xy 10.498426 -9.127599) (xy 10.523263 -9.236414) (xy 10.556162 -9.34307)
			(xy 10.596939 -9.446968) (xy 10.645366 -9.547529) (xy 10.701173 -9.64419) (xy 10.764048 -9.73641)
			(xy 10.833638 -9.823673) (xy 10.909555 -9.905492) (xy 10.991374 -9.981409) (xy 11.078637 -10.051)
			(xy 11.170857 -10.113875) (xy 11.267517 -10.169682) (xy 11.368078 -10.21811) (xy 11.471977 -10.258887)
			(xy 11.578632 -10.291786) (xy 11.687448 -10.316623) (xy 11.797815 -10.333259) (xy 11.909117 -10.3416)
			(xy 11.964924 -10.342118)
		)
		(stroke
			(width 0)
			(type solid)
		)
		(fill yes)
		(layer "In2.Cu")
		(net "COUPON_GND2")
	)
	(gr_poly
		(pts
			(xy 5.34797 -57.917334) (xy 5.354573 -57.917112) (xy 5.367314 -57.913636) (xy 5.373116 -57.910476)
			(xy 5.37337 -57.910476) (xy 5.399786 -57.89549) (xy 5.404612 -57.89041) (xy 5.409438 -57.885584)
			(xy 5.412486 -57.88025) (xy 5.427362 -57.856341) (xy 5.463038 -57.812775) (xy 5.504727 -57.774923)
			(xy 5.551524 -57.743605) (xy 5.602414 -57.719503) (xy 5.656293 -57.703138) (xy 5.711991 -57.694865)
			(xy 5.768301 -57.694865) (xy 5.823999 -57.703138) (xy 5.877878 -57.719503) (xy 5.928768 -57.743605)
			(xy 5.975565 -57.774923) (xy 6.017254 -57.812775) (xy 6.05293 -57.856341) (xy 6.067806 -57.88025)
			(xy 6.070854 -57.885584) (xy 6.07568 -57.89041) (xy 6.080506 -57.89549) (xy 6.106922 -57.910476)
			(xy 6.107176 -57.910476) (xy 6.112996 -57.913589) (xy 6.125727 -57.917051) (xy 6.132322 -57.917334)
			(xy 13.02893 -57.917334) (xy 13.038996 -57.916904) (xy 13.057587 -57.909174) (xy 13.064998 -57.902348)
			(xy 13.507466 -57.45988) (xy 13.513551 -57.453366) (xy 13.521095 -57.43723) (xy 13.522198 -57.428384)
			(xy 13.52511 -57.400013) (xy 13.538346 -57.344538) (xy 13.559709 -57.291659) (xy 13.57376 -57.26684)
			(xy 13.577062 -57.261252) (xy 13.58265 -57.241948) (xy 13.584682 -57.234836) (xy 13.584682 -57.06364)
			(xy 13.584174 -57.056528) (xy 13.58265 -57.04586) (xy 13.577062 -57.026556) (xy 13.57376 -57.020968)
			(xy 13.561176 -56.998834) (xy 13.541337 -56.951942) (xy 13.527903 -56.90283) (xy 13.521112 -56.85237)
			(xy 13.520674 -56.826912) (xy 13.520674 -56.825896) (xy 13.521092 -56.800436) (xy 13.527863 -56.749968)
			(xy 13.541297 -56.700853) (xy 13.561156 -56.653965) (xy 13.57376 -56.63184) (xy 13.577062 -56.626252)
			(xy 13.58265 -56.606948) (xy 13.584682 -56.599836) (xy 13.584682 -54.968648) (xy 13.584174 -54.961536)
			(xy 13.58265 -54.950868) (xy 13.577062 -54.931564) (xy 13.57376 -54.925976) (xy 13.561176 -54.903842)
			(xy 13.541336 -54.85695) (xy 13.527901 -54.807839) (xy 13.521108 -54.757378) (xy 13.520674 -54.73192)
			(xy 13.520674 -54.730904) (xy 13.521091 -54.705444) (xy 13.527862 -54.654976) (xy 13.541295 -54.60586)
			(xy 13.561152 -54.558971) (xy 13.57376 -54.536848) (xy 13.577062 -54.53126) (xy 13.58265 -54.511956)
			(xy 13.584682 -54.504844) (xy 13.584682 -54.333648) (xy 13.584174 -54.326536) (xy 13.58265 -54.315868)
			(xy 13.577062 -54.296564) (xy 13.57376 -54.290976) (xy 13.561176 -54.268842) (xy 13.541336 -54.22195)
			(xy 13.527901 -54.172839) (xy 13.521108 -54.122378) (xy 13.520674 -54.09692) (xy 13.520674 -54.095904)
			(xy 13.521091 -54.070444) (xy 13.527862 -54.019976) (xy 13.541295 -53.97086) (xy 13.561152 -53.923971)
			(xy 13.57376 -53.901848) (xy 13.577062 -53.89626) (xy 13.58265 -53.876956) (xy 13.584682 -53.869844)
			(xy 13.584682 -53.698648) (xy 13.584174 -53.691536) (xy 13.58265 -53.680868) (xy 13.577062 -53.661564)
			(xy 13.57376 -53.655976) (xy 13.561176 -53.633842) (xy 13.541336 -53.58695) (xy 13.527901 -53.537839)
			(xy 13.521108 -53.487378) (xy 13.520674 -53.46192) (xy 13.520674 -53.460904) (xy 13.521091 -53.435444)
			(xy 13.527862 -53.384976) (xy 13.541295 -53.33586) (xy 13.561152 -53.288971) (xy 13.57376 -53.266848)
			(xy 13.577062 -53.26126) (xy 13.58265 -53.241956) (xy 13.584682 -53.234844) (xy 13.584682 -53.063648)
			(xy 13.584174 -53.056536) (xy 13.58265 -53.045868) (xy 13.577062 -53.026564) (xy 13.57376 -53.020976)
			(xy 13.561176 -52.998842) (xy 13.541336 -52.95195) (xy 13.527901 -52.902839) (xy 13.521108 -52.852378)
			(xy 13.520674 -52.82692) (xy 13.520674 -52.825904) (xy 13.521091 -52.800444) (xy 13.527862 -52.749976)
			(xy 13.541295 -52.70086) (xy 13.561152 -52.653971) (xy 13.57376 -52.631848) (xy 13.577062 -52.62626)
			(xy 13.58265 -52.606956) (xy 13.584682 -52.599844) (xy 13.584682 -50.415698) (xy 13.585171 -50.390749)
			(xy 13.592977 -50.341464) (xy 13.608396 -50.294008) (xy 13.631049 -50.249547) (xy 13.660378 -50.209177)
			(xy 13.677646 -50.191162) (xy 14.023594 -49.845214) (xy 14.041594 -49.827933) (xy 14.081979 -49.798631)
			(xy 14.126445 -49.775998) (xy 14.173902 -49.760589) (xy 14.223182 -49.752783) (xy 14.24813 -49.75225)
			(xy 26.950924 -49.75225) (xy 26.957011 -49.752042) (xy 26.968823 -49.749089) (xy 26.974292 -49.746408)
			(xy 26.994358 -49.735994) (xy 27.00274 -49.73066) (xy 27.00782 -49.726596) (xy 27.011376 -49.72177)
			(xy 27.028045 -49.700645) (xy 27.066337 -49.662839) (xy 27.109558 -49.630785) (xy 27.156852 -49.605117)
			(xy 27.207282 -49.586345) (xy 27.259848 -49.574839) (xy 27.313509 -49.570828) (xy 27.367201 -49.574392)
			(xy 27.419861 -49.58546) (xy 27.470445 -49.603812) (xy 27.517951 -49.629085) (xy 27.561438 -49.660778)
			(xy 27.600043 -49.698264) (xy 27.616912 -49.71923) (xy 27.621484 -49.725834) (xy 27.62758 -49.73066)
			(xy 27.635962 -49.735994) (xy 27.656028 -49.746408) (xy 27.661501 -49.749076) (xy 27.673311 -49.752018)
			(xy 27.679396 -49.75225) (xy 52.950872 -49.75225) (xy 52.956957 -49.752036) (xy 52.968764 -49.749073)
			(xy 52.97424 -49.746408) (xy 52.994306 -49.735994) (xy 53.002688 -49.73066) (xy 53.007768 -49.726596)
			(xy 53.011324 -49.72177) (xy 53.027993 -49.700641) (xy 53.066286 -49.662829) (xy 53.109509 -49.630767)
			(xy 53.156806 -49.605093) (xy 53.20724 -49.586314) (xy 53.25981 -49.574802) (xy 53.313477 -49.570787)
			(xy 53.367175 -49.574347) (xy 53.419842 -49.585411) (xy 53.470433 -49.603761) (xy 53.517946 -49.629033)
			(xy 53.56144 -49.660726) (xy 53.600053 -49.698212) (xy 53.61686 -49.71923) (xy 53.621432 -49.725834)
			(xy 53.627528 -49.73066) (xy 53.63591 -49.735994) (xy 53.655976 -49.746408) (xy 53.661448 -49.749081)
			(xy 53.673258 -49.752036) (xy 53.679344 -49.75225) (xy 78.95082 -49.75225) (xy 78.956907 -49.752042)
			(xy 78.96872 -49.74909) (xy 78.974188 -49.746408) (xy 78.994254 -49.735994) (xy 79.002636 -49.73066)
			(xy 79.007716 -49.726596) (xy 79.011272 -49.72177) (xy 79.027941 -49.700645) (xy 79.066233 -49.662839)
			(xy 79.109454 -49.630784) (xy 79.156749 -49.605115) (xy 79.207179 -49.586342) (xy 79.259745 -49.574836)
			(xy 79.313406 -49.570825) (xy 79.367099 -49.574388) (xy 79.419759 -49.585456) (xy 79.470344 -49.603808)
			(xy 79.517851 -49.629081) (xy 79.561338 -49.660774) (xy 79.599944 -49.69826) (xy 79.616808 -49.71923)
			(xy 79.62138 -49.725834) (xy 79.627476 -49.73066) (xy 79.635858 -49.735994) (xy 79.655924 -49.746408)
			(xy 79.661397 -49.749076) (xy 79.673207 -49.75202) (xy 79.679292 -49.75225) (xy 104.950768 -49.75225)
			(xy 104.956854 -49.752037) (xy 104.968661 -49.749075) (xy 104.974136 -49.746408) (xy 104.994202 -49.735994)
			(xy 105.002584 -49.73066) (xy 105.007664 -49.726596) (xy 105.01122 -49.72177) (xy 105.027889 -49.700641)
			(xy 105.066182 -49.662828) (xy 105.109405 -49.630766) (xy 105.156703 -49.605091) (xy 105.207137 -49.586311)
			(xy 105.259708 -49.5748) (xy 105.313374 -49.570784) (xy 105.367073 -49.574343) (xy 105.41974 -49.585407)
			(xy 105.470332 -49.603757) (xy 105.517846 -49.629029) (xy 105.56134 -49.660722) (xy 105.599954 -49.698208)
			(xy 105.616756 -49.71923) (xy 105.621328 -49.725834) (xy 105.627424 -49.73066) (xy 105.635806 -49.735994)
			(xy 105.655872 -49.746408) (xy 105.661344 -49.749082) (xy 105.673154 -49.752037) (xy 105.67924 -49.75225)
			(xy 143.051022 -49.75225) (xy 143.057109 -49.752042) (xy 143.068921 -49.749089) (xy 143.07439 -49.746408)
			(xy 143.094456 -49.735994) (xy 143.102838 -49.73066) (xy 143.107918 -49.726596) (xy 143.111474 -49.72177)
			(xy 143.128143 -49.700645) (xy 143.166435 -49.662839) (xy 143.209656 -49.630784) (xy 143.25695 -49.605116)
			(xy 143.30738 -49.586343) (xy 143.359946 -49.574837) (xy 143.413607 -49.570827) (xy 143.4673 -49.57439)
			(xy 143.51996 -49.585458) (xy 143.570544 -49.60381) (xy 143.618051 -49.629083) (xy 143.661538 -49.660776)
			(xy 143.700144 -49.698262) (xy 143.71701 -49.71923) (xy 143.721582 -49.725834) (xy 143.727678 -49.73066)
			(xy 143.73606 -49.735994) (xy 143.756126 -49.746408) (xy 143.761599 -49.749076) (xy 143.773409 -49.752019)
			(xy 143.779494 -49.75225) (xy 169.05097 -49.75225) (xy 169.057056 -49.752037) (xy 169.068863 -49.749074)
			(xy 169.074338 -49.746408) (xy 169.094404 -49.735994) (xy 169.102786 -49.73066) (xy 169.107866 -49.726596)
			(xy 169.111422 -49.72177) (xy 169.128091 -49.700641) (xy 169.166384 -49.662828) (xy 169.209607 -49.630767)
			(xy 169.256904 -49.605092) (xy 169.307338 -49.586313) (xy 169.359909 -49.574801) (xy 169.413575 -49.570785)
			(xy 169.467274 -49.574345) (xy 169.519941 -49.585409) (xy 169.570532 -49.603759) (xy 169.618046 -49.629031)
			(xy 169.66154 -49.660724) (xy 169.700153 -49.69821) (xy 169.716958 -49.71923) (xy 169.72153 -49.725834)
			(xy 169.727626 -49.73066) (xy 169.736008 -49.735994) (xy 169.756074 -49.746408) (xy 169.761546 -49.749082)
			(xy 169.773356 -49.752036) (xy 169.779442 -49.75225) (xy 221.050866 -49.75225) (xy 221.056952 -49.752037)
			(xy 221.068759 -49.749075) (xy 221.074234 -49.746408) (xy 221.0943 -49.735994) (xy 221.102682 -49.73066)
			(xy 221.107762 -49.726596) (xy 221.111318 -49.72177) (xy 221.127987 -49.700641) (xy 221.16628 -49.662827)
			(xy 221.209504 -49.630765) (xy 221.256801 -49.60509) (xy 221.307235 -49.58631) (xy 221.359806 -49.574798)
			(xy 221.413473 -49.570782) (xy 221.467172 -49.574341) (xy 221.519839 -49.585405) (xy 221.570431 -49.603755)
			(xy 221.617945 -49.629027) (xy 221.66144 -49.66072) (xy 221.700054 -49.698206) (xy 221.716854 -49.71923)
			(xy 221.721426 -49.725834) (xy 221.727522 -49.73066) (xy 221.735904 -49.735994) (xy 221.75597 -49.746408)
			(xy 221.761441 -49.749082) (xy 221.773252 -49.752038) (xy 221.779338 -49.75225) (xy 259.150866 -49.75225)
			(xy 259.156952 -49.752037) (xy 259.168759 -49.749075) (xy 259.174234 -49.746408) (xy 259.1943 -49.735994)
			(xy 259.202682 -49.73066) (xy 259.207762 -49.726596) (xy 259.211318 -49.72177) (xy 259.227987 -49.700641)
			(xy 259.26628 -49.662827) (xy 259.309504 -49.630765) (xy 259.356801 -49.60509) (xy 259.407235 -49.58631)
			(xy 259.459806 -49.574798) (xy 259.513473 -49.570782) (xy 259.567172 -49.574341) (xy 259.619839 -49.585405)
			(xy 259.670431 -49.603755) (xy 259.717945 -49.629027) (xy 259.76144 -49.66072) (xy 259.800054 -49.698206)
			(xy 259.816854 -49.71923) (xy 259.821426 -49.725834) (xy 259.827522 -49.73066) (xy 259.835904 -49.735994)
			(xy 259.85597 -49.746408) (xy 259.861441 -49.749082) (xy 259.873252 -49.752038) (xy 259.879338 -49.75225)
			(xy 285.150814 -49.75225) (xy 285.156901 -49.752043) (xy 285.168715 -49.749092) (xy 285.174182 -49.746408)
			(xy 285.194248 -49.735994) (xy 285.20263 -49.73066) (xy 285.20771 -49.726596) (xy 285.211266 -49.72177)
			(xy 285.227935 -49.700644) (xy 285.266227 -49.662837) (xy 285.309449 -49.630782) (xy 285.356743 -49.605113)
			(xy 285.407174 -49.586339) (xy 285.459741 -49.574832) (xy 285.513402 -49.57082) (xy 285.567096 -49.574383)
			(xy 285.619757 -49.58545) (xy 285.670343 -49.603802) (xy 285.71785 -49.629075) (xy 285.761338 -49.660768)
			(xy 285.799945 -49.698254) (xy 285.816802 -49.71923) (xy 285.821374 -49.725834) (xy 285.82747 -49.73066)
			(xy 285.835852 -49.735994) (xy 285.855918 -49.746408) (xy 285.861391 -49.749077) (xy 285.873201 -49.752022)
			(xy 285.879286 -49.75225) (xy 337.15071 -49.75225) (xy 337.156797 -49.752044) (xy 337.168611 -49.749093)
			(xy 337.174078 -49.746408) (xy 337.194144 -49.735994) (xy 337.202526 -49.73066) (xy 337.207606 -49.726596)
			(xy 337.211162 -49.72177) (xy 337.227831 -49.700644) (xy 337.266123 -49.662837) (xy 337.309345 -49.63078)
			(xy 337.35664 -49.605111) (xy 337.40707 -49.586336) (xy 337.459638 -49.574829) (xy 337.5133 -49.570817)
			(xy 337.566994 -49.57438) (xy 337.619656 -49.585446) (xy 337.670242 -49.603798) (xy 337.71775 -49.629071)
			(xy 337.761238 -49.660764) (xy 337.799846 -49.69825) (xy 337.816698 -49.71923) (xy 337.82127 -49.725834)
			(xy 337.827366 -49.73066) (xy 337.835748 -49.735994) (xy 337.855814 -49.746408) (xy 337.861286 -49.749077)
			(xy 337.873097 -49.752023) (xy 337.879182 -49.75225) (xy 375.250964 -49.75225) (xy 375.25705 -49.752037)
			(xy 375.268857 -49.749076) (xy 375.274332 -49.746408) (xy 375.293636 -49.736502) (xy 375.297029 -49.734626)
			(xy 375.303273 -49.730031) (xy 375.306082 -49.727358) (xy 375.310908 -49.722532) (xy 375.31294 -49.719992)
			(xy 375.329697 -49.699016) (xy 375.368122 -49.661522) (xy 375.411422 -49.62978) (xy 375.458741 -49.604419)
			(xy 375.509147 -49.585938) (xy 375.561645 -49.574701) (xy 375.6152 -49.570931) (xy 375.668755 -49.574701)
			(xy 375.721253 -49.585938) (xy 375.771659 -49.604419) (xy 375.818978 -49.62978) (xy 375.862278 -49.661522)
			(xy 375.900703 -49.699016) (xy 375.91746 -49.719992) (xy 375.919492 -49.722532) (xy 375.924572 -49.727612)
			(xy 375.927396 -49.730402) (xy 375.933779 -49.735123) (xy 375.937272 -49.73701) (xy 375.956322 -49.746662)
			(xy 375.961748 -49.749249) (xy 375.973428 -49.75208) (xy 375.979436 -49.75225) (xy 401.250912 -49.75225)
			(xy 401.256999 -49.752043) (xy 401.268813 -49.749093) (xy 401.27428 -49.746408) (xy 401.293584 -49.736502)
			(xy 401.296979 -49.734629) (xy 401.303228 -49.730038) (xy 401.30603 -49.727358) (xy 401.310856 -49.722532)
			(xy 401.312888 -49.719992) (xy 401.329645 -49.699016) (xy 401.36807 -49.661522) (xy 401.41137 -49.62978)
			(xy 401.458689 -49.604419) (xy 401.509095 -49.585938) (xy 401.561593 -49.574701) (xy 401.615148 -49.570931)
			(xy 401.668703 -49.574701) (xy 401.721201 -49.585938) (xy 401.771607 -49.604419) (xy 401.818926 -49.62978)
			(xy 401.862226 -49.661522) (xy 401.900651 -49.699016) (xy 401.917408 -49.719992) (xy 401.91944 -49.722532)
			(xy 401.92452 -49.727612) (xy 401.927346 -49.7304) (xy 401.933732 -49.735115) (xy 401.93722 -49.73701)
			(xy 401.95627 -49.746662) (xy 401.961697 -49.749244) (xy 401.973377 -49.752064) (xy 401.979384 -49.75225)
			(xy 453.250808 -49.75225) (xy 453.256896 -49.752044) (xy 453.268709 -49.749094) (xy 453.274176 -49.746408)
			(xy 453.29348 -49.736502) (xy 453.296875 -49.734629) (xy 453.303124 -49.730038) (xy 453.305926 -49.727358)
			(xy 453.310752 -49.722532) (xy 453.312784 -49.719992) (xy 453.329541 -49.699016) (xy 453.367966 -49.661522)
			(xy 453.411266 -49.62978) (xy 453.458585 -49.604419) (xy 453.508991 -49.585938) (xy 453.561489 -49.574701)
			(xy 453.615044 -49.570931) (xy 453.668599 -49.574701) (xy 453.721097 -49.585938) (xy 453.771503 -49.604419)
			(xy 453.818822 -49.62978) (xy 453.862122 -49.661522) (xy 453.900547 -49.699016) (xy 453.917304 -49.719992)
			(xy 453.919336 -49.722532) (xy 453.924416 -49.727612) (xy 453.927242 -49.7304) (xy 453.933627 -49.735116)
			(xy 453.937116 -49.73701) (xy 453.956166 -49.746662) (xy 453.961593 -49.749244) (xy 453.973273 -49.752065)
			(xy 453.97928 -49.75225) (xy 466.02523 -49.75225) (xy 466.035237 -49.751757) (xy 466.053727 -49.744094)
			(xy 466.067883 -49.729944) (xy 466.075553 -49.711457) (xy 466.07603 -49.70145) (xy 466.07603 -1.999996)
			(xy 466.07552 -1.96883) (xy 466.067384 -1.907032) (xy 466.051252 -1.846825) (xy 466.027399 -1.789238)
			(xy 465.996235 -1.735257) (xy 465.958291 -1.685805) (xy 465.914217 -1.641729) (xy 465.864768 -1.603782)
			(xy 465.810789 -1.572614) (xy 465.753204 -1.548758) (xy 465.692997 -1.532622) (xy 465.6312 -1.524482)
			(xy 465.600034 -1.524) (xy 459.989174 -1.524) (xy 459.979558 -1.524417) (xy 459.961681 -1.531509)
			(xy 459.947672 -1.544686) (xy 459.9432 -1.55321) (xy 459.897734 -1.64973) (xy 459.901544 -1.67894)
			(xy 459.910942 -1.69037) (xy 459.974368 -1.76736) (xy 460.095946 -1.925536) (xy 460.211337 -2.088279)
			(xy 460.320371 -2.255349) (xy 460.422885 -2.426496) (xy 460.518728 -2.601467) (xy 460.607756 -2.780001)
			(xy 460.689837 -2.961834) (xy 460.76485 -3.146695) (xy 460.832683 -3.33431) (xy 460.893236 -3.5244)
			(xy 460.946417 -3.716681) (xy 460.992149 -3.91087) (xy 461.030364 -4.106677) (xy 461.061003 -4.30381)
			(xy 461.084023 -4.501979) (xy 461.099389 -4.700887) (xy 461.107078 -4.90024) (xy 461.107536 -4.99999)
			(xy 461.107282 -5.057394) (xy 461.107282 -5.059934) (xy 461.108044 -5.06984) (xy 461.108552 -5.071872)
			(xy 461.124558 -5.16361) (xy 461.150865 -5.347988) (xy 461.170629 -5.533182) (xy 461.183824 -5.718959)
			(xy 461.190435 -5.905087) (xy 461.190848 -5.99821) (xy 461.190848 -5.999988) (xy 461.190354 -6.101963)
			(xy 461.182445 -6.30576) (xy 461.166641 -6.509097) (xy 461.142964 -6.711669) (xy 461.111449 -6.913169)
			(xy 461.072146 -7.113297) (xy 461.025112 -7.31175) (xy 460.970418 -7.50823) (xy 460.908146 -7.702441)
			(xy 460.838391 -7.894092) (xy 460.761257 -8.082893) (xy 460.67686 -8.268562) (xy 460.585328 -8.450819)
			(xy 460.486797 -8.629389) (xy 460.381416 -8.804005) (xy 460.269343 -8.974403) (xy 460.150747 -9.140327)
			(xy 460.025807 -9.301528) (xy 459.894711 -9.457763) (xy 459.757654 -9.608797) (xy 459.614845 -9.754403)
			(xy 459.466497 -9.894363) (xy 459.312833 -10.028464) (xy 459.154085 -10.156507) (xy 458.990492 -10.278298)
			(xy 458.822299 -10.393653) (xy 458.64976 -10.502401) (xy 458.473134 -10.604376) (xy 458.292686 -10.699426)
			(xy 458.108689 -10.787407) (xy 457.921418 -10.868188) (xy 457.731156 -10.941646) (xy 457.538189 -11.007672)
			(xy 457.342807 -11.066165) (xy 457.145303 -11.117039) (xy 456.945976 -11.160216) (xy 456.745124 -11.195631)
			(xy 456.54305 -11.223232) (xy 456.340057 -11.242977) (xy 456.136452 -11.254836) (xy 455.93254 -11.258791)
			(xy 455.728628 -11.254836) (xy 455.525023 -11.242977) (xy 455.32203 -11.223232) (xy 455.119956 -11.195631)
			(xy 454.919104 -11.160216) (xy 454.719777 -11.117039) (xy 454.522273 -11.066165) (xy 454.326891 -11.007672)
			(xy 454.133924 -10.941646) (xy 453.943662 -10.868188) (xy 453.756391 -10.787407) (xy 453.572394 -10.699426)
			(xy 453.391946 -10.604376) (xy 453.21532 -10.502401) (xy 453.042781 -10.393653) (xy 452.874588 -10.278298)
			(xy 452.710995 -10.156507) (xy 452.552247 -10.028464) (xy 452.398583 -9.894363) (xy 452.250235 -9.754403)
			(xy 452.107426 -9.608797) (xy 451.970369 -9.457763) (xy 451.839273 -9.301528) (xy 451.714333 -9.140327)
			(xy 451.595737 -8.974403) (xy 451.483664 -8.804005) (xy 451.378283 -8.629389) (xy 451.279752 -8.450819)
			(xy 451.18822 -8.268562) (xy 451.103823 -8.082893) (xy 451.026689 -7.894092) (xy 450.956934 -7.702441)
			(xy 450.894662 -7.50823) (xy 450.839968 -7.31175) (xy 450.792934 -7.113297) (xy 450.753631 -6.913169)
			(xy 450.722116 -6.711669) (xy 450.698439 -6.509097) (xy 450.682635 -6.30576) (xy 450.674726 -6.101963)
			(xy 450.674232 -5.999988) (xy 450.674232 -5.99821) (xy 450.674646 -5.905087) (xy 450.68125 -5.718959)
			(xy 450.694442 -5.533181) (xy 450.714207 -5.347987) (xy 450.740518 -5.163609) (xy 450.756528 -5.071872)
			(xy 450.757036 -5.06984) (xy 450.757798 -5.059934) (xy 450.757798 -5.057394) (xy 450.757544 -4.99999)
			(xy 450.758023 -4.900314) (xy 450.7657 -4.701111) (xy 450.781042 -4.502351) (xy 450.804026 -4.304329)
			(xy 450.834617 -4.107339) (xy 450.872772 -3.911673) (xy 450.918432 -3.717621) (xy 450.971531 -3.525472)
			(xy 451.03199 -3.335509) (xy 451.099718 -3.148016) (xy 451.174616 -2.96327) (xy 451.256573 -2.781544)
			(xy 451.345466 -2.60311) (xy 451.441164 -2.42823) (xy 451.543525 -2.257165) (xy 451.652397 -2.090169)
			(xy 451.767619 -1.927489) (xy 451.88902 -1.769366) (xy 451.95236 -1.692402) (xy 451.962266 -1.682496)
			(xy 451.967854 -1.651) (xy 451.92188 -1.55321) (xy 451.917419 -1.54468) (xy 451.903405 -1.531504)
			(xy 451.885523 -1.524417) (xy 451.875906 -1.524) (xy 446.265046 -1.524) (xy 446.233877 -1.524485)
			(xy 446.172073 -1.532616) (xy 446.111859 -1.548745) (xy 446.054265 -1.572596) (xy 446.000278 -1.603761)
			(xy 445.95082 -1.641706) (xy 445.906739 -1.685783) (xy 445.868789 -1.735236) (xy 445.837618 -1.78922)
			(xy 445.813761 -1.846812) (xy 445.797626 -1.907024) (xy 445.789488 -1.968828) (xy 445.78905 -1.999996)
			(xy 445.78905 -11.850116) (xy 445.788562 -11.920918) (xy 445.780621 -12.062299) (xy 445.764766 -12.203013)
			(xy 445.741045 -12.342616) (xy 445.709534 -12.48067) (xy 445.670332 -12.61674) (xy 445.623562 -12.750397)
			(xy 445.569371 -12.881222) (xy 445.50793 -13.008802) (xy 445.439432 -13.132737) (xy 445.364092 -13.252636)
			(xy 445.282149 -13.368122) (xy 445.193859 -13.478831) (xy 445.0995 -13.584416) (xy 444.999369 -13.684544)
			(xy 444.893782 -13.7789) (xy 444.78307 -13.867187) (xy 444.667582 -13.949128) (xy 444.547682 -14.024464)
			(xy 444.423745 -14.092959) (xy 444.296163 -14.154397) (xy 444.165337 -14.208584) (xy 444.031679 -14.255351)
			(xy 443.895608 -14.29455) (xy 443.757554 -14.326057) (xy 443.61795 -14.349774) (xy 443.477236 -14.365627)
			(xy 443.335854 -14.373564) (xy 443.265052 -14.374114) (xy 435.265068 -14.374114) (xy 435.194266 -14.373617)
			(xy 435.052884 -14.365675) (xy 434.91217 -14.349819) (xy 434.772567 -14.326098) (xy 434.634513 -14.294586)
			(xy 434.498443 -14.255384) (xy 434.364786 -14.208614) (xy 434.233961 -14.154423) (xy 434.10638 -14.092982)
			(xy 433.982445 -14.024485) (xy 433.862545 -13.949146) (xy 433.747059 -13.867203) (xy 433.636348 -13.778914)
			(xy 433.530763 -13.684556) (xy 433.430633 -13.584426) (xy 433.336276 -13.478839) (xy 433.247987 -13.368128)
			(xy 433.166045 -13.252641) (xy 433.090707 -13.132741) (xy 433.02221 -13.008806) (xy 432.96077 -12.881225)
			(xy 432.90658 -12.750399) (xy 432.859811 -12.616741) (xy 432.82061 -12.480671) (xy 432.789099 -12.342617)
			(xy 432.765379 -12.203014) (xy 432.749524 -12.0623) (xy 432.741583 -11.920918) (xy 432.74107 -11.850116)
			(xy 432.74107 -1.999996) (xy 432.740582 -1.96883) (xy 432.732445 -1.907032) (xy 432.716312 -1.846825)
			(xy 432.692457 -1.789239) (xy 432.661291 -1.735259) (xy 432.623344 -1.685809) (xy 432.579268 -1.641736)
			(xy 432.529816 -1.603793) (xy 432.475834 -1.572629) (xy 432.418246 -1.548779) (xy 432.358038 -1.532649)
			(xy 432.29624 -1.524516) (xy 432.265074 -1.524) (xy 420.265098 -1.524) (xy 420.233933 -1.52451) (xy 420.172136 -1.532646)
			(xy 420.11193 -1.548778) (xy 420.054345 -1.572631) (xy 420.000365 -1.603796) (xy 419.950915 -1.64174)
			(xy 419.906841 -1.685814) (xy 419.868897 -1.735263) (xy 419.837732 -1.789243) (xy 419.813879 -1.846828)
			(xy 419.797746 -1.907034) (xy 419.78961 -1.968831) (xy 419.789102 -1.999996) (xy 419.789102 -11.850116)
			(xy 419.788605 -11.920918) (xy 419.780664 -12.0623) (xy 419.764809 -12.203015) (xy 419.741088 -12.342618)
			(xy 419.709578 -12.480673) (xy 419.670376 -12.616743) (xy 419.623606 -12.750401) (xy 419.569416 -12.881227)
			(xy 419.507975 -13.008808) (xy 419.439478 -13.132743) (xy 419.364139 -13.252643) (xy 419.282196 -13.36813)
			(xy 419.193907 -13.478841) (xy 419.099549 -13.584427) (xy 418.999419 -13.684557) (xy 418.893832 -13.778914)
			(xy 418.783121 -13.867203) (xy 418.667633 -13.949146) (xy 418.547733 -14.024484) (xy 418.423797 -14.092981)
			(xy 418.296216 -14.154421) (xy 418.16539 -14.20861) (xy 418.031732 -14.255379) (xy 417.895661 -14.294581)
			(xy 417.757607 -14.326091) (xy 417.618003 -14.34981) (xy 417.477288 -14.365665) (xy 417.335906 -14.373605)
			(xy 417.265104 -14.374114) (xy 409.26512 -14.374114) (xy 409.194317 -14.373627) (xy 409.052933 -14.365688)
			(xy 408.912216 -14.349834) (xy 408.77261 -14.326115) (xy 408.634553 -14.294606) (xy 408.49848 -14.255405)
			(xy 408.36482 -14.208636) (xy 408.233992 -14.154447) (xy 408.106408 -14.093007) (xy 407.98247 -14.02451)
			(xy 407.862567 -13.949172) (xy 407.747078 -13.867229) (xy 407.636365 -13.778939) (xy 407.530776 -13.684581)
			(xy 407.430644 -13.58445) (xy 407.336284 -13.478863) (xy 407.247993 -13.368151) (xy 407.166048 -13.252662)
			(xy 407.090708 -13.132761) (xy 407.02221 -13.008824) (xy 406.960768 -12.881241) (xy 406.906576 -12.750414)
			(xy 406.859806 -12.616754) (xy 406.820603 -12.480682) (xy 406.789092 -12.342626) (xy 406.765371 -12.20302)
			(xy 406.749515 -12.062303) (xy 406.741574 -11.920919) (xy 406.741122 -11.850116) (xy 406.741122 -1.999996)
			(xy 406.740612 -1.968831) (xy 406.732476 -1.907033) (xy 406.716344 -1.846826) (xy 406.692491 -1.789239)
			(xy 406.661326 -1.735259) (xy 406.623383 -1.685808) (xy 406.579309 -1.641732) (xy 406.52986 -1.603786)
			(xy 406.47588 -1.572619) (xy 406.418295 -1.548763) (xy 406.358089 -1.532628) (xy 406.296291 -1.524489)
			(xy 406.265126 -1.524) (xy 404.321518 -1.524) (xy 404.311897 -1.524409) (xy 404.294007 -1.531492)
			(xy 404.279985 -1.544667) (xy 404.275544 -1.55321) (xy 404.230078 -1.64973) (xy 404.233888 -1.67894)
			(xy 404.243286 -1.69037) (xy 404.306713 -1.76736) (xy 404.428292 -1.925535) (xy 404.543684 -2.088278)
			(xy 404.652719 -2.255347) (xy 404.755234 -2.426494) (xy 404.851078 -2.601465) (xy 404.940107 -2.779999)
			(xy 405.022189 -2.961832) (xy 405.097203 -3.146693) (xy 405.165037 -3.334308) (xy 405.22559 -3.524398)
			(xy 405.278772 -3.71668) (xy 405.324505 -3.910868) (xy 405.36272 -4.106675) (xy 405.39336 -4.303809)
			(xy 405.41638 -4.501978) (xy 405.431746 -4.700886) (xy 405.439435 -4.900239) (xy 405.43988 -4.99999)
			(xy 405.439626 -5.057394) (xy 405.439626 -5.059934) (xy 405.440388 -5.06984) (xy 405.440896 -5.071872)
			(xy 405.456901 -5.16361) (xy 405.483209 -5.347988) (xy 405.502972 -5.533182) (xy 405.516167 -5.718959)
			(xy 405.522778 -5.905087) (xy 405.523192 -5.99821) (xy 405.523192 -5.999988) (xy 405.522698 -6.101963)
			(xy 405.514789 -6.30576) (xy 405.498985 -6.509097) (xy 405.475308 -6.711669) (xy 405.443793 -6.913169)
			(xy 405.40449 -7.113297) (xy 405.357456 -7.31175) (xy 405.302762 -7.50823) (xy 405.24049 -7.702441)
			(xy 405.170735 -7.894092) (xy 405.093601 -8.082893) (xy 405.009204 -8.268562) (xy 404.917672 -8.450819)
			(xy 404.819141 -8.629389) (xy 404.71376 -8.804005) (xy 404.601687 -8.974403) (xy 404.483091 -9.140327)
			(xy 404.358151 -9.301528) (xy 404.227055 -9.457763) (xy 404.089998 -9.608797) (xy 403.947189 -9.754403)
			(xy 403.798841 -9.894363) (xy 403.645177 -10.028464) (xy 403.486429 -10.156507) (xy 403.322836 -10.278298)
			(xy 403.154643 -10.393653) (xy 402.982104 -10.502401) (xy 402.805478 -10.604376) (xy 402.62503 -10.699426)
			(xy 402.441033 -10.787407) (xy 402.253762 -10.868188) (xy 402.0635 -10.941646) (xy 401.870533 -11.007672)
			(xy 401.675151 -11.066165) (xy 401.477647 -11.117039) (xy 401.27832 -11.160216) (xy 401.077468 -11.195631)
			(xy 400.875394 -11.223232) (xy 400.672401 -11.242977) (xy 400.468796 -11.254836) (xy 400.264884 -11.258791)
			(xy 400.060972 -11.254836) (xy 399.857367 -11.242977) (xy 399.654374 -11.223232) (xy 399.4523 -11.195631)
			(xy 399.251448 -11.160216) (xy 399.052121 -11.117039) (xy 398.854617 -11.066165) (xy 398.659235 -11.007672)
			(xy 398.466268 -10.941646) (xy 398.276006 -10.868188) (xy 398.088735 -10.787407) (xy 397.904738 -10.699426)
			(xy 397.72429 -10.604376) (xy 397.547664 -10.502401) (xy 397.375125 -10.393653) (xy 397.206932 -10.278298)
			(xy 397.043339 -10.156507) (xy 396.884591 -10.028464) (xy 396.730927 -9.894363) (xy 396.582579 -9.754403)
			(xy 396.43977 -9.608797) (xy 396.302713 -9.457763) (xy 396.171617 -9.301528) (xy 396.046677 -9.140327)
			(xy 395.928081 -8.974403) (xy 395.816008 -8.804005) (xy 395.710627 -8.629389) (xy 395.612096 -8.450819)
			(xy 395.520564 -8.268562) (xy 395.436167 -8.082893) (xy 395.359033 -7.894092) (xy 395.289278 -7.702441)
			(xy 395.227006 -7.50823) (xy 395.172312 -7.31175) (xy 395.125278 -7.113297) (xy 395.085975 -6.913169)
			(xy 395.05446 -6.711669) (xy 395.030783 -6.509097) (xy 395.014979 -6.30576) (xy 395.00707 -6.101963)
			(xy 395.006576 -5.999988) (xy 395.006576 -5.99821) (xy 395.00699 -5.905087) (xy 395.013594 -5.718959)
			(xy 395.026786 -5.533181) (xy 395.046551 -5.347987) (xy 395.072863 -5.163609) (xy 395.088872 -5.071872)
			(xy 395.08938 -5.06984) (xy 395.090142 -5.059934) (xy 395.090142 -5.057394) (xy 395.089888 -4.99999)
			(xy 395.090368 -4.900314) (xy 395.098044 -4.701111) (xy 395.113386 -4.502351) (xy 395.13637 -4.304329)
			(xy 395.166962 -4.10734) (xy 395.205117 -3.911674) (xy 395.250778 -3.717622) (xy 395.303877 -3.525473)
			(xy 395.364336 -3.335511) (xy 395.432065 -3.148018) (xy 395.506963 -2.963272) (xy 395.58892 -2.781547)
			(xy 395.677814 -2.603113) (xy 395.773513 -2.428234) (xy 395.875874 -2.257169) (xy 395.984747 -2.090174)
			(xy 396.09997 -1.927494) (xy 396.221371 -1.769372) (xy 396.284704 -1.692402) (xy 396.29461 -1.682496)
			(xy 396.300198 -1.651) (xy 396.254224 -1.55321) (xy 396.249765 -1.544675) (xy 396.235754 -1.531487)
			(xy 396.217871 -1.524385) (xy 396.20825 -1.524) (xy 394.264896 -1.524) (xy 394.233731 -1.52451) (xy 394.171934 -1.532646)
			(xy 394.111729 -1.548779) (xy 394.054143 -1.572631) (xy 394.000164 -1.603797) (xy 393.950715 -1.641741)
			(xy 393.906641 -1.685815) (xy 393.868697 -1.735264) (xy 393.837531 -1.789243) (xy 393.813679 -1.846829)
			(xy 393.797546 -1.907034) (xy 393.78941 -1.968831) (xy 393.7889 -1.999996) (xy 393.7889 -11.850116)
			(xy 393.788403 -11.920918) (xy 393.780462 -12.0623) (xy 393.764607 -12.203014) (xy 393.740886 -12.342618)
			(xy 393.709376 -12.480673) (xy 393.670174 -12.616743) (xy 393.623404 -12.750401) (xy 393.569214 -12.881226)
			(xy 393.507773 -13.008807) (xy 393.439276 -13.132743) (xy 393.363937 -13.252643) (xy 393.281994 -13.36813)
			(xy 393.193705 -13.478841) (xy 393.099346 -13.584427) (xy 392.999216 -13.684556) (xy 392.89363 -13.778914)
			(xy 392.782919 -13.867202) (xy 392.667431 -13.949145) (xy 392.547531 -14.024483) (xy 392.423595 -14.092979)
			(xy 392.296014 -14.154419) (xy 392.165188 -14.208609) (xy 392.031529 -14.255378) (xy 391.895459 -14.294579)
			(xy 391.757405 -14.326089) (xy 391.617801 -14.349809) (xy 391.477086 -14.365663) (xy 391.335704 -14.373603)
			(xy 391.264902 -14.374114) (xy 383.264918 -14.374114) (xy 383.194115 -14.373627) (xy 383.052731 -14.365688)
			(xy 382.912014 -14.349834) (xy 382.772408 -14.326115) (xy 382.634352 -14.294606) (xy 382.498279 -14.255405)
			(xy 382.364618 -14.208636) (xy 382.23379 -14.154446) (xy 382.106207 -14.093006) (xy 381.982269 -14.024509)
			(xy 381.862366 -13.949171) (xy 381.746877 -13.867228) (xy 381.636164 -13.778938) (xy 381.530575 -13.68458)
			(xy 381.430444 -13.584449) (xy 381.336084 -13.478862) (xy 381.247793 -13.36815) (xy 381.165848 -13.252662)
			(xy 381.090508 -13.13276) (xy 381.022009 -13.008823) (xy 380.960568 -12.881241) (xy 380.906376 -12.750413)
			(xy 380.859606 -12.616753) (xy 380.820403 -12.480681) (xy 380.788892 -12.342625) (xy 380.765171 -12.203019)
			(xy 380.749315 -12.062303) (xy 380.741374 -11.920919) (xy 380.74092 -11.850116) (xy 380.74092 -1.999996)
			(xy 380.74041 -1.968831) (xy 380.732274 -1.907033) (xy 380.716142 -1.846826) (xy 380.692289 -1.78924)
			(xy 380.661124 -1.735259) (xy 380.62318 -1.685808) (xy 380.579107 -1.641733) (xy 380.529657 -1.603787)
			(xy 380.475678 -1.57262) (xy 380.418093 -1.548765) (xy 380.357887 -1.53263) (xy 380.296089 -1.524491)
			(xy 380.264924 -1.524) (xy 368.264948 -1.524) (xy 368.233779 -1.524485) (xy 368.171975 -1.532616)
			(xy 368.11176 -1.548745) (xy 368.054167 -1.572595) (xy 368.000179 -1.60376) (xy 367.950721 -1.641706)
			(xy 367.90664 -1.685782) (xy 367.868689 -1.735236) (xy 367.837518 -1.78922) (xy 367.813661 -1.846811)
			(xy 367.797526 -1.907024) (xy 367.789388 -1.968827) (xy 367.788952 -1.999996) (xy 367.788952 -11.850116)
			(xy 367.788464 -11.920918) (xy 367.780523 -12.0623) (xy 367.764668 -12.203013) (xy 367.740947 -12.342617)
			(xy 367.709436 -12.48067) (xy 367.670234 -12.61674) (xy 367.623464 -12.750397) (xy 367.569273 -12.881222)
			(xy 367.507832 -13.008803) (xy 367.439334 -13.132737) (xy 367.363995 -13.252636) (xy 367.282051 -13.368122)
			(xy 367.193761 -13.478832) (xy 367.099402 -13.584417) (xy 366.999272 -13.684545) (xy 366.893684 -13.778901)
			(xy 366.782973 -13.867188) (xy 366.667485 -13.949129) (xy 366.547584 -14.024465) (xy 366.423647 -14.09296)
			(xy 366.296066 -14.154398) (xy 366.165239 -14.208586) (xy 366.031581 -14.255352) (xy 365.89551 -14.294551)
			(xy 365.757456 -14.326059) (xy 365.617852 -14.349776) (xy 365.477138 -14.365628) (xy 365.335756 -14.373566)
			(xy 365.264954 -14.374114) (xy 357.26497 -14.374114) (xy 357.194168 -14.373617) (xy 357.052786 -14.365675)
			(xy 356.912072 -14.349819) (xy 356.772469 -14.326098) (xy 356.634415 -14.294587) (xy 356.498345 -14.255384)
			(xy 356.364687 -14.208614) (xy 356.233862 -14.154424) (xy 356.106281 -14.092983) (xy 355.982346 -14.024485)
			(xy 355.862447 -13.949147) (xy 355.74696 -13.867204) (xy 355.636249 -13.778914) (xy 355.530663 -13.684556)
			(xy 355.430534 -13.584426) (xy 355.336177 -13.47884) (xy 355.247888 -13.368129) (xy 355.165946 -13.252642)
			(xy 355.090607 -13.132742) (xy 355.022111 -13.008806) (xy 354.960671 -12.881225) (xy 354.906481 -12.7504)
			(xy 354.859711 -12.616742) (xy 354.82051 -12.480672) (xy 354.788999 -12.342618) (xy 354.765279 -12.203014)
			(xy 354.749424 -12.0623) (xy 354.741483 -11.920918) (xy 354.740972 -11.850116) (xy 354.740972 -1.999996)
			(xy 354.740484 -1.96883) (xy 354.732347 -1.907032) (xy 354.716214 -1.846825) (xy 354.69236 -1.789239)
			(xy 354.661193 -1.735259) (xy 354.623246 -1.685809) (xy 354.57917 -1.641735) (xy 354.529718 -1.603792)
			(xy 354.475736 -1.572628) (xy 354.418149 -1.548777) (xy 354.35794 -1.532647) (xy 354.296142 -1.524514)
			(xy 354.264976 -1.524) (xy 330.164948 -1.524) (xy 330.133779 -1.524485) (xy 330.071975 -1.532616)
			(xy 330.01176 -1.548745) (xy 329.954167 -1.572595) (xy 329.900179 -1.60376) (xy 329.850721 -1.641706)
			(xy 329.80664 -1.685782) (xy 329.768689 -1.735236) (xy 329.737518 -1.78922) (xy 329.713661 -1.846811)
			(xy 329.697526 -1.907024) (xy 329.689388 -1.968827) (xy 329.688952 -1.999996) (xy 329.688952 -7.35711)
			(xy 329.689546 -7.368369) (xy 329.699157 -7.388732) (xy 329.716537 -7.403049) (xy 329.727306 -7.406386)
			(xy 329.728068 -7.406386) (xy 329.755361 -7.413587) (xy 329.807615 -7.434931) (xy 329.856153 -7.463741)
			(xy 329.899918 -7.499388) (xy 329.937953 -7.541094) (xy 329.969429 -7.587948) (xy 329.993658 -7.638928)
			(xy 330.010113 -7.692921) (xy 330.018433 -7.74875) (xy 330.018898 -7.776972) (xy 330.018353 -7.806696)
			(xy 330.009173 -7.86543) (xy 329.990985 -7.922026) (xy 329.964229 -7.975111) (xy 329.929555 -8.023398)
			(xy 329.887804 -8.065715) (xy 329.864212 -8.083804) (xy 329.85837 -8.08863) (xy 329.853544 -8.093456)
			(xy 329.850853 -8.096179) (xy 329.84626 -8.102303) (xy 329.8444 -8.105648) (xy 329.834748 -8.12419)
			(xy 329.832056 -8.129722) (xy 329.829106 -8.141663) (xy 329.828906 -8.147812) (xy 329.828906 -8.206232)
			(xy 329.829071 -8.212386) (xy 329.832015 -8.224338) (xy 329.834748 -8.229854) (xy 329.845416 -8.250174)
			(xy 329.848226 -8.255167) (xy 329.855659 -8.263885) (xy 329.860148 -8.267446) (xy 329.860656 -8.2677)
			(xy 329.86091 -8.267954) (xy 329.881527 -8.28339) (xy 329.918819 -8.318915) (xy 329.950994 -8.359133)
			(xy 329.977469 -8.403312) (xy 329.997762 -8.450649) (xy 330.011505 -8.500286) (xy 330.018448 -8.55132)
			(xy 330.018898 -8.577072) (xy 330.01839 -8.605305) (xy 330.010068 -8.661155) (xy 329.993604 -8.715167)
			(xy 329.969355 -8.766162) (xy 329.937853 -8.813024) (xy 329.899786 -8.85473) (xy 329.855987 -8.890367)
			(xy 329.807411 -8.919157) (xy 329.755122 -8.94047) (xy 329.727814 -8.947658) (xy 329.710542 -8.951976)
			(xy 329.688952 -8.979408) (xy 329.688952 -11.850116) (xy 329.688464 -11.920918) (xy 329.680523 -12.0623)
			(xy 329.664668 -12.203013) (xy 329.640947 -12.342617) (xy 329.609436 -12.48067) (xy 329.570234 -12.61674)
			(xy 329.523464 -12.750397) (xy 329.469273 -12.881222) (xy 329.407832 -13.008803) (xy 329.339334 -13.132737)
			(xy 329.263995 -13.252636) (xy 329.182051 -13.368122) (xy 329.093761 -13.478832) (xy 328.999402 -13.584417)
			(xy 328.899272 -13.684545) (xy 328.793684 -13.778901) (xy 328.682973 -13.867188) (xy 328.567485 -13.949129)
			(xy 328.447584 -14.024465) (xy 328.323647 -14.09296) (xy 328.196066 -14.154398) (xy 328.065239 -14.208586)
			(xy 327.931581 -14.255352) (xy 327.79551 -14.294551) (xy 327.657456 -14.326059) (xy 327.517852 -14.349776)
			(xy 327.377138 -14.365628) (xy 327.235756 -14.373566) (xy 327.164954 -14.374114) (xy 319.16497 -14.374114)
			(xy 319.094168 -14.373617) (xy 318.952786 -14.365675) (xy 318.812072 -14.349819) (xy 318.672469 -14.326098)
			(xy 318.534415 -14.294587) (xy 318.398345 -14.255384) (xy 318.264687 -14.208614) (xy 318.133862 -14.154424)
			(xy 318.006281 -14.092983) (xy 317.882346 -14.024485) (xy 317.762447 -13.949147) (xy 317.64696 -13.867204)
			(xy 317.536249 -13.778914) (xy 317.430663 -13.684556) (xy 317.330534 -13.584426) (xy 317.236177 -13.47884)
			(xy 317.147888 -13.368129) (xy 317.065946 -13.252642) (xy 316.990607 -13.132742) (xy 316.922111 -13.008806)
			(xy 316.860671 -12.881225) (xy 316.806481 -12.7504) (xy 316.759711 -12.616742) (xy 316.72051 -12.480672)
			(xy 316.688999 -12.342618) (xy 316.665279 -12.203014) (xy 316.649424 -12.0623) (xy 316.641483 -11.920918)
			(xy 316.640972 -11.850116) (xy 316.640972 -1.999996) (xy 316.640484 -1.96883) (xy 316.632347 -1.907032)
			(xy 316.616214 -1.846825) (xy 316.59236 -1.789239) (xy 316.561193 -1.735259) (xy 316.523246 -1.685809)
			(xy 316.47917 -1.641735) (xy 316.429718 -1.603792) (xy 316.375736 -1.572628) (xy 316.318149 -1.548777)
			(xy 316.25794 -1.532647) (xy 316.196142 -1.524514) (xy 316.164976 -1.524) (xy 304.165 -1.524) (xy 304.133835 -1.52451)
			(xy 304.072038 -1.532645) (xy 304.011832 -1.548778) (xy 303.954246 -1.57263) (xy 303.900266 -1.603795)
			(xy 303.850816 -1.641739) (xy 303.806742 -1.685813) (xy 303.768797 -1.735263) (xy 303.737632 -1.789242)
			(xy 303.713779 -1.846828) (xy 303.697646 -1.907034) (xy 303.68951 -1.968831) (xy 303.689004 -1.999996)
			(xy 303.689004 -11.850116) (xy 303.688507 -11.920918) (xy 303.680566 -12.0623) (xy 303.664711 -12.203015)
			(xy 303.64099 -12.342619) (xy 303.60948 -12.480673) (xy 303.570278 -12.616743) (xy 303.523508 -12.750401)
			(xy 303.469318 -12.881227) (xy 303.407877 -13.008808) (xy 303.33938 -13.132744) (xy 303.264041 -13.252644)
			(xy 303.182098 -13.368131) (xy 303.093809 -13.478842) (xy 302.999451 -13.584428) (xy 302.899321 -13.684558)
			(xy 302.793734 -13.778915) (xy 302.683023 -13.867204) (xy 302.567535 -13.949147) (xy 302.447635 -14.024485)
			(xy 302.323699 -14.092982) (xy 302.196118 -14.154422) (xy 302.065292 -14.208612) (xy 301.931634 -14.255381)
			(xy 301.795563 -14.294582) (xy 301.657509 -14.326092) (xy 301.517905 -14.349812) (xy 301.37719 -14.365667)
			(xy 301.235808 -14.373607) (xy 301.165006 -14.374114) (xy 293.165022 -14.374114) (xy 293.094219 -14.373627)
			(xy 292.952834 -14.365688) (xy 292.812118 -14.349835) (xy 292.672512 -14.326116) (xy 292.534455 -14.294606)
			(xy 292.398382 -14.255406) (xy 292.264721 -14.208637) (xy 292.133893 -14.154447) (xy 292.006309 -14.093008)
			(xy 291.882371 -14.024511) (xy 291.762469 -13.949172) (xy 291.646979 -13.867229) (xy 291.536266 -13.77894)
			(xy 291.430677 -13.684581) (xy 291.330545 -13.584451) (xy 291.236185 -13.478864) (xy 291.147894 -13.368151)
			(xy 291.065949 -13.252663) (xy 290.990609 -13.132762) (xy 290.92211 -13.008825) (xy 290.860668 -12.881242)
			(xy 290.806477 -12.750414) (xy 290.759706 -12.616754) (xy 290.720503 -12.480682) (xy 290.688992 -12.342626)
			(xy 290.665271 -12.20302) (xy 290.649415 -12.062303) (xy 290.641474 -11.920919) (xy 290.641024 -11.850116)
			(xy 290.641024 -1.999996) (xy 290.640514 -1.96883) (xy 290.632378 -1.907033) (xy 290.616246 -1.846826)
			(xy 290.592393 -1.789239) (xy 290.561228 -1.735258) (xy 290.523285 -1.685807) (xy 290.479211 -1.641731)
			(xy 290.429762 -1.603785) (xy 290.375783 -1.572617) (xy 290.318197 -1.548762) (xy 290.257991 -1.532627)
			(xy 290.196193 -1.524488) (xy 290.165028 -1.524) (xy 288.221674 -1.524) (xy 288.212058 -1.524417)
			(xy 288.194181 -1.531509) (xy 288.180172 -1.544686) (xy 288.1757 -1.55321) (xy 288.130234 -1.64973)
			(xy 288.134044 -1.67894) (xy 288.143442 -1.69037) (xy 288.206868 -1.76736) (xy 288.328446 -1.925536)
			(xy 288.443837 -2.088279) (xy 288.552871 -2.255349) (xy 288.655385 -2.426496) (xy 288.751228 -2.601467)
			(xy 288.840256 -2.780001) (xy 288.922337 -2.961834) (xy 288.99735 -3.146695) (xy 289.065183 -3.33431)
			(xy 289.125736 -3.5244) (xy 289.178917 -3.716681) (xy 289.224649 -3.91087) (xy 289.262864 -4.106677)
			(xy 289.293503 -4.30381) (xy 289.316523 -4.501979) (xy 289.331889 -4.700887) (xy 289.339578 -4.90024)
			(xy 289.340036 -4.99999) (xy 289.339782 -5.057394) (xy 289.339782 -5.059934) (xy 289.340544 -5.06984)
			(xy 289.341052 -5.071872) (xy 289.357058 -5.16361) (xy 289.383365 -5.347988) (xy 289.403129 -5.533182)
			(xy 289.416324 -5.718959) (xy 289.422935 -5.905087) (xy 289.423348 -5.99821) (xy 289.423348 -5.999988)
			(xy 289.422854 -6.101963) (xy 289.414945 -6.30576) (xy 289.399141 -6.509097) (xy 289.375464 -6.711669)
			(xy 289.343949 -6.913169) (xy 289.304646 -7.113297) (xy 289.257612 -7.31175) (xy 289.202918 -7.50823)
			(xy 289.140646 -7.702441) (xy 289.070891 -7.894092) (xy 288.993757 -8.082893) (xy 288.90936 -8.268562)
			(xy 288.817828 -8.450819) (xy 288.719297 -8.629389) (xy 288.613916 -8.804005) (xy 288.501843 -8.974403)
			(xy 288.383247 -9.140327) (xy 288.258307 -9.301528) (xy 288.127211 -9.457763) (xy 287.990154 -9.608797)
			(xy 287.847345 -9.754403) (xy 287.698997 -9.894363) (xy 287.545333 -10.028464) (xy 287.386585 -10.156507)
			(xy 287.222992 -10.278298) (xy 287.054799 -10.393653) (xy 286.88226 -10.502401) (xy 286.705634 -10.604376)
			(xy 286.525186 -10.699426) (xy 286.341189 -10.787407) (xy 286.153918 -10.868188) (xy 285.963656 -10.941646)
			(xy 285.770689 -11.007672) (xy 285.575307 -11.066165) (xy 285.377803 -11.117039) (xy 285.178476 -11.160216)
			(xy 284.977624 -11.195631) (xy 284.77555 -11.223232) (xy 284.572557 -11.242977) (xy 284.368952 -11.254836)
			(xy 284.16504 -11.258791) (xy 283.961128 -11.254836) (xy 283.757523 -11.242977) (xy 283.55453 -11.223232)
			(xy 283.352456 -11.195631) (xy 283.151604 -11.160216) (xy 282.952277 -11.117039) (xy 282.754773 -11.066165)
			(xy 282.559391 -11.007672) (xy 282.366424 -10.941646) (xy 282.176162 -10.868188) (xy 281.988891 -10.787407)
			(xy 281.804894 -10.699426) (xy 281.624446 -10.604376) (xy 281.44782 -10.502401) (xy 281.275281 -10.393653)
			(xy 281.107088 -10.278298) (xy 280.943495 -10.156507) (xy 280.784747 -10.028464) (xy 280.631083 -9.894363)
			(xy 280.482735 -9.754403) (xy 280.339926 -9.608797) (xy 280.202869 -9.457763) (xy 280.071773 -9.301528)
			(xy 279.946833 -9.140327) (xy 279.828237 -8.974403) (xy 279.716164 -8.804005) (xy 279.610783 -8.629389)
			(xy 279.512252 -8.450819) (xy 279.42072 -8.268562) (xy 279.336323 -8.082893) (xy 279.259189 -7.894092)
			(xy 279.189434 -7.702441) (xy 279.127162 -7.50823) (xy 279.072468 -7.31175) (xy 279.025434 -7.113297)
			(xy 278.986131 -6.913169) (xy 278.954616 -6.711669) (xy 278.930939 -6.509097) (xy 278.915135 -6.30576)
			(xy 278.907226 -6.101963) (xy 278.906732 -5.999988) (xy 278.906732 -5.99821) (xy 278.907146 -5.905087)
			(xy 278.91375 -5.718959) (xy 278.926942 -5.533181) (xy 278.946707 -5.347987) (xy 278.973018 -5.163609)
			(xy 278.989028 -5.071872) (xy 278.989536 -5.06984) (xy 278.990298 -5.059934) (xy 278.990298 -5.057394)
			(xy 278.990044 -4.99999) (xy 278.990523 -4.900314) (xy 278.9982 -4.701111) (xy 279.013542 -4.502351)
			(xy 279.036526 -4.304329) (xy 279.067117 -4.107339) (xy 279.105272 -3.911673) (xy 279.150932 -3.717621)
			(xy 279.204031 -3.525472) (xy 279.26449 -3.335509) (xy 279.332218 -3.148016) (xy 279.407116 -2.96327)
			(xy 279.489073 -2.781544) (xy 279.577966 -2.60311) (xy 279.673664 -2.42823) (xy 279.776025 -2.257165)
			(xy 279.884897 -2.090169) (xy 280.000119 -1.927489) (xy 280.12152 -1.769366) (xy 280.18486 -1.692402)
			(xy 280.194766 -1.682496) (xy 280.200354 -1.651) (xy 280.15438 -1.55321) (xy 280.149919 -1.54468)
			(xy 280.135905 -1.531504) (xy 280.118023 -1.524417) (xy 280.108406 -1.524) (xy 278.165052 -1.524)
			(xy 278.133889 -1.524513) (xy 278.072097 -1.532654) (xy 278.011895 -1.54879) (xy 277.954315 -1.572645)
			(xy 277.900341 -1.603812) (xy 277.850897 -1.641756) (xy 277.806827 -1.68583) (xy 277.768887 -1.735278)
			(xy 277.737726 -1.789255) (xy 277.713876 -1.846837) (xy 277.697745 -1.90704) (xy 277.68961 -1.968833)
			(xy 277.689056 -1.999996) (xy 277.689056 -11.850116) (xy 277.688568 -11.920918) (xy 277.680627 -12.0623)
			(xy 277.664772 -12.203013) (xy 277.641051 -12.342617) (xy 277.60954 -12.480671) (xy 277.570338 -12.61674)
			(xy 277.523568 -12.750398) (xy 277.469377 -12.881223) (xy 277.407936 -13.008803) (xy 277.339438 -13.132738)
			(xy 277.264099 -13.252637) (xy 277.182155 -13.368123) (xy 277.093865 -13.478833) (xy 276.999506 -13.584418)
			(xy 276.899376 -13.684546) (xy 276.793789 -13.778903) (xy 276.683077 -13.86719) (xy 276.567589 -13.949131)
			(xy 276.447688 -14.024467) (xy 276.323752 -14.092962) (xy 276.19617 -14.154401) (xy 276.065344 -14.208588)
			(xy 275.931685 -14.255355) (xy 275.795614 -14.294554) (xy 275.65756 -14.326062) (xy 275.517956 -14.34978)
			(xy 275.377242 -14.365632) (xy 275.23586 -14.37357) (xy 275.165058 -14.374114) (xy 267.165074 -14.374114)
			(xy 267.094272 -14.373617) (xy 266.95289 -14.365676) (xy 266.812176 -14.34982) (xy 266.672572 -14.326099)
			(xy 266.534518 -14.294588) (xy 266.398448 -14.255385) (xy 266.26479 -14.208615) (xy 266.133965 -14.154425)
			(xy 266.006384 -14.092984) (xy 265.882448 -14.024487) (xy 265.762549 -13.949148) (xy 265.647062 -13.867205)
			(xy 265.536351 -13.778916) (xy 265.430765 -13.684558) (xy 265.330635 -13.584428) (xy 265.236278 -13.478841)
			(xy 265.147989 -13.36813) (xy 265.066046 -13.252643) (xy 264.990708 -13.132743) (xy 264.922211 -13.008807)
			(xy 264.860771 -12.881226) (xy 264.806581 -12.750401) (xy 264.759812 -12.616743) (xy 264.72061 -12.480672)
			(xy 264.689099 -12.342618) (xy 264.665379 -12.203014) (xy 264.649524 -12.0623) (xy 264.641583 -11.920918)
			(xy 264.641076 -11.850116) (xy 264.641076 -1.999996) (xy 264.640588 -1.96883) (xy 264.632451 -1.907032)
			(xy 264.616318 -1.846824) (xy 264.592464 -1.789238) (xy 264.561297 -1.735258) (xy 264.523351 -1.685808)
			(xy 264.479274 -1.641734) (xy 264.429822 -1.60379) (xy 264.375841 -1.572626) (xy 264.318253 -1.548774)
			(xy 264.258045 -1.532644) (xy 264.196246 -1.52451) (xy 264.16508 -1.524) (xy 252.165104 -1.524) (xy 252.133939 -1.524509)
			(xy 252.072141 -1.532645) (xy 252.011935 -1.548777) (xy 251.954348 -1.572629) (xy 251.900368 -1.603794)
			(xy 251.850918 -1.641738) (xy 251.806843 -1.685812) (xy 251.768898 -1.735262) (xy 251.737732 -1.789241)
			(xy 251.713879 -1.846827) (xy 251.697746 -1.907033) (xy 251.68961 -1.968831) (xy 251.689108 -1.999996)
			(xy 251.689108 -11.850116) (xy 251.688611 -11.920918) (xy 251.68067 -12.0623) (xy 251.664815 -12.203015)
			(xy 251.641094 -12.342619) (xy 251.609584 -12.480673) (xy 251.570382 -12.616744) (xy 251.523612 -12.750402)
			(xy 251.469422 -12.881228) (xy 251.407981 -13.008809) (xy 251.339484 -13.132745) (xy 251.264145 -13.252645)
			(xy 251.182202 -13.368132) (xy 251.093913 -13.478843) (xy 250.999555 -13.584429) (xy 250.899425 -13.684559)
			(xy 250.793838 -13.778917) (xy 250.683127 -13.867206) (xy 250.56764 -13.949149) (xy 250.44774 -14.024487)
			(xy 250.323804 -14.092984) (xy 250.196222 -14.154424) (xy 250.065396 -14.208614) (xy 249.931738 -14.255384)
			(xy 249.795667 -14.294585) (xy 249.657613 -14.326096) (xy 249.518009 -14.349816) (xy 249.377295 -14.365671)
			(xy 249.235912 -14.373611) (xy 249.16511 -14.374114) (xy 241.164872 -14.374114) (xy 241.094072 -14.373631)
			(xy 240.952696 -14.365701) (xy 240.811986 -14.349856) (xy 240.672386 -14.326146) (xy 240.534335 -14.294646)
			(xy 240.398268 -14.255455) (xy 240.264612 -14.208696) (xy 240.133788 -14.154516) (xy 240.006208 -14.093085)
			(xy 239.882274 -14.024598) (xy 239.762374 -13.949269) (xy 239.646888 -13.867336) (xy 239.536176 -13.779056)
			(xy 239.43059 -13.684707) (xy 239.330459 -13.584586) (xy 239.2361 -13.479009) (xy 239.14781 -13.368306)
			(xy 239.065865 -13.252827) (xy 238.990525 -13.132935) (xy 238.922026 -13.009007) (xy 238.860583 -12.881433)
			(xy 238.806391 -12.750614) (xy 238.759619 -12.616963) (xy 238.720414 -12.480899) (xy 238.688901 -12.342851)
			(xy 238.665178 -12.203254) (xy 238.649319 -12.062546) (xy 238.641376 -11.92117) (xy 238.640874 -11.85037)
			(xy 238.640874 -1.999996) (xy 238.640386 -1.96883) (xy 238.632249 -1.907032) (xy 238.616116 -1.846825)
			(xy 238.592262 -1.789238) (xy 238.561095 -1.735258) (xy 238.523148 -1.685808) (xy 238.479072 -1.641734)
			(xy 238.42962 -1.603791) (xy 238.375638 -1.572627) (xy 238.318051 -1.548776) (xy 238.257842 -1.532646)
			(xy 238.196044 -1.524512) (xy 238.164878 -1.524) (xy 230.171752 -1.524) (xy 230.162128 -1.524403)
			(xy 230.144228 -1.531479) (xy 230.130196 -1.544653) (xy 230.125778 -1.55321) (xy 230.080312 -1.64973)
			(xy 230.084122 -1.67894) (xy 230.09352 -1.69037) (xy 230.156947 -1.76736) (xy 230.278525 -1.925535)
			(xy 230.393916 -2.088278) (xy 230.502951 -2.255348) (xy 230.605465 -2.426495) (xy 230.701308 -2.601466)
			(xy 230.790336 -2.780001) (xy 230.872418 -2.961833) (xy 230.947432 -3.146695) (xy 231.015265 -3.334309)
			(xy 231.075818 -3.524399) (xy 231.129 -3.716681) (xy 231.174732 -3.910869) (xy 231.212946 -4.106676)
			(xy 231.243586 -4.30381) (xy 231.266606 -4.501978) (xy 231.281972 -4.700887) (xy 231.289661 -4.90024)
			(xy 231.290114 -4.99999) (xy 231.28986 -5.057648) (xy 231.28986 -5.060188) (xy 231.290622 -5.06857)
			(xy 231.290876 -5.070856) (xy 231.29113 -5.072634) (xy 231.291384 -5.073396) (xy 231.307392 -5.165159)
			(xy 231.333704 -5.349588) (xy 231.353469 -5.534833) (xy 231.366663 -5.720661) (xy 231.37327 -5.90684)
			(xy 231.37368 -5.999988) (xy 231.373186 -6.101968) (xy 231.365277 -6.305775) (xy 231.349472 -6.509122)
			(xy 231.325793 -6.711703) (xy 231.294278 -6.913214) (xy 231.254972 -7.113351) (xy 231.207936 -7.311813)
			(xy 231.153239 -7.508302) (xy 231.090965 -7.702523) (xy 231.021206 -7.894183) (xy 230.944068 -8.082994)
			(xy 230.859667 -8.268672) (xy 230.76813 -8.450937) (xy 230.669595 -8.629516) (xy 230.564208 -8.80414)
			(xy 230.45213 -8.974547) (xy 230.333529 -9.140479) (xy 230.208583 -9.301687) (xy 230.07748 -9.45793)
			(xy 229.940417 -9.608972) (xy 229.797601 -9.754585) (xy 229.649245 -9.894551) (xy 229.495574 -10.028659)
			(xy 229.336819 -10.156708) (xy 229.173218 -10.278504) (xy 229.005017 -10.393866) (xy 228.832469 -10.502618)
			(xy 228.655834 -10.604598) (xy 228.475378 -10.699653) (xy 228.291372 -10.787638) (xy 228.104092 -10.868423)
			(xy 227.913821 -10.941885) (xy 227.720845 -11.007913) (xy 227.525453 -11.06641) (xy 227.32794 -11.117286)
			(xy 227.128603 -11.160465) (xy 226.927741 -11.195882) (xy 226.725657 -11.223485) (xy 226.522655 -11.24323)
			(xy 226.31904 -11.255089) (xy 226.115118 -11.259045) (xy 225.911196 -11.255089) (xy 225.707581 -11.24323)
			(xy 225.504579 -11.223485) (xy 225.302495 -11.195882) (xy 225.101633 -11.160465) (xy 224.902296 -11.117286)
			(xy 224.704783 -11.06641) (xy 224.509391 -11.007913) (xy 224.316415 -10.941885) (xy 224.126144 -10.868423)
			(xy 223.938864 -10.787638) (xy 223.754858 -10.699653) (xy 223.574402 -10.604598) (xy 223.397767 -10.502618)
			(xy 223.225219 -10.393866) (xy 223.057018 -10.278504) (xy 222.893417 -10.156708) (xy 222.734662 -10.028659)
			(xy 222.580991 -9.894551) (xy 222.432635 -9.754585) (xy 222.289819 -9.608972) (xy 222.152756 -9.45793)
			(xy 222.021653 -9.301687) (xy 221.896707 -9.140479) (xy 221.778106 -8.974547) (xy 221.666028 -8.80414)
			(xy 221.560641 -8.629516) (xy 221.462106 -8.450937) (xy 221.370569 -8.268672) (xy 221.286168 -8.082994)
			(xy 221.20903 -7.894183) (xy 221.139271 -7.702523) (xy 221.076997 -7.508302) (xy 221.0223 -7.311813)
			(xy 220.975264 -7.113351) (xy 220.935958 -6.913214) (xy 220.904443 -6.711703) (xy 220.880764 -6.509122)
			(xy 220.864959 -6.305775) (xy 220.85705 -6.101968) (xy 220.856556 -5.999988) (xy 220.856966 -5.90684)
			(xy 220.863564 -5.72066) (xy 220.876754 -5.534831) (xy 220.896521 -5.349587) (xy 220.92284 -5.165159)
			(xy 220.938852 -5.073396) (xy 220.939106 -5.072634) (xy 220.93936 -5.070856) (xy 220.939614 -5.06857)
			(xy 220.940376 -5.060188) (xy 220.940376 -5.057648) (xy 220.940122 -4.99999) (xy 220.940601 -4.900314)
			(xy 220.948278 -4.701111) (xy 220.96362 -4.502351) (xy 220.986603 -4.304329) (xy 221.017195 -4.107339)
			(xy 221.055349 -3.911673) (xy 221.10101 -3.717621) (xy 221.154109 -3.525471) (xy 221.214567 -3.335509)
			(xy 221.282295 -3.148015) (xy 221.357193 -2.963268) (xy 221.439149 -2.781543) (xy 221.528042 -2.603108)
			(xy 221.62374 -2.428228) (xy 221.7261 -2.257163) (xy 221.834972 -2.090167) (xy 221.950194 -1.927486)
			(xy 222.071594 -1.769363) (xy 222.134938 -1.692402) (xy 222.144844 -1.682496) (xy 222.150432 -1.651)
			(xy 222.104458 -1.55321) (xy 222.099996 -1.544682) (xy 222.085981 -1.531512) (xy 222.0681 -1.524433)
			(xy 222.058484 -1.524) (xy 214.065104 -1.524) (xy 214.033939 -1.524509) (xy 213.972141 -1.532645)
			(xy 213.911935 -1.548777) (xy 213.854348 -1.572629) (xy 213.800368 -1.603794) (xy 213.750918 -1.641738)
			(xy 213.706843 -1.685812) (xy 213.668898 -1.735262) (xy 213.637732 -1.789241) (xy 213.613879 -1.846827)
			(xy 213.597746 -1.907033) (xy 213.58961 -1.968831) (xy 213.589108 -1.999996) (xy 213.589108 -11.850116)
			(xy 213.588611 -11.920918) (xy 213.58067 -12.0623) (xy 213.564815 -12.203015) (xy 213.541094 -12.342619)
			(xy 213.509584 -12.480673) (xy 213.470382 -12.616744) (xy 213.423612 -12.750402) (xy 213.369422 -12.881228)
			(xy 213.307981 -13.008809) (xy 213.239484 -13.132745) (xy 213.164145 -13.252645) (xy 213.082202 -13.368132)
			(xy 212.993913 -13.478843) (xy 212.899555 -13.584429) (xy 212.799425 -13.684559) (xy 212.693838 -13.778917)
			(xy 212.583127 -13.867206) (xy 212.46764 -13.949149) (xy 212.34774 -14.024487) (xy 212.223804 -14.092984)
			(xy 212.096222 -14.154424) (xy 211.965396 -14.208614) (xy 211.831738 -14.255384) (xy 211.695667 -14.294585)
			(xy 211.557613 -14.326096) (xy 211.418009 -14.349816) (xy 211.277295 -14.365671) (xy 211.135912 -14.373611)
			(xy 211.06511 -14.374114) (xy 203.064872 -14.374114) (xy 202.994072 -14.373631) (xy 202.852696 -14.365701)
			(xy 202.711986 -14.349856) (xy 202.572386 -14.326146) (xy 202.434335 -14.294646) (xy 202.298268 -14.255455)
			(xy 202.164612 -14.208696) (xy 202.033788 -14.154516) (xy 201.906208 -14.093085) (xy 201.782274 -14.024598)
			(xy 201.662374 -13.949269) (xy 201.546888 -13.867336) (xy 201.436176 -13.779056) (xy 201.33059 -13.684707)
			(xy 201.230459 -13.584586) (xy 201.1361 -13.479009) (xy 201.04781 -13.368306) (xy 200.965865 -13.252827)
			(xy 200.890525 -13.132935) (xy 200.822026 -13.009007) (xy 200.760583 -12.881433) (xy 200.706391 -12.750614)
			(xy 200.659619 -12.616963) (xy 200.620414 -12.480899) (xy 200.588901 -12.342851) (xy 200.565178 -12.203254)
			(xy 200.549319 -12.062546) (xy 200.541376 -11.92117) (xy 200.540874 -11.85037) (xy 200.540874 -1.999996)
			(xy 200.540386 -1.96883) (xy 200.532249 -1.907032) (xy 200.516116 -1.846825) (xy 200.492262 -1.789238)
			(xy 200.461095 -1.735258) (xy 200.423148 -1.685808) (xy 200.379072 -1.641734) (xy 200.32962 -1.603791)
			(xy 200.275638 -1.572627) (xy 200.218051 -1.548776) (xy 200.157842 -1.532646) (xy 200.096044 -1.524512)
			(xy 200.064878 -1.524) (xy 188.064902 -1.524) (xy 188.033737 -1.52451) (xy 187.97194 -1.532645) (xy 187.911733 -1.548777)
			(xy 187.854147 -1.57263) (xy 187.800167 -1.603794) (xy 187.750717 -1.641739) (xy 187.706642 -1.685812)
			(xy 187.668698 -1.735262) (xy 187.637532 -1.789242) (xy 187.613679 -1.846827) (xy 187.597546 -1.907034)
			(xy 187.58941 -1.968831) (xy 187.588906 -1.999996) (xy 187.588906 -11.850116) (xy 187.588409 -11.920918)
			(xy 187.580468 -12.0623) (xy 187.564613 -12.203015) (xy 187.540892 -12.342619) (xy 187.509382 -12.480673)
			(xy 187.47018 -12.616743) (xy 187.42341 -12.750402) (xy 187.36922 -12.881227) (xy 187.307779 -13.008809)
			(xy 187.239282 -13.132744) (xy 187.163943 -13.252644) (xy 187.082 -13.368131) (xy 186.993711 -13.478842)
			(xy 186.899353 -13.584429) (xy 186.799223 -13.684558) (xy 186.693636 -13.778916) (xy 186.582925 -13.867205)
			(xy 186.467438 -13.949148) (xy 186.347537 -14.024486) (xy 186.223601 -14.092983) (xy 186.09602 -14.154423)
			(xy 185.965194 -14.208613) (xy 185.831536 -14.255382) (xy 185.695465 -14.294584) (xy 185.557411 -14.326094)
			(xy 185.417807 -14.349814) (xy 185.277092 -14.365669) (xy 185.13571 -14.373609) (xy 185.064908 -14.374114)
			(xy 177.064924 -14.374114) (xy 176.994121 -14.373627) (xy 176.852736 -14.365688) (xy 176.71202 -14.349835)
			(xy 176.572413 -14.326116) (xy 176.434356 -14.294607) (xy 176.298284 -14.255406) (xy 176.164623 -14.208638)
			(xy 176.033794 -14.154448) (xy 175.906211 -14.093008) (xy 175.782272 -14.024511) (xy 175.66237 -13.949173)
			(xy 175.54688 -13.86723) (xy 175.436166 -13.77894) (xy 175.330578 -13.684582) (xy 175.230445 -13.584452)
			(xy 175.136085 -13.478864) (xy 175.047794 -13.368152) (xy 174.965849 -13.252664) (xy 174.890509 -13.132762)
			(xy 174.82201 -13.008825) (xy 174.760568 -12.881242) (xy 174.706377 -12.750415) (xy 174.659606 -12.616755)
			(xy 174.620403 -12.480682) (xy 174.588892 -12.342626) (xy 174.565171 -12.20302) (xy 174.549315 -12.062304)
			(xy 174.541374 -11.920919) (xy 174.540926 -11.850116) (xy 174.540926 -1.999996) (xy 174.540416 -1.96883)
			(xy 174.53228 -1.907033) (xy 174.516148 -1.846825) (xy 174.492295 -1.789239) (xy 174.46113 -1.735258)
			(xy 174.423187 -1.685806) (xy 174.379113 -1.64173) (xy 174.329664 -1.603784) (xy 174.275685 -1.572616)
			(xy 174.218099 -1.548761) (xy 174.157893 -1.532625) (xy 174.096096 -1.524486) (xy 174.06493 -1.524)
			(xy 172.121576 -1.524) (xy 172.11196 -1.524416) (xy 172.094082 -1.531508) (xy 172.080072 -1.544685)
			(xy 172.075602 -1.55321) (xy 172.030136 -1.64973) (xy 172.033946 -1.67894) (xy 172.043344 -1.69037)
			(xy 172.10677 -1.76736) (xy 172.228348 -1.925536) (xy 172.343739 -2.088279) (xy 172.452773 -2.255349)
			(xy 172.555287 -2.426496) (xy 172.651129 -2.601467) (xy 172.740157 -2.780001) (xy 172.822239 -2.961834)
			(xy 172.897252 -3.146696) (xy 172.965085 -3.33431) (xy 173.025637 -3.5244) (xy 173.078819 -3.716681)
			(xy 173.124551 -3.91087) (xy 173.162765 -4.106677) (xy 173.193405 -4.30381) (xy 173.216425 -4.501979)
			(xy 173.231791 -4.700887) (xy 173.239479 -4.90024) (xy 173.239938 -4.99999) (xy 173.239938 -5.00507)
			(xy 173.239938 -5.005324) (xy 173.239684 -5.056124) (xy 173.239684 -5.058664) (xy 173.240446 -5.067046)
			(xy 173.2407 -5.069332) (xy 173.240954 -5.07111) (xy 173.241208 -5.071872) (xy 173.25721 -5.163585)
			(xy 173.283512 -5.347912) (xy 173.303274 -5.533055) (xy 173.316471 -5.718782) (xy 173.323087 -5.904859)
			(xy 173.323504 -5.997956) (xy 173.323504 -5.999988) (xy 173.32301 -6.101963) (xy 173.315101 -6.30576)
			(xy 173.299297 -6.509097) (xy 173.27562 -6.711669) (xy 173.244105 -6.913169) (xy 173.204802 -7.113297)
			(xy 173.157768 -7.31175) (xy 173.103074 -7.50823) (xy 173.040802 -7.702441) (xy 172.971047 -7.894092)
			(xy 172.893913 -8.082893) (xy 172.809516 -8.268562) (xy 172.717984 -8.450819) (xy 172.619453 -8.629389)
			(xy 172.514072 -8.804005) (xy 172.401999 -8.974403) (xy 172.283403 -9.140327) (xy 172.158463 -9.301528)
			(xy 172.027367 -9.457763) (xy 171.89031 -9.608797) (xy 171.747501 -9.754403) (xy 171.599153 -9.894363)
			(xy 171.445489 -10.028464) (xy 171.286741 -10.156507) (xy 171.123148 -10.278298) (xy 170.954955 -10.393653)
			(xy 170.782416 -10.502401) (xy 170.60579 -10.604376) (xy 170.425342 -10.699426) (xy 170.241345 -10.787407)
			(xy 170.054074 -10.868188) (xy 169.863812 -10.941646) (xy 169.670845 -11.007672) (xy 169.475463 -11.066165)
			(xy 169.277959 -11.117039) (xy 169.078632 -11.160216) (xy 168.87778 -11.195631) (xy 168.675706 -11.223232)
			(xy 168.472713 -11.242977) (xy 168.269108 -11.254836) (xy 168.065196 -11.258791) (xy 167.861284 -11.254836)
			(xy 167.657679 -11.242977) (xy 167.454686 -11.223232) (xy 167.252612 -11.195631) (xy 167.05176 -11.160216)
			(xy 166.852433 -11.117039) (xy 166.654929 -11.066165) (xy 166.459547 -11.007672) (xy 166.26658 -10.941646)
			(xy 166.076318 -10.868188) (xy 165.889047 -10.787407) (xy 165.70505 -10.699426) (xy 165.524602 -10.604376)
			(xy 165.347976 -10.502401) (xy 165.175437 -10.393653) (xy 165.007244 -10.278298) (xy 164.843651 -10.156507)
			(xy 164.684903 -10.028464) (xy 164.531239 -9.894363) (xy 164.382891 -9.754403) (xy 164.240082 -9.608797)
			(xy 164.103025 -9.457763) (xy 163.971929 -9.301528) (xy 163.846989 -9.140327) (xy 163.728393 -8.974403)
			(xy 163.61632 -8.804005) (xy 163.510939 -8.629389) (xy 163.412408 -8.450819) (xy 163.320876 -8.268562)
			(xy 163.236479 -8.082893) (xy 163.159345 -7.894092) (xy 163.08959 -7.702441) (xy 163.027318 -7.50823)
			(xy 162.972624 -7.31175) (xy 162.92559 -7.113297) (xy 162.886287 -6.913169) (xy 162.854772 -6.711669)
			(xy 162.831095 -6.509097) (xy 162.815291 -6.30576) (xy 162.807382 -6.101963) (xy 162.806888 -5.999988)
			(xy 162.806888 -5.997956) (xy 162.807305 -5.904988) (xy 162.813895 -5.719169) (xy 162.827049 -5.533698)
			(xy 162.846749 -5.348809) (xy 162.872971 -5.164731) (xy 162.88893 -5.073142) (xy 162.889438 -5.07111)
			(xy 162.8902 -5.061204) (xy 162.8902 -5.058664) (xy 162.889946 -4.99999) (xy 162.890425 -4.900314)
			(xy 162.898102 -4.701111) (xy 162.913444 -4.502351) (xy 162.936428 -4.304329) (xy 162.967019 -4.107339)
			(xy 163.005174 -3.911673) (xy 163.050834 -3.717621) (xy 163.103933 -3.525472) (xy 163.164392 -3.335509)
			(xy 163.232121 -3.148016) (xy 163.307018 -2.96327) (xy 163.388975 -2.781544) (xy 163.477868 -2.60311)
			(xy 163.573566 -2.42823) (xy 163.675927 -2.257166) (xy 163.784799 -2.090169) (xy 163.900021 -1.927489)
			(xy 164.021422 -1.769366) (xy 164.084762 -1.692402) (xy 164.094668 -1.682496) (xy 164.100256 -1.651)
			(xy 164.054282 -1.55321) (xy 164.047932 -1.539748) (xy 164.023294 -1.524) (xy 162.064954 -1.524)
			(xy 162.033791 -1.524513) (xy 161.971998 -1.532653) (xy 161.911797 -1.548789) (xy 161.854217 -1.572645)
			(xy 161.800242 -1.603811) (xy 161.750797 -1.641756) (xy 161.706728 -1.685829) (xy 161.668788 -1.735277)
			(xy 161.637626 -1.789254) (xy 161.613776 -1.846837) (xy 161.597645 -1.90704) (xy 161.58951 -1.968833)
			(xy 161.588958 -1.999996) (xy 161.588958 -11.850116) (xy 161.58847 -11.920918) (xy 161.580529 -12.0623)
			(xy 161.564674 -12.203014) (xy 161.540953 -12.342617) (xy 161.509442 -12.480671) (xy 161.47024 -12.616741)
			(xy 161.42347 -12.750398) (xy 161.369279 -12.881223) (xy 161.307838 -13.008804) (xy 161.23934 -13.132738)
			(xy 161.164001 -13.252638) (xy 161.082057 -13.368124) (xy 160.993767 -13.478834) (xy 160.899409 -13.584419)
			(xy 160.799278 -13.684547) (xy 160.693691 -13.778903) (xy 160.582979 -13.867191) (xy 160.467491 -13.949132)
			(xy 160.34759 -14.024468) (xy 160.223654 -14.092964) (xy 160.096072 -14.154402) (xy 159.965246 -14.20859)
			(xy 159.831587 -14.255357) (xy 159.695517 -14.294556) (xy 159.557462 -14.326064) (xy 159.417858 -14.349781)
			(xy 159.277144 -14.365634) (xy 159.135762 -14.373572) (xy 159.06496 -14.374114) (xy 151.064976 -14.374114)
			(xy 150.994174 -14.373617) (xy 150.852792 -14.365676) (xy 150.712078 -14.34982) (xy 150.572474 -14.326099)
			(xy 150.43442 -14.294588) (xy 150.298349 -14.255386) (xy 150.164691 -14.208616) (xy 150.033866 -14.154426)
			(xy 149.906285 -14.092985) (xy 149.782349 -14.024487) (xy 149.66245 -13.949149) (xy 149.546963 -13.867206)
			(xy 149.436252 -13.778916) (xy 149.330666 -13.684558) (xy 149.230536 -13.584429) (xy 149.136178 -13.478842)
			(xy 149.047889 -13.368131) (xy 148.965947 -13.252644) (xy 148.890608 -13.132744) (xy 148.822111 -13.008808)
			(xy 148.760671 -12.881227) (xy 148.706481 -12.750401) (xy 148.659712 -12.616743) (xy 148.62051 -12.480673)
			(xy 148.588999 -12.342618) (xy 148.565279 -12.203014) (xy 148.549424 -12.0623) (xy 148.541483 -11.920918)
			(xy 148.540978 -11.850116) (xy 148.540978 -1.999996) (xy 148.54049 -1.96883) (xy 148.532353 -1.907032)
			(xy 148.51622 -1.846824) (xy 148.492366 -1.789238) (xy 148.461199 -1.735257) (xy 148.423253 -1.685807)
			(xy 148.379176 -1.641733) (xy 148.329724 -1.603789) (xy 148.275743 -1.572625) (xy 148.218155 -1.548773)
			(xy 148.157947 -1.532642) (xy 148.096148 -1.524509) (xy 148.064982 -1.524) (xy 136.065006 -1.524)
			(xy 136.033839 -1.524487) (xy 135.972039 -1.532623) (xy 135.911829 -1.548755) (xy 135.85424 -1.572609)
			(xy 135.800257 -1.603775) (xy 135.750804 -1.641721) (xy 135.706727 -1.685797) (xy 135.66878 -1.735249)
			(xy 135.637613 -1.789231) (xy 135.613758 -1.846819) (xy 135.597625 -1.907029) (xy 135.589488 -1.968829)
			(xy 135.58901 -1.999996) (xy 135.58901 -11.850116) (xy 135.588513 -11.920918) (xy 135.580572 -12.062301)
			(xy 135.564717 -12.203015) (xy 135.540996 -12.342619) (xy 135.509486 -12.480673) (xy 135.470284 -12.616744)
			(xy 135.423514 -12.750402) (xy 135.369324 -12.881228) (xy 135.307883 -13.008809) (xy 135.239386 -13.132745)
			(xy 135.164047 -13.252645) (xy 135.082104 -13.368133) (xy 134.993815 -13.478844) (xy 134.899457 -13.58443)
			(xy 134.799327 -13.68456) (xy 134.69374 -13.778918) (xy 134.583029 -13.867207) (xy 134.467542 -13.94915)
			(xy 134.347642 -14.024488) (xy 134.223706 -14.092985) (xy 134.096124 -14.154425) (xy 133.965299 -14.208616)
			(xy 133.83164 -14.255385) (xy 133.69557 -14.294587) (xy 133.557515 -14.326097) (xy 133.417911 -14.349817)
			(xy 133.277197 -14.365673) (xy 133.135814 -14.373613) (xy 133.065012 -14.374114) (xy 125.065028 -14.374114)
			(xy 124.994224 -14.373627) (xy 124.85284 -14.365689) (xy 124.712123 -14.349835) (xy 124.572517 -14.326117)
			(xy 124.43446 -14.294608) (xy 124.298387 -14.255407) (xy 124.164726 -14.208639) (xy 124.033897 -14.154449)
			(xy 123.906313 -14.09301) (xy 123.782374 -14.024513) (xy 123.662472 -13.949174) (xy 123.546982 -13.867231)
			(xy 123.436268 -13.778942) (xy 123.330679 -13.684583) (xy 123.230547 -13.584453) (xy 123.136187 -13.478866)
			(xy 123.047895 -13.368153) (xy 122.96595 -13.252665) (xy 122.89061 -13.132763) (xy 122.822111 -13.008826)
			(xy 122.760669 -12.881243) (xy 122.706477 -12.750416) (xy 122.659706 -12.616755) (xy 122.620503 -12.480683)
			(xy 122.588992 -12.342626) (xy 122.565271 -12.20302) (xy 122.549415 -12.062304) (xy 122.541474 -11.92092)
			(xy 122.54103 -11.850116) (xy 122.54103 -1.999996) (xy 122.54052 -1.96883) (xy 122.532384 -1.907032)
			(xy 122.516252 -1.846825) (xy 122.492399 -1.789238) (xy 122.461235 -1.735257) (xy 122.423291 -1.685805)
			(xy 122.379217 -1.641729) (xy 122.329768 -1.603782) (xy 122.275789 -1.572614) (xy 122.218204 -1.548758)
			(xy 122.157997 -1.532622) (xy 122.0962 -1.524482) (xy 122.065034 -1.524) (xy 97.965006 -1.524) (xy 97.933839 -1.524487)
			(xy 97.872039 -1.532623) (xy 97.811829 -1.548755) (xy 97.75424 -1.572609) (xy 97.700257 -1.603775)
			(xy 97.650804 -1.641721) (xy 97.606727 -1.685797) (xy 97.56878 -1.735249) (xy 97.537613 -1.789231)
			(xy 97.513758 -1.846819) (xy 97.497625 -1.907029) (xy 97.489488 -1.968829) (xy 97.48901 -1.999996)
			(xy 97.48901 -7.35711) (xy 97.489603 -7.368371) (xy 97.499211 -7.388742) (xy 97.516587 -7.403071)
			(xy 97.527364 -7.406386) (xy 97.528126 -7.406386) (xy 97.555421 -7.413584) (xy 97.60768 -7.434925)
			(xy 97.656224 -7.463733) (xy 97.699993 -7.499378) (xy 97.738033 -7.541084) (xy 97.769512 -7.587939)
			(xy 97.793745 -7.638921) (xy 97.810201 -7.692917) (xy 97.818523 -7.748748) (xy 97.818956 -7.776972)
			(xy 97.818411 -7.806695) (xy 97.809231 -7.865428) (xy 97.791041 -7.922023) (xy 97.764283 -7.975106)
			(xy 97.729606 -8.02339) (xy 97.687853 -8.065704) (xy 97.66427 -8.083804) (xy 97.658428 -8.08863)
			(xy 97.653602 -8.093456) (xy 97.650909 -8.096177) (xy 97.646311 -8.102298) (xy 97.644458 -8.105648)
			(xy 97.634806 -8.12419) (xy 97.632111 -8.129721) (xy 97.629158 -8.141662) (xy 97.628964 -8.147812)
			(xy 97.628964 -8.212328) (xy 97.632012 -8.224266) (xy 97.634806 -8.229854) (xy 97.645474 -8.250174)
			(xy 97.648287 -8.255165) (xy 97.655724 -8.263876) (xy 97.660206 -8.267446) (xy 97.660714 -8.2677)
			(xy 97.660968 -8.267954) (xy 97.681587 -8.283389) (xy 97.718882 -8.318912) (xy 97.751061 -8.359129)
			(xy 97.777539 -8.403308) (xy 97.797835 -8.450646) (xy 97.811579 -8.500284) (xy 97.818523 -8.551319)
			(xy 97.818956 -8.577072) (xy 97.818448 -8.605304) (xy 97.810126 -8.661152) (xy 97.79366 -8.715163)
			(xy 97.769411 -8.766155) (xy 97.737908 -8.813014) (xy 97.69984 -8.854716) (xy 97.656038 -8.890349)
			(xy 97.607462 -8.919134) (xy 97.555172 -8.940442) (xy 97.527872 -8.947658) (xy 97.5106 -8.951976)
			(xy 97.48901 -8.979408) (xy 97.48901 -11.850116) (xy 97.488513 -11.920918) (xy 97.480572 -12.062301)
			(xy 97.464717 -12.203015) (xy 97.440996 -12.342619) (xy 97.409486 -12.480673) (xy 97.370284 -12.616744)
			(xy 97.323514 -12.750402) (xy 97.269324 -12.881228) (xy 97.207883 -13.008809) (xy 97.139386 -13.132745)
			(xy 97.064047 -13.252645) (xy 96.982104 -13.368133) (xy 96.893815 -13.478844) (xy 96.799457 -13.58443)
			(xy 96.699327 -13.68456) (xy 96.59374 -13.778918) (xy 96.483029 -13.867207) (xy 96.367542 -13.94915)
			(xy 96.247642 -14.024488) (xy 96.123706 -14.092985) (xy 95.996124 -14.154425) (xy 95.865299 -14.208616)
			(xy 95.73164 -14.255385) (xy 95.59557 -14.294587) (xy 95.457515 -14.326097) (xy 95.317911 -14.349817)
			(xy 95.177197 -14.365673) (xy 95.035814 -14.373613) (xy 94.965012 -14.374114) (xy 86.965028 -14.374114)
			(xy 86.894224 -14.373627) (xy 86.75284 -14.365689) (xy 86.612123 -14.349835) (xy 86.472517 -14.326117)
			(xy 86.33446 -14.294608) (xy 86.198387 -14.255407) (xy 86.064726 -14.208639) (xy 85.933897 -14.154449)
			(xy 85.806313 -14.09301) (xy 85.682374 -14.024513) (xy 85.562472 -13.949174) (xy 85.446982 -13.867231)
			(xy 85.336268 -13.778942) (xy 85.230679 -13.684583) (xy 85.130547 -13.584453) (xy 85.036187 -13.478866)
			(xy 84.947895 -13.368153) (xy 84.86595 -13.252665) (xy 84.79061 -13.132763) (xy 84.722111 -13.008826)
			(xy 84.660669 -12.881243) (xy 84.606477 -12.750416) (xy 84.559706 -12.616755) (xy 84.520503 -12.480683)
			(xy 84.488992 -12.342626) (xy 84.465271 -12.20302) (xy 84.449415 -12.062304) (xy 84.441474 -11.92092)
			(xy 84.44103 -11.850116) (xy 84.44103 -1.999996) (xy 84.44052 -1.96883) (xy 84.432384 -1.907032)
			(xy 84.416252 -1.846825) (xy 84.392399 -1.789238) (xy 84.361235 -1.735257) (xy 84.323291 -1.685805)
			(xy 84.279217 -1.641729) (xy 84.229768 -1.603782) (xy 84.175789 -1.572614) (xy 84.118204 -1.548758)
			(xy 84.057997 -1.532622) (xy 83.9962 -1.524482) (xy 83.965034 -1.524) (xy 71.965058 -1.524) (xy 71.933895 -1.524512)
			(xy 71.872102 -1.532653) (xy 71.8119 -1.548788) (xy 71.754319 -1.572643) (xy 71.700344 -1.60381)
			(xy 71.650899 -1.641754) (xy 71.606829 -1.685828) (xy 71.568889 -1.735276) (xy 71.537727 -1.789253)
			(xy 71.513876 -1.846836) (xy 71.497745 -1.907039) (xy 71.48961 -1.968833) (xy 71.489062 -1.999996)
			(xy 71.489062 -11.850116) (xy 71.488574 -11.920918) (xy 71.480633 -12.0623) (xy 71.464778 -12.203014)
			(xy 71.441057 -12.342617) (xy 71.409546 -12.480671) (xy 71.370344 -12.616741) (xy 71.323574 -12.750399)
			(xy 71.269383 -12.881224) (xy 71.207942 -13.008804) (xy 71.139444 -13.132739) (xy 71.064105 -13.252639)
			(xy 70.982161 -13.368125) (xy 70.893871 -13.478835) (xy 70.799513 -13.58442) (xy 70.699382 -13.684548)
			(xy 70.593795 -13.778905) (xy 70.483083 -13.867193) (xy 70.367595 -13.949134) (xy 70.247695 -14.024471)
			(xy 70.123758 -14.092966) (xy 69.996176 -14.154404) (xy 69.86535 -14.208592) (xy 69.731692 -14.25536)
			(xy 69.595621 -14.294559) (xy 69.457566 -14.326067) (xy 69.317962 -14.349785) (xy 69.177248 -14.365638)
			(xy 69.035866 -14.373575) (xy 68.965064 -14.374114) (xy 60.96508 -14.374114) (xy 60.894278 -14.373617)
			(xy 60.752896 -14.365676) (xy 60.612181 -14.34982) (xy 60.472577 -14.3261) (xy 60.334523 -14.294589)
			(xy 60.198453 -14.255387) (xy 60.064794 -14.208617) (xy 59.933969 -14.154427) (xy 59.806387 -14.092986)
			(xy 59.682452 -14.024489) (xy 59.562552 -13.94915) (xy 59.447065 -13.867207) (xy 59.336354 -13.778918)
			(xy 59.230767 -13.68456) (xy 59.130637 -13.58443) (xy 59.03628 -13.478843) (xy 58.94799 -13.368132)
			(xy 58.866048 -13.252645) (xy 58.790709 -13.132745) (xy 58.722212 -13.008809) (xy 58.660772 -12.881228)
			(xy 58.606581 -12.750402) (xy 58.559812 -12.616744) (xy 58.52061 -12.480673) (xy 58.4891 -12.342619)
			(xy 58.465379 -12.203015) (xy 58.449524 -12.0623) (xy 58.441583 -11.920918) (xy 58.441082 -11.850116)
			(xy 58.441082 -1.999996) (xy 58.440594 -1.96883) (xy 58.432457 -1.907031) (xy 58.416324 -1.846824)
			(xy 58.39247 -1.789237) (xy 58.361303 -1.735256) (xy 58.323357 -1.685806) (xy 58.279281 -1.641731)
			(xy 58.229829 -1.603787) (xy 58.175847 -1.572622) (xy 58.118259 -1.54877) (xy 58.058051 -1.532639)
			(xy 57.996252 -1.524505) (xy 57.965086 -1.524) (xy 45.96511 -1.524) (xy 45.933943 -1.524487) (xy 45.872142 -1.532622)
			(xy 45.811932 -1.548754) (xy 45.754342 -1.572607) (xy 45.700359 -1.603773) (xy 45.650906 -1.641719)
			(xy 45.606828 -1.685795) (xy 45.568881 -1.735248) (xy 45.537714 -1.78923) (xy 45.513859 -1.846819)
			(xy 45.497725 -1.907028) (xy 45.489588 -1.968829) (xy 45.489114 -1.999996) (xy 45.489114 -11.850116)
			(xy 45.488617 -11.920918) (xy 45.480676 -12.062301) (xy 45.464821 -12.203015) (xy 45.4411 -12.342619)
			(xy 45.40959 -12.480674) (xy 45.370388 -12.616744) (xy 45.323618 -12.750403) (xy 45.269428 -12.881229)
			(xy 45.207987 -13.00881) (xy 45.13949 -13.132746) (xy 45.064152 -13.252646) (xy 44.982209 -13.368134)
			(xy 44.893919 -13.478845) (xy 44.799561 -13.584431) (xy 44.699431 -13.684561) (xy 44.593845 -13.778919)
			(xy 44.483134 -13.867209) (xy 44.367646 -13.949152) (xy 44.247746 -14.02449) (xy 44.12381 -14.092987)
			(xy 43.996229 -14.154428) (xy 43.865403 -14.208618) (xy 43.731744 -14.255388) (xy 43.595674 -14.29459)
			(xy 43.457619 -14.3261) (xy 43.318015 -14.349821) (xy 43.177301 -14.365676) (xy 43.035918 -14.373617)
			(xy 42.965116 -14.374114) (xy 34.964878 -14.374114) (xy 34.894076 -14.373617) (xy 34.752694 -14.365676)
			(xy 34.611979 -14.34982) (xy 34.472376 -14.326099) (xy 34.334321 -14.294588) (xy 34.198251 -14.255386)
			(xy 34.064593 -14.208617) (xy 33.933767 -14.154426) (xy 33.806186 -14.092986) (xy 33.682251 -14.024488)
			(xy 33.562351 -13.949149) (xy 33.446864 -13.867207) (xy 33.336153 -13.778917) (xy 33.230566 -13.684559)
			(xy 33.130437 -13.584429) (xy 33.036079 -13.478843) (xy 32.94779 -13.368132) (xy 32.865847 -13.252644)
			(xy 32.790509 -13.132744) (xy 32.722012 -13.008809) (xy 32.660571 -12.881227) (xy 32.606381 -12.750402)
			(xy 32.559612 -12.616743) (xy 32.52041 -12.480673) (xy 32.488899 -12.342619) (xy 32.465179 -12.203015)
			(xy 32.449324 -12.0623) (xy 32.441383 -11.920918) (xy 32.44088 -11.850116) (xy 32.44088 -1.999996)
			(xy 32.440392 -1.96883) (xy 32.432255 -1.907032) (xy 32.416122 -1.846824) (xy 32.392268 -1.789237)
			(xy 32.361101 -1.735257) (xy 32.323155 -1.685806) (xy 32.279079 -1.641732) (xy 32.229627 -1.603788)
			(xy 32.175645 -1.572623) (xy 32.118057 -1.548772) (xy 32.057849 -1.532641) (xy 31.99605 -1.524507)
			(xy 31.964884 -1.524) (xy 19.964908 -1.524) (xy 19.933741 -1.524487) (xy 19.87194 -1.532622) (xy 19.81173 -1.548755)
			(xy 19.754141 -1.572608) (xy 19.700158 -1.603774) (xy 19.650705 -1.64172) (xy 19.606628 -1.685796)
			(xy 19.568681 -1.735248) (xy 19.537513 -1.78923) (xy 19.513659 -1.846819) (xy 19.497525 -1.907029)
			(xy 19.489388 -1.968829) (xy 19.488912 -1.999996) (xy 19.488912 -11.850116) (xy 19.488416 -11.920919)
			(xy 19.480476 -12.062301) (xy 19.464621 -12.203017) (xy 19.440902 -12.342621) (xy 19.409392 -12.480676)
			(xy 19.370191 -12.616748) (xy 19.323421 -12.750407) (xy 19.269232 -12.881233) (xy 19.207792 -13.008815)
			(xy 19.139294 -13.132752) (xy 19.063956 -13.252653) (xy 18.982013 -13.368141) (xy 18.893724 -13.478853)
			(xy 18.799366 -13.58444) (xy 18.699236 -13.68457) (xy 18.593649 -13.778929) (xy 18.482937 -13.867218)
			(xy 18.36745 -13.949162) (xy 18.247549 -14.0245) (xy 18.123613 -14.092998) (xy 17.996031 -14.154438)
			(xy 17.865204 -14.208629) (xy 17.731545 -14.255398) (xy 17.595474 -14.2946) (xy 17.457419 -14.32611)
			(xy 17.317814 -14.34983) (xy 17.177099 -14.365685) (xy 17.035717 -14.373625) (xy 16.964914 -14.374114)
			(xy 8.96493 -14.374114) (xy 8.894127 -14.373626) (xy 8.752744 -14.365687) (xy 8.612029 -14.349832)
			(xy 8.472424 -14.326112) (xy 8.334369 -14.294602) (xy 8.198297 -14.2554) (xy 8.064638 -14.208631)
			(xy 7.933812 -14.15444) (xy 7.806229 -14.093) (xy 7.682293 -14.024503) (xy 7.562392 -13.949164) (xy 7.446904 -13.867221)
			(xy 7.336192 -13.778931) (xy 7.230605 -13.684572) (xy 7.130475 -13.584442) (xy 7.036117 -13.478855)
			(xy 6.947827 -13.368143) (xy 6.865884 -13.252655) (xy 6.790545 -13.132754) (xy 6.722048 -13.008817)
			(xy 6.660608 -12.881235) (xy 6.606418 -12.750408) (xy 6.559649 -12.616749) (xy 6.520447 -12.480677)
			(xy 6.488937 -12.342622) (xy 6.465218 -12.203017) (xy 6.449363 -12.062302) (xy 6.441423 -11.920919)
			(xy 6.440932 -11.850116) (xy 6.440932 -1.999996) (xy 6.440422 -1.96883) (xy 6.432286 -1.907032) (xy 6.416154 -1.846825)
			(xy 6.392301 -1.789238) (xy 6.361137 -1.735256) (xy 6.323193 -1.685804) (xy 6.27912 -1.641728) (xy 6.22967 -1.603781)
			(xy 6.175691 -1.572613) (xy 6.118106 -1.548756) (xy 6.057899 -1.53262) (xy 5.996102 -1.52448) (xy 5.964936 -1.524)
			(xy 1.999996 -1.524) (xy 1.968831 -1.52451) (xy 1.907034 -1.532646) (xy 1.846829 -1.548779) (xy 1.789243 -1.572631)
			(xy 1.735264 -1.603797) (xy 1.685815 -1.641741) (xy 1.641741 -1.685815) (xy 1.603797 -1.735264) (xy 1.572631 -1.789243)
			(xy 1.548779 -1.846829) (xy 1.532646 -1.907034) (xy 1.52451 -1.968831) (xy 1.524 -1.999996) (xy 1.524 -16.969994)
			(xy 13.748519 -16.969994) (xy 13.752523 -16.882109) (xy 13.764503 -16.794952) (xy 13.784358 -16.709245)
			(xy 13.811925 -16.6257) (xy 13.846975 -16.545007) (xy 13.889217 -16.467835) (xy 13.938302 -16.394825)
			(xy 13.993823 -16.326581) (xy 14.05532 -16.263668) (xy 14.122282 -16.206608) (xy 14.194156 -16.155874)
			(xy 14.270346 -16.111886) (xy 14.35022 -16.075008) (xy 14.433117 -16.045547) (xy 14.518349 -16.023745)
			(xy 14.605211 -16.009785) (xy 14.692982 -16.003781) (xy 14.780936 -16.005784) (xy 14.868343 -16.015776)
			(xy 14.954479 -16.033676) (xy 15.038631 -16.059334) (xy 15.120101 -16.092538) (xy 15.198214 -16.133012)
			(xy 15.272322 -16.180423) (xy 15.341813 -16.234376) (xy 15.406109 -16.294424) (xy 15.464678 -16.360071)
			(xy 15.517035 -16.430771) (xy 15.562747 -16.50594) (xy 15.601433 -16.584954) (xy 15.632774 -16.667159)
			(xy 15.656509 -16.751873) (xy 15.672443 -16.838394) (xy 15.680443 -16.926006) (xy 15.680944 -16.969994)
			(xy 15.680443 -17.013982) (xy 15.672443 -17.101594) (xy 15.656509 -17.188115) (xy 15.632774 -17.272829)
			(xy 15.601433 -17.355034) (xy 15.562747 -17.434048) (xy 15.517035 -17.509217) (xy 15.464678 -17.579917)
			(xy 15.406109 -17.645564) (xy 15.341813 -17.705612) (xy 15.272322 -17.759565) (xy 15.198214 -17.806976)
			(xy 15.120101 -17.84745) (xy 15.038631 -17.880654) (xy 14.954479 -17.906312) (xy 14.868343 -17.924212)
			(xy 14.780936 -17.934204) (xy 14.692982 -17.936207) (xy 14.605211 -17.930203) (xy 14.518349 -17.916243)
			(xy 14.433117 -17.894441) (xy 14.35022 -17.86498) (xy 14.270346 -17.828102) (xy 14.194156 -17.784114)
			(xy 14.122282 -17.73338) (xy 14.05532 -17.67632) (xy 13.993823 -17.613407) (xy 13.938302 -17.545163)
			(xy 13.889217 -17.472153) (xy 13.846975 -17.394981) (xy 13.811925 -17.314288) (xy 13.784358 -17.230743)
			(xy 13.764503 -17.145036) (xy 13.752523 -17.057879) (xy 13.748519 -16.969994) (xy 1.524 -16.969994)
			(xy 1.524 -17.999964) (xy 20.705834 -17.999964) (xy 20.709838 -17.794776) (xy 20.721845 -17.5899)
			(xy 20.741836 -17.385649) (xy 20.769781 -17.182334) (xy 20.805637 -16.980263) (xy 20.849351 -16.779745)
			(xy 20.900854 -16.581086) (xy 20.960069 -16.384587) (xy 21.026905 -16.190548) (xy 21.101261 -15.999265)
			(xy 21.183024 -15.811028) (xy 21.272069 -15.626125) (xy 21.36826 -15.444837) (xy 21.471451 -15.26744)
			(xy 21.581485 -15.094203) (xy 21.698194 -14.925392) (xy 21.8214 -14.761263) (xy 21.950917 -14.602066)
			(xy 22.086546 -14.448044) (xy 22.228081 -14.29943) (xy 22.375306 -14.156452) (xy 22.527998 -14.019327)
			(xy 22.685924 -13.888263) (xy 22.848843 -13.763461) (xy 23.016508 -13.645111) (xy 23.188662 -13.533392)
			(xy 23.365044 -13.428475) (xy 23.545385 -13.33052) (xy 23.729411 -13.239676) (xy 23.916841 -13.15608)
			(xy 24.10739 -13.079861) (xy 24.300767 -13.011135) (xy 24.496679 -12.950006) (xy 24.694826 -12.896567)
			(xy 24.894908 -12.8509) (xy 25.096619 -12.813073) (xy 25.299652 -12.783146) (xy 25.503699 -12.761163)
			(xy 25.708448 -12.747158) (xy 25.913587 -12.741152) (xy 26.118804 -12.743154) (xy 26.323787 -12.753162)
			(xy 26.528224 -12.771159) (xy 26.731802 -12.797119) (xy 26.934213 -12.831002) (xy 27.135147 -12.872757)
			(xy 27.3343 -12.92232) (xy 27.531367 -12.979615) (xy 27.726049 -13.044555) (xy 27.918049 -13.117041)
			(xy 28.107074 -13.196964) (xy 28.292837 -13.2842) (xy 28.475055 -13.378618) (xy 28.653451 -13.480073)
			(xy 28.827752 -13.588412) (xy 28.997694 -13.703468) (xy 29.163017 -13.825068) (xy 29.32347 -13.953025)
			(xy 29.478809 -14.087144) (xy 29.628796 -14.227223) (xy 29.773204 -14.373047) (xy 29.911812 -14.524393)
			(xy 30.04441 -14.681033) (xy 30.170796 -14.842727) (xy 30.290776 -15.009229) (xy 30.404169 -15.180285)
			(xy 30.510802 -15.355635) (xy 30.610512 -15.535012) (xy 30.703148 -15.718142) (xy 30.788568 -15.904748)
			(xy 30.866642 -16.094544) (xy 30.937252 -16.287242) (xy 31.000289 -16.482548) (xy 31.055659 -16.680164)
			(xy 31.103276 -16.879791) (xy 31.121104 -16.969994) (xy 39.748467 -16.969994) (xy 39.752471 -16.882109)
			(xy 39.764451 -16.794952) (xy 39.784306 -16.709245) (xy 39.811873 -16.6257) (xy 39.846923 -16.545007)
			(xy 39.889165 -16.467835) (xy 39.93825 -16.394825) (xy 39.993771 -16.326581) (xy 40.055268 -16.263668)
			(xy 40.12223 -16.206608) (xy 40.194104 -16.155874) (xy 40.270294 -16.111886) (xy 40.350168 -16.075008)
			(xy 40.433065 -16.045547) (xy 40.518297 -16.023745) (xy 40.605159 -16.009785) (xy 40.69293 -16.003781)
			(xy 40.780884 -16.005784) (xy 40.868291 -16.015776) (xy 40.954427 -16.033676) (xy 41.038579 -16.059334)
			(xy 41.120049 -16.092538) (xy 41.198162 -16.133012) (xy 41.27227 -16.180423) (xy 41.341761 -16.234376)
			(xy 41.406057 -16.294424) (xy 41.464626 -16.360071) (xy 41.516983 -16.430771) (xy 41.562695 -16.50594)
			(xy 41.601381 -16.584954) (xy 41.632722 -16.667159) (xy 41.656457 -16.751873) (xy 41.672391 -16.838394)
			(xy 41.680391 -16.926006) (xy 41.680892 -16.969994) (xy 65.748415 -16.969994) (xy 65.752419 -16.882109)
			(xy 65.764399 -16.794952) (xy 65.784254 -16.709245) (xy 65.811821 -16.6257) (xy 65.846871 -16.545007)
			(xy 65.889113 -16.467835) (xy 65.938198 -16.394825) (xy 65.993719 -16.326581) (xy 66.055216 -16.263668)
			(xy 66.122178 -16.206608) (xy 66.194052 -16.155874) (xy 66.270242 -16.111886) (xy 66.350116 -16.075008)
			(xy 66.433013 -16.045547) (xy 66.518245 -16.023745) (xy 66.605107 -16.009785) (xy 66.692878 -16.003781)
			(xy 66.780832 -16.005784) (xy 66.868239 -16.015776) (xy 66.954375 -16.033676) (xy 67.038527 -16.059334)
			(xy 67.119997 -16.092538) (xy 67.19811 -16.133012) (xy 67.272218 -16.180423) (xy 67.341709 -16.234376)
			(xy 67.406005 -16.294424) (xy 67.464574 -16.360071) (xy 67.516931 -16.430771) (xy 67.562643 -16.50594)
			(xy 67.601329 -16.584954) (xy 67.63267 -16.667159) (xy 67.656405 -16.751873) (xy 67.672339 -16.838394)
			(xy 67.680339 -16.926006) (xy 67.68084 -16.969994) (xy 91.748363 -16.969994) (xy 91.752367 -16.882109)
			(xy 91.764347 -16.794952) (xy 91.784202 -16.709245) (xy 91.811769 -16.6257) (xy 91.846819 -16.545007)
			(xy 91.889061 -16.467835) (xy 91.938146 -16.394825) (xy 91.993667 -16.326581) (xy 92.055164 -16.263668)
			(xy 92.122126 -16.206608) (xy 92.194 -16.155874) (xy 92.27019 -16.111886) (xy 92.350064 -16.075008)
			(xy 92.432961 -16.045547) (xy 92.518193 -16.023745) (xy 92.605055 -16.009785) (xy 92.692826 -16.003781)
			(xy 92.78078 -16.005784) (xy 92.868187 -16.015776) (xy 92.954323 -16.033676) (xy 93.038475 -16.059334)
			(xy 93.119945 -16.092538) (xy 93.198058 -16.133012) (xy 93.272166 -16.180423) (xy 93.341657 -16.234376)
			(xy 93.405953 -16.294424) (xy 93.464522 -16.360071) (xy 93.516879 -16.430771) (xy 93.562591 -16.50594)
			(xy 93.601277 -16.584954) (xy 93.632618 -16.667159) (xy 93.656353 -16.751873) (xy 93.672287 -16.838394)
			(xy 93.680287 -16.926006) (xy 93.680788 -16.969994) (xy 93.680287 -17.013982) (xy 93.672287 -17.101594)
			(xy 93.656353 -17.188115) (xy 93.632618 -17.272829) (xy 93.601277 -17.355034) (xy 93.562591 -17.434048)
			(xy 93.516879 -17.509217) (xy 93.464522 -17.579917) (xy 93.405953 -17.645564) (xy 93.341657 -17.705612)
			(xy 93.272166 -17.759565) (xy 93.198058 -17.806976) (xy 93.119945 -17.84745) (xy 93.038475 -17.880654)
			(xy 92.954323 -17.906312) (xy 92.868187 -17.924212) (xy 92.78078 -17.934204) (xy 92.692826 -17.936207)
			(xy 92.605055 -17.930203) (xy 92.518193 -17.916243) (xy 92.432961 -17.894441) (xy 92.350064 -17.86498)
			(xy 92.27019 -17.828102) (xy 92.194 -17.784114) (xy 92.122126 -17.73338) (xy 92.055164 -17.67632)
			(xy 91.993667 -17.613407) (xy 91.938146 -17.545163) (xy 91.889061 -17.472153) (xy 91.846819 -17.394981)
			(xy 91.811769 -17.314288) (xy 91.784202 -17.230743) (xy 91.764347 -17.145036) (xy 91.752367 -17.057879)
			(xy 91.748363 -16.969994) (xy 67.68084 -16.969994) (xy 67.680339 -17.013982) (xy 67.672339 -17.101594)
			(xy 67.656405 -17.188115) (xy 67.63267 -17.272829) (xy 67.601329 -17.355034) (xy 67.562643 -17.434048)
			(xy 67.516931 -17.509217) (xy 67.464574 -17.579917) (xy 67.406005 -17.645564) (xy 67.341709 -17.705612)
			(xy 67.272218 -17.759565) (xy 67.19811 -17.806976) (xy 67.119997 -17.84745) (xy 67.038527 -17.880654)
			(xy 66.954375 -17.906312) (xy 66.868239 -17.924212) (xy 66.780832 -17.934204) (xy 66.692878 -17.936207)
			(xy 66.605107 -17.930203) (xy 66.518245 -17.916243) (xy 66.433013 -17.894441) (xy 66.350116 -17.86498)
			(xy 66.270242 -17.828102) (xy 66.194052 -17.784114) (xy 66.122178 -17.73338) (xy 66.055216 -17.67632)
			(xy 65.993719 -17.613407) (xy 65.938198 -17.545163) (xy 65.889113 -17.472153) (xy 65.846871 -17.394981)
			(xy 65.811821 -17.314288) (xy 65.784254 -17.230743) (xy 65.764399 -17.145036) (xy 65.752419 -17.057879)
			(xy 65.748415 -16.969994) (xy 41.680892 -16.969994) (xy 41.680391 -17.013982) (xy 41.672391 -17.101594)
			(xy 41.656457 -17.188115) (xy 41.632722 -17.272829) (xy 41.601381 -17.355034) (xy 41.562695 -17.434048)
			(xy 41.516983 -17.509217) (xy 41.464626 -17.579917) (xy 41.406057 -17.645564) (xy 41.341761 -17.705612)
			(xy 41.27227 -17.759565) (xy 41.198162 -17.806976) (xy 41.120049 -17.84745) (xy 41.038579 -17.880654)
			(xy 40.954427 -17.906312) (xy 40.868291 -17.924212) (xy 40.780884 -17.934204) (xy 40.69293 -17.936207)
			(xy 40.605159 -17.930203) (xy 40.518297 -17.916243) (xy 40.433065 -17.894441) (xy 40.350168 -17.86498)
			(xy 40.270294 -17.828102) (xy 40.194104 -17.784114) (xy 40.12223 -17.73338) (xy 40.055268 -17.67632)
			(xy 39.993771 -17.613407) (xy 39.93825 -17.545163) (xy 39.889165 -17.472153) (xy 39.846923 -17.394981)
			(xy 39.811873 -17.314288) (xy 39.784306 -17.230743) (xy 39.764451 -17.145036) (xy 39.752471 -17.057879)
			(xy 39.748467 -16.969994) (xy 31.121104 -16.969994) (xy 31.143068 -17.081123) (xy 31.174975 -17.283855)
			(xy 31.198948 -17.487677) (xy 31.21495 -17.69228) (xy 31.222957 -17.89735) (xy 31.223458 -17.999964)
			(xy 104.755958 -17.999964) (xy 104.759962 -17.794776) (xy 104.771969 -17.5899) (xy 104.79196 -17.385649)
			(xy 104.819905 -17.182334) (xy 104.855761 -16.980263) (xy 104.899475 -16.779745) (xy 104.950978 -16.581086)
			(xy 105.010193 -16.384587) (xy 105.077029 -16.190548) (xy 105.151385 -15.999265) (xy 105.233148 -15.811028)
			(xy 105.322193 -15.626125) (xy 105.418384 -15.444837) (xy 105.521575 -15.26744) (xy 105.631609 -15.094203)
			(xy 105.748318 -14.925392) (xy 105.871524 -14.761263) (xy 106.001041 -14.602066) (xy 106.13667 -14.448044)
			(xy 106.278205 -14.29943) (xy 106.42543 -14.156452) (xy 106.578122 -14.019327) (xy 106.736048 -13.888263)
			(xy 106.898967 -13.763461) (xy 107.066632 -13.645111) (xy 107.238786 -13.533392) (xy 107.415168 -13.428475)
			(xy 107.595509 -13.33052) (xy 107.779535 -13.239676) (xy 107.966965 -13.15608) (xy 108.157514 -13.079861)
			(xy 108.350891 -13.011135) (xy 108.546803 -12.950006) (xy 108.74495 -12.896567) (xy 108.945032 -12.8509)
			(xy 109.146743 -12.813073) (xy 109.349776 -12.783146) (xy 109.553823 -12.761163) (xy 109.758572 -12.747158)
			(xy 109.963711 -12.741152) (xy 110.168928 -12.743154) (xy 110.373911 -12.753162) (xy 110.578348 -12.771159)
			(xy 110.781926 -12.797119) (xy 110.984337 -12.831002) (xy 111.185271 -12.872757) (xy 111.384424 -12.92232)
			(xy 111.581491 -12.979615) (xy 111.776173 -13.044555) (xy 111.968173 -13.117041) (xy 112.157198 -13.196964)
			(xy 112.342961 -13.2842) (xy 112.525179 -13.378618) (xy 112.703575 -13.480073) (xy 112.877876 -13.588412)
			(xy 113.047818 -13.703468) (xy 113.213141 -13.825068) (xy 113.373594 -13.953025) (xy 113.528933 -14.087144)
			(xy 113.67892 -14.227223) (xy 113.823328 -14.373047) (xy 113.961936 -14.524393) (xy 114.094534 -14.681033)
			(xy 114.22092 -14.842727) (xy 114.3409 -15.009229) (xy 114.454293 -15.180285) (xy 114.560926 -15.355635)
			(xy 114.660636 -15.535012) (xy 114.753272 -15.718142) (xy 114.838692 -15.904748) (xy 114.916766 -16.094544)
			(xy 114.987376 -16.287242) (xy 115.050413 -16.482548) (xy 115.105783 -16.680164) (xy 115.1534 -16.879791)
			(xy 115.171228 -16.969994) (xy 129.848617 -16.969994) (xy 129.852621 -16.882109) (xy 129.864601 -16.794952)
			(xy 129.884456 -16.709245) (xy 129.912023 -16.6257) (xy 129.947073 -16.545007) (xy 129.989315 -16.467835)
			(xy 130.0384 -16.394825) (xy 130.093921 -16.326581) (xy 130.155418 -16.263668) (xy 130.22238 -16.206608)
			(xy 130.294254 -16.155874) (xy 130.370444 -16.111886) (xy 130.450318 -16.075008) (xy 130.533215 -16.045547)
			(xy 130.618447 -16.023745) (xy 130.705309 -16.009785) (xy 130.79308 -16.003781) (xy 130.881034 -16.005784)
			(xy 130.968441 -16.015776) (xy 131.054577 -16.033676) (xy 131.138729 -16.059334) (xy 131.220199 -16.092538)
			(xy 131.298312 -16.133012) (xy 131.37242 -16.180423) (xy 131.441911 -16.234376) (xy 131.506207 -16.294424)
			(xy 131.564776 -16.360071) (xy 131.617133 -16.430771) (xy 131.662845 -16.50594) (xy 131.701531 -16.584954)
			(xy 131.732872 -16.667159) (xy 131.756607 -16.751873) (xy 131.772541 -16.838394) (xy 131.780541 -16.926006)
			(xy 131.781042 -16.969994) (xy 155.848565 -16.969994) (xy 155.852569 -16.882109) (xy 155.864549 -16.794952)
			(xy 155.884404 -16.709245) (xy 155.911971 -16.6257) (xy 155.947021 -16.545007) (xy 155.989263 -16.467835)
			(xy 156.038348 -16.394825) (xy 156.093869 -16.326581) (xy 156.155366 -16.263668) (xy 156.222328 -16.206608)
			(xy 156.294202 -16.155874) (xy 156.370392 -16.111886) (xy 156.450266 -16.075008) (xy 156.533163 -16.045547)
			(xy 156.618395 -16.023745) (xy 156.705257 -16.009785) (xy 156.793028 -16.003781) (xy 156.880982 -16.005784)
			(xy 156.968389 -16.015776) (xy 157.054525 -16.033676) (xy 157.138677 -16.059334) (xy 157.220147 -16.092538)
			(xy 157.29826 -16.133012) (xy 157.372368 -16.180423) (xy 157.441859 -16.234376) (xy 157.506155 -16.294424)
			(xy 157.564724 -16.360071) (xy 157.617081 -16.430771) (xy 157.662793 -16.50594) (xy 157.701479 -16.584954)
			(xy 157.73282 -16.667159) (xy 157.756555 -16.751873) (xy 157.772489 -16.838394) (xy 157.780489 -16.926006)
			(xy 157.78099 -16.969994) (xy 181.848513 -16.969994) (xy 181.852517 -16.882109) (xy 181.864497 -16.794952)
			(xy 181.884352 -16.709245) (xy 181.911919 -16.6257) (xy 181.946969 -16.545007) (xy 181.989211 -16.467835)
			(xy 182.038296 -16.394825) (xy 182.093817 -16.326581) (xy 182.155314 -16.263668) (xy 182.222276 -16.206608)
			(xy 182.29415 -16.155874) (xy 182.37034 -16.111886) (xy 182.450214 -16.075008) (xy 182.533111 -16.045547)
			(xy 182.618343 -16.023745) (xy 182.705205 -16.009785) (xy 182.792976 -16.003781) (xy 182.88093 -16.005784)
			(xy 182.968337 -16.015776) (xy 183.054473 -16.033676) (xy 183.138625 -16.059334) (xy 183.220095 -16.092538)
			(xy 183.298208 -16.133012) (xy 183.372316 -16.180423) (xy 183.441807 -16.234376) (xy 183.506103 -16.294424)
			(xy 183.564672 -16.360071) (xy 183.617029 -16.430771) (xy 183.662741 -16.50594) (xy 183.701427 -16.584954)
			(xy 183.732768 -16.667159) (xy 183.756503 -16.751873) (xy 183.772437 -16.838394) (xy 183.780437 -16.926006)
			(xy 183.780938 -16.969994) (xy 207.848461 -16.969994) (xy 207.852465 -16.882109) (xy 207.864445 -16.794952)
			(xy 207.8843 -16.709245) (xy 207.911867 -16.6257) (xy 207.946917 -16.545007) (xy 207.989159 -16.467835)
			(xy 208.038244 -16.394825) (xy 208.093765 -16.326581) (xy 208.155262 -16.263668) (xy 208.222224 -16.206608)
			(xy 208.294098 -16.155874) (xy 208.370288 -16.111886) (xy 208.450162 -16.075008) (xy 208.533059 -16.045547)
			(xy 208.618291 -16.023745) (xy 208.705153 -16.009785) (xy 208.792924 -16.003781) (xy 208.880878 -16.005784)
			(xy 208.968285 -16.015776) (xy 209.054421 -16.033676) (xy 209.138573 -16.059334) (xy 209.220043 -16.092538)
			(xy 209.298156 -16.133012) (xy 209.372264 -16.180423) (xy 209.441755 -16.234376) (xy 209.506051 -16.294424)
			(xy 209.56462 -16.360071) (xy 209.616977 -16.430771) (xy 209.662689 -16.50594) (xy 209.701375 -16.584954)
			(xy 209.732716 -16.667159) (xy 209.756451 -16.751873) (xy 209.772385 -16.838394) (xy 209.780385 -16.926006)
			(xy 209.780886 -16.969994) (xy 245.948461 -16.969994) (xy 245.952465 -16.882109) (xy 245.964445 -16.794952)
			(xy 245.9843 -16.709245) (xy 246.011867 -16.6257) (xy 246.046917 -16.545007) (xy 246.089159 -16.467835)
			(xy 246.138244 -16.394825) (xy 246.193765 -16.326581) (xy 246.255262 -16.263668) (xy 246.322224 -16.206608)
			(xy 246.394098 -16.155874) (xy 246.470288 -16.111886) (xy 246.550162 -16.075008) (xy 246.633059 -16.045547)
			(xy 246.718291 -16.023745) (xy 246.805153 -16.009785) (xy 246.892924 -16.003781) (xy 246.980878 -16.005784)
			(xy 247.068285 -16.015776) (xy 247.154421 -16.033676) (xy 247.238573 -16.059334) (xy 247.320043 -16.092538)
			(xy 247.398156 -16.133012) (xy 247.472264 -16.180423) (xy 247.541755 -16.234376) (xy 247.606051 -16.294424)
			(xy 247.66462 -16.360071) (xy 247.716977 -16.430771) (xy 247.762689 -16.50594) (xy 247.801375 -16.584954)
			(xy 247.832716 -16.667159) (xy 247.856451 -16.751873) (xy 247.872385 -16.838394) (xy 247.880385 -16.926006)
			(xy 247.880886 -16.969994) (xy 271.948409 -16.969994) (xy 271.952413 -16.882109) (xy 271.964393 -16.794952)
			(xy 271.984248 -16.709245) (xy 272.011815 -16.6257) (xy 272.046865 -16.545007) (xy 272.089107 -16.467835)
			(xy 272.138192 -16.394825) (xy 272.193713 -16.326581) (xy 272.25521 -16.263668) (xy 272.322172 -16.206608)
			(xy 272.394046 -16.155874) (xy 272.470236 -16.111886) (xy 272.55011 -16.075008) (xy 272.633007 -16.045547)
			(xy 272.718239 -16.023745) (xy 272.805101 -16.009785) (xy 272.892872 -16.003781) (xy 272.980826 -16.005784)
			(xy 273.068233 -16.015776) (xy 273.154369 -16.033676) (xy 273.238521 -16.059334) (xy 273.319991 -16.092538)
			(xy 273.398104 -16.133012) (xy 273.472212 -16.180423) (xy 273.541703 -16.234376) (xy 273.605999 -16.294424)
			(xy 273.664568 -16.360071) (xy 273.716925 -16.430771) (xy 273.762637 -16.50594) (xy 273.801323 -16.584954)
			(xy 273.832664 -16.667159) (xy 273.856399 -16.751873) (xy 273.872333 -16.838394) (xy 273.880333 -16.926006)
			(xy 273.880834 -16.969994) (xy 297.948357 -16.969994) (xy 297.952361 -16.882109) (xy 297.964341 -16.794952)
			(xy 297.984196 -16.709245) (xy 298.011763 -16.6257) (xy 298.046813 -16.545007) (xy 298.089055 -16.467835)
			(xy 298.13814 -16.394825) (xy 298.193661 -16.326581) (xy 298.255158 -16.263668) (xy 298.32212 -16.206608)
			(xy 298.393994 -16.155874) (xy 298.470184 -16.111886) (xy 298.550058 -16.075008) (xy 298.632955 -16.045547)
			(xy 298.718187 -16.023745) (xy 298.805049 -16.009785) (xy 298.89282 -16.003781) (xy 298.980774 -16.005784)
			(xy 299.068181 -16.015776) (xy 299.154317 -16.033676) (xy 299.238469 -16.059334) (xy 299.319939 -16.092538)
			(xy 299.398052 -16.133012) (xy 299.47216 -16.180423) (xy 299.541651 -16.234376) (xy 299.605947 -16.294424)
			(xy 299.664516 -16.360071) (xy 299.716873 -16.430771) (xy 299.762585 -16.50594) (xy 299.801271 -16.584954)
			(xy 299.832612 -16.667159) (xy 299.856347 -16.751873) (xy 299.872281 -16.838394) (xy 299.880281 -16.926006)
			(xy 299.880782 -16.969994) (xy 323.948305 -16.969994) (xy 323.952309 -16.882109) (xy 323.964289 -16.794952)
			(xy 323.984144 -16.709245) (xy 324.011711 -16.6257) (xy 324.046761 -16.545007) (xy 324.089003 -16.467835)
			(xy 324.138088 -16.394825) (xy 324.193609 -16.326581) (xy 324.255106 -16.263668) (xy 324.322068 -16.206608)
			(xy 324.393942 -16.155874) (xy 324.470132 -16.111886) (xy 324.550006 -16.075008) (xy 324.632903 -16.045547)
			(xy 324.718135 -16.023745) (xy 324.804997 -16.009785) (xy 324.892768 -16.003781) (xy 324.980722 -16.005784)
			(xy 325.068129 -16.015776) (xy 325.154265 -16.033676) (xy 325.238417 -16.059334) (xy 325.319887 -16.092538)
			(xy 325.398 -16.133012) (xy 325.472108 -16.180423) (xy 325.541599 -16.234376) (xy 325.605895 -16.294424)
			(xy 325.664464 -16.360071) (xy 325.716821 -16.430771) (xy 325.762533 -16.50594) (xy 325.801219 -16.584954)
			(xy 325.83256 -16.667159) (xy 325.856295 -16.751873) (xy 325.872229 -16.838394) (xy 325.880229 -16.926006)
			(xy 325.88073 -16.969994) (xy 325.880229 -17.013982) (xy 325.872229 -17.101594) (xy 325.856295 -17.188115)
			(xy 325.83256 -17.272829) (xy 325.801219 -17.355034) (xy 325.762533 -17.434048) (xy 325.716821 -17.509217)
			(xy 325.664464 -17.579917) (xy 325.605895 -17.645564) (xy 325.541599 -17.705612) (xy 325.472108 -17.759565)
			(xy 325.398 -17.806976) (xy 325.319887 -17.84745) (xy 325.238417 -17.880654) (xy 325.154265 -17.906312)
			(xy 325.068129 -17.924212) (xy 324.980722 -17.934204) (xy 324.892768 -17.936207) (xy 324.804997 -17.930203)
			(xy 324.718135 -17.916243) (xy 324.632903 -17.894441) (xy 324.550006 -17.86498) (xy 324.470132 -17.828102)
			(xy 324.393942 -17.784114) (xy 324.322068 -17.73338) (xy 324.255106 -17.67632) (xy 324.193609 -17.613407)
			(xy 324.138088 -17.545163) (xy 324.089003 -17.472153) (xy 324.046761 -17.394981) (xy 324.011711 -17.314288)
			(xy 323.984144 -17.230743) (xy 323.964289 -17.145036) (xy 323.952309 -17.057879) (xy 323.948305 -16.969994)
			(xy 299.880782 -16.969994) (xy 299.880281 -17.013982) (xy 299.872281 -17.101594) (xy 299.856347 -17.188115)
			(xy 299.832612 -17.272829) (xy 299.801271 -17.355034) (xy 299.762585 -17.434048) (xy 299.716873 -17.509217)
			(xy 299.664516 -17.579917) (xy 299.605947 -17.645564) (xy 299.541651 -17.705612) (xy 299.47216 -17.759565)
			(xy 299.398052 -17.806976) (xy 299.319939 -17.84745) (xy 299.238469 -17.880654) (xy 299.154317 -17.906312)
			(xy 299.068181 -17.924212) (xy 298.980774 -17.934204) (xy 298.89282 -17.936207) (xy 298.805049 -17.930203)
			(xy 298.718187 -17.916243) (xy 298.632955 -17.894441) (xy 298.550058 -17.86498) (xy 298.470184 -17.828102)
			(xy 298.393994 -17.784114) (xy 298.32212 -17.73338) (xy 298.255158 -17.67632) (xy 298.193661 -17.613407)
			(xy 298.13814 -17.545163) (xy 298.089055 -17.472153) (xy 298.046813 -17.394981) (xy 298.011763 -17.314288)
			(xy 297.984196 -17.230743) (xy 297.964341 -17.145036) (xy 297.952361 -17.057879) (xy 297.948357 -16.969994)
			(xy 273.880834 -16.969994) (xy 273.880333 -17.013982) (xy 273.872333 -17.101594) (xy 273.856399 -17.188115)
			(xy 273.832664 -17.272829) (xy 273.801323 -17.355034) (xy 273.762637 -17.434048) (xy 273.716925 -17.509217)
			(xy 273.664568 -17.579917) (xy 273.605999 -17.645564) (xy 273.541703 -17.705612) (xy 273.472212 -17.759565)
			(xy 273.398104 -17.806976) (xy 273.319991 -17.84745) (xy 273.238521 -17.880654) (xy 273.154369 -17.906312)
			(xy 273.068233 -17.924212) (xy 272.980826 -17.934204) (xy 272.892872 -17.936207) (xy 272.805101 -17.930203)
			(xy 272.718239 -17.916243) (xy 272.633007 -17.894441) (xy 272.55011 -17.86498) (xy 272.470236 -17.828102)
			(xy 272.394046 -17.784114) (xy 272.322172 -17.73338) (xy 272.25521 -17.67632) (xy 272.193713 -17.613407)
			(xy 272.138192 -17.545163) (xy 272.089107 -17.472153) (xy 272.046865 -17.394981) (xy 272.011815 -17.314288)
			(xy 271.984248 -17.230743) (xy 271.964393 -17.145036) (xy 271.952413 -17.057879) (xy 271.948409 -16.969994)
			(xy 247.880886 -16.969994) (xy 247.880385 -17.013982) (xy 247.872385 -17.101594) (xy 247.856451 -17.188115)
			(xy 247.832716 -17.272829) (xy 247.801375 -17.355034) (xy 247.762689 -17.434048) (xy 247.716977 -17.509217)
			(xy 247.66462 -17.579917) (xy 247.606051 -17.645564) (xy 247.541755 -17.705612) (xy 247.472264 -17.759565)
			(xy 247.398156 -17.806976) (xy 247.320043 -17.84745) (xy 247.238573 -17.880654) (xy 247.154421 -17.906312)
			(xy 247.068285 -17.924212) (xy 246.980878 -17.934204) (xy 246.892924 -17.936207) (xy 246.805153 -17.930203)
			(xy 246.718291 -17.916243) (xy 246.633059 -17.894441) (xy 246.550162 -17.86498) (xy 246.470288 -17.828102)
			(xy 246.394098 -17.784114) (xy 246.322224 -17.73338) (xy 246.255262 -17.67632) (xy 246.193765 -17.613407)
			(xy 246.138244 -17.545163) (xy 246.089159 -17.472153) (xy 246.046917 -17.394981) (xy 246.011867 -17.314288)
			(xy 245.9843 -17.230743) (xy 245.964445 -17.145036) (xy 245.952465 -17.057879) (xy 245.948461 -16.969994)
			(xy 209.780886 -16.969994) (xy 209.780385 -17.013982) (xy 209.772385 -17.101594) (xy 209.756451 -17.188115)
			(xy 209.732716 -17.272829) (xy 209.701375 -17.355034) (xy 209.662689 -17.434048) (xy 209.616977 -17.509217)
			(xy 209.56462 -17.579917) (xy 209.506051 -17.645564) (xy 209.441755 -17.705612) (xy 209.372264 -17.759565)
			(xy 209.298156 -17.806976) (xy 209.220043 -17.84745) (xy 209.138573 -17.880654) (xy 209.054421 -17.906312)
			(xy 208.968285 -17.924212) (xy 208.880878 -17.934204) (xy 208.792924 -17.936207) (xy 208.705153 -17.930203)
			(xy 208.618291 -17.916243) (xy 208.533059 -17.894441) (xy 208.450162 -17.86498) (xy 208.370288 -17.828102)
			(xy 208.294098 -17.784114) (xy 208.222224 -17.73338) (xy 208.155262 -17.67632) (xy 208.093765 -17.613407)
			(xy 208.038244 -17.545163) (xy 207.989159 -17.472153) (xy 207.946917 -17.394981) (xy 207.911867 -17.314288)
			(xy 207.8843 -17.230743) (xy 207.864445 -17.145036) (xy 207.852465 -17.057879) (xy 207.848461 -16.969994)
			(xy 183.780938 -16.969994) (xy 183.780437 -17.013982) (xy 183.772437 -17.101594) (xy 183.756503 -17.188115)
			(xy 183.732768 -17.272829) (xy 183.701427 -17.355034) (xy 183.662741 -17.434048) (xy 183.617029 -17.509217)
			(xy 183.564672 -17.579917) (xy 183.506103 -17.645564) (xy 183.441807 -17.705612) (xy 183.372316 -17.759565)
			(xy 183.298208 -17.806976) (xy 183.220095 -17.84745) (xy 183.138625 -17.880654) (xy 183.054473 -17.906312)
			(xy 182.968337 -17.924212) (xy 182.88093 -17.934204) (xy 182.792976 -17.936207) (xy 182.705205 -17.930203)
			(xy 182.618343 -17.916243) (xy 182.533111 -17.894441) (xy 182.450214 -17.86498) (xy 182.37034 -17.828102)
			(xy 182.29415 -17.784114) (xy 182.222276 -17.73338) (xy 182.155314 -17.67632) (xy 182.093817 -17.613407)
			(xy 182.038296 -17.545163) (xy 181.989211 -17.472153) (xy 181.946969 -17.394981) (xy 181.911919 -17.314288)
			(xy 181.884352 -17.230743) (xy 181.864497 -17.145036) (xy 181.852517 -17.057879) (xy 181.848513 -16.969994)
			(xy 157.78099 -16.969994) (xy 157.780489 -17.013982) (xy 157.772489 -17.101594) (xy 157.756555 -17.188115)
			(xy 157.73282 -17.272829) (xy 157.701479 -17.355034) (xy 157.662793 -17.434048) (xy 157.617081 -17.509217)
			(xy 157.564724 -17.579917) (xy 157.506155 -17.645564) (xy 157.441859 -17.705612) (xy 157.372368 -17.759565)
			(xy 157.29826 -17.806976) (xy 157.220147 -17.84745) (xy 157.138677 -17.880654) (xy 157.054525 -17.906312)
			(xy 156.968389 -17.924212) (xy 156.880982 -17.934204) (xy 156.793028 -17.936207) (xy 156.705257 -17.930203)
			(xy 156.618395 -17.916243) (xy 156.533163 -17.894441) (xy 156.450266 -17.86498) (xy 156.370392 -17.828102)
			(xy 156.294202 -17.784114) (xy 156.222328 -17.73338) (xy 156.155366 -17.67632) (xy 156.093869 -17.613407)
			(xy 156.038348 -17.545163) (xy 155.989263 -17.472153) (xy 155.947021 -17.394981) (xy 155.911971 -17.314288)
			(xy 155.884404 -17.230743) (xy 155.864549 -17.145036) (xy 155.852569 -17.057879) (xy 155.848565 -16.969994)
			(xy 131.781042 -16.969994) (xy 131.780541 -17.013982) (xy 131.772541 -17.101594) (xy 131.756607 -17.188115)
			(xy 131.732872 -17.272829) (xy 131.701531 -17.355034) (xy 131.662845 -17.434048) (xy 131.617133 -17.509217)
			(xy 131.564776 -17.579917) (xy 131.506207 -17.645564) (xy 131.441911 -17.705612) (xy 131.37242 -17.759565)
			(xy 131.298312 -17.806976) (xy 131.220199 -17.84745) (xy 131.138729 -17.880654) (xy 131.054577 -17.906312)
			(xy 130.968441 -17.924212) (xy 130.881034 -17.934204) (xy 130.79308 -17.936207) (xy 130.705309 -17.930203)
			(xy 130.618447 -17.916243) (xy 130.533215 -17.894441) (xy 130.450318 -17.86498) (xy 130.370444 -17.828102)
			(xy 130.294254 -17.784114) (xy 130.22238 -17.73338) (xy 130.155418 -17.67632) (xy 130.093921 -17.613407)
			(xy 130.0384 -17.545163) (xy 129.989315 -17.472153) (xy 129.947073 -17.394981) (xy 129.912023 -17.314288)
			(xy 129.884456 -17.230743) (xy 129.864601 -17.145036) (xy 129.852621 -17.057879) (xy 129.848617 -16.969994)
			(xy 115.171228 -16.969994) (xy 115.193192 -17.081123) (xy 115.225099 -17.283855) (xy 115.249072 -17.487677)
			(xy 115.265074 -17.69228) (xy 115.273081 -17.89735) (xy 115.273582 -17.999964) (xy 336.9559 -17.999964)
			(xy 336.959904 -17.794776) (xy 336.971911 -17.5899) (xy 336.991902 -17.385649) (xy 337.019847 -17.182334)
			(xy 337.055703 -16.980263) (xy 337.099417 -16.779745) (xy 337.15092 -16.581086) (xy 337.210135 -16.384587)
			(xy 337.276971 -16.190548) (xy 337.351327 -15.999265) (xy 337.43309 -15.811028) (xy 337.522135 -15.626125)
			(xy 337.618326 -15.444837) (xy 337.721517 -15.26744) (xy 337.831551 -15.094203) (xy 337.94826 -14.925392)
			(xy 338.071466 -14.761263) (xy 338.200983 -14.602066) (xy 338.336612 -14.448044) (xy 338.478147 -14.29943)
			(xy 338.625372 -14.156452) (xy 338.778064 -14.019327) (xy 338.93599 -13.888263) (xy 339.098909 -13.763461)
			(xy 339.266574 -13.645111) (xy 339.438728 -13.533392) (xy 339.61511 -13.428475) (xy 339.795451 -13.33052)
			(xy 339.979477 -13.239676) (xy 340.166907 -13.15608) (xy 340.357456 -13.079861) (xy 340.550833 -13.011135)
			(xy 340.746745 -12.950006) (xy 340.944892 -12.896567) (xy 341.144974 -12.8509) (xy 341.346685 -12.813073)
			(xy 341.549718 -12.783146) (xy 341.753765 -12.761163) (xy 341.958514 -12.747158) (xy 342.163653 -12.741152)
			(xy 342.36887 -12.743154) (xy 342.573853 -12.753162) (xy 342.77829 -12.771159) (xy 342.981868 -12.797119)
			(xy 343.184279 -12.831002) (xy 343.385213 -12.872757) (xy 343.584366 -12.92232) (xy 343.781433 -12.979615)
			(xy 343.976115 -13.044555) (xy 344.168115 -13.117041) (xy 344.35714 -13.196964) (xy 344.542903 -13.2842)
			(xy 344.725121 -13.378618) (xy 344.903517 -13.480073) (xy 345.077818 -13.588412) (xy 345.24776 -13.703468)
			(xy 345.413083 -13.825068) (xy 345.573536 -13.953025) (xy 345.728875 -14.087144) (xy 345.878862 -14.227223)
			(xy 346.02327 -14.373047) (xy 346.161878 -14.524393) (xy 346.294476 -14.681033) (xy 346.420862 -14.842727)
			(xy 346.540842 -15.009229) (xy 346.654235 -15.180285) (xy 346.666298 -15.200122) (xy 459.541372 -15.200122)
			(xy 459.541372 -13.599922) (xy 459.54188 -13.535242) (xy 459.550003 -13.406136) (xy 459.566216 -13.277796)
			(xy 459.590456 -13.150726) (xy 459.622626 -13.02543) (xy 459.662601 -12.9024) (xy 459.710222 -12.782124)
			(xy 459.765301 -12.665075) (xy 459.827621 -12.551715) (xy 459.896936 -12.442492) (xy 459.972972 -12.337837)
			(xy 460.05543 -12.238163) (xy 460.143983 -12.143863) (xy 460.238283 -12.05531) (xy 460.337957 -11.972852)
			(xy 460.442612 -11.896816) (xy 460.551835 -11.827501) (xy 460.665195 -11.765181) (xy 460.782244 -11.710102)
			(xy 460.90252 -11.662481) (xy 461.02555 -11.622506) (xy 461.150846 -11.590336) (xy 461.277916 -11.566096)
			(xy 461.406256 -11.549883) (xy 461.535362 -11.54176) (xy 461.664722 -11.54176) (xy 461.793828 -11.549883)
			(xy 461.922168 -11.566096) (xy 462.049238 -11.590336) (xy 462.174534 -11.622506) (xy 462.297564 -11.662481)
			(xy 462.41784 -11.710102) (xy 462.534889 -11.765181) (xy 462.648249 -11.827501) (xy 462.757472 -11.896816)
			(xy 462.862127 -11.972852) (xy 462.961801 -12.05531) (xy 463.056101 -12.143863) (xy 463.144654 -12.238163)
			(xy 463.227112 -12.337837) (xy 463.303148 -12.442492) (xy 463.372463 -12.551715) (xy 463.434783 -12.665075)
			(xy 463.489862 -12.782124) (xy 463.537483 -12.9024) (xy 463.577458 -13.02543) (xy 463.609628 -13.150726)
			(xy 463.633868 -13.277796) (xy 463.650081 -13.406136) (xy 463.658204 -13.535242) (xy 463.658712 -13.599922)
			(xy 463.658712 -15.200122) (xy 463.658204 -15.264802) (xy 463.650081 -15.393908) (xy 463.633868 -15.522248)
			(xy 463.609628 -15.649318) (xy 463.577458 -15.774614) (xy 463.537483 -15.897644) (xy 463.489862 -16.01792)
			(xy 463.434783 -16.134969) (xy 463.372463 -16.248329) (xy 463.303148 -16.357552) (xy 463.227112 -16.462207)
			(xy 463.144654 -16.561881) (xy 463.056101 -16.656181) (xy 462.961801 -16.744734) (xy 462.862127 -16.827192)
			(xy 462.757472 -16.903228) (xy 462.648249 -16.972543) (xy 462.534889 -17.034863) (xy 462.41784 -17.089942)
			(xy 462.297564 -17.137563) (xy 462.174534 -17.177538) (xy 462.049238 -17.209708) (xy 461.922168 -17.233948)
			(xy 461.793828 -17.250161) (xy 461.664722 -17.258284) (xy 461.535362 -17.258284) (xy 461.406256 -17.250161)
			(xy 461.277916 -17.233948) (xy 461.150846 -17.209708) (xy 461.02555 -17.177538) (xy 460.90252 -17.137563)
			(xy 460.782244 -17.089942) (xy 460.665195 -17.034863) (xy 460.551835 -16.972543) (xy 460.442612 -16.903228)
			(xy 460.337957 -16.827192) (xy 460.238283 -16.744734) (xy 460.143983 -16.656181) (xy 460.05543 -16.561881)
			(xy 459.972972 -16.462207) (xy 459.896936 -16.357552) (xy 459.827621 -16.248329) (xy 459.765301 -16.134969)
			(xy 459.710222 -16.01792) (xy 459.662601 -15.897644) (xy 459.622626 -15.774614) (xy 459.590456 -15.649318)
			(xy 459.566216 -15.522248) (xy 459.550003 -15.393908) (xy 459.54188 -15.264802) (xy 459.541372 -15.200122)
			(xy 346.666298 -15.200122) (xy 346.760868 -15.355635) (xy 346.860578 -15.535012) (xy 346.953214 -15.718142)
			(xy 347.038634 -15.904748) (xy 347.116708 -16.094544) (xy 347.187318 -16.287242) (xy 347.250355 -16.482548)
			(xy 347.305725 -16.680164) (xy 347.353342 -16.879791) (xy 347.37117 -16.969994) (xy 362.048559 -16.969994)
			(xy 362.052563 -16.882109) (xy 362.064543 -16.794952) (xy 362.084398 -16.709245) (xy 362.111965 -16.6257)
			(xy 362.147015 -16.545007) (xy 362.189257 -16.467835) (xy 362.238342 -16.394825) (xy 362.293863 -16.326581)
			(xy 362.35536 -16.263668) (xy 362.422322 -16.206608) (xy 362.494196 -16.155874) (xy 362.570386 -16.111886)
			(xy 362.65026 -16.075008) (xy 362.733157 -16.045547) (xy 362.818389 -16.023745) (xy 362.905251 -16.009785)
			(xy 362.993022 -16.003781) (xy 363.080976 -16.005784) (xy 363.168383 -16.015776) (xy 363.254519 -16.033676)
			(xy 363.338671 -16.059334) (xy 363.420141 -16.092538) (xy 363.498254 -16.133012) (xy 363.572362 -16.180423)
			(xy 363.641853 -16.234376) (xy 363.706149 -16.294424) (xy 363.764718 -16.360071) (xy 363.817075 -16.430771)
			(xy 363.862787 -16.50594) (xy 363.901473 -16.584954) (xy 363.932814 -16.667159) (xy 363.956549 -16.751873)
			(xy 363.972483 -16.838394) (xy 363.980483 -16.926006) (xy 363.980984 -16.969994) (xy 388.048507 -16.969994)
			(xy 388.052511 -16.882109) (xy 388.064491 -16.794952) (xy 388.084346 -16.709245) (xy 388.111913 -16.6257)
			(xy 388.146963 -16.545007) (xy 388.189205 -16.467835) (xy 388.23829 -16.394825) (xy 388.293811 -16.326581)
			(xy 388.355308 -16.263668) (xy 388.42227 -16.206608) (xy 388.494144 -16.155874) (xy 388.570334 -16.111886)
			(xy 388.650208 -16.075008) (xy 388.733105 -16.045547) (xy 388.818337 -16.023745) (xy 388.905199 -16.009785)
			(xy 388.99297 -16.003781) (xy 389.080924 -16.005784) (xy 389.168331 -16.015776) (xy 389.254467 -16.033676)
			(xy 389.338619 -16.059334) (xy 389.420089 -16.092538) (xy 389.498202 -16.133012) (xy 389.57231 -16.180423)
			(xy 389.641801 -16.234376) (xy 389.706097 -16.294424) (xy 389.764666 -16.360071) (xy 389.817023 -16.430771)
			(xy 389.862735 -16.50594) (xy 389.901421 -16.584954) (xy 389.932762 -16.667159) (xy 389.956497 -16.751873)
			(xy 389.972431 -16.838394) (xy 389.980431 -16.926006) (xy 389.980932 -16.969994) (xy 414.048455 -16.969994)
			(xy 414.052459 -16.882109) (xy 414.064439 -16.794952) (xy 414.084294 -16.709245) (xy 414.111861 -16.6257)
			(xy 414.146911 -16.545007) (xy 414.189153 -16.467835) (xy 414.238238 -16.394825) (xy 414.293759 -16.326581)
			(xy 414.355256 -16.263668) (xy 414.422218 -16.206608) (xy 414.494092 -16.155874) (xy 414.570282 -16.111886)
			(xy 414.650156 -16.075008) (xy 414.733053 -16.045547) (xy 414.818285 -16.023745) (xy 414.905147 -16.009785)
			(xy 414.992918 -16.003781) (xy 415.080872 -16.005784) (xy 415.168279 -16.015776) (xy 415.254415 -16.033676)
			(xy 415.338567 -16.059334) (xy 415.420037 -16.092538) (xy 415.49815 -16.133012) (xy 415.572258 -16.180423)
			(xy 415.641749 -16.234376) (xy 415.706045 -16.294424) (xy 415.764614 -16.360071) (xy 415.816971 -16.430771)
			(xy 415.862683 -16.50594) (xy 415.901369 -16.584954) (xy 415.93271 -16.667159) (xy 415.956445 -16.751873)
			(xy 415.972379 -16.838394) (xy 415.980379 -16.926006) (xy 415.98088 -16.969994) (xy 440.048403 -16.969994)
			(xy 440.052407 -16.882109) (xy 440.064387 -16.794952) (xy 440.084242 -16.709245) (xy 440.111809 -16.6257)
			(xy 440.146859 -16.545007) (xy 440.189101 -16.467835) (xy 440.238186 -16.394825) (xy 440.293707 -16.326581)
			(xy 440.355204 -16.263668) (xy 440.422166 -16.206608) (xy 440.49404 -16.155874) (xy 440.57023 -16.111886)
			(xy 440.650104 -16.075008) (xy 440.733001 -16.045547) (xy 440.818233 -16.023745) (xy 440.905095 -16.009785)
			(xy 440.992866 -16.003781) (xy 441.08082 -16.005784) (xy 441.168227 -16.015776) (xy 441.254363 -16.033676)
			(xy 441.338515 -16.059334) (xy 441.419985 -16.092538) (xy 441.498098 -16.133012) (xy 441.572206 -16.180423)
			(xy 441.641697 -16.234376) (xy 441.705993 -16.294424) (xy 441.764562 -16.360071) (xy 441.816919 -16.430771)
			(xy 441.862631 -16.50594) (xy 441.901317 -16.584954) (xy 441.932658 -16.667159) (xy 441.956393 -16.751873)
			(xy 441.972327 -16.838394) (xy 441.980327 -16.926006) (xy 441.980828 -16.969994) (xy 441.980327 -17.013982)
			(xy 441.972327 -17.101594) (xy 441.956393 -17.188115) (xy 441.932658 -17.272829) (xy 441.901317 -17.355034)
			(xy 441.862631 -17.434048) (xy 441.816919 -17.509217) (xy 441.764562 -17.579917) (xy 441.705993 -17.645564)
			(xy 441.641697 -17.705612) (xy 441.572206 -17.759565) (xy 441.498098 -17.806976) (xy 441.419985 -17.84745)
			(xy 441.338515 -17.880654) (xy 441.254363 -17.906312) (xy 441.168227 -17.924212) (xy 441.08082 -17.934204)
			(xy 440.992866 -17.936207) (xy 440.905095 -17.930203) (xy 440.818233 -17.916243) (xy 440.733001 -17.894441)
			(xy 440.650104 -17.86498) (xy 440.57023 -17.828102) (xy 440.49404 -17.784114) (xy 440.422166 -17.73338)
			(xy 440.355204 -17.67632) (xy 440.293707 -17.613407) (xy 440.238186 -17.545163) (xy 440.189101 -17.472153)
			(xy 440.146859 -17.394981) (xy 440.111809 -17.314288) (xy 440.084242 -17.230743) (xy 440.064387 -17.145036)
			(xy 440.052407 -17.057879) (xy 440.048403 -16.969994) (xy 415.98088 -16.969994) (xy 415.980379 -17.013982)
			(xy 415.972379 -17.101594) (xy 415.956445 -17.188115) (xy 415.93271 -17.272829) (xy 415.901369 -17.355034)
			(xy 415.862683 -17.434048) (xy 415.816971 -17.509217) (xy 415.764614 -17.579917) (xy 415.706045 -17.645564)
			(xy 415.641749 -17.705612) (xy 415.572258 -17.759565) (xy 415.49815 -17.806976) (xy 415.420037 -17.84745)
			(xy 415.338567 -17.880654) (xy 415.254415 -17.906312) (xy 415.168279 -17.924212) (xy 415.080872 -17.934204)
			(xy 414.992918 -17.936207) (xy 414.905147 -17.930203) (xy 414.818285 -17.916243) (xy 414.733053 -17.894441)
			(xy 414.650156 -17.86498) (xy 414.570282 -17.828102) (xy 414.494092 -17.784114) (xy 414.422218 -17.73338)
			(xy 414.355256 -17.67632) (xy 414.293759 -17.613407) (xy 414.238238 -17.545163) (xy 414.189153 -17.472153)
			(xy 414.146911 -17.394981) (xy 414.111861 -17.314288) (xy 414.084294 -17.230743) (xy 414.064439 -17.145036)
			(xy 414.052459 -17.057879) (xy 414.048455 -16.969994) (xy 389.980932 -16.969994) (xy 389.980431 -17.013982)
			(xy 389.972431 -17.101594) (xy 389.956497 -17.188115) (xy 389.932762 -17.272829) (xy 389.901421 -17.355034)
			(xy 389.862735 -17.434048) (xy 389.817023 -17.509217) (xy 389.764666 -17.579917) (xy 389.706097 -17.645564)
			(xy 389.641801 -17.705612) (xy 389.57231 -17.759565) (xy 389.498202 -17.806976) (xy 389.420089 -17.84745)
			(xy 389.338619 -17.880654) (xy 389.254467 -17.906312) (xy 389.168331 -17.924212) (xy 389.080924 -17.934204)
			(xy 388.99297 -17.936207) (xy 388.905199 -17.930203) (xy 388.818337 -17.916243) (xy 388.733105 -17.894441)
			(xy 388.650208 -17.86498) (xy 388.570334 -17.828102) (xy 388.494144 -17.784114) (xy 388.42227 -17.73338)
			(xy 388.355308 -17.67632) (xy 388.293811 -17.613407) (xy 388.23829 -17.545163) (xy 388.189205 -17.472153)
			(xy 388.146963 -17.394981) (xy 388.111913 -17.314288) (xy 388.084346 -17.230743) (xy 388.064491 -17.145036)
			(xy 388.052511 -17.057879) (xy 388.048507 -16.969994) (xy 363.980984 -16.969994) (xy 363.980483 -17.013982)
			(xy 363.972483 -17.101594) (xy 363.956549 -17.188115) (xy 363.932814 -17.272829) (xy 363.901473 -17.355034)
			(xy 363.862787 -17.434048) (xy 363.817075 -17.509217) (xy 363.764718 -17.579917) (xy 363.706149 -17.645564)
			(xy 363.641853 -17.705612) (xy 363.572362 -17.759565) (xy 363.498254 -17.806976) (xy 363.420141 -17.84745)
			(xy 363.338671 -17.880654) (xy 363.254519 -17.906312) (xy 363.168383 -17.924212) (xy 363.080976 -17.934204)
			(xy 362.993022 -17.936207) (xy 362.905251 -17.930203) (xy 362.818389 -17.916243) (xy 362.733157 -17.894441)
			(xy 362.65026 -17.86498) (xy 362.570386 -17.828102) (xy 362.494196 -17.784114) (xy 362.422322 -17.73338)
			(xy 362.35536 -17.67632) (xy 362.293863 -17.613407) (xy 362.238342 -17.545163) (xy 362.189257 -17.472153)
			(xy 362.147015 -17.394981) (xy 362.111965 -17.314288) (xy 362.084398 -17.230743) (xy 362.064543 -17.145036)
			(xy 362.052563 -17.057879) (xy 362.048559 -16.969994) (xy 347.37117 -16.969994) (xy 347.393134 -17.081123)
			(xy 347.425041 -17.283855) (xy 347.449014 -17.487677) (xy 347.465016 -17.69228) (xy 347.473023 -17.89735)
			(xy 347.473524 -17.999964) (xy 347.473023 -18.102578) (xy 347.465016 -18.307648) (xy 347.449014 -18.512251)
			(xy 347.425041 -18.716073) (xy 347.393134 -18.918805) (xy 347.353342 -19.120137) (xy 347.305725 -19.319764)
			(xy 347.250355 -19.51738) (xy 347.187318 -19.712686) (xy 347.116708 -19.905384) (xy 347.038634 -20.09518)
			(xy 346.953214 -20.281786) (xy 346.860578 -20.464916) (xy 346.760868 -20.644293) (xy 346.654235 -20.819643)
			(xy 346.540842 -20.990699) (xy 346.420862 -21.157201) (xy 346.294476 -21.318895) (xy 346.161878 -21.475535)
			(xy 346.02327 -21.626881) (xy 345.878862 -21.772705) (xy 345.728875 -21.912784) (xy 345.573536 -22.046903)
			(xy 345.413083 -22.17486) (xy 345.24776 -22.29646) (xy 345.077818 -22.411516) (xy 344.903517 -22.519855)
			(xy 344.725121 -22.62131) (xy 344.542903 -22.715728) (xy 344.35714 -22.802964) (xy 344.168115 -22.882887)
			(xy 343.976115 -22.955373) (xy 343.781433 -23.020313) (xy 343.584366 -23.077608) (xy 343.385213 -23.127171)
			(xy 343.184279 -23.168926) (xy 342.981868 -23.202809) (xy 342.77829 -23.228769) (xy 342.573853 -23.246766)
			(xy 342.36887 -23.256774) (xy 342.163653 -23.258776) (xy 341.958514 -23.25277) (xy 341.753765 -23.238765)
			(xy 341.549718 -23.216782) (xy 341.346685 -23.186855) (xy 341.144974 -23.149028) (xy 340.944892 -23.103361)
			(xy 340.746745 -23.049922) (xy 340.550833 -22.988793) (xy 340.357456 -22.920067) (xy 340.166907 -22.843848)
			(xy 339.979477 -22.760252) (xy 339.795451 -22.669408) (xy 339.61511 -22.571453) (xy 339.438728 -22.466536)
			(xy 339.266574 -22.354817) (xy 339.098909 -22.236467) (xy 338.93599 -22.111665) (xy 338.778064 -21.980601)
			(xy 338.625372 -21.843476) (xy 338.478147 -21.700498) (xy 338.336612 -21.551884) (xy 338.200983 -21.397862)
			(xy 338.071466 -21.238665) (xy 337.94826 -21.074536) (xy 337.831551 -20.905725) (xy 337.721517 -20.732488)
			(xy 337.618326 -20.555091) (xy 337.522135 -20.373803) (xy 337.43309 -20.1889) (xy 337.351327 -20.000663)
			(xy 337.276971 -19.80938) (xy 337.210135 -19.615341) (xy 337.15092 -19.418842) (xy 337.099417 -19.220183)
			(xy 337.055703 -19.019665) (xy 337.019847 -18.817594) (xy 336.991902 -18.614279) (xy 336.971911 -18.410028)
			(xy 336.959904 -18.205152) (xy 336.9559 -17.999964) (xy 115.273582 -17.999964) (xy 115.273081 -18.102578)
			(xy 115.265074 -18.307648) (xy 115.249072 -18.512251) (xy 115.225099 -18.716073) (xy 115.193192 -18.918805)
			(xy 115.1534 -19.120137) (xy 115.105783 -19.319764) (xy 115.050413 -19.51738) (xy 114.987376 -19.712686)
			(xy 114.916766 -19.905384) (xy 114.838692 -20.09518) (xy 114.753272 -20.281786) (xy 114.660636 -20.464916)
			(xy 114.560926 -20.644293) (xy 114.454293 -20.819643) (xy 114.3409 -20.990699) (xy 114.22092 -21.157201)
			(xy 114.094534 -21.318895) (xy 113.961936 -21.475535) (xy 113.823328 -21.626881) (xy 113.67892 -21.772705)
			(xy 113.528933 -21.912784) (xy 113.373594 -22.046903) (xy 113.213141 -22.17486) (xy 113.047818 -22.29646)
			(xy 112.877876 -22.411516) (xy 112.703575 -22.519855) (xy 112.525179 -22.62131) (xy 112.342961 -22.715728)
			(xy 112.157198 -22.802964) (xy 111.968173 -22.882887) (xy 111.776173 -22.955373) (xy 111.581491 -23.020313)
			(xy 111.384424 -23.077608) (xy 111.185271 -23.127171) (xy 110.984337 -23.168926) (xy 110.781926 -23.202809)
			(xy 110.578348 -23.228769) (xy 110.373911 -23.246766) (xy 110.168928 -23.256774) (xy 109.963711 -23.258776)
			(xy 109.758572 -23.25277) (xy 109.553823 -23.238765) (xy 109.349776 -23.216782) (xy 109.146743 -23.186855)
			(xy 108.945032 -23.149028) (xy 108.74495 -23.103361) (xy 108.546803 -23.049922) (xy 108.350891 -22.988793)
			(xy 108.157514 -22.920067) (xy 107.966965 -22.843848) (xy 107.779535 -22.760252) (xy 107.595509 -22.669408)
			(xy 107.415168 -22.571453) (xy 107.238786 -22.466536) (xy 107.066632 -22.354817) (xy 106.898967 -22.236467)
			(xy 106.736048 -22.111665) (xy 106.578122 -21.980601) (xy 106.42543 -21.843476) (xy 106.278205 -21.700498)
			(xy 106.13667 -21.551884) (xy 106.001041 -21.397862) (xy 105.871524 -21.238665) (xy 105.748318 -21.074536)
			(xy 105.631609 -20.905725) (xy 105.521575 -20.732488) (xy 105.418384 -20.555091) (xy 105.322193 -20.373803)
			(xy 105.233148 -20.1889) (xy 105.151385 -20.000663) (xy 105.077029 -19.80938) (xy 105.010193 -19.615341)
			(xy 104.950978 -19.418842) (xy 104.899475 -19.220183) (xy 104.855761 -19.019665) (xy 104.819905 -18.817594)
			(xy 104.79196 -18.614279) (xy 104.771969 -18.410028) (xy 104.759962 -18.205152) (xy 104.755958 -17.999964)
			(xy 31.223458 -17.999964) (xy 31.222957 -18.102578) (xy 31.21495 -18.307648) (xy 31.198948 -18.512251)
			(xy 31.174975 -18.716073) (xy 31.143068 -18.918805) (xy 31.103276 -19.120137) (xy 31.055659 -19.319764)
			(xy 31.000289 -19.51738) (xy 30.937252 -19.712686) (xy 30.866642 -19.905384) (xy 30.788568 -20.09518)
			(xy 30.703148 -20.281786) (xy 30.610512 -20.464916) (xy 30.510802 -20.644293) (xy 30.404169 -20.819643)
			(xy 30.290776 -20.990699) (xy 30.170796 -21.157201) (xy 30.04441 -21.318895) (xy 29.911812 -21.475535)
			(xy 29.773204 -21.626881) (xy 29.628796 -21.772705) (xy 29.478809 -21.912784) (xy 29.32347 -22.046903)
			(xy 29.163017 -22.17486) (xy 28.997694 -22.29646) (xy 28.827752 -22.411516) (xy 28.653451 -22.519855)
			(xy 28.475055 -22.62131) (xy 28.292837 -22.715728) (xy 28.107074 -22.802964) (xy 27.918049 -22.882887)
			(xy 27.726049 -22.955373) (xy 27.531367 -23.020313) (xy 27.3343 -23.077608) (xy 27.135147 -23.127171)
			(xy 26.934213 -23.168926) (xy 26.731802 -23.202809) (xy 26.528224 -23.228769) (xy 26.323787 -23.246766)
			(xy 26.118804 -23.256774) (xy 25.913587 -23.258776) (xy 25.708448 -23.25277) (xy 25.503699 -23.238765)
			(xy 25.299652 -23.216782) (xy 25.096619 -23.186855) (xy 24.894908 -23.149028) (xy 24.694826 -23.103361)
			(xy 24.496679 -23.049922) (xy 24.300767 -22.988793) (xy 24.10739 -22.920067) (xy 23.916841 -22.843848)
			(xy 23.729411 -22.760252) (xy 23.545385 -22.669408) (xy 23.365044 -22.571453) (xy 23.188662 -22.466536)
			(xy 23.016508 -22.354817) (xy 22.848843 -22.236467) (xy 22.685924 -22.111665) (xy 22.527998 -21.980601)
			(xy 22.375306 -21.843476) (xy 22.228081 -21.700498) (xy 22.086546 -21.551884) (xy 21.950917 -21.397862)
			(xy 21.8214 -21.238665) (xy 21.698194 -21.074536) (xy 21.581485 -20.905725) (xy 21.471451 -20.732488)
			(xy 21.36826 -20.555091) (xy 21.272069 -20.373803) (xy 21.183024 -20.1889) (xy 21.101261 -20.000663)
			(xy 21.026905 -19.80938) (xy 20.960069 -19.615341) (xy 20.900854 -19.418842) (xy 20.849351 -19.220183)
			(xy 20.805637 -19.019665) (xy 20.769781 -18.817594) (xy 20.741836 -18.614279) (xy 20.721845 -18.410028)
			(xy 20.709838 -18.205152) (xy 20.705834 -17.999964) (xy 1.524 -17.999964) (xy 1.524 -27.342846) (xy 16.523716 -27.342846)
			(xy 16.523716 -26.479246) (xy 16.524206 -26.449278) (xy 16.532029 -26.389856) (xy 16.547542 -26.331963)
			(xy 16.570478 -26.27659) (xy 16.600445 -26.224684) (xy 16.636932 -26.177134) (xy 16.679312 -26.134754)
			(xy 16.726862 -26.098267) (xy 16.778768 -26.0683) (xy 16.834141 -26.045364) (xy 16.892034 -26.029851)
			(xy 16.951456 -26.022028) (xy 17.011392 -26.022028) (xy 17.070814 -26.029851) (xy 17.128707 -26.045364)
			(xy 17.18408 -26.0683) (xy 17.235986 -26.098267) (xy 17.283536 -26.134754) (xy 17.325916 -26.177134)
			(xy 17.362403 -26.224684) (xy 17.39237 -26.27659) (xy 17.415306 -26.331963) (xy 17.430819 -26.389856)
			(xy 17.438642 -26.449278) (xy 17.439132 -26.479246) (xy 17.439132 -27.342846) (xy 42.523664 -27.342846)
			(xy 42.523664 -26.479246) (xy 42.524154 -26.449278) (xy 42.531977 -26.389856) (xy 42.54749 -26.331963)
			(xy 42.570426 -26.27659) (xy 42.600393 -26.224684) (xy 42.63688 -26.177134) (xy 42.67926 -26.134754)
			(xy 42.72681 -26.098267) (xy 42.778716 -26.0683) (xy 42.834089 -26.045364) (xy 42.891982 -26.029851)
			(xy 42.951404 -26.022028) (xy 43.01134 -26.022028) (xy 43.070762 -26.029851) (xy 43.128655 -26.045364)
			(xy 43.184028 -26.0683) (xy 43.235934 -26.098267) (xy 43.283484 -26.134754) (xy 43.325864 -26.177134)
			(xy 43.362351 -26.224684) (xy 43.392318 -26.27659) (xy 43.415254 -26.331963) (xy 43.430767 -26.389856)
			(xy 43.43859 -26.449278) (xy 43.43908 -26.479246) (xy 43.43908 -27.342846) (xy 68.523612 -27.342846)
			(xy 68.523612 -26.479246) (xy 68.524102 -26.449278) (xy 68.531925 -26.389856) (xy 68.547438 -26.331963)
			(xy 68.570374 -26.27659) (xy 68.600341 -26.224684) (xy 68.636828 -26.177134) (xy 68.679208 -26.134754)
			(xy 68.726758 -26.098267) (xy 68.778664 -26.0683) (xy 68.834037 -26.045364) (xy 68.89193 -26.029851)
			(xy 68.951352 -26.022028) (xy 69.011288 -26.022028) (xy 69.07071 -26.029851) (xy 69.128603 -26.045364)
			(xy 69.183976 -26.0683) (xy 69.235882 -26.098267) (xy 69.283432 -26.134754) (xy 69.325812 -26.177134)
			(xy 69.362299 -26.224684) (xy 69.392266 -26.27659) (xy 69.415202 -26.331963) (xy 69.430715 -26.389856)
			(xy 69.438538 -26.449278) (xy 69.439028 -26.479246) (xy 69.439028 -27.342846) (xy 94.52356 -27.342846)
			(xy 94.52356 -26.479246) (xy 94.52405 -26.449278) (xy 94.531873 -26.389856) (xy 94.547386 -26.331963)
			(xy 94.570322 -26.27659) (xy 94.600289 -26.224684) (xy 94.636776 -26.177134) (xy 94.679156 -26.134754)
			(xy 94.726706 -26.098267) (xy 94.778612 -26.0683) (xy 94.833985 -26.045364) (xy 94.891878 -26.029851)
			(xy 94.9513 -26.022028) (xy 95.011236 -26.022028) (xy 95.070658 -26.029851) (xy 95.128551 -26.045364)
			(xy 95.183924 -26.0683) (xy 95.23583 -26.098267) (xy 95.28338 -26.134754) (xy 95.32576 -26.177134)
			(xy 95.362247 -26.224684) (xy 95.392214 -26.27659) (xy 95.41515 -26.331963) (xy 95.430663 -26.389856)
			(xy 95.438486 -26.449278) (xy 95.438976 -26.479246) (xy 95.438976 -27.342846) (xy 132.62356 -27.342846)
			(xy 132.62356 -26.479246) (xy 132.62405 -26.449262) (xy 132.631878 -26.389806) (xy 132.647399 -26.331881)
			(xy 132.670348 -26.276477) (xy 132.700332 -26.224543) (xy 132.736838 -26.176967) (xy 132.779243 -26.134562)
			(xy 132.826819 -26.098056) (xy 132.878753 -26.068072) (xy 132.934157 -26.045123) (xy 132.992082 -26.029602)
			(xy 133.051538 -26.021774) (xy 133.111506 -26.021774) (xy 133.170962 -26.029602) (xy 133.228887 -26.045123)
			(xy 133.284291 -26.068072) (xy 133.336225 -26.098056) (xy 133.383801 -26.134562) (xy 133.426206 -26.176967)
			(xy 133.462712 -26.224543) (xy 133.492696 -26.276477) (xy 133.515645 -26.331881) (xy 133.531166 -26.389806)
			(xy 133.538994 -26.449262) (xy 133.539484 -26.479246) (xy 133.539484 -27.342846) (xy 158.623508 -27.342846)
			(xy 158.623508 -26.479246) (xy 158.623998 -26.449262) (xy 158.631826 -26.389806) (xy 158.647347 -26.331881)
			(xy 158.670296 -26.276477) (xy 158.70028 -26.224543) (xy 158.736786 -26.176967) (xy 158.779191 -26.134562)
			(xy 158.826767 -26.098056) (xy 158.878701 -26.068072) (xy 158.934105 -26.045123) (xy 158.99203 -26.029602)
			(xy 159.051486 -26.021774) (xy 159.111454 -26.021774) (xy 159.17091 -26.029602) (xy 159.228835 -26.045123)
			(xy 159.284239 -26.068072) (xy 159.336173 -26.098056) (xy 159.383749 -26.134562) (xy 159.426154 -26.176967)
			(xy 159.46266 -26.224543) (xy 159.492644 -26.276477) (xy 159.515593 -26.331881) (xy 159.531114 -26.389806)
			(xy 159.538942 -26.449262) (xy 159.539432 -26.479246) (xy 159.539432 -27.342846) (xy 184.623456 -27.342846)
			(xy 184.623456 -26.479246) (xy 184.623946 -26.449262) (xy 184.631774 -26.389806) (xy 184.647295 -26.331881)
			(xy 184.670244 -26.276477) (xy 184.700228 -26.224543) (xy 184.736734 -26.176967) (xy 184.779139 -26.134562)
			(xy 184.826715 -26.098056) (xy 184.878649 -26.068072) (xy 184.934053 -26.045123) (xy 184.991978 -26.029602)
			(xy 185.051434 -26.021774) (xy 185.111402 -26.021774) (xy 185.170858 -26.029602) (xy 185.228783 -26.045123)
			(xy 185.284187 -26.068072) (xy 185.336121 -26.098056) (xy 185.383697 -26.134562) (xy 185.426102 -26.176967)
			(xy 185.462608 -26.224543) (xy 185.492592 -26.276477) (xy 185.515541 -26.331881) (xy 185.531062 -26.389806)
			(xy 185.53889 -26.449262) (xy 185.53938 -26.479246) (xy 185.53938 -27.342846) (xy 210.623404 -27.342846)
			(xy 210.623404 -26.479246) (xy 210.623894 -26.449262) (xy 210.631722 -26.389806) (xy 210.647243 -26.331881)
			(xy 210.670192 -26.276477) (xy 210.700176 -26.224543) (xy 210.736682 -26.176967) (xy 210.779087 -26.134562)
			(xy 210.826663 -26.098056) (xy 210.878597 -26.068072) (xy 210.934001 -26.045123) (xy 210.991926 -26.029602)
			(xy 211.051382 -26.021774) (xy 211.11135 -26.021774) (xy 211.170806 -26.029602) (xy 211.228731 -26.045123)
			(xy 211.284135 -26.068072) (xy 211.336069 -26.098056) (xy 211.383645 -26.134562) (xy 211.42605 -26.176967)
			(xy 211.462556 -26.224543) (xy 211.49254 -26.276477) (xy 211.515489 -26.331881) (xy 211.53101 -26.389806)
			(xy 211.538838 -26.449262) (xy 211.539328 -26.479246) (xy 211.539328 -27.342846) (xy 248.723404 -27.342846)
			(xy 248.723404 -26.479246) (xy 248.723894 -26.449262) (xy 248.731722 -26.389806) (xy 248.747243 -26.331881)
			(xy 248.770192 -26.276477) (xy 248.800176 -26.224543) (xy 248.836682 -26.176967) (xy 248.879087 -26.134562)
			(xy 248.926663 -26.098056) (xy 248.978597 -26.068072) (xy 249.034001 -26.045123) (xy 249.091926 -26.029602)
			(xy 249.151382 -26.021774) (xy 249.21135 -26.021774) (xy 249.270806 -26.029602) (xy 249.328731 -26.045123)
			(xy 249.384135 -26.068072) (xy 249.436069 -26.098056) (xy 249.483645 -26.134562) (xy 249.52605 -26.176967)
			(xy 249.562556 -26.224543) (xy 249.59254 -26.276477) (xy 249.615489 -26.331881) (xy 249.63101 -26.389806)
			(xy 249.638838 -26.449262) (xy 249.639328 -26.479246) (xy 249.639328 -27.342846) (xy 274.723352 -27.342846)
			(xy 274.723352 -26.479246) (xy 274.723842 -26.449262) (xy 274.73167 -26.389806) (xy 274.747191 -26.331881)
			(xy 274.77014 -26.276477) (xy 274.800124 -26.224543) (xy 274.83663 -26.176967) (xy 274.879035 -26.134562)
			(xy 274.926611 -26.098056) (xy 274.978545 -26.068072) (xy 275.033949 -26.045123) (xy 275.091874 -26.029602)
			(xy 275.15133 -26.021774) (xy 275.211298 -26.021774) (xy 275.270754 -26.029602) (xy 275.328679 -26.045123)
			(xy 275.384083 -26.068072) (xy 275.436017 -26.098056) (xy 275.483593 -26.134562) (xy 275.525998 -26.176967)
			(xy 275.562504 -26.224543) (xy 275.592488 -26.276477) (xy 275.615437 -26.331881) (xy 275.630958 -26.389806)
			(xy 275.638786 -26.449262) (xy 275.639276 -26.479246) (xy 275.639276 -27.342846) (xy 300.7233 -27.342846)
			(xy 300.7233 -26.479246) (xy 300.72379 -26.449262) (xy 300.731618 -26.389806) (xy 300.747139 -26.331881)
			(xy 300.770088 -26.276477) (xy 300.800072 -26.224543) (xy 300.836578 -26.176967) (xy 300.878983 -26.134562)
			(xy 300.926559 -26.098056) (xy 300.978493 -26.068072) (xy 301.033897 -26.045123) (xy 301.091822 -26.029602)
			(xy 301.151278 -26.021774) (xy 301.211246 -26.021774) (xy 301.270702 -26.029602) (xy 301.328627 -26.045123)
			(xy 301.384031 -26.068072) (xy 301.435965 -26.098056) (xy 301.483541 -26.134562) (xy 301.525946 -26.176967)
			(xy 301.562452 -26.224543) (xy 301.592436 -26.276477) (xy 301.615385 -26.331881) (xy 301.630906 -26.389806)
			(xy 301.638734 -26.449262) (xy 301.639224 -26.479246) (xy 301.639224 -27.342846) (xy 326.723248 -27.342846)
			(xy 326.723248 -26.479246) (xy 326.723738 -26.449262) (xy 326.731566 -26.389806) (xy 326.747087 -26.331881)
			(xy 326.770036 -26.276477) (xy 326.80002 -26.224543) (xy 326.836526 -26.176967) (xy 326.878931 -26.134562)
			(xy 326.926507 -26.098056) (xy 326.978441 -26.068072) (xy 327.033845 -26.045123) (xy 327.09177 -26.029602)
			(xy 327.151226 -26.021774) (xy 327.211194 -26.021774) (xy 327.27065 -26.029602) (xy 327.328575 -26.045123)
			(xy 327.383979 -26.068072) (xy 327.435913 -26.098056) (xy 327.483489 -26.134562) (xy 327.525894 -26.176967)
			(xy 327.5624 -26.224543) (xy 327.592384 -26.276477) (xy 327.615333 -26.331881) (xy 327.630854 -26.389806)
			(xy 327.638682 -26.449262) (xy 327.639172 -26.479246) (xy 327.639172 -27.342846) (xy 364.823756 -27.342846)
			(xy 364.823756 -26.479246) (xy 364.824246 -26.449278) (xy 364.832069 -26.389856) (xy 364.847582 -26.331963)
			(xy 364.870518 -26.27659) (xy 364.900485 -26.224684) (xy 364.936972 -26.177134) (xy 364.979352 -26.134754)
			(xy 365.026902 -26.098267) (xy 365.078808 -26.0683) (xy 365.134181 -26.045364) (xy 365.192074 -26.029851)
			(xy 365.251496 -26.022028) (xy 365.311432 -26.022028) (xy 365.370854 -26.029851) (xy 365.428747 -26.045364)
			(xy 365.48412 -26.0683) (xy 365.536026 -26.098267) (xy 365.583576 -26.134754) (xy 365.625956 -26.177134)
			(xy 365.662443 -26.224684) (xy 365.69241 -26.27659) (xy 365.715346 -26.331963) (xy 365.730859 -26.389856)
			(xy 365.738682 -26.449278) (xy 365.739172 -26.479246) (xy 365.739172 -27.342846) (xy 390.823704 -27.342846)
			(xy 390.823704 -26.479246) (xy 390.824194 -26.449278) (xy 390.832017 -26.389856) (xy 390.84753 -26.331963)
			(xy 390.870466 -26.27659) (xy 390.900433 -26.224684) (xy 390.93692 -26.177134) (xy 390.9793 -26.134754)
			(xy 391.02685 -26.098267) (xy 391.078756 -26.0683) (xy 391.134129 -26.045364) (xy 391.192022 -26.029851)
			(xy 391.251444 -26.022028) (xy 391.31138 -26.022028) (xy 391.370802 -26.029851) (xy 391.428695 -26.045364)
			(xy 391.484068 -26.0683) (xy 391.535974 -26.098267) (xy 391.583524 -26.134754) (xy 391.625904 -26.177134)
			(xy 391.662391 -26.224684) (xy 391.692358 -26.27659) (xy 391.715294 -26.331963) (xy 391.730807 -26.389856)
			(xy 391.73863 -26.449278) (xy 391.73912 -26.479246) (xy 391.73912 -27.342846) (xy 416.823652 -27.342846)
			(xy 416.823652 -26.479246) (xy 416.824142 -26.449278) (xy 416.831965 -26.389856) (xy 416.847478 -26.331963)
			(xy 416.870414 -26.27659) (xy 416.900381 -26.224684) (xy 416.936868 -26.177134) (xy 416.979248 -26.134754)
			(xy 417.026798 -26.098267) (xy 417.078704 -26.0683) (xy 417.134077 -26.045364) (xy 417.19197 -26.029851)
			(xy 417.251392 -26.022028) (xy 417.311328 -26.022028) (xy 417.37075 -26.029851) (xy 417.428643 -26.045364)
			(xy 417.484016 -26.0683) (xy 417.535922 -26.098267) (xy 417.583472 -26.134754) (xy 417.625852 -26.177134)
			(xy 417.662339 -26.224684) (xy 417.692306 -26.27659) (xy 417.715242 -26.331963) (xy 417.730755 -26.389856)
			(xy 417.738578 -26.449278) (xy 417.739068 -26.479246) (xy 417.739068 -27.342846) (xy 442.8236 -27.342846)
			(xy 442.8236 -26.479246) (xy 442.82409 -26.449278) (xy 442.831913 -26.389856) (xy 442.847426 -26.331963)
			(xy 442.870362 -26.27659) (xy 442.900329 -26.224684) (xy 442.936816 -26.177134) (xy 442.979196 -26.134754)
			(xy 443.026746 -26.098267) (xy 443.078652 -26.0683) (xy 443.134025 -26.045364) (xy 443.191918 -26.029851)
			(xy 443.25134 -26.022028) (xy 443.311276 -26.022028) (xy 443.370698 -26.029851) (xy 443.428591 -26.045364)
			(xy 443.483964 -26.0683) (xy 443.53587 -26.098267) (xy 443.58342 -26.134754) (xy 443.6258 -26.177134)
			(xy 443.662287 -26.224684) (xy 443.692254 -26.27659) (xy 443.71519 -26.331963) (xy 443.730703 -26.389856)
			(xy 443.738526 -26.449278) (xy 443.739016 -26.479246) (xy 443.739016 -27.342846) (xy 443.738526 -27.372814)
			(xy 443.730703 -27.432236) (xy 443.71519 -27.490129) (xy 443.692254 -27.545502) (xy 443.662287 -27.597408)
			(xy 443.6258 -27.644958) (xy 443.58342 -27.687338) (xy 443.53587 -27.723825) (xy 443.483964 -27.753792)
			(xy 443.428591 -27.776728) (xy 443.370698 -27.792241) (xy 443.311276 -27.800064) (xy 443.25134 -27.800064)
			(xy 443.191918 -27.792241) (xy 443.134025 -27.776728) (xy 443.078652 -27.753792) (xy 443.026746 -27.723825)
			(xy 442.979196 -27.687338) (xy 442.936816 -27.644958) (xy 442.900329 -27.597408) (xy 442.870362 -27.545502)
			(xy 442.847426 -27.490129) (xy 442.831913 -27.432236) (xy 442.82409 -27.372814) (xy 442.8236 -27.342846)
			(xy 417.739068 -27.342846) (xy 417.738578 -27.372814) (xy 417.730755 -27.432236) (xy 417.715242 -27.490129)
			(xy 417.692306 -27.545502) (xy 417.662339 -27.597408) (xy 417.625852 -27.644958) (xy 417.583472 -27.687338)
			(xy 417.535922 -27.723825) (xy 417.484016 -27.753792) (xy 417.428643 -27.776728) (xy 417.37075 -27.792241)
			(xy 417.311328 -27.800064) (xy 417.251392 -27.800064) (xy 417.19197 -27.792241) (xy 417.134077 -27.776728)
			(xy 417.078704 -27.753792) (xy 417.026798 -27.723825) (xy 416.979248 -27.687338) (xy 416.936868 -27.644958)
			(xy 416.900381 -27.597408) (xy 416.870414 -27.545502) (xy 416.847478 -27.490129) (xy 416.831965 -27.432236)
			(xy 416.824142 -27.372814) (xy 416.823652 -27.342846) (xy 391.73912 -27.342846) (xy 391.73863 -27.372814)
			(xy 391.730807 -27.432236) (xy 391.715294 -27.490129) (xy 391.692358 -27.545502) (xy 391.662391 -27.597408)
			(xy 391.625904 -27.644958) (xy 391.583524 -27.687338) (xy 391.535974 -27.723825) (xy 391.484068 -27.753792)
			(xy 391.428695 -27.776728) (xy 391.370802 -27.792241) (xy 391.31138 -27.800064) (xy 391.251444 -27.800064)
			(xy 391.192022 -27.792241) (xy 391.134129 -27.776728) (xy 391.078756 -27.753792) (xy 391.02685 -27.723825)
			(xy 390.9793 -27.687338) (xy 390.93692 -27.644958) (xy 390.900433 -27.597408) (xy 390.870466 -27.545502)
			(xy 390.84753 -27.490129) (xy 390.832017 -27.432236) (xy 390.824194 -27.372814) (xy 390.823704 -27.342846)
			(xy 365.739172 -27.342846) (xy 365.738682 -27.372814) (xy 365.730859 -27.432236) (xy 365.715346 -27.490129)
			(xy 365.69241 -27.545502) (xy 365.662443 -27.597408) (xy 365.625956 -27.644958) (xy 365.583576 -27.687338)
			(xy 365.536026 -27.723825) (xy 365.48412 -27.753792) (xy 365.428747 -27.776728) (xy 365.370854 -27.792241)
			(xy 365.311432 -27.800064) (xy 365.251496 -27.800064) (xy 365.192074 -27.792241) (xy 365.134181 -27.776728)
			(xy 365.078808 -27.753792) (xy 365.026902 -27.723825) (xy 364.979352 -27.687338) (xy 364.936972 -27.644958)
			(xy 364.900485 -27.597408) (xy 364.870518 -27.545502) (xy 364.847582 -27.490129) (xy 364.832069 -27.432236)
			(xy 364.824246 -27.372814) (xy 364.823756 -27.342846) (xy 327.639172 -27.342846) (xy 327.638682 -27.37283)
			(xy 327.630854 -27.432286) (xy 327.615333 -27.490211) (xy 327.592384 -27.545615) (xy 327.5624 -27.597549)
			(xy 327.525894 -27.645125) (xy 327.483489 -27.68753) (xy 327.435913 -27.724036) (xy 327.383979 -27.75402)
			(xy 327.328575 -27.776969) (xy 327.27065 -27.79249) (xy 327.211194 -27.800318) (xy 327.151226 -27.800318)
			(xy 327.09177 -27.79249) (xy 327.033845 -27.776969) (xy 326.978441 -27.75402) (xy 326.926507 -27.724036)
			(xy 326.878931 -27.68753) (xy 326.836526 -27.645125) (xy 326.80002 -27.597549) (xy 326.770036 -27.545615)
			(xy 326.747087 -27.490211) (xy 326.731566 -27.432286) (xy 326.723738 -27.37283) (xy 326.723248 -27.342846)
			(xy 301.639224 -27.342846) (xy 301.638734 -27.37283) (xy 301.630906 -27.432286) (xy 301.615385 -27.490211)
			(xy 301.592436 -27.545615) (xy 301.562452 -27.597549) (xy 301.525946 -27.645125) (xy 301.483541 -27.68753)
			(xy 301.435965 -27.724036) (xy 301.384031 -27.75402) (xy 301.328627 -27.776969) (xy 301.270702 -27.79249)
			(xy 301.211246 -27.800318) (xy 301.151278 -27.800318) (xy 301.091822 -27.79249) (xy 301.033897 -27.776969)
			(xy 300.978493 -27.75402) (xy 300.926559 -27.724036) (xy 300.878983 -27.68753) (xy 300.836578 -27.645125)
			(xy 300.800072 -27.597549) (xy 300.770088 -27.545615) (xy 300.747139 -27.490211) (xy 300.731618 -27.432286)
			(xy 300.72379 -27.37283) (xy 300.7233 -27.342846) (xy 275.639276 -27.342846) (xy 275.638786 -27.37283)
			(xy 275.630958 -27.432286) (xy 275.615437 -27.490211) (xy 275.592488 -27.545615) (xy 275.562504 -27.597549)
			(xy 275.525998 -27.645125) (xy 275.483593 -27.68753) (xy 275.436017 -27.724036) (xy 275.384083 -27.75402)
			(xy 275.328679 -27.776969) (xy 275.270754 -27.79249) (xy 275.211298 -27.800318) (xy 275.15133 -27.800318)
			(xy 275.091874 -27.79249) (xy 275.033949 -27.776969) (xy 274.978545 -27.75402) (xy 274.926611 -27.724036)
			(xy 274.879035 -27.68753) (xy 274.83663 -27.645125) (xy 274.800124 -27.597549) (xy 274.77014 -27.545615)
			(xy 274.747191 -27.490211) (xy 274.73167 -27.432286) (xy 274.723842 -27.37283) (xy 274.723352 -27.342846)
			(xy 249.639328 -27.342846) (xy 249.638838 -27.37283) (xy 249.63101 -27.432286) (xy 249.615489 -27.490211)
			(xy 249.59254 -27.545615) (xy 249.562556 -27.597549) (xy 249.52605 -27.645125) (xy 249.483645 -27.68753)
			(xy 249.436069 -27.724036) (xy 249.384135 -27.75402) (xy 249.328731 -27.776969) (xy 249.270806 -27.79249)
			(xy 249.21135 -27.800318) (xy 249.151382 -27.800318) (xy 249.091926 -27.79249) (xy 249.034001 -27.776969)
			(xy 248.978597 -27.75402) (xy 248.926663 -27.724036) (xy 248.879087 -27.68753) (xy 248.836682 -27.645125)
			(xy 248.800176 -27.597549) (xy 248.770192 -27.545615) (xy 248.747243 -27.490211) (xy 248.731722 -27.432286)
			(xy 248.723894 -27.37283) (xy 248.723404 -27.342846) (xy 211.539328 -27.342846) (xy 211.538838 -27.37283)
			(xy 211.53101 -27.432286) (xy 211.515489 -27.490211) (xy 211.49254 -27.545615) (xy 211.462556 -27.597549)
			(xy 211.42605 -27.645125) (xy 211.383645 -27.68753) (xy 211.336069 -27.724036) (xy 211.284135 -27.75402)
			(xy 211.228731 -27.776969) (xy 211.170806 -27.79249) (xy 211.11135 -27.800318) (xy 211.051382 -27.800318)
			(xy 210.991926 -27.79249) (xy 210.934001 -27.776969) (xy 210.878597 -27.75402) (xy 210.826663 -27.724036)
			(xy 210.779087 -27.68753) (xy 210.736682 -27.645125) (xy 210.700176 -27.597549) (xy 210.670192 -27.545615)
			(xy 210.647243 -27.490211) (xy 210.631722 -27.432286) (xy 210.623894 -27.37283) (xy 210.623404 -27.342846)
			(xy 185.53938 -27.342846) (xy 185.53889 -27.37283) (xy 185.531062 -27.432286) (xy 185.515541 -27.490211)
			(xy 185.492592 -27.545615) (xy 185.462608 -27.597549) (xy 185.426102 -27.645125) (xy 185.383697 -27.68753)
			(xy 185.336121 -27.724036) (xy 185.284187 -27.75402) (xy 185.228783 -27.776969) (xy 185.170858 -27.79249)
			(xy 185.111402 -27.800318) (xy 185.051434 -27.800318) (xy 184.991978 -27.79249) (xy 184.934053 -27.776969)
			(xy 184.878649 -27.75402) (xy 184.826715 -27.724036) (xy 184.779139 -27.68753) (xy 184.736734 -27.645125)
			(xy 184.700228 -27.597549) (xy 184.670244 -27.545615) (xy 184.647295 -27.490211) (xy 184.631774 -27.432286)
			(xy 184.623946 -27.37283) (xy 184.623456 -27.342846) (xy 159.539432 -27.342846) (xy 159.538942 -27.37283)
			(xy 159.531114 -27.432286) (xy 159.515593 -27.490211) (xy 159.492644 -27.545615) (xy 159.46266 -27.597549)
			(xy 159.426154 -27.645125) (xy 159.383749 -27.68753) (xy 159.336173 -27.724036) (xy 159.284239 -27.75402)
			(xy 159.228835 -27.776969) (xy 159.17091 -27.79249) (xy 159.111454 -27.800318) (xy 159.051486 -27.800318)
			(xy 158.99203 -27.79249) (xy 158.934105 -27.776969) (xy 158.878701 -27.75402) (xy 158.826767 -27.724036)
			(xy 158.779191 -27.68753) (xy 158.736786 -27.645125) (xy 158.70028 -27.597549) (xy 158.670296 -27.545615)
			(xy 158.647347 -27.490211) (xy 158.631826 -27.432286) (xy 158.623998 -27.37283) (xy 158.623508 -27.342846)
			(xy 133.539484 -27.342846) (xy 133.538994 -27.37283) (xy 133.531166 -27.432286) (xy 133.515645 -27.490211)
			(xy 133.492696 -27.545615) (xy 133.462712 -27.597549) (xy 133.426206 -27.645125) (xy 133.383801 -27.68753)
			(xy 133.336225 -27.724036) (xy 133.284291 -27.75402) (xy 133.228887 -27.776969) (xy 133.170962 -27.79249)
			(xy 133.111506 -27.800318) (xy 133.051538 -27.800318) (xy 132.992082 -27.79249) (xy 132.934157 -27.776969)
			(xy 132.878753 -27.75402) (xy 132.826819 -27.724036) (xy 132.779243 -27.68753) (xy 132.736838 -27.645125)
			(xy 132.700332 -27.597549) (xy 132.670348 -27.545615) (xy 132.647399 -27.490211) (xy 132.631878 -27.432286)
			(xy 132.62405 -27.37283) (xy 132.62356 -27.342846) (xy 95.438976 -27.342846) (xy 95.438486 -27.372814)
			(xy 95.430663 -27.432236) (xy 95.41515 -27.490129) (xy 95.392214 -27.545502) (xy 95.362247 -27.597408)
			(xy 95.32576 -27.644958) (xy 95.28338 -27.687338) (xy 95.23583 -27.723825) (xy 95.183924 -27.753792)
			(xy 95.128551 -27.776728) (xy 95.070658 -27.792241) (xy 95.011236 -27.800064) (xy 94.9513 -27.800064)
			(xy 94.891878 -27.792241) (xy 94.833985 -27.776728) (xy 94.778612 -27.753792) (xy 94.726706 -27.723825)
			(xy 94.679156 -27.687338) (xy 94.636776 -27.644958) (xy 94.600289 -27.597408) (xy 94.570322 -27.545502)
			(xy 94.547386 -27.490129) (xy 94.531873 -27.432236) (xy 94.52405 -27.372814) (xy 94.52356 -27.342846)
			(xy 69.439028 -27.342846) (xy 69.438538 -27.372814) (xy 69.430715 -27.432236) (xy 69.415202 -27.490129)
			(xy 69.392266 -27.545502) (xy 69.362299 -27.597408) (xy 69.325812 -27.644958) (xy 69.283432 -27.687338)
			(xy 69.235882 -27.723825) (xy 69.183976 -27.753792) (xy 69.128603 -27.776728) (xy 69.07071 -27.792241)
			(xy 69.011288 -27.800064) (xy 68.951352 -27.800064) (xy 68.89193 -27.792241) (xy 68.834037 -27.776728)
			(xy 68.778664 -27.753792) (xy 68.726758 -27.723825) (xy 68.679208 -27.687338) (xy 68.636828 -27.644958)
			(xy 68.600341 -27.597408) (xy 68.570374 -27.545502) (xy 68.547438 -27.490129) (xy 68.531925 -27.432236)
			(xy 68.524102 -27.372814) (xy 68.523612 -27.342846) (xy 43.43908 -27.342846) (xy 43.43859 -27.372814)
			(xy 43.430767 -27.432236) (xy 43.415254 -27.490129) (xy 43.392318 -27.545502) (xy 43.362351 -27.597408)
			(xy 43.325864 -27.644958) (xy 43.283484 -27.687338) (xy 43.235934 -27.723825) (xy 43.184028 -27.753792)
			(xy 43.128655 -27.776728) (xy 43.070762 -27.792241) (xy 43.01134 -27.800064) (xy 42.951404 -27.800064)
			(xy 42.891982 -27.792241) (xy 42.834089 -27.776728) (xy 42.778716 -27.753792) (xy 42.72681 -27.723825)
			(xy 42.67926 -27.687338) (xy 42.63688 -27.644958) (xy 42.600393 -27.597408) (xy 42.570426 -27.545502)
			(xy 42.54749 -27.490129) (xy 42.531977 -27.432236) (xy 42.524154 -27.372814) (xy 42.523664 -27.342846)
			(xy 17.439132 -27.342846) (xy 17.438642 -27.372814) (xy 17.430819 -27.432236) (xy 17.415306 -27.490129)
			(xy 17.39237 -27.545502) (xy 17.362403 -27.597408) (xy 17.325916 -27.644958) (xy 17.283536 -27.687338)
			(xy 17.235986 -27.723825) (xy 17.18408 -27.753792) (xy 17.128707 -27.776728) (xy 17.070814 -27.792241)
			(xy 17.011392 -27.800064) (xy 16.951456 -27.800064) (xy 16.892034 -27.792241) (xy 16.834141 -27.776728)
			(xy 16.778768 -27.753792) (xy 16.726862 -27.723825) (xy 16.679312 -27.687338) (xy 16.636932 -27.644958)
			(xy 16.600445 -27.597408) (xy 16.570478 -27.545502) (xy 16.547542 -27.490129) (xy 16.532029 -27.432236)
			(xy 16.524206 -27.372814) (xy 16.523716 -27.342846) (xy 1.524 -27.342846) (xy 1.524 -29.12237) (xy 8.607044 -29.12237)
			(xy 8.607044 -28.25877) (xy 8.607534 -28.228802) (xy 8.615357 -28.16938) (xy 8.63087 -28.111487)
			(xy 8.653806 -28.056114) (xy 8.683773 -28.004208) (xy 8.72026 -27.956658) (xy 8.76264 -27.914278)
			(xy 8.81019 -27.877791) (xy 8.862096 -27.847824) (xy 8.917469 -27.824888) (xy 8.975362 -27.809375)
			(xy 9.034784 -27.801552) (xy 9.09472 -27.801552) (xy 9.154142 -27.809375) (xy 9.212035 -27.824888)
			(xy 9.267408 -27.847824) (xy 9.319314 -27.877791) (xy 9.366864 -27.914278) (xy 9.409244 -27.956658)
			(xy 9.445731 -28.004208) (xy 9.475698 -28.056114) (xy 9.498634 -28.111487) (xy 9.514147 -28.16938)
			(xy 9.52197 -28.228802) (xy 9.52246 -28.25877) (xy 9.52246 -29.114242) (xy 18.847308 -29.114242)
			(xy 18.847308 -28.250642) (xy 18.847798 -28.220658) (xy 18.855626 -28.161202) (xy 18.871147 -28.103277)
			(xy 18.894096 -28.047873) (xy 18.92408 -27.995939) (xy 18.960586 -27.948363) (xy 19.002991 -27.905958)
			(xy 19.050567 -27.869452) (xy 19.102501 -27.839468) (xy 19.157905 -27.816519) (xy 19.21583 -27.800998)
			(xy 19.275286 -27.79317) (xy 19.335254 -27.79317) (xy 19.39471 -27.800998) (xy 19.452635 -27.816519)
			(xy 19.508039 -27.839468) (xy 19.559973 -27.869452) (xy 19.607549 -27.905958) (xy 19.649954 -27.948363)
			(xy 19.68646 -27.995939) (xy 19.716444 -28.047873) (xy 19.739393 -28.103277) (xy 19.754914 -28.161202)
			(xy 19.762742 -28.220658) (xy 19.763232 -28.250642) (xy 19.763232 -29.114242) (xy 19.763099 -29.12237)
			(xy 34.606992 -29.12237) (xy 34.606992 -28.25877) (xy 34.607482 -28.228802) (xy 34.615305 -28.16938)
			(xy 34.630818 -28.111487) (xy 34.653754 -28.056114) (xy 34.683721 -28.004208) (xy 34.720208 -27.956658)
			(xy 34.762588 -27.914278) (xy 34.810138 -27.877791) (xy 34.862044 -27.847824) (xy 34.917417 -27.824888)
			(xy 34.97531 -27.809375) (xy 35.034732 -27.801552) (xy 35.094668 -27.801552) (xy 35.15409 -27.809375)
			(xy 35.211983 -27.824888) (xy 35.267356 -27.847824) (xy 35.319262 -27.877791) (xy 35.366812 -27.914278)
			(xy 35.409192 -27.956658) (xy 35.445679 -28.004208) (xy 35.475646 -28.056114) (xy 35.498582 -28.111487)
			(xy 35.514095 -28.16938) (xy 35.521918 -28.228802) (xy 35.522408 -28.25877) (xy 35.522408 -29.114242)
			(xy 44.847256 -29.114242) (xy 44.847256 -28.250642) (xy 44.847746 -28.220658) (xy 44.855574 -28.161202)
			(xy 44.871095 -28.103277) (xy 44.894044 -28.047873) (xy 44.924028 -27.995939) (xy 44.960534 -27.948363)
			(xy 45.002939 -27.905958) (xy 45.050515 -27.869452) (xy 45.102449 -27.839468) (xy 45.157853 -27.816519)
			(xy 45.215778 -27.800998) (xy 45.275234 -27.79317) (xy 45.335202 -27.79317) (xy 45.394658 -27.800998)
			(xy 45.452583 -27.816519) (xy 45.507987 -27.839468) (xy 45.559921 -27.869452) (xy 45.607497 -27.905958)
			(xy 45.649902 -27.948363) (xy 45.686408 -27.995939) (xy 45.716392 -28.047873) (xy 45.739341 -28.103277)
			(xy 45.754862 -28.161202) (xy 45.76269 -28.220658) (xy 45.76318 -28.250642) (xy 45.76318 -29.114242)
			(xy 45.763047 -29.12237) (xy 60.60694 -29.12237) (xy 60.60694 -28.25877) (xy 60.60743 -28.228802)
			(xy 60.615253 -28.16938) (xy 60.630766 -28.111487) (xy 60.653702 -28.056114) (xy 60.683669 -28.004208)
			(xy 60.720156 -27.956658) (xy 60.762536 -27.914278) (xy 60.810086 -27.877791) (xy 60.861992 -27.847824)
			(xy 60.917365 -27.824888) (xy 60.975258 -27.809375) (xy 61.03468 -27.801552) (xy 61.094616 -27.801552)
			(xy 61.154038 -27.809375) (xy 61.211931 -27.824888) (xy 61.267304 -27.847824) (xy 61.31921 -27.877791)
			(xy 61.36676 -27.914278) (xy 61.40914 -27.956658) (xy 61.445627 -28.004208) (xy 61.475594 -28.056114)
			(xy 61.49853 -28.111487) (xy 61.514043 -28.16938) (xy 61.521866 -28.228802) (xy 61.522356 -28.25877)
			(xy 61.522356 -29.114242) (xy 70.847204 -29.114242) (xy 70.847204 -28.250642) (xy 70.847694 -28.220658)
			(xy 70.855522 -28.161202) (xy 70.871043 -28.103277) (xy 70.893992 -28.047873) (xy 70.923976 -27.995939)
			(xy 70.960482 -27.948363) (xy 71.002887 -27.905958) (xy 71.050463 -27.869452) (xy 71.102397 -27.839468)
			(xy 71.157801 -27.816519) (xy 71.215726 -27.800998) (xy 71.275182 -27.79317) (xy 71.33515 -27.79317)
			(xy 71.394606 -27.800998) (xy 71.452531 -27.816519) (xy 71.507935 -27.839468) (xy 71.559869 -27.869452)
			(xy 71.607445 -27.905958) (xy 71.64985 -27.948363) (xy 71.686356 -27.995939) (xy 71.71634 -28.047873)
			(xy 71.739289 -28.103277) (xy 71.75481 -28.161202) (xy 71.762638 -28.220658) (xy 71.763128 -28.250642)
			(xy 71.763128 -29.114242) (xy 71.762995 -29.12237) (xy 86.606888 -29.12237) (xy 86.606888 -28.25877)
			(xy 86.607378 -28.228802) (xy 86.615201 -28.16938) (xy 86.630714 -28.111487) (xy 86.65365 -28.056114)
			(xy 86.683617 -28.004208) (xy 86.720104 -27.956658) (xy 86.762484 -27.914278) (xy 86.810034 -27.877791)
			(xy 86.86194 -27.847824) (xy 86.917313 -27.824888) (xy 86.975206 -27.809375) (xy 87.034628 -27.801552)
			(xy 87.094564 -27.801552) (xy 87.153986 -27.809375) (xy 87.211879 -27.824888) (xy 87.267252 -27.847824)
			(xy 87.319158 -27.877791) (xy 87.366708 -27.914278) (xy 87.409088 -27.956658) (xy 87.445575 -28.004208)
			(xy 87.475542 -28.056114) (xy 87.498478 -28.111487) (xy 87.513991 -28.16938) (xy 87.521814 -28.228802)
			(xy 87.522304 -28.25877) (xy 87.522304 -29.114242) (xy 96.847152 -29.114242) (xy 96.847152 -28.250642)
			(xy 96.847642 -28.220658) (xy 96.85547 -28.161202) (xy 96.870991 -28.103277) (xy 96.89394 -28.047873)
			(xy 96.923924 -27.995939) (xy 96.96043 -27.948363) (xy 97.002835 -27.905958) (xy 97.050411 -27.869452)
			(xy 97.102345 -27.839468) (xy 97.157749 -27.816519) (xy 97.215674 -27.800998) (xy 97.27513 -27.79317)
			(xy 97.335098 -27.79317) (xy 97.394554 -27.800998) (xy 97.452479 -27.816519) (xy 97.507883 -27.839468)
			(xy 97.559817 -27.869452) (xy 97.607393 -27.905958) (xy 97.649798 -27.948363) (xy 97.686304 -27.995939)
			(xy 97.716288 -28.047873) (xy 97.739237 -28.103277) (xy 97.754758 -28.161202) (xy 97.762586 -28.220658)
			(xy 97.763076 -28.250642) (xy 97.763076 -29.114242) (xy 97.762943 -29.12237) (xy 124.706888 -29.12237)
			(xy 124.706888 -28.25877) (xy 124.707378 -28.228786) (xy 124.715206 -28.16933) (xy 124.730727 -28.111405)
			(xy 124.753676 -28.056001) (xy 124.78366 -28.004067) (xy 124.820166 -27.956491) (xy 124.862571 -27.914086)
			(xy 124.910147 -27.87758) (xy 124.962081 -27.847596) (xy 125.017485 -27.824647) (xy 125.07541 -27.809126)
			(xy 125.134866 -27.801298) (xy 125.194834 -27.801298) (xy 125.25429 -27.809126) (xy 125.312215 -27.824647)
			(xy 125.367619 -27.847596) (xy 125.419553 -27.87758) (xy 125.467129 -27.914086) (xy 125.509534 -27.956491)
			(xy 125.54604 -28.004067) (xy 125.576024 -28.056001) (xy 125.598973 -28.111405) (xy 125.614494 -28.16933)
			(xy 125.622322 -28.228786) (xy 125.622812 -28.25877) (xy 125.622812 -29.114242) (xy 134.94766 -29.114242)
			(xy 134.94766 -28.250642) (xy 134.94815 -28.220674) (xy 134.955973 -28.161252) (xy 134.971486 -28.103359)
			(xy 134.994422 -28.047986) (xy 135.024389 -27.99608) (xy 135.060876 -27.94853) (xy 135.103256 -27.90615)
			(xy 135.150806 -27.869663) (xy 135.202712 -27.839696) (xy 135.258085 -27.81676) (xy 135.315978 -27.801247)
			(xy 135.3754 -27.793424) (xy 135.435336 -27.793424) (xy 135.494758 -27.801247) (xy 135.552651 -27.81676)
			(xy 135.608024 -27.839696) (xy 135.65993 -27.869663) (xy 135.70748 -27.90615) (xy 135.74986 -27.94853)
			(xy 135.786347 -27.99608) (xy 135.816314 -28.047986) (xy 135.83925 -28.103359) (xy 135.854763 -28.161252)
			(xy 135.862586 -28.220674) (xy 135.863076 -28.250642) (xy 135.863076 -29.114242) (xy 135.862943 -29.12237)
			(xy 150.706836 -29.12237) (xy 150.706836 -28.25877) (xy 150.707326 -28.228786) (xy 150.715154 -28.16933)
			(xy 150.730675 -28.111405) (xy 150.753624 -28.056001) (xy 150.783608 -28.004067) (xy 150.820114 -27.956491)
			(xy 150.862519 -27.914086) (xy 150.910095 -27.87758) (xy 150.962029 -27.847596) (xy 151.017433 -27.824647)
			(xy 151.075358 -27.809126) (xy 151.134814 -27.801298) (xy 151.194782 -27.801298) (xy 151.254238 -27.809126)
			(xy 151.312163 -27.824647) (xy 151.367567 -27.847596) (xy 151.419501 -27.87758) (xy 151.467077 -27.914086)
			(xy 151.509482 -27.956491) (xy 151.545988 -28.004067) (xy 151.575972 -28.056001) (xy 151.598921 -28.111405)
			(xy 151.614442 -28.16933) (xy 151.62227 -28.228786) (xy 151.62276 -28.25877) (xy 151.62276 -29.114242)
			(xy 160.947608 -29.114242) (xy 160.947608 -28.250642) (xy 160.948098 -28.220674) (xy 160.955921 -28.161252)
			(xy 160.971434 -28.103359) (xy 160.99437 -28.047986) (xy 161.024337 -27.99608) (xy 161.060824 -27.94853)
			(xy 161.103204 -27.90615) (xy 161.150754 -27.869663) (xy 161.20266 -27.839696) (xy 161.258033 -27.81676)
			(xy 161.315926 -27.801247) (xy 161.375348 -27.793424) (xy 161.435284 -27.793424) (xy 161.494706 -27.801247)
			(xy 161.552599 -27.81676) (xy 161.607972 -27.839696) (xy 161.659878 -27.869663) (xy 161.707428 -27.90615)
			(xy 161.749808 -27.94853) (xy 161.786295 -27.99608) (xy 161.816262 -28.047986) (xy 161.839198 -28.103359)
			(xy 161.854711 -28.161252) (xy 161.862534 -28.220674) (xy 161.863024 -28.250642) (xy 161.863024 -29.114242)
			(xy 161.862891 -29.12237) (xy 176.706784 -29.12237) (xy 176.706784 -28.25877) (xy 176.707274 -28.228786)
			(xy 176.715102 -28.16933) (xy 176.730623 -28.111405) (xy 176.753572 -28.056001) (xy 176.783556 -28.004067)
			(xy 176.820062 -27.956491) (xy 176.862467 -27.914086) (xy 176.910043 -27.87758) (xy 176.961977 -27.847596)
			(xy 177.017381 -27.824647) (xy 177.075306 -27.809126) (xy 177.134762 -27.801298) (xy 177.19473 -27.801298)
			(xy 177.254186 -27.809126) (xy 177.312111 -27.824647) (xy 177.367515 -27.847596) (xy 177.419449 -27.87758)
			(xy 177.467025 -27.914086) (xy 177.50943 -27.956491) (xy 177.545936 -28.004067) (xy 177.57592 -28.056001)
			(xy 177.598869 -28.111405) (xy 177.61439 -28.16933) (xy 177.622218 -28.228786) (xy 177.622708 -28.25877)
			(xy 177.622708 -29.114242) (xy 186.947556 -29.114242) (xy 186.947556 -28.250642) (xy 186.948046 -28.220674)
			(xy 186.955869 -28.161252) (xy 186.971382 -28.103359) (xy 186.994318 -28.047986) (xy 187.024285 -27.99608)
			(xy 187.060772 -27.94853) (xy 187.103152 -27.90615) (xy 187.150702 -27.869663) (xy 187.202608 -27.839696)
			(xy 187.257981 -27.81676) (xy 187.315874 -27.801247) (xy 187.375296 -27.793424) (xy 187.435232 -27.793424)
			(xy 187.494654 -27.801247) (xy 187.552547 -27.81676) (xy 187.60792 -27.839696) (xy 187.659826 -27.869663)
			(xy 187.707376 -27.90615) (xy 187.749756 -27.94853) (xy 187.786243 -27.99608) (xy 187.81621 -28.047986)
			(xy 187.839146 -28.103359) (xy 187.854659 -28.161252) (xy 187.862482 -28.220674) (xy 187.862972 -28.250642)
			(xy 187.862972 -29.114242) (xy 187.862839 -29.12237) (xy 202.706732 -29.12237) (xy 202.706732 -28.25877)
			(xy 202.707222 -28.228786) (xy 202.71505 -28.16933) (xy 202.730571 -28.111405) (xy 202.75352 -28.056001)
			(xy 202.783504 -28.004067) (xy 202.82001 -27.956491) (xy 202.862415 -27.914086) (xy 202.909991 -27.87758)
			(xy 202.961925 -27.847596) (xy 203.017329 -27.824647) (xy 203.075254 -27.809126) (xy 203.13471 -27.801298)
			(xy 203.194678 -27.801298) (xy 203.254134 -27.809126) (xy 203.312059 -27.824647) (xy 203.367463 -27.847596)
			(xy 203.419397 -27.87758) (xy 203.466973 -27.914086) (xy 203.509378 -27.956491) (xy 203.545884 -28.004067)
			(xy 203.575868 -28.056001) (xy 203.598817 -28.111405) (xy 203.614338 -28.16933) (xy 203.622166 -28.228786)
			(xy 203.622656 -28.25877) (xy 203.622656 -29.114242) (xy 212.947504 -29.114242) (xy 212.947504 -28.250642)
			(xy 212.947994 -28.220674) (xy 212.955817 -28.161252) (xy 212.97133 -28.103359) (xy 212.994266 -28.047986)
			(xy 213.024233 -27.99608) (xy 213.06072 -27.94853) (xy 213.1031 -27.90615) (xy 213.15065 -27.869663)
			(xy 213.202556 -27.839696) (xy 213.257929 -27.81676) (xy 213.315822 -27.801247) (xy 213.375244 -27.793424)
			(xy 213.43518 -27.793424) (xy 213.494602 -27.801247) (xy 213.552495 -27.81676) (xy 213.607868 -27.839696)
			(xy 213.659774 -27.869663) (xy 213.707324 -27.90615) (xy 213.749704 -27.94853) (xy 213.786191 -27.99608)
			(xy 213.816158 -28.047986) (xy 213.839094 -28.103359) (xy 213.854607 -28.161252) (xy 213.86243 -28.220674)
			(xy 213.86292 -28.250642) (xy 213.86292 -29.114242) (xy 213.862787 -29.12237) (xy 240.806732 -29.12237)
			(xy 240.806732 -28.25877) (xy 240.807222 -28.228786) (xy 240.81505 -28.16933) (xy 240.830571 -28.111405)
			(xy 240.85352 -28.056001) (xy 240.883504 -28.004067) (xy 240.92001 -27.956491) (xy 240.962415 -27.914086)
			(xy 241.009991 -27.87758) (xy 241.061925 -27.847596) (xy 241.117329 -27.824647) (xy 241.175254 -27.809126)
			(xy 241.23471 -27.801298) (xy 241.294678 -27.801298) (xy 241.354134 -27.809126) (xy 241.412059 -27.824647)
			(xy 241.467463 -27.847596) (xy 241.519397 -27.87758) (xy 241.566973 -27.914086) (xy 241.609378 -27.956491)
			(xy 241.645884 -28.004067) (xy 241.675868 -28.056001) (xy 241.698817 -28.111405) (xy 241.714338 -28.16933)
			(xy 241.722166 -28.228786) (xy 241.722656 -28.25877) (xy 241.722656 -29.114242) (xy 251.047504 -29.114242)
			(xy 251.047504 -28.250642) (xy 251.047994 -28.220674) (xy 251.055817 -28.161252) (xy 251.07133 -28.103359)
			(xy 251.094266 -28.047986) (xy 251.124233 -27.99608) (xy 251.16072 -27.94853) (xy 251.2031 -27.90615)
			(xy 251.25065 -27.869663) (xy 251.302556 -27.839696) (xy 251.357929 -27.81676) (xy 251.415822 -27.801247)
			(xy 251.475244 -27.793424) (xy 251.53518 -27.793424) (xy 251.594602 -27.801247) (xy 251.652495 -27.81676)
			(xy 251.707868 -27.839696) (xy 251.759774 -27.869663) (xy 251.807324 -27.90615) (xy 251.849704 -27.94853)
			(xy 251.886191 -27.99608) (xy 251.916158 -28.047986) (xy 251.939094 -28.103359) (xy 251.954607 -28.161252)
			(xy 251.96243 -28.220674) (xy 251.96292 -28.250642) (xy 251.96292 -29.114242) (xy 251.962787 -29.12237)
			(xy 266.80668 -29.12237) (xy 266.80668 -28.25877) (xy 266.80717 -28.228786) (xy 266.814998 -28.16933)
			(xy 266.830519 -28.111405) (xy 266.853468 -28.056001) (xy 266.883452 -28.004067) (xy 266.919958 -27.956491)
			(xy 266.962363 -27.914086) (xy 267.009939 -27.87758) (xy 267.061873 -27.847596) (xy 267.117277 -27.824647)
			(xy 267.175202 -27.809126) (xy 267.234658 -27.801298) (xy 267.294626 -27.801298) (xy 267.354082 -27.809126)
			(xy 267.412007 -27.824647) (xy 267.467411 -27.847596) (xy 267.519345 -27.87758) (xy 267.566921 -27.914086)
			(xy 267.609326 -27.956491) (xy 267.645832 -28.004067) (xy 267.675816 -28.056001) (xy 267.698765 -28.111405)
			(xy 267.714286 -28.16933) (xy 267.722114 -28.228786) (xy 267.722604 -28.25877) (xy 267.722604 -29.114242)
			(xy 277.047452 -29.114242) (xy 277.047452 -28.250642) (xy 277.047942 -28.220674) (xy 277.055765 -28.161252)
			(xy 277.071278 -28.103359) (xy 277.094214 -28.047986) (xy 277.124181 -27.99608) (xy 277.160668 -27.94853)
			(xy 277.203048 -27.90615) (xy 277.250598 -27.869663) (xy 277.302504 -27.839696) (xy 277.357877 -27.81676)
			(xy 277.41577 -27.801247) (xy 277.475192 -27.793424) (xy 277.535128 -27.793424) (xy 277.59455 -27.801247)
			(xy 277.652443 -27.81676) (xy 277.707816 -27.839696) (xy 277.759722 -27.869663) (xy 277.807272 -27.90615)
			(xy 277.849652 -27.94853) (xy 277.886139 -27.99608) (xy 277.916106 -28.047986) (xy 277.939042 -28.103359)
			(xy 277.954555 -28.161252) (xy 277.962378 -28.220674) (xy 277.962868 -28.250642) (xy 277.962868 -29.114242)
			(xy 277.962735 -29.12237) (xy 292.806628 -29.12237) (xy 292.806628 -28.25877) (xy 292.807118 -28.228786)
			(xy 292.814946 -28.16933) (xy 292.830467 -28.111405) (xy 292.853416 -28.056001) (xy 292.8834 -28.004067)
			(xy 292.919906 -27.956491) (xy 292.962311 -27.914086) (xy 293.009887 -27.87758) (xy 293.061821 -27.847596)
			(xy 293.117225 -27.824647) (xy 293.17515 -27.809126) (xy 293.234606 -27.801298) (xy 293.294574 -27.801298)
			(xy 293.35403 -27.809126) (xy 293.411955 -27.824647) (xy 293.467359 -27.847596) (xy 293.519293 -27.87758)
			(xy 293.566869 -27.914086) (xy 293.609274 -27.956491) (xy 293.64578 -28.004067) (xy 293.675764 -28.056001)
			(xy 293.698713 -28.111405) (xy 293.714234 -28.16933) (xy 293.722062 -28.228786) (xy 293.722552 -28.25877)
			(xy 293.722552 -29.114242) (xy 303.0474 -29.114242) (xy 303.0474 -28.250642) (xy 303.04789 -28.220674)
			(xy 303.055713 -28.161252) (xy 303.071226 -28.103359) (xy 303.094162 -28.047986) (xy 303.124129 -27.99608)
			(xy 303.160616 -27.94853) (xy 303.202996 -27.90615) (xy 303.250546 -27.869663) (xy 303.302452 -27.839696)
			(xy 303.357825 -27.81676) (xy 303.415718 -27.801247) (xy 303.47514 -27.793424) (xy 303.535076 -27.793424)
			(xy 303.594498 -27.801247) (xy 303.652391 -27.81676) (xy 303.707764 -27.839696) (xy 303.75967 -27.869663)
			(xy 303.80722 -27.90615) (xy 303.8496 -27.94853) (xy 303.886087 -27.99608) (xy 303.916054 -28.047986)
			(xy 303.93899 -28.103359) (xy 303.954503 -28.161252) (xy 303.962326 -28.220674) (xy 303.962816 -28.250642)
			(xy 303.962816 -29.114242) (xy 303.962683 -29.12237) (xy 318.806576 -29.12237) (xy 318.806576 -28.25877)
			(xy 318.807066 -28.228786) (xy 318.814894 -28.16933) (xy 318.830415 -28.111405) (xy 318.853364 -28.056001)
			(xy 318.883348 -28.004067) (xy 318.919854 -27.956491) (xy 318.962259 -27.914086) (xy 319.009835 -27.87758)
			(xy 319.061769 -27.847596) (xy 319.117173 -27.824647) (xy 319.175098 -27.809126) (xy 319.234554 -27.801298)
			(xy 319.294522 -27.801298) (xy 319.353978 -27.809126) (xy 319.411903 -27.824647) (xy 319.467307 -27.847596)
			(xy 319.519241 -27.87758) (xy 319.566817 -27.914086) (xy 319.609222 -27.956491) (xy 319.645728 -28.004067)
			(xy 319.675712 -28.056001) (xy 319.698661 -28.111405) (xy 319.714182 -28.16933) (xy 319.72201 -28.228786)
			(xy 319.7225 -28.25877) (xy 319.7225 -29.114242) (xy 329.047348 -29.114242) (xy 329.047348 -28.250642)
			(xy 329.047838 -28.220674) (xy 329.055661 -28.161252) (xy 329.071174 -28.103359) (xy 329.09411 -28.047986)
			(xy 329.124077 -27.99608) (xy 329.160564 -27.94853) (xy 329.202944 -27.90615) (xy 329.250494 -27.869663)
			(xy 329.3024 -27.839696) (xy 329.357773 -27.81676) (xy 329.415666 -27.801247) (xy 329.475088 -27.793424)
			(xy 329.535024 -27.793424) (xy 329.594446 -27.801247) (xy 329.652339 -27.81676) (xy 329.707712 -27.839696)
			(xy 329.759618 -27.869663) (xy 329.807168 -27.90615) (xy 329.849548 -27.94853) (xy 329.886035 -27.99608)
			(xy 329.916002 -28.047986) (xy 329.938938 -28.103359) (xy 329.954451 -28.161252) (xy 329.962274 -28.220674)
			(xy 329.962764 -28.250642) (xy 329.962764 -29.114242) (xy 329.962631 -29.12237) (xy 356.907084 -29.12237)
			(xy 356.907084 -28.25877) (xy 356.907574 -28.228802) (xy 356.915397 -28.16938) (xy 356.93091 -28.111487)
			(xy 356.953846 -28.056114) (xy 356.983813 -28.004208) (xy 357.0203 -27.956658) (xy 357.06268 -27.914278)
			(xy 357.11023 -27.877791) (xy 357.162136 -27.847824) (xy 357.217509 -27.824888) (xy 357.275402 -27.809375)
			(xy 357.334824 -27.801552) (xy 357.39476 -27.801552) (xy 357.454182 -27.809375) (xy 357.512075 -27.824888)
			(xy 357.567448 -27.847824) (xy 357.619354 -27.877791) (xy 357.666904 -27.914278) (xy 357.709284 -27.956658)
			(xy 357.745771 -28.004208) (xy 357.775738 -28.056114) (xy 357.798674 -28.111487) (xy 357.814187 -28.16938)
			(xy 357.82201 -28.228802) (xy 357.8225 -28.25877) (xy 357.8225 -29.114242) (xy 367.147348 -29.114242)
			(xy 367.147348 -28.250642) (xy 367.147838 -28.220658) (xy 367.155666 -28.161202) (xy 367.171187 -28.103277)
			(xy 367.194136 -28.047873) (xy 367.22412 -27.995939) (xy 367.260626 -27.948363) (xy 367.303031 -27.905958)
			(xy 367.350607 -27.869452) (xy 367.402541 -27.839468) (xy 367.457945 -27.816519) (xy 367.51587 -27.800998)
			(xy 367.575326 -27.79317) (xy 367.635294 -27.79317) (xy 367.69475 -27.800998) (xy 367.752675 -27.816519)
			(xy 367.808079 -27.839468) (xy 367.860013 -27.869452) (xy 367.907589 -27.905958) (xy 367.949994 -27.948363)
			(xy 367.9865 -27.995939) (xy 368.016484 -28.047873) (xy 368.039433 -28.103277) (xy 368.054954 -28.161202)
			(xy 368.062782 -28.220658) (xy 368.063272 -28.250642) (xy 368.063272 -29.114242) (xy 368.063139 -29.12237)
			(xy 382.907032 -29.12237) (xy 382.907032 -28.25877) (xy 382.907522 -28.228802) (xy 382.915345 -28.16938)
			(xy 382.930858 -28.111487) (xy 382.953794 -28.056114) (xy 382.983761 -28.004208) (xy 383.020248 -27.956658)
			(xy 383.062628 -27.914278) (xy 383.110178 -27.877791) (xy 383.162084 -27.847824) (xy 383.217457 -27.824888)
			(xy 383.27535 -27.809375) (xy 383.334772 -27.801552) (xy 383.394708 -27.801552) (xy 383.45413 -27.809375)
			(xy 383.512023 -27.824888) (xy 383.567396 -27.847824) (xy 383.619302 -27.877791) (xy 383.666852 -27.914278)
			(xy 383.709232 -27.956658) (xy 383.745719 -28.004208) (xy 383.775686 -28.056114) (xy 383.798622 -28.111487)
			(xy 383.814135 -28.16938) (xy 383.821958 -28.228802) (xy 383.822448 -28.25877) (xy 383.822448 -29.114242)
			(xy 393.147296 -29.114242) (xy 393.147296 -28.250642) (xy 393.147786 -28.220658) (xy 393.155614 -28.161202)
			(xy 393.171135 -28.103277) (xy 393.194084 -28.047873) (xy 393.224068 -27.995939) (xy 393.260574 -27.948363)
			(xy 393.302979 -27.905958) (xy 393.350555 -27.869452) (xy 393.402489 -27.839468) (xy 393.457893 -27.816519)
			(xy 393.515818 -27.800998) (xy 393.575274 -27.79317) (xy 393.635242 -27.79317) (xy 393.694698 -27.800998)
			(xy 393.752623 -27.816519) (xy 393.808027 -27.839468) (xy 393.859961 -27.869452) (xy 393.907537 -27.905958)
			(xy 393.949942 -27.948363) (xy 393.986448 -27.995939) (xy 394.016432 -28.047873) (xy 394.039381 -28.103277)
			(xy 394.054902 -28.161202) (xy 394.06273 -28.220658) (xy 394.06322 -28.250642) (xy 394.06322 -29.114242)
			(xy 394.063087 -29.12237) (xy 408.90698 -29.12237) (xy 408.90698 -28.25877) (xy 408.90747 -28.228802)
			(xy 408.915293 -28.16938) (xy 408.930806 -28.111487) (xy 408.953742 -28.056114) (xy 408.983709 -28.004208)
			(xy 409.020196 -27.956658) (xy 409.062576 -27.914278) (xy 409.110126 -27.877791) (xy 409.162032 -27.847824)
			(xy 409.217405 -27.824888) (xy 409.275298 -27.809375) (xy 409.33472 -27.801552) (xy 409.394656 -27.801552)
			(xy 409.454078 -27.809375) (xy 409.511971 -27.824888) (xy 409.567344 -27.847824) (xy 409.61925 -27.877791)
			(xy 409.6668 -27.914278) (xy 409.70918 -27.956658) (xy 409.745667 -28.004208) (xy 409.775634 -28.056114)
			(xy 409.79857 -28.111487) (xy 409.814083 -28.16938) (xy 409.821906 -28.228802) (xy 409.822396 -28.25877)
			(xy 409.822396 -29.114242) (xy 419.147244 -29.114242) (xy 419.147244 -28.250642) (xy 419.147734 -28.220658)
			(xy 419.155562 -28.161202) (xy 419.171083 -28.103277) (xy 419.194032 -28.047873) (xy 419.224016 -27.995939)
			(xy 419.260522 -27.948363) (xy 419.302927 -27.905958) (xy 419.350503 -27.869452) (xy 419.402437 -27.839468)
			(xy 419.457841 -27.816519) (xy 419.515766 -27.800998) (xy 419.575222 -27.79317) (xy 419.63519 -27.79317)
			(xy 419.694646 -27.800998) (xy 419.752571 -27.816519) (xy 419.807975 -27.839468) (xy 419.859909 -27.869452)
			(xy 419.907485 -27.905958) (xy 419.94989 -27.948363) (xy 419.986396 -27.995939) (xy 420.01638 -28.047873)
			(xy 420.039329 -28.103277) (xy 420.05485 -28.161202) (xy 420.062678 -28.220658) (xy 420.063168 -28.250642)
			(xy 420.063168 -29.114242) (xy 420.063035 -29.12237) (xy 434.906928 -29.12237) (xy 434.906928 -28.25877)
			(xy 434.907418 -28.228802) (xy 434.915241 -28.16938) (xy 434.930754 -28.111487) (xy 434.95369 -28.056114)
			(xy 434.983657 -28.004208) (xy 435.020144 -27.956658) (xy 435.062524 -27.914278) (xy 435.110074 -27.877791)
			(xy 435.16198 -27.847824) (xy 435.217353 -27.824888) (xy 435.275246 -27.809375) (xy 435.334668 -27.801552)
			(xy 435.394604 -27.801552) (xy 435.454026 -27.809375) (xy 435.511919 -27.824888) (xy 435.567292 -27.847824)
			(xy 435.619198 -27.877791) (xy 435.666748 -27.914278) (xy 435.709128 -27.956658) (xy 435.745615 -28.004208)
			(xy 435.775582 -28.056114) (xy 435.798518 -28.111487) (xy 435.814031 -28.16938) (xy 435.821854 -28.228802)
			(xy 435.822344 -28.25877) (xy 435.822344 -29.114242) (xy 445.147192 -29.114242) (xy 445.147192 -28.250642)
			(xy 445.147682 -28.220658) (xy 445.15551 -28.161202) (xy 445.171031 -28.103277) (xy 445.19398 -28.047873)
			(xy 445.223964 -27.995939) (xy 445.26047 -27.948363) (xy 445.302875 -27.905958) (xy 445.350451 -27.869452)
			(xy 445.402385 -27.839468) (xy 445.457789 -27.816519) (xy 445.515714 -27.800998) (xy 445.57517 -27.79317)
			(xy 445.635138 -27.79317) (xy 445.694594 -27.800998) (xy 445.752519 -27.816519) (xy 445.807923 -27.839468)
			(xy 445.859857 -27.869452) (xy 445.907433 -27.905958) (xy 445.949838 -27.948363) (xy 445.986344 -27.995939)
			(xy 446.016328 -28.047873) (xy 446.039277 -28.103277) (xy 446.054798 -28.161202) (xy 446.062626 -28.220658)
			(xy 446.063116 -28.250642) (xy 446.063116 -29.114242) (xy 446.062626 -29.144226) (xy 446.054798 -29.203682)
			(xy 446.039277 -29.261607) (xy 446.016328 -29.317011) (xy 445.986344 -29.368945) (xy 445.949838 -29.416521)
			(xy 445.907433 -29.458926) (xy 445.859857 -29.495432) (xy 445.807923 -29.525416) (xy 445.752519 -29.548365)
			(xy 445.694594 -29.563886) (xy 445.635138 -29.571714) (xy 445.57517 -29.571714) (xy 445.515714 -29.563886)
			(xy 445.457789 -29.548365) (xy 445.402385 -29.525416) (xy 445.350451 -29.495432) (xy 445.302875 -29.458926)
			(xy 445.26047 -29.416521) (xy 445.223964 -29.368945) (xy 445.19398 -29.317011) (xy 445.171031 -29.261607)
			(xy 445.15551 -29.203682) (xy 445.147682 -29.144226) (xy 445.147192 -29.114242) (xy 435.822344 -29.114242)
			(xy 435.822344 -29.12237) (xy 435.821854 -29.152338) (xy 435.814031 -29.21176) (xy 435.798518 -29.269653)
			(xy 435.775582 -29.325026) (xy 435.745615 -29.376932) (xy 435.709128 -29.424482) (xy 435.666748 -29.466862)
			(xy 435.619198 -29.503349) (xy 435.567292 -29.533316) (xy 435.511919 -29.556252) (xy 435.454026 -29.571765)
			(xy 435.394604 -29.579588) (xy 435.334668 -29.579588) (xy 435.275246 -29.571765) (xy 435.217353 -29.556252)
			(xy 435.16198 -29.533316) (xy 435.110074 -29.503349) (xy 435.062524 -29.466862) (xy 435.020144 -29.424482)
			(xy 434.983657 -29.376932) (xy 434.95369 -29.325026) (xy 434.930754 -29.269653) (xy 434.915241 -29.21176)
			(xy 434.907418 -29.152338) (xy 434.906928 -29.12237) (xy 420.063035 -29.12237) (xy 420.062678 -29.144226)
			(xy 420.05485 -29.203682) (xy 420.039329 -29.261607) (xy 420.01638 -29.317011) (xy 419.986396 -29.368945)
			(xy 419.94989 -29.416521) (xy 419.907485 -29.458926) (xy 419.859909 -29.495432) (xy 419.807975 -29.525416)
			(xy 419.752571 -29.548365) (xy 419.694646 -29.563886) (xy 419.63519 -29.571714) (xy 419.575222 -29.571714)
			(xy 419.515766 -29.563886) (xy 419.457841 -29.548365) (xy 419.402437 -29.525416) (xy 419.350503 -29.495432)
			(xy 419.302927 -29.458926) (xy 419.260522 -29.416521) (xy 419.224016 -29.368945) (xy 419.194032 -29.317011)
			(xy 419.171083 -29.261607) (xy 419.155562 -29.203682) (xy 419.147734 -29.144226) (xy 419.147244 -29.114242)
			(xy 409.822396 -29.114242) (xy 409.822396 -29.12237) (xy 409.821906 -29.152338) (xy 409.814083 -29.21176)
			(xy 409.79857 -29.269653) (xy 409.775634 -29.325026) (xy 409.745667 -29.376932) (xy 409.70918 -29.424482)
			(xy 409.6668 -29.466862) (xy 409.61925 -29.503349) (xy 409.567344 -29.533316) (xy 409.511971 -29.556252)
			(xy 409.454078 -29.571765) (xy 409.394656 -29.579588) (xy 409.33472 -29.579588) (xy 409.275298 -29.571765)
			(xy 409.217405 -29.556252) (xy 409.162032 -29.533316) (xy 409.110126 -29.503349) (xy 409.062576 -29.466862)
			(xy 409.020196 -29.424482) (xy 408.983709 -29.376932) (xy 408.953742 -29.325026) (xy 408.930806 -29.269653)
			(xy 408.915293 -29.21176) (xy 408.90747 -29.152338) (xy 408.90698 -29.12237) (xy 394.063087 -29.12237)
			(xy 394.06273 -29.144226) (xy 394.054902 -29.203682) (xy 394.039381 -29.261607) (xy 394.016432 -29.317011)
			(xy 393.986448 -29.368945) (xy 393.949942 -29.416521) (xy 393.907537 -29.458926) (xy 393.859961 -29.495432)
			(xy 393.808027 -29.525416) (xy 393.752623 -29.548365) (xy 393.694698 -29.563886) (xy 393.635242 -29.571714)
			(xy 393.575274 -29.571714) (xy 393.515818 -29.563886) (xy 393.457893 -29.548365) (xy 393.402489 -29.525416)
			(xy 393.350555 -29.495432) (xy 393.302979 -29.458926) (xy 393.260574 -29.416521) (xy 393.224068 -29.368945)
			(xy 393.194084 -29.317011) (xy 393.171135 -29.261607) (xy 393.155614 -29.203682) (xy 393.147786 -29.144226)
			(xy 393.147296 -29.114242) (xy 383.822448 -29.114242) (xy 383.822448 -29.12237) (xy 383.821958 -29.152338)
			(xy 383.814135 -29.21176) (xy 383.798622 -29.269653) (xy 383.775686 -29.325026) (xy 383.745719 -29.376932)
			(xy 383.709232 -29.424482) (xy 383.666852 -29.466862) (xy 383.619302 -29.503349) (xy 383.567396 -29.533316)
			(xy 383.512023 -29.556252) (xy 383.45413 -29.571765) (xy 383.394708 -29.579588) (xy 383.334772 -29.579588)
			(xy 383.27535 -29.571765) (xy 383.217457 -29.556252) (xy 383.162084 -29.533316) (xy 383.110178 -29.503349)
			(xy 383.062628 -29.466862) (xy 383.020248 -29.424482) (xy 382.983761 -29.376932) (xy 382.953794 -29.325026)
			(xy 382.930858 -29.269653) (xy 382.915345 -29.21176) (xy 382.907522 -29.152338) (xy 382.907032 -29.12237)
			(xy 368.063139 -29.12237) (xy 368.062782 -29.144226) (xy 368.054954 -29.203682) (xy 368.039433 -29.261607)
			(xy 368.016484 -29.317011) (xy 367.9865 -29.368945) (xy 367.949994 -29.416521) (xy 367.907589 -29.458926)
			(xy 367.860013 -29.495432) (xy 367.808079 -29.525416) (xy 367.752675 -29.548365) (xy 367.69475 -29.563886)
			(xy 367.635294 -29.571714) (xy 367.575326 -29.571714) (xy 367.51587 -29.563886) (xy 367.457945 -29.548365)
			(xy 367.402541 -29.525416) (xy 367.350607 -29.495432) (xy 367.303031 -29.458926) (xy 367.260626 -29.416521)
			(xy 367.22412 -29.368945) (xy 367.194136 -29.317011) (xy 367.171187 -29.261607) (xy 367.155666 -29.203682)
			(xy 367.147838 -29.144226) (xy 367.147348 -29.114242) (xy 357.8225 -29.114242) (xy 357.8225 -29.12237)
			(xy 357.82201 -29.152338) (xy 357.814187 -29.21176) (xy 357.798674 -29.269653) (xy 357.775738 -29.325026)
			(xy 357.745771 -29.376932) (xy 357.709284 -29.424482) (xy 357.666904 -29.466862) (xy 357.619354 -29.503349)
			(xy 357.567448 -29.533316) (xy 357.512075 -29.556252) (xy 357.454182 -29.571765) (xy 357.39476 -29.579588)
			(xy 357.334824 -29.579588) (xy 357.275402 -29.571765) (xy 357.217509 -29.556252) (xy 357.162136 -29.533316)
			(xy 357.11023 -29.503349) (xy 357.06268 -29.466862) (xy 357.0203 -29.424482) (xy 356.983813 -29.376932)
			(xy 356.953846 -29.325026) (xy 356.93091 -29.269653) (xy 356.915397 -29.21176) (xy 356.907574 -29.152338)
			(xy 356.907084 -29.12237) (xy 329.962631 -29.12237) (xy 329.962274 -29.14421) (xy 329.954451 -29.203632)
			(xy 329.938938 -29.261525) (xy 329.916002 -29.316898) (xy 329.886035 -29.368804) (xy 329.849548 -29.416354)
			(xy 329.807168 -29.458734) (xy 329.759618 -29.495221) (xy 329.707712 -29.525188) (xy 329.652339 -29.548124)
			(xy 329.594446 -29.563637) (xy 329.535024 -29.57146) (xy 329.475088 -29.57146) (xy 329.415666 -29.563637)
			(xy 329.357773 -29.548124) (xy 329.3024 -29.525188) (xy 329.250494 -29.495221) (xy 329.202944 -29.458734)
			(xy 329.160564 -29.416354) (xy 329.124077 -29.368804) (xy 329.09411 -29.316898) (xy 329.071174 -29.261525)
			(xy 329.055661 -29.203632) (xy 329.047838 -29.14421) (xy 329.047348 -29.114242) (xy 319.7225 -29.114242)
			(xy 319.7225 -29.12237) (xy 319.72201 -29.152354) (xy 319.714182 -29.21181) (xy 319.698661 -29.269735)
			(xy 319.675712 -29.325139) (xy 319.645728 -29.377073) (xy 319.609222 -29.424649) (xy 319.566817 -29.467054)
			(xy 319.519241 -29.50356) (xy 319.467307 -29.533544) (xy 319.411903 -29.556493) (xy 319.353978 -29.572014)
			(xy 319.294522 -29.579842) (xy 319.234554 -29.579842) (xy 319.175098 -29.572014) (xy 319.117173 -29.556493)
			(xy 319.061769 -29.533544) (xy 319.009835 -29.50356) (xy 318.962259 -29.467054) (xy 318.919854 -29.424649)
			(xy 318.883348 -29.377073) (xy 318.853364 -29.325139) (xy 318.830415 -29.269735) (xy 318.814894 -29.21181)
			(xy 318.807066 -29.152354) (xy 318.806576 -29.12237) (xy 303.962683 -29.12237) (xy 303.962326 -29.14421)
			(xy 303.954503 -29.203632) (xy 303.93899 -29.261525) (xy 303.916054 -29.316898) (xy 303.886087 -29.368804)
			(xy 303.8496 -29.416354) (xy 303.80722 -29.458734) (xy 303.75967 -29.495221) (xy 303.707764 -29.525188)
			(xy 303.652391 -29.548124) (xy 303.594498 -29.563637) (xy 303.535076 -29.57146) (xy 303.47514 -29.57146)
			(xy 303.415718 -29.563637) (xy 303.357825 -29.548124) (xy 303.302452 -29.525188) (xy 303.250546 -29.495221)
			(xy 303.202996 -29.458734) (xy 303.160616 -29.416354) (xy 303.124129 -29.368804) (xy 303.094162 -29.316898)
			(xy 303.071226 -29.261525) (xy 303.055713 -29.203632) (xy 303.04789 -29.14421) (xy 303.0474 -29.114242)
			(xy 293.722552 -29.114242) (xy 293.722552 -29.12237) (xy 293.722062 -29.152354) (xy 293.714234 -29.21181)
			(xy 293.698713 -29.269735) (xy 293.675764 -29.325139) (xy 293.64578 -29.377073) (xy 293.609274 -29.424649)
			(xy 293.566869 -29.467054) (xy 293.519293 -29.50356) (xy 293.467359 -29.533544) (xy 293.411955 -29.556493)
			(xy 293.35403 -29.572014) (xy 293.294574 -29.579842) (xy 293.234606 -29.579842) (xy 293.17515 -29.572014)
			(xy 293.117225 -29.556493) (xy 293.061821 -29.533544) (xy 293.009887 -29.50356) (xy 292.962311 -29.467054)
			(xy 292.919906 -29.424649) (xy 292.8834 -29.377073) (xy 292.853416 -29.325139) (xy 292.830467 -29.269735)
			(xy 292.814946 -29.21181) (xy 292.807118 -29.152354) (xy 292.806628 -29.12237) (xy 277.962735 -29.12237)
			(xy 277.962378 -29.14421) (xy 277.954555 -29.203632) (xy 277.939042 -29.261525) (xy 277.916106 -29.316898)
			(xy 277.886139 -29.368804) (xy 277.849652 -29.416354) (xy 277.807272 -29.458734) (xy 277.759722 -29.495221)
			(xy 277.707816 -29.525188) (xy 277.652443 -29.548124) (xy 277.59455 -29.563637) (xy 277.535128 -29.57146)
			(xy 277.475192 -29.57146) (xy 277.41577 -29.563637) (xy 277.357877 -29.548124) (xy 277.302504 -29.525188)
			(xy 277.250598 -29.495221) (xy 277.203048 -29.458734) (xy 277.160668 -29.416354) (xy 277.124181 -29.368804)
			(xy 277.094214 -29.316898) (xy 277.071278 -29.261525) (xy 277.055765 -29.203632) (xy 277.047942 -29.14421)
			(xy 277.047452 -29.114242) (xy 267.722604 -29.114242) (xy 267.722604 -29.12237) (xy 267.722114 -29.152354)
			(xy 267.714286 -29.21181) (xy 267.698765 -29.269735) (xy 267.675816 -29.325139) (xy 267.645832 -29.377073)
			(xy 267.609326 -29.424649) (xy 267.566921 -29.467054) (xy 267.519345 -29.50356) (xy 267.467411 -29.533544)
			(xy 267.412007 -29.556493) (xy 267.354082 -29.572014) (xy 267.294626 -29.579842) (xy 267.234658 -29.579842)
			(xy 267.175202 -29.572014) (xy 267.117277 -29.556493) (xy 267.061873 -29.533544) (xy 267.009939 -29.50356)
			(xy 266.962363 -29.467054) (xy 266.919958 -29.424649) (xy 266.883452 -29.377073) (xy 266.853468 -29.325139)
			(xy 266.830519 -29.269735) (xy 266.814998 -29.21181) (xy 266.80717 -29.152354) (xy 266.80668 -29.12237)
			(xy 251.962787 -29.12237) (xy 251.96243 -29.14421) (xy 251.954607 -29.203632) (xy 251.939094 -29.261525)
			(xy 251.916158 -29.316898) (xy 251.886191 -29.368804) (xy 251.849704 -29.416354) (xy 251.807324 -29.458734)
			(xy 251.759774 -29.495221) (xy 251.707868 -29.525188) (xy 251.652495 -29.548124) (xy 251.594602 -29.563637)
			(xy 251.53518 -29.57146) (xy 251.475244 -29.57146) (xy 251.415822 -29.563637) (xy 251.357929 -29.548124)
			(xy 251.302556 -29.525188) (xy 251.25065 -29.495221) (xy 251.2031 -29.458734) (xy 251.16072 -29.416354)
			(xy 251.124233 -29.368804) (xy 251.094266 -29.316898) (xy 251.07133 -29.261525) (xy 251.055817 -29.203632)
			(xy 251.047994 -29.14421) (xy 251.047504 -29.114242) (xy 241.722656 -29.114242) (xy 241.722656 -29.12237)
			(xy 241.722166 -29.152354) (xy 241.714338 -29.21181) (xy 241.698817 -29.269735) (xy 241.675868 -29.325139)
			(xy 241.645884 -29.377073) (xy 241.609378 -29.424649) (xy 241.566973 -29.467054) (xy 241.519397 -29.50356)
			(xy 241.467463 -29.533544) (xy 241.412059 -29.556493) (xy 241.354134 -29.572014) (xy 241.294678 -29.579842)
			(xy 241.23471 -29.579842) (xy 241.175254 -29.572014) (xy 241.117329 -29.556493) (xy 241.061925 -29.533544)
			(xy 241.009991 -29.50356) (xy 240.962415 -29.467054) (xy 240.92001 -29.424649) (xy 240.883504 -29.377073)
			(xy 240.85352 -29.325139) (xy 240.830571 -29.269735) (xy 240.81505 -29.21181) (xy 240.807222 -29.152354)
			(xy 240.806732 -29.12237) (xy 213.862787 -29.12237) (xy 213.86243 -29.14421) (xy 213.854607 -29.203632)
			(xy 213.839094 -29.261525) (xy 213.816158 -29.316898) (xy 213.786191 -29.368804) (xy 213.749704 -29.416354)
			(xy 213.707324 -29.458734) (xy 213.659774 -29.495221) (xy 213.607868 -29.525188) (xy 213.552495 -29.548124)
			(xy 213.494602 -29.563637) (xy 213.43518 -29.57146) (xy 213.375244 -29.57146) (xy 213.315822 -29.563637)
			(xy 213.257929 -29.548124) (xy 213.202556 -29.525188) (xy 213.15065 -29.495221) (xy 213.1031 -29.458734)
			(xy 213.06072 -29.416354) (xy 213.024233 -29.368804) (xy 212.994266 -29.316898) (xy 212.97133 -29.261525)
			(xy 212.955817 -29.203632) (xy 212.947994 -29.14421) (xy 212.947504 -29.114242) (xy 203.622656 -29.114242)
			(xy 203.622656 -29.12237) (xy 203.622166 -29.152354) (xy 203.614338 -29.21181) (xy 203.598817 -29.269735)
			(xy 203.575868 -29.325139) (xy 203.545884 -29.377073) (xy 203.509378 -29.424649) (xy 203.466973 -29.467054)
			(xy 203.419397 -29.50356) (xy 203.367463 -29.533544) (xy 203.312059 -29.556493) (xy 203.254134 -29.572014)
			(xy 203.194678 -29.579842) (xy 203.13471 -29.579842) (xy 203.075254 -29.572014) (xy 203.017329 -29.556493)
			(xy 202.961925 -29.533544) (xy 202.909991 -29.50356) (xy 202.862415 -29.467054) (xy 202.82001 -29.424649)
			(xy 202.783504 -29.377073) (xy 202.75352 -29.325139) (xy 202.730571 -29.269735) (xy 202.71505 -29.21181)
			(xy 202.707222 -29.152354) (xy 202.706732 -29.12237) (xy 187.862839 -29.12237) (xy 187.862482 -29.14421)
			(xy 187.854659 -29.203632) (xy 187.839146 -29.261525) (xy 187.81621 -29.316898) (xy 187.786243 -29.368804)
			(xy 187.749756 -29.416354) (xy 187.707376 -29.458734) (xy 187.659826 -29.495221) (xy 187.60792 -29.525188)
			(xy 187.552547 -29.548124) (xy 187.494654 -29.563637) (xy 187.435232 -29.57146) (xy 187.375296 -29.57146)
			(xy 187.315874 -29.563637) (xy 187.257981 -29.548124) (xy 187.202608 -29.525188) (xy 187.150702 -29.495221)
			(xy 187.103152 -29.458734) (xy 187.060772 -29.416354) (xy 187.024285 -29.368804) (xy 186.994318 -29.316898)
			(xy 186.971382 -29.261525) (xy 186.955869 -29.203632) (xy 186.948046 -29.14421) (xy 186.947556 -29.114242)
			(xy 177.622708 -29.114242) (xy 177.622708 -29.12237) (xy 177.622218 -29.152354) (xy 177.61439 -29.21181)
			(xy 177.598869 -29.269735) (xy 177.57592 -29.325139) (xy 177.545936 -29.377073) (xy 177.50943 -29.424649)
			(xy 177.467025 -29.467054) (xy 177.419449 -29.50356) (xy 177.367515 -29.533544) (xy 177.312111 -29.556493)
			(xy 177.254186 -29.572014) (xy 177.19473 -29.579842) (xy 177.134762 -29.579842) (xy 177.075306 -29.572014)
			(xy 177.017381 -29.556493) (xy 176.961977 -29.533544) (xy 176.910043 -29.50356) (xy 176.862467 -29.467054)
			(xy 176.820062 -29.424649) (xy 176.783556 -29.377073) (xy 176.753572 -29.325139) (xy 176.730623 -29.269735)
			(xy 176.715102 -29.21181) (xy 176.707274 -29.152354) (xy 176.706784 -29.12237) (xy 161.862891 -29.12237)
			(xy 161.862534 -29.14421) (xy 161.854711 -29.203632) (xy 161.839198 -29.261525) (xy 161.816262 -29.316898)
			(xy 161.786295 -29.368804) (xy 161.749808 -29.416354) (xy 161.707428 -29.458734) (xy 161.659878 -29.495221)
			(xy 161.607972 -29.525188) (xy 161.552599 -29.548124) (xy 161.494706 -29.563637) (xy 161.435284 -29.57146)
			(xy 161.375348 -29.57146) (xy 161.315926 -29.563637) (xy 161.258033 -29.548124) (xy 161.20266 -29.525188)
			(xy 161.150754 -29.495221) (xy 161.103204 -29.458734) (xy 161.060824 -29.416354) (xy 161.024337 -29.368804)
			(xy 160.99437 -29.316898) (xy 160.971434 -29.261525) (xy 160.955921 -29.203632) (xy 160.948098 -29.14421)
			(xy 160.947608 -29.114242) (xy 151.62276 -29.114242) (xy 151.62276 -29.12237) (xy 151.62227 -29.152354)
			(xy 151.614442 -29.21181) (xy 151.598921 -29.269735) (xy 151.575972 -29.325139) (xy 151.545988 -29.377073)
			(xy 151.509482 -29.424649) (xy 151.467077 -29.467054) (xy 151.419501 -29.50356) (xy 151.367567 -29.533544)
			(xy 151.312163 -29.556493) (xy 151.254238 -29.572014) (xy 151.194782 -29.579842) (xy 151.134814 -29.579842)
			(xy 151.075358 -29.572014) (xy 151.017433 -29.556493) (xy 150.962029 -29.533544) (xy 150.910095 -29.50356)
			(xy 150.862519 -29.467054) (xy 150.820114 -29.424649) (xy 150.783608 -29.377073) (xy 150.753624 -29.325139)
			(xy 150.730675 -29.269735) (xy 150.715154 -29.21181) (xy 150.707326 -29.152354) (xy 150.706836 -29.12237)
			(xy 135.862943 -29.12237) (xy 135.862586 -29.14421) (xy 135.854763 -29.203632) (xy 135.83925 -29.261525)
			(xy 135.816314 -29.316898) (xy 135.786347 -29.368804) (xy 135.74986 -29.416354) (xy 135.70748 -29.458734)
			(xy 135.65993 -29.495221) (xy 135.608024 -29.525188) (xy 135.552651 -29.548124) (xy 135.494758 -29.563637)
			(xy 135.435336 -29.57146) (xy 135.3754 -29.57146) (xy 135.315978 -29.563637) (xy 135.258085 -29.548124)
			(xy 135.202712 -29.525188) (xy 135.150806 -29.495221) (xy 135.103256 -29.458734) (xy 135.060876 -29.416354)
			(xy 135.024389 -29.368804) (xy 134.994422 -29.316898) (xy 134.971486 -29.261525) (xy 134.955973 -29.203632)
			(xy 134.94815 -29.14421) (xy 134.94766 -29.114242) (xy 125.622812 -29.114242) (xy 125.622812 -29.12237)
			(xy 125.622322 -29.152354) (xy 125.614494 -29.21181) (xy 125.598973 -29.269735) (xy 125.576024 -29.325139)
			(xy 125.54604 -29.377073) (xy 125.509534 -29.424649) (xy 125.467129 -29.467054) (xy 125.419553 -29.50356)
			(xy 125.367619 -29.533544) (xy 125.312215 -29.556493) (xy 125.25429 -29.572014) (xy 125.194834 -29.579842)
			(xy 125.134866 -29.579842) (xy 125.07541 -29.572014) (xy 125.017485 -29.556493) (xy 124.962081 -29.533544)
			(xy 124.910147 -29.50356) (xy 124.862571 -29.467054) (xy 124.820166 -29.424649) (xy 124.78366 -29.377073)
			(xy 124.753676 -29.325139) (xy 124.730727 -29.269735) (xy 124.715206 -29.21181) (xy 124.707378 -29.152354)
			(xy 124.706888 -29.12237) (xy 97.762943 -29.12237) (xy 97.762586 -29.144226) (xy 97.754758 -29.203682)
			(xy 97.739237 -29.261607) (xy 97.716288 -29.317011) (xy 97.686304 -29.368945) (xy 97.649798 -29.416521)
			(xy 97.607393 -29.458926) (xy 97.559817 -29.495432) (xy 97.507883 -29.525416) (xy 97.452479 -29.548365)
			(xy 97.394554 -29.563886) (xy 97.335098 -29.571714) (xy 97.27513 -29.571714) (xy 97.215674 -29.563886)
			(xy 97.157749 -29.548365) (xy 97.102345 -29.525416) (xy 97.050411 -29.495432) (xy 97.002835 -29.458926)
			(xy 96.96043 -29.416521) (xy 96.923924 -29.368945) (xy 96.89394 -29.317011) (xy 96.870991 -29.261607)
			(xy 96.85547 -29.203682) (xy 96.847642 -29.144226) (xy 96.847152 -29.114242) (xy 87.522304 -29.114242)
			(xy 87.522304 -29.12237) (xy 87.521814 -29.152338) (xy 87.513991 -29.21176) (xy 87.498478 -29.269653)
			(xy 87.475542 -29.325026) (xy 87.445575 -29.376932) (xy 87.409088 -29.424482) (xy 87.366708 -29.466862)
			(xy 87.319158 -29.503349) (xy 87.267252 -29.533316) (xy 87.211879 -29.556252) (xy 87.153986 -29.571765)
			(xy 87.094564 -29.579588) (xy 87.034628 -29.579588) (xy 86.975206 -29.571765) (xy 86.917313 -29.556252)
			(xy 86.86194 -29.533316) (xy 86.810034 -29.503349) (xy 86.762484 -29.466862) (xy 86.720104 -29.424482)
			(xy 86.683617 -29.376932) (xy 86.65365 -29.325026) (xy 86.630714 -29.269653) (xy 86.615201 -29.21176)
			(xy 86.607378 -29.152338) (xy 86.606888 -29.12237) (xy 71.762995 -29.12237) (xy 71.762638 -29.144226)
			(xy 71.75481 -29.203682) (xy 71.739289 -29.261607) (xy 71.71634 -29.317011) (xy 71.686356 -29.368945)
			(xy 71.64985 -29.416521) (xy 71.607445 -29.458926) (xy 71.559869 -29.495432) (xy 71.507935 -29.525416)
			(xy 71.452531 -29.548365) (xy 71.394606 -29.563886) (xy 71.33515 -29.571714) (xy 71.275182 -29.571714)
			(xy 71.215726 -29.563886) (xy 71.157801 -29.548365) (xy 71.102397 -29.525416) (xy 71.050463 -29.495432)
			(xy 71.002887 -29.458926) (xy 70.960482 -29.416521) (xy 70.923976 -29.368945) (xy 70.893992 -29.317011)
			(xy 70.871043 -29.261607) (xy 70.855522 -29.203682) (xy 70.847694 -29.144226) (xy 70.847204 -29.114242)
			(xy 61.522356 -29.114242) (xy 61.522356 -29.12237) (xy 61.521866 -29.152338) (xy 61.514043 -29.21176)
			(xy 61.49853 -29.269653) (xy 61.475594 -29.325026) (xy 61.445627 -29.376932) (xy 61.40914 -29.424482)
			(xy 61.36676 -29.466862) (xy 61.31921 -29.503349) (xy 61.267304 -29.533316) (xy 61.211931 -29.556252)
			(xy 61.154038 -29.571765) (xy 61.094616 -29.579588) (xy 61.03468 -29.579588) (xy 60.975258 -29.571765)
			(xy 60.917365 -29.556252) (xy 60.861992 -29.533316) (xy 60.810086 -29.503349) (xy 60.762536 -29.466862)
			(xy 60.720156 -29.424482) (xy 60.683669 -29.376932) (xy 60.653702 -29.325026) (xy 60.630766 -29.269653)
			(xy 60.615253 -29.21176) (xy 60.60743 -29.152338) (xy 60.60694 -29.12237) (xy 45.763047 -29.12237)
			(xy 45.76269 -29.144226) (xy 45.754862 -29.203682) (xy 45.739341 -29.261607) (xy 45.716392 -29.317011)
			(xy 45.686408 -29.368945) (xy 45.649902 -29.416521) (xy 45.607497 -29.458926) (xy 45.559921 -29.495432)
			(xy 45.507987 -29.525416) (xy 45.452583 -29.548365) (xy 45.394658 -29.563886) (xy 45.335202 -29.571714)
			(xy 45.275234 -29.571714) (xy 45.215778 -29.563886) (xy 45.157853 -29.548365) (xy 45.102449 -29.525416)
			(xy 45.050515 -29.495432) (xy 45.002939 -29.458926) (xy 44.960534 -29.416521) (xy 44.924028 -29.368945)
			(xy 44.894044 -29.317011) (xy 44.871095 -29.261607) (xy 44.855574 -29.203682) (xy 44.847746 -29.144226)
			(xy 44.847256 -29.114242) (xy 35.522408 -29.114242) (xy 35.522408 -29.12237) (xy 35.521918 -29.152338)
			(xy 35.514095 -29.21176) (xy 35.498582 -29.269653) (xy 35.475646 -29.325026) (xy 35.445679 -29.376932)
			(xy 35.409192 -29.424482) (xy 35.366812 -29.466862) (xy 35.319262 -29.503349) (xy 35.267356 -29.533316)
			(xy 35.211983 -29.556252) (xy 35.15409 -29.571765) (xy 35.094668 -29.579588) (xy 35.034732 -29.579588)
			(xy 34.97531 -29.571765) (xy 34.917417 -29.556252) (xy 34.862044 -29.533316) (xy 34.810138 -29.503349)
			(xy 34.762588 -29.466862) (xy 34.720208 -29.424482) (xy 34.683721 -29.376932) (xy 34.653754 -29.325026)
			(xy 34.630818 -29.269653) (xy 34.615305 -29.21176) (xy 34.607482 -29.152338) (xy 34.606992 -29.12237)
			(xy 19.763099 -29.12237) (xy 19.762742 -29.144226) (xy 19.754914 -29.203682) (xy 19.739393 -29.261607)
			(xy 19.716444 -29.317011) (xy 19.68646 -29.368945) (xy 19.649954 -29.416521) (xy 19.607549 -29.458926)
			(xy 19.559973 -29.495432) (xy 19.508039 -29.525416) (xy 19.452635 -29.548365) (xy 19.39471 -29.563886)
			(xy 19.335254 -29.571714) (xy 19.275286 -29.571714) (xy 19.21583 -29.563886) (xy 19.157905 -29.548365)
			(xy 19.102501 -29.525416) (xy 19.050567 -29.495432) (xy 19.002991 -29.458926) (xy 18.960586 -29.416521)
			(xy 18.92408 -29.368945) (xy 18.894096 -29.317011) (xy 18.871147 -29.261607) (xy 18.855626 -29.203682)
			(xy 18.847798 -29.144226) (xy 18.847308 -29.114242) (xy 9.52246 -29.114242) (xy 9.52246 -29.12237)
			(xy 9.52197 -29.152338) (xy 9.514147 -29.21176) (xy 9.498634 -29.269653) (xy 9.475698 -29.325026)
			(xy 9.445731 -29.376932) (xy 9.409244 -29.424482) (xy 9.366864 -29.466862) (xy 9.319314 -29.503349)
			(xy 9.267408 -29.533316) (xy 9.212035 -29.556252) (xy 9.154142 -29.571765) (xy 9.09472 -29.579588)
			(xy 9.034784 -29.579588) (xy 8.975362 -29.571765) (xy 8.917469 -29.556252) (xy 8.862096 -29.533316)
			(xy 8.81019 -29.503349) (xy 8.76264 -29.466862) (xy 8.72026 -29.424482) (xy 8.683773 -29.376932)
			(xy 8.653806 -29.325026) (xy 8.63087 -29.269653) (xy 8.615357 -29.21176) (xy 8.607534 -29.152338)
			(xy 8.607044 -29.12237) (xy 1.524 -29.12237) (xy 1.524 -30.922468) (xy 6.752844 -30.922468) (xy 6.752844 -30.058868)
			(xy 6.753334 -30.0289) (xy 6.761157 -29.969478) (xy 6.77667 -29.911585) (xy 6.799606 -29.856212)
			(xy 6.829573 -29.804306) (xy 6.86606 -29.756756) (xy 6.90844 -29.714376) (xy 6.95599 -29.677889)
			(xy 7.007896 -29.647922) (xy 7.063269 -29.624986) (xy 7.121162 -29.609473) (xy 7.180584 -29.60165)
			(xy 7.24052 -29.60165) (xy 7.299942 -29.609473) (xy 7.357835 -29.624986) (xy 7.413208 -29.647922)
			(xy 7.465114 -29.677889) (xy 7.512664 -29.714376) (xy 7.555044 -29.756756) (xy 7.591531 -29.804306)
			(xy 7.621498 -29.856212) (xy 7.644434 -29.911585) (xy 7.659947 -29.969478) (xy 7.66777 -30.0289)
			(xy 7.66826 -30.058868) (xy 7.66826 -30.92069) (xy 21.489416 -30.92069) (xy 21.489416 -30.05709)
			(xy 21.489906 -30.027106) (xy 21.497734 -29.96765) (xy 21.513255 -29.909725) (xy 21.536204 -29.854321)
			(xy 21.566188 -29.802387) (xy 21.602694 -29.754811) (xy 21.645099 -29.712406) (xy 21.692675 -29.6759)
			(xy 21.744609 -29.645916) (xy 21.800013 -29.622967) (xy 21.857938 -29.607446) (xy 21.917394 -29.599618)
			(xy 21.977362 -29.599618) (xy 22.036818 -29.607446) (xy 22.094743 -29.622967) (xy 22.150147 -29.645916)
			(xy 22.202081 -29.6759) (xy 22.249657 -29.712406) (xy 22.292062 -29.754811) (xy 22.328568 -29.802387)
			(xy 22.358552 -29.854321) (xy 22.381501 -29.909725) (xy 22.397022 -29.96765) (xy 22.40485 -30.027106)
			(xy 22.40534 -30.05709) (xy 22.40534 -30.92069) (xy 22.405311 -30.922468) (xy 32.752792 -30.922468)
			(xy 32.752792 -30.058868) (xy 32.753282 -30.0289) (xy 32.761105 -29.969478) (xy 32.776618 -29.911585)
			(xy 32.799554 -29.856212) (xy 32.829521 -29.804306) (xy 32.866008 -29.756756) (xy 32.908388 -29.714376)
			(xy 32.955938 -29.677889) (xy 33.007844 -29.647922) (xy 33.063217 -29.624986) (xy 33.12111 -29.609473)
			(xy 33.180532 -29.60165) (xy 33.240468 -29.60165) (xy 33.29989 -29.609473) (xy 33.357783 -29.624986)
			(xy 33.413156 -29.647922) (xy 33.465062 -29.677889) (xy 33.512612 -29.714376) (xy 33.554992 -29.756756)
			(xy 33.591479 -29.804306) (xy 33.621446 -29.856212) (xy 33.644382 -29.911585) (xy 33.659895 -29.969478)
			(xy 33.667718 -30.0289) (xy 33.668208 -30.058868) (xy 33.668208 -30.92069) (xy 47.489364 -30.92069)
			(xy 47.489364 -30.05709) (xy 47.489854 -30.027106) (xy 47.497682 -29.96765) (xy 47.513203 -29.909725)
			(xy 47.536152 -29.854321) (xy 47.566136 -29.802387) (xy 47.602642 -29.754811) (xy 47.645047 -29.712406)
			(xy 47.692623 -29.6759) (xy 47.744557 -29.645916) (xy 47.799961 -29.622967) (xy 47.857886 -29.607446)
			(xy 47.917342 -29.599618) (xy 47.97731 -29.599618) (xy 48.036766 -29.607446) (xy 48.094691 -29.622967)
			(xy 48.150095 -29.645916) (xy 48.202029 -29.6759) (xy 48.249605 -29.712406) (xy 48.29201 -29.754811)
			(xy 48.328516 -29.802387) (xy 48.3585 -29.854321) (xy 48.381449 -29.909725) (xy 48.39697 -29.96765)
			(xy 48.404798 -30.027106) (xy 48.405288 -30.05709) (xy 48.405288 -30.92069) (xy 48.405259 -30.922468)
			(xy 58.75274 -30.922468) (xy 58.75274 -30.058868) (xy 58.75323 -30.0289) (xy 58.761053 -29.969478)
			(xy 58.776566 -29.911585) (xy 58.799502 -29.856212) (xy 58.829469 -29.804306) (xy 58.865956 -29.756756)
			(xy 58.908336 -29.714376) (xy 58.955886 -29.677889) (xy 59.007792 -29.647922) (xy 59.063165 -29.624986)
			(xy 59.121058 -29.609473) (xy 59.18048 -29.60165) (xy 59.240416 -29.60165) (xy 59.299838 -29.609473)
			(xy 59.357731 -29.624986) (xy 59.413104 -29.647922) (xy 59.46501 -29.677889) (xy 59.51256 -29.714376)
			(xy 59.55494 -29.756756) (xy 59.591427 -29.804306) (xy 59.621394 -29.856212) (xy 59.64433 -29.911585)
			(xy 59.659843 -29.969478) (xy 59.667666 -30.0289) (xy 59.668156 -30.058868) (xy 59.668156 -30.92069)
			(xy 73.489312 -30.92069) (xy 73.489312 -30.05709) (xy 73.489802 -30.027106) (xy 73.49763 -29.96765)
			(xy 73.513151 -29.909725) (xy 73.5361 -29.854321) (xy 73.566084 -29.802387) (xy 73.60259 -29.754811)
			(xy 73.644995 -29.712406) (xy 73.692571 -29.6759) (xy 73.744505 -29.645916) (xy 73.799909 -29.622967)
			(xy 73.857834 -29.607446) (xy 73.91729 -29.599618) (xy 73.977258 -29.599618) (xy 74.036714 -29.607446)
			(xy 74.094639 -29.622967) (xy 74.150043 -29.645916) (xy 74.201977 -29.6759) (xy 74.249553 -29.712406)
			(xy 74.291958 -29.754811) (xy 74.328464 -29.802387) (xy 74.358448 -29.854321) (xy 74.381397 -29.909725)
			(xy 74.396918 -29.96765) (xy 74.404746 -30.027106) (xy 74.405236 -30.05709) (xy 74.405236 -30.92069)
			(xy 74.405207 -30.922468) (xy 84.752688 -30.922468) (xy 84.752688 -30.058868) (xy 84.753178 -30.0289)
			(xy 84.761001 -29.969478) (xy 84.776514 -29.911585) (xy 84.79945 -29.856212) (xy 84.829417 -29.804306)
			(xy 84.865904 -29.756756) (xy 84.908284 -29.714376) (xy 84.955834 -29.677889) (xy 85.00774 -29.647922)
			(xy 85.063113 -29.624986) (xy 85.121006 -29.609473) (xy 85.180428 -29.60165) (xy 85.240364 -29.60165)
			(xy 85.299786 -29.609473) (xy 85.357679 -29.624986) (xy 85.413052 -29.647922) (xy 85.464958 -29.677889)
			(xy 85.512508 -29.714376) (xy 85.554888 -29.756756) (xy 85.591375 -29.804306) (xy 85.621342 -29.856212)
			(xy 85.644278 -29.911585) (xy 85.659791 -29.969478) (xy 85.667614 -30.0289) (xy 85.668104 -30.058868)
			(xy 85.668104 -30.92069) (xy 99.48926 -30.92069) (xy 99.48926 -30.05709) (xy 99.48975 -30.027106)
			(xy 99.497578 -29.96765) (xy 99.513099 -29.909725) (xy 99.536048 -29.854321) (xy 99.566032 -29.802387)
			(xy 99.602538 -29.754811) (xy 99.644943 -29.712406) (xy 99.692519 -29.6759) (xy 99.744453 -29.645916)
			(xy 99.799857 -29.622967) (xy 99.857782 -29.607446) (xy 99.917238 -29.599618) (xy 99.977206 -29.599618)
			(xy 100.036662 -29.607446) (xy 100.094587 -29.622967) (xy 100.149991 -29.645916) (xy 100.201925 -29.6759)
			(xy 100.249501 -29.712406) (xy 100.291906 -29.754811) (xy 100.328412 -29.802387) (xy 100.358396 -29.854321)
			(xy 100.381345 -29.909725) (xy 100.396866 -29.96765) (xy 100.404694 -30.027106) (xy 100.405184 -30.05709)
			(xy 100.405184 -30.92069) (xy 100.405155 -30.922468) (xy 122.852688 -30.922468) (xy 122.852688 -30.058868)
			(xy 122.853178 -30.028884) (xy 122.861006 -29.969428) (xy 122.876527 -29.911503) (xy 122.899476 -29.856099)
			(xy 122.92946 -29.804165) (xy 122.965966 -29.756589) (xy 123.008371 -29.714184) (xy 123.055947 -29.677678)
			(xy 123.107881 -29.647694) (xy 123.163285 -29.624745) (xy 123.22121 -29.609224) (xy 123.280666 -29.601396)
			(xy 123.340634 -29.601396) (xy 123.40009 -29.609224) (xy 123.458015 -29.624745) (xy 123.513419 -29.647694)
			(xy 123.565353 -29.677678) (xy 123.612929 -29.714184) (xy 123.655334 -29.756589) (xy 123.69184 -29.804165)
			(xy 123.721824 -29.856099) (xy 123.744773 -29.911503) (xy 123.760294 -29.969428) (xy 123.768122 -30.028884)
			(xy 123.768612 -30.058868) (xy 123.768612 -30.92069) (xy 137.589768 -30.92069) (xy 137.589768 -30.05709)
			(xy 137.590258 -30.027122) (xy 137.598081 -29.9677) (xy 137.613594 -29.909807) (xy 137.63653 -29.854434)
			(xy 137.666497 -29.802528) (xy 137.702984 -29.754978) (xy 137.745364 -29.712598) (xy 137.792914 -29.676111)
			(xy 137.84482 -29.646144) (xy 137.900193 -29.623208) (xy 137.958086 -29.607695) (xy 138.017508 -29.599872)
			(xy 138.077444 -29.599872) (xy 138.136866 -29.607695) (xy 138.194759 -29.623208) (xy 138.250132 -29.646144)
			(xy 138.302038 -29.676111) (xy 138.349588 -29.712598) (xy 138.391968 -29.754978) (xy 138.428455 -29.802528)
			(xy 138.458422 -29.854434) (xy 138.481358 -29.909807) (xy 138.496871 -29.9677) (xy 138.504694 -30.027122)
			(xy 138.505184 -30.05709) (xy 138.505184 -30.92069) (xy 138.505155 -30.922468) (xy 148.852636 -30.922468)
			(xy 148.852636 -30.058868) (xy 148.853126 -30.028884) (xy 148.860954 -29.969428) (xy 148.876475 -29.911503)
			(xy 148.899424 -29.856099) (xy 148.929408 -29.804165) (xy 148.965914 -29.756589) (xy 149.008319 -29.714184)
			(xy 149.055895 -29.677678) (xy 149.107829 -29.647694) (xy 149.163233 -29.624745) (xy 149.221158 -29.609224)
			(xy 149.280614 -29.601396) (xy 149.340582 -29.601396) (xy 149.400038 -29.609224) (xy 149.457963 -29.624745)
			(xy 149.513367 -29.647694) (xy 149.565301 -29.677678) (xy 149.612877 -29.714184) (xy 149.655282 -29.756589)
			(xy 149.691788 -29.804165) (xy 149.721772 -29.856099) (xy 149.744721 -29.911503) (xy 149.760242 -29.969428)
			(xy 149.76807 -30.028884) (xy 149.76856 -30.058868) (xy 149.76856 -30.92069) (xy 163.589716 -30.92069)
			(xy 163.589716 -30.05709) (xy 163.590206 -30.027122) (xy 163.598029 -29.9677) (xy 163.613542 -29.909807)
			(xy 163.636478 -29.854434) (xy 163.666445 -29.802528) (xy 163.702932 -29.754978) (xy 163.745312 -29.712598)
			(xy 163.792862 -29.676111) (xy 163.844768 -29.646144) (xy 163.900141 -29.623208) (xy 163.958034 -29.607695)
			(xy 164.017456 -29.599872) (xy 164.077392 -29.599872) (xy 164.136814 -29.607695) (xy 164.194707 -29.623208)
			(xy 164.25008 -29.646144) (xy 164.301986 -29.676111) (xy 164.349536 -29.712598) (xy 164.391916 -29.754978)
			(xy 164.428403 -29.802528) (xy 164.45837 -29.854434) (xy 164.481306 -29.909807) (xy 164.496819 -29.9677)
			(xy 164.504642 -30.027122) (xy 164.505132 -30.05709) (xy 164.505132 -30.92069) (xy 164.505103 -30.922468)
			(xy 174.852584 -30.922468) (xy 174.852584 -30.058868) (xy 174.853074 -30.028884) (xy 174.860902 -29.969428)
			(xy 174.876423 -29.911503) (xy 174.899372 -29.856099) (xy 174.929356 -29.804165) (xy 174.965862 -29.756589)
			(xy 175.008267 -29.714184) (xy 175.055843 -29.677678) (xy 175.107777 -29.647694) (xy 175.163181 -29.624745)
			(xy 175.221106 -29.609224) (xy 175.280562 -29.601396) (xy 175.34053 -29.601396) (xy 175.399986 -29.609224)
			(xy 175.457911 -29.624745) (xy 175.513315 -29.647694) (xy 175.565249 -29.677678) (xy 175.612825 -29.714184)
			(xy 175.65523 -29.756589) (xy 175.691736 -29.804165) (xy 175.72172 -29.856099) (xy 175.744669 -29.911503)
			(xy 175.76019 -29.969428) (xy 175.768018 -30.028884) (xy 175.768508 -30.058868) (xy 175.768508 -30.92069)
			(xy 189.589664 -30.92069) (xy 189.589664 -30.05709) (xy 189.590154 -30.027122) (xy 189.597977 -29.9677)
			(xy 189.61349 -29.909807) (xy 189.636426 -29.854434) (xy 189.666393 -29.802528) (xy 189.70288 -29.754978)
			(xy 189.74526 -29.712598) (xy 189.79281 -29.676111) (xy 189.844716 -29.646144) (xy 189.900089 -29.623208)
			(xy 189.957982 -29.607695) (xy 190.017404 -29.599872) (xy 190.07734 -29.599872) (xy 190.136762 -29.607695)
			(xy 190.194655 -29.623208) (xy 190.250028 -29.646144) (xy 190.301934 -29.676111) (xy 190.349484 -29.712598)
			(xy 190.391864 -29.754978) (xy 190.428351 -29.802528) (xy 190.458318 -29.854434) (xy 190.481254 -29.909807)
			(xy 190.496767 -29.9677) (xy 190.50459 -30.027122) (xy 190.50508 -30.05709) (xy 190.50508 -30.92069)
			(xy 190.505051 -30.922468) (xy 200.852532 -30.922468) (xy 200.852532 -30.058868) (xy 200.853022 -30.028884)
			(xy 200.86085 -29.969428) (xy 200.876371 -29.911503) (xy 200.89932 -29.856099) (xy 200.929304 -29.804165)
			(xy 200.96581 -29.756589) (xy 201.008215 -29.714184) (xy 201.055791 -29.677678) (xy 201.107725 -29.647694)
			(xy 201.163129 -29.624745) (xy 201.221054 -29.609224) (xy 201.28051 -29.601396) (xy 201.340478 -29.601396)
			(xy 201.399934 -29.609224) (xy 201.457859 -29.624745) (xy 201.513263 -29.647694) (xy 201.565197 -29.677678)
			(xy 201.612773 -29.714184) (xy 201.655178 -29.756589) (xy 201.691684 -29.804165) (xy 201.721668 -29.856099)
			(xy 201.744617 -29.911503) (xy 201.760138 -29.969428) (xy 201.767966 -30.028884) (xy 201.768456 -30.058868)
			(xy 201.768456 -30.92069) (xy 215.589612 -30.92069) (xy 215.589612 -30.05709) (xy 215.590102 -30.027122)
			(xy 215.597925 -29.9677) (xy 215.613438 -29.909807) (xy 215.636374 -29.854434) (xy 215.666341 -29.802528)
			(xy 215.702828 -29.754978) (xy 215.745208 -29.712598) (xy 215.792758 -29.676111) (xy 215.844664 -29.646144)
			(xy 215.900037 -29.623208) (xy 215.95793 -29.607695) (xy 216.017352 -29.599872) (xy 216.077288 -29.599872)
			(xy 216.13671 -29.607695) (xy 216.194603 -29.623208) (xy 216.249976 -29.646144) (xy 216.301882 -29.676111)
			(xy 216.349432 -29.712598) (xy 216.391812 -29.754978) (xy 216.428299 -29.802528) (xy 216.458266 -29.854434)
			(xy 216.481202 -29.909807) (xy 216.496715 -29.9677) (xy 216.504538 -30.027122) (xy 216.505028 -30.05709)
			(xy 216.505028 -30.92069) (xy 216.504999 -30.922468) (xy 238.952532 -30.922468) (xy 238.952532 -30.058868)
			(xy 238.953022 -30.028884) (xy 238.96085 -29.969428) (xy 238.976371 -29.911503) (xy 238.99932 -29.856099)
			(xy 239.029304 -29.804165) (xy 239.06581 -29.756589) (xy 239.108215 -29.714184) (xy 239.155791 -29.677678)
			(xy 239.207725 -29.647694) (xy 239.263129 -29.624745) (xy 239.321054 -29.609224) (xy 239.38051 -29.601396)
			(xy 239.440478 -29.601396) (xy 239.499934 -29.609224) (xy 239.557859 -29.624745) (xy 239.613263 -29.647694)
			(xy 239.665197 -29.677678) (xy 239.712773 -29.714184) (xy 239.755178 -29.756589) (xy 239.791684 -29.804165)
			(xy 239.821668 -29.856099) (xy 239.844617 -29.911503) (xy 239.860138 -29.969428) (xy 239.867966 -30.028884)
			(xy 239.868456 -30.058868) (xy 239.868456 -30.92069) (xy 253.689612 -30.92069) (xy 253.689612 -30.05709)
			(xy 253.690102 -30.027122) (xy 253.697925 -29.9677) (xy 253.713438 -29.909807) (xy 253.736374 -29.854434)
			(xy 253.766341 -29.802528) (xy 253.802828 -29.754978) (xy 253.845208 -29.712598) (xy 253.892758 -29.676111)
			(xy 253.944664 -29.646144) (xy 254.000037 -29.623208) (xy 254.05793 -29.607695) (xy 254.117352 -29.599872)
			(xy 254.177288 -29.599872) (xy 254.23671 -29.607695) (xy 254.294603 -29.623208) (xy 254.349976 -29.646144)
			(xy 254.401882 -29.676111) (xy 254.449432 -29.712598) (xy 254.491812 -29.754978) (xy 254.528299 -29.802528)
			(xy 254.558266 -29.854434) (xy 254.581202 -29.909807) (xy 254.596715 -29.9677) (xy 254.604538 -30.027122)
			(xy 254.605028 -30.05709) (xy 254.605028 -30.92069) (xy 254.604999 -30.922468) (xy 264.95248 -30.922468)
			(xy 264.95248 -30.058868) (xy 264.95297 -30.028884) (xy 264.960798 -29.969428) (xy 264.976319 -29.911503)
			(xy 264.999268 -29.856099) (xy 265.029252 -29.804165) (xy 265.065758 -29.756589) (xy 265.108163 -29.714184)
			(xy 265.155739 -29.677678) (xy 265.207673 -29.647694) (xy 265.263077 -29.624745) (xy 265.321002 -29.609224)
			(xy 265.380458 -29.601396) (xy 265.440426 -29.601396) (xy 265.499882 -29.609224) (xy 265.557807 -29.624745)
			(xy 265.613211 -29.647694) (xy 265.665145 -29.677678) (xy 265.712721 -29.714184) (xy 265.755126 -29.756589)
			(xy 265.791632 -29.804165) (xy 265.821616 -29.856099) (xy 265.844565 -29.911503) (xy 265.860086 -29.969428)
			(xy 265.867914 -30.028884) (xy 265.868404 -30.058868) (xy 265.868404 -30.92069) (xy 279.68956 -30.92069)
			(xy 279.68956 -30.05709) (xy 279.69005 -30.027122) (xy 279.697873 -29.9677) (xy 279.713386 -29.909807)
			(xy 279.736322 -29.854434) (xy 279.766289 -29.802528) (xy 279.802776 -29.754978) (xy 279.845156 -29.712598)
			(xy 279.892706 -29.676111) (xy 279.944612 -29.646144) (xy 279.999985 -29.623208) (xy 280.057878 -29.607695)
			(xy 280.1173 -29.599872) (xy 280.177236 -29.599872) (xy 280.236658 -29.607695) (xy 280.294551 -29.623208)
			(xy 280.349924 -29.646144) (xy 280.40183 -29.676111) (xy 280.44938 -29.712598) (xy 280.49176 -29.754978)
			(xy 280.528247 -29.802528) (xy 280.558214 -29.854434) (xy 280.58115 -29.909807) (xy 280.596663 -29.9677)
			(xy 280.604486 -30.027122) (xy 280.604976 -30.05709) (xy 280.604976 -30.92069) (xy 280.604947 -30.922468)
			(xy 290.952428 -30.922468) (xy 290.952428 -30.058868) (xy 290.952918 -30.028884) (xy 290.960746 -29.969428)
			(xy 290.976267 -29.911503) (xy 290.999216 -29.856099) (xy 291.0292 -29.804165) (xy 291.065706 -29.756589)
			(xy 291.108111 -29.714184) (xy 291.155687 -29.677678) (xy 291.207621 -29.647694) (xy 291.263025 -29.624745)
			(xy 291.32095 -29.609224) (xy 291.380406 -29.601396) (xy 291.440374 -29.601396) (xy 291.49983 -29.609224)
			(xy 291.557755 -29.624745) (xy 291.613159 -29.647694) (xy 291.665093 -29.677678) (xy 291.712669 -29.714184)
			(xy 291.755074 -29.756589) (xy 291.79158 -29.804165) (xy 291.821564 -29.856099) (xy 291.844513 -29.911503)
			(xy 291.860034 -29.969428) (xy 291.867862 -30.028884) (xy 291.868352 -30.058868) (xy 291.868352 -30.92069)
			(xy 305.689508 -30.92069) (xy 305.689508 -30.05709) (xy 305.689998 -30.027122) (xy 305.697821 -29.9677)
			(xy 305.713334 -29.909807) (xy 305.73627 -29.854434) (xy 305.766237 -29.802528) (xy 305.802724 -29.754978)
			(xy 305.845104 -29.712598) (xy 305.892654 -29.676111) (xy 305.94456 -29.646144) (xy 305.999933 -29.623208)
			(xy 306.057826 -29.607695) (xy 306.117248 -29.599872) (xy 306.177184 -29.599872) (xy 306.236606 -29.607695)
			(xy 306.294499 -29.623208) (xy 306.349872 -29.646144) (xy 306.401778 -29.676111) (xy 306.449328 -29.712598)
			(xy 306.491708 -29.754978) (xy 306.528195 -29.802528) (xy 306.558162 -29.854434) (xy 306.581098 -29.909807)
			(xy 306.596611 -29.9677) (xy 306.604434 -30.027122) (xy 306.604924 -30.05709) (xy 306.604924 -30.92069)
			(xy 306.604895 -30.922468) (xy 316.952376 -30.922468) (xy 316.952376 -30.058868) (xy 316.952866 -30.028884)
			(xy 316.960694 -29.969428) (xy 316.976215 -29.911503) (xy 316.999164 -29.856099) (xy 317.029148 -29.804165)
			(xy 317.065654 -29.756589) (xy 317.108059 -29.714184) (xy 317.155635 -29.677678) (xy 317.207569 -29.647694)
			(xy 317.262973 -29.624745) (xy 317.320898 -29.609224) (xy 317.380354 -29.601396) (xy 317.440322 -29.601396)
			(xy 317.499778 -29.609224) (xy 317.557703 -29.624745) (xy 317.613107 -29.647694) (xy 317.665041 -29.677678)
			(xy 317.712617 -29.714184) (xy 317.755022 -29.756589) (xy 317.791528 -29.804165) (xy 317.821512 -29.856099)
			(xy 317.844461 -29.911503) (xy 317.859982 -29.969428) (xy 317.86781 -30.028884) (xy 317.8683 -30.058868)
			(xy 317.8683 -30.92069) (xy 331.689456 -30.92069) (xy 331.689456 -30.05709) (xy 331.689946 -30.027122)
			(xy 331.697769 -29.9677) (xy 331.713282 -29.909807) (xy 331.736218 -29.854434) (xy 331.766185 -29.802528)
			(xy 331.802672 -29.754978) (xy 331.845052 -29.712598) (xy 331.892602 -29.676111) (xy 331.944508 -29.646144)
			(xy 331.999881 -29.623208) (xy 332.057774 -29.607695) (xy 332.117196 -29.599872) (xy 332.177132 -29.599872)
			(xy 332.236554 -29.607695) (xy 332.294447 -29.623208) (xy 332.34982 -29.646144) (xy 332.401726 -29.676111)
			(xy 332.449276 -29.712598) (xy 332.491656 -29.754978) (xy 332.528143 -29.802528) (xy 332.55811 -29.854434)
			(xy 332.581046 -29.909807) (xy 332.596559 -29.9677) (xy 332.604382 -30.027122) (xy 332.604872 -30.05709)
			(xy 332.604872 -30.92069) (xy 332.604843 -30.922468) (xy 355.052884 -30.922468) (xy 355.052884 -30.058868)
			(xy 355.053374 -30.0289) (xy 355.061197 -29.969478) (xy 355.07671 -29.911585) (xy 355.099646 -29.856212)
			(xy 355.129613 -29.804306) (xy 355.1661 -29.756756) (xy 355.20848 -29.714376) (xy 355.25603 -29.677889)
			(xy 355.307936 -29.647922) (xy 355.363309 -29.624986) (xy 355.421202 -29.609473) (xy 355.480624 -29.60165)
			(xy 355.54056 -29.60165) (xy 355.599982 -29.609473) (xy 355.657875 -29.624986) (xy 355.713248 -29.647922)
			(xy 355.765154 -29.677889) (xy 355.812704 -29.714376) (xy 355.855084 -29.756756) (xy 355.891571 -29.804306)
			(xy 355.921538 -29.856212) (xy 355.944474 -29.911585) (xy 355.959987 -29.969478) (xy 355.96781 -30.0289)
			(xy 355.9683 -30.058868) (xy 355.9683 -30.92069) (xy 369.789456 -30.92069) (xy 369.789456 -30.05709)
			(xy 369.789946 -30.027106) (xy 369.797774 -29.96765) (xy 369.813295 -29.909725) (xy 369.836244 -29.854321)
			(xy 369.866228 -29.802387) (xy 369.902734 -29.754811) (xy 369.945139 -29.712406) (xy 369.992715 -29.6759)
			(xy 370.044649 -29.645916) (xy 370.100053 -29.622967) (xy 370.157978 -29.607446) (xy 370.217434 -29.599618)
			(xy 370.277402 -29.599618) (xy 370.336858 -29.607446) (xy 370.394783 -29.622967) (xy 370.450187 -29.645916)
			(xy 370.502121 -29.6759) (xy 370.549697 -29.712406) (xy 370.592102 -29.754811) (xy 370.628608 -29.802387)
			(xy 370.658592 -29.854321) (xy 370.681541 -29.909725) (xy 370.697062 -29.96765) (xy 370.70489 -30.027106)
			(xy 370.70538 -30.05709) (xy 370.70538 -30.92069) (xy 370.705351 -30.922468) (xy 381.052832 -30.922468)
			(xy 381.052832 -30.058868) (xy 381.053322 -30.0289) (xy 381.061145 -29.969478) (xy 381.076658 -29.911585)
			(xy 381.099594 -29.856212) (xy 381.129561 -29.804306) (xy 381.166048 -29.756756) (xy 381.208428 -29.714376)
			(xy 381.255978 -29.677889) (xy 381.307884 -29.647922) (xy 381.363257 -29.624986) (xy 381.42115 -29.609473)
			(xy 381.480572 -29.60165) (xy 381.540508 -29.60165) (xy 381.59993 -29.609473) (xy 381.657823 -29.624986)
			(xy 381.713196 -29.647922) (xy 381.765102 -29.677889) (xy 381.812652 -29.714376) (xy 381.855032 -29.756756)
			(xy 381.891519 -29.804306) (xy 381.921486 -29.856212) (xy 381.944422 -29.911585) (xy 381.959935 -29.969478)
			(xy 381.967758 -30.0289) (xy 381.968248 -30.058868) (xy 381.968248 -30.92069) (xy 395.789404 -30.92069)
			(xy 395.789404 -30.05709) (xy 395.789894 -30.027106) (xy 395.797722 -29.96765) (xy 395.813243 -29.909725)
			(xy 395.836192 -29.854321) (xy 395.866176 -29.802387) (xy 395.902682 -29.754811) (xy 395.945087 -29.712406)
			(xy 395.992663 -29.6759) (xy 396.044597 -29.645916) (xy 396.100001 -29.622967) (xy 396.157926 -29.607446)
			(xy 396.217382 -29.599618) (xy 396.27735 -29.599618) (xy 396.336806 -29.607446) (xy 396.394731 -29.622967)
			(xy 396.450135 -29.645916) (xy 396.502069 -29.6759) (xy 396.549645 -29.712406) (xy 396.59205 -29.754811)
			(xy 396.628556 -29.802387) (xy 396.65854 -29.854321) (xy 396.681489 -29.909725) (xy 396.69701 -29.96765)
			(xy 396.704838 -30.027106) (xy 396.705328 -30.05709) (xy 396.705328 -30.92069) (xy 396.705299 -30.922468)
			(xy 407.05278 -30.922468) (xy 407.05278 -30.058868) (xy 407.05327 -30.0289) (xy 407.061093 -29.969478)
			(xy 407.076606 -29.911585) (xy 407.099542 -29.856212) (xy 407.129509 -29.804306) (xy 407.165996 -29.756756)
			(xy 407.208376 -29.714376) (xy 407.255926 -29.677889) (xy 407.307832 -29.647922) (xy 407.363205 -29.624986)
			(xy 407.421098 -29.609473) (xy 407.48052 -29.60165) (xy 407.540456 -29.60165) (xy 407.599878 -29.609473)
			(xy 407.657771 -29.624986) (xy 407.713144 -29.647922) (xy 407.76505 -29.677889) (xy 407.8126 -29.714376)
			(xy 407.85498 -29.756756) (xy 407.891467 -29.804306) (xy 407.921434 -29.856212) (xy 407.94437 -29.911585)
			(xy 407.959883 -29.969478) (xy 407.967706 -30.0289) (xy 407.968196 -30.058868) (xy 407.968196 -30.92069)
			(xy 421.789352 -30.92069) (xy 421.789352 -30.05709) (xy 421.789842 -30.027106) (xy 421.79767 -29.96765)
			(xy 421.813191 -29.909725) (xy 421.83614 -29.854321) (xy 421.866124 -29.802387) (xy 421.90263 -29.754811)
			(xy 421.945035 -29.712406) (xy 421.992611 -29.6759) (xy 422.044545 -29.645916) (xy 422.099949 -29.622967)
			(xy 422.157874 -29.607446) (xy 422.21733 -29.599618) (xy 422.277298 -29.599618) (xy 422.336754 -29.607446)
			(xy 422.394679 -29.622967) (xy 422.450083 -29.645916) (xy 422.502017 -29.6759) (xy 422.549593 -29.712406)
			(xy 422.591998 -29.754811) (xy 422.628504 -29.802387) (xy 422.658488 -29.854321) (xy 422.681437 -29.909725)
			(xy 422.696958 -29.96765) (xy 422.704786 -30.027106) (xy 422.705276 -30.05709) (xy 422.705276 -30.92069)
			(xy 422.705247 -30.922468) (xy 433.052728 -30.922468) (xy 433.052728 -30.058868) (xy 433.053218 -30.0289)
			(xy 433.061041 -29.969478) (xy 433.076554 -29.911585) (xy 433.09949 -29.856212) (xy 433.129457 -29.804306)
			(xy 433.165944 -29.756756) (xy 433.208324 -29.714376) (xy 433.255874 -29.677889) (xy 433.30778 -29.647922)
			(xy 433.363153 -29.624986) (xy 433.421046 -29.609473) (xy 433.480468 -29.60165) (xy 433.540404 -29.60165)
			(xy 433.599826 -29.609473) (xy 433.657719 -29.624986) (xy 433.713092 -29.647922) (xy 433.764998 -29.677889)
			(xy 433.812548 -29.714376) (xy 433.854928 -29.756756) (xy 433.891415 -29.804306) (xy 433.921382 -29.856212)
			(xy 433.944318 -29.911585) (xy 433.959831 -29.969478) (xy 433.967654 -30.0289) (xy 433.968144 -30.058868)
			(xy 433.968144 -30.92069) (xy 447.7893 -30.92069) (xy 447.7893 -30.05709) (xy 447.78979 -30.027106)
			(xy 447.797618 -29.96765) (xy 447.813139 -29.909725) (xy 447.836088 -29.854321) (xy 447.866072 -29.802387)
			(xy 447.902578 -29.754811) (xy 447.944983 -29.712406) (xy 447.992559 -29.6759) (xy 448.044493 -29.645916)
			(xy 448.099897 -29.622967) (xy 448.157822 -29.607446) (xy 448.217278 -29.599618) (xy 448.277246 -29.599618)
			(xy 448.336702 -29.607446) (xy 448.394627 -29.622967) (xy 448.450031 -29.645916) (xy 448.501965 -29.6759)
			(xy 448.549541 -29.712406) (xy 448.591946 -29.754811) (xy 448.628452 -29.802387) (xy 448.658436 -29.854321)
			(xy 448.681385 -29.909725) (xy 448.696906 -29.96765) (xy 448.704734 -30.027106) (xy 448.705224 -30.05709)
			(xy 448.705224 -30.745738) (xy 457.614517 -30.745738) (xy 457.614517 -30.616598) (xy 457.622467 -30.487703)
			(xy 457.638337 -30.359543) (xy 457.662066 -30.232602) (xy 457.693565 -30.107363) (xy 457.732714 -29.9843)
			(xy 457.779365 -29.863881) (xy 457.83334 -29.746562) (xy 457.894435 -29.632788) (xy 457.962418 -29.522991)
			(xy 458.037032 -29.417588) (xy 458.117993 -29.316978) (xy 458.204993 -29.221543) (xy 458.297704 -29.131644)
			(xy 458.395774 -29.047623) (xy 458.498829 -28.969799) (xy 458.60648 -28.898467) (xy 458.718319 -28.833897)
			(xy 458.83392 -28.776335) (xy 458.952845 -28.725998) (xy 459.074644 -28.683078) (xy 459.198854 -28.647737)
			(xy 459.325003 -28.62011) (xy 459.452615 -28.600301) (xy 459.581204 -28.588385) (xy 459.710282 -28.584409)
			(xy 459.83936 -28.588385) (xy 459.967949 -28.600301) (xy 460.095561 -28.62011) (xy 460.22171 -28.647737)
			(xy 460.34592 -28.683078) (xy 460.467719 -28.725998) (xy 460.586644 -28.776335) (xy 460.702245 -28.833897)
			(xy 460.814084 -28.898467) (xy 460.921735 -28.969799) (xy 461.02479 -29.047623) (xy 461.12286 -29.131644)
			(xy 461.215571 -29.221543) (xy 461.302571 -29.316978) (xy 461.383532 -29.417588) (xy 461.458146 -29.522991)
			(xy 461.526129 -29.632788) (xy 461.587224 -29.746562) (xy 461.641199 -29.863881) (xy 461.68785 -29.9843)
			(xy 461.726999 -30.107363) (xy 461.758498 -30.232602) (xy 461.782227 -30.359543) (xy 461.798097 -30.487703)
			(xy 461.806047 -30.616598) (xy 461.806544 -30.681168) (xy 461.806047 -30.745738) (xy 461.798097 -30.874633)
			(xy 461.782227 -31.002793) (xy 461.758498 -31.129734) (xy 461.726999 -31.254973) (xy 461.68785 -31.378036)
			(xy 461.641199 -31.498455) (xy 461.587224 -31.615774) (xy 461.526129 -31.729548) (xy 461.458146 -31.839345)
			(xy 461.383532 -31.944748) (xy 461.302571 -32.045358) (xy 461.215571 -32.140793) (xy 461.12286 -32.230692)
			(xy 461.02479 -32.314713) (xy 460.921735 -32.392537) (xy 460.814084 -32.463869) (xy 460.702245 -32.528439)
			(xy 460.586644 -32.586001) (xy 460.467719 -32.636338) (xy 460.34592 -32.679258) (xy 460.22171 -32.714599)
			(xy 460.095561 -32.742226) (xy 459.967949 -32.762035) (xy 459.83936 -32.773951) (xy 459.710282 -32.777928)
			(xy 459.581204 -32.773951) (xy 459.452615 -32.762035) (xy 459.325003 -32.742226) (xy 459.198854 -32.714599)
			(xy 459.074644 -32.679258) (xy 458.952845 -32.636338) (xy 458.83392 -32.586001) (xy 458.718319 -32.528439)
			(xy 458.60648 -32.463869) (xy 458.498829 -32.392537) (xy 458.395774 -32.314713) (xy 458.297704 -32.230692)
			(xy 458.204993 -32.140793) (xy 458.117993 -32.045358) (xy 458.037032 -31.944748) (xy 457.962418 -31.839345)
			(xy 457.894435 -31.729548) (xy 457.83334 -31.615774) (xy 457.779365 -31.498455) (xy 457.732714 -31.378036)
			(xy 457.693565 -31.254973) (xy 457.662066 -31.129734) (xy 457.638337 -31.002793) (xy 457.622467 -30.874633)
			(xy 457.614517 -30.745738) (xy 448.705224 -30.745738) (xy 448.705224 -30.92069) (xy 448.704734 -30.950674)
			(xy 448.696906 -31.01013) (xy 448.681385 -31.068055) (xy 448.658436 -31.123459) (xy 448.628452 -31.175393)
			(xy 448.591946 -31.222969) (xy 448.549541 -31.265374) (xy 448.501965 -31.30188) (xy 448.450031 -31.331864)
			(xy 448.394627 -31.354813) (xy 448.336702 -31.370334) (xy 448.277246 -31.378162) (xy 448.217278 -31.378162)
			(xy 448.157822 -31.370334) (xy 448.099897 -31.354813) (xy 448.044493 -31.331864) (xy 447.992559 -31.30188)
			(xy 447.944983 -31.265374) (xy 447.902578 -31.222969) (xy 447.866072 -31.175393) (xy 447.836088 -31.123459)
			(xy 447.813139 -31.068055) (xy 447.797618 -31.01013) (xy 447.78979 -30.950674) (xy 447.7893 -30.92069)
			(xy 433.968144 -30.92069) (xy 433.968144 -30.922468) (xy 433.967654 -30.952436) (xy 433.959831 -31.011858)
			(xy 433.944318 -31.069751) (xy 433.921382 -31.125124) (xy 433.891415 -31.17703) (xy 433.854928 -31.22458)
			(xy 433.812548 -31.26696) (xy 433.764998 -31.303447) (xy 433.713092 -31.333414) (xy 433.657719 -31.35635)
			(xy 433.599826 -31.371863) (xy 433.540404 -31.379686) (xy 433.480468 -31.379686) (xy 433.421046 -31.371863)
			(xy 433.363153 -31.35635) (xy 433.30778 -31.333414) (xy 433.255874 -31.303447) (xy 433.208324 -31.26696)
			(xy 433.165944 -31.22458) (xy 433.129457 -31.17703) (xy 433.09949 -31.125124) (xy 433.076554 -31.069751)
			(xy 433.061041 -31.011858) (xy 433.053218 -30.952436) (xy 433.052728 -30.922468) (xy 422.705247 -30.922468)
			(xy 422.704786 -30.950674) (xy 422.696958 -31.01013) (xy 422.681437 -31.068055) (xy 422.658488 -31.123459)
			(xy 422.628504 -31.175393) (xy 422.591998 -31.222969) (xy 422.549593 -31.265374) (xy 422.502017 -31.30188)
			(xy 422.450083 -31.331864) (xy 422.394679 -31.354813) (xy 422.336754 -31.370334) (xy 422.277298 -31.378162)
			(xy 422.21733 -31.378162) (xy 422.157874 -31.370334) (xy 422.099949 -31.354813) (xy 422.044545 -31.331864)
			(xy 421.992611 -31.30188) (xy 421.945035 -31.265374) (xy 421.90263 -31.222969) (xy 421.866124 -31.175393)
			(xy 421.83614 -31.123459) (xy 421.813191 -31.068055) (xy 421.79767 -31.01013) (xy 421.789842 -30.950674)
			(xy 421.789352 -30.92069) (xy 407.968196 -30.92069) (xy 407.968196 -30.922468) (xy 407.967706 -30.952436)
			(xy 407.959883 -31.011858) (xy 407.94437 -31.069751) (xy 407.921434 -31.125124) (xy 407.891467 -31.17703)
			(xy 407.85498 -31.22458) (xy 407.8126 -31.26696) (xy 407.76505 -31.303447) (xy 407.713144 -31.333414)
			(xy 407.657771 -31.35635) (xy 407.599878 -31.371863) (xy 407.540456 -31.379686) (xy 407.48052 -31.379686)
			(xy 407.421098 -31.371863) (xy 407.363205 -31.35635) (xy 407.307832 -31.333414) (xy 407.255926 -31.303447)
			(xy 407.208376 -31.26696) (xy 407.165996 -31.22458) (xy 407.129509 -31.17703) (xy 407.099542 -31.125124)
			(xy 407.076606 -31.069751) (xy 407.061093 -31.011858) (xy 407.05327 -30.952436) (xy 407.05278 -30.922468)
			(xy 396.705299 -30.922468) (xy 396.704838 -30.950674) (xy 396.69701 -31.01013) (xy 396.681489 -31.068055)
			(xy 396.65854 -31.123459) (xy 396.628556 -31.175393) (xy 396.59205 -31.222969) (xy 396.549645 -31.265374)
			(xy 396.502069 -31.30188) (xy 396.450135 -31.331864) (xy 396.394731 -31.354813) (xy 396.336806 -31.370334)
			(xy 396.27735 -31.378162) (xy 396.217382 -31.378162) (xy 396.157926 -31.370334) (xy 396.100001 -31.354813)
			(xy 396.044597 -31.331864) (xy 395.992663 -31.30188) (xy 395.945087 -31.265374) (xy 395.902682 -31.222969)
			(xy 395.866176 -31.175393) (xy 395.836192 -31.123459) (xy 395.813243 -31.068055) (xy 395.797722 -31.01013)
			(xy 395.789894 -30.950674) (xy 395.789404 -30.92069) (xy 381.968248 -30.92069) (xy 381.968248 -30.922468)
			(xy 381.967758 -30.952436) (xy 381.959935 -31.011858) (xy 381.944422 -31.069751) (xy 381.921486 -31.125124)
			(xy 381.891519 -31.17703) (xy 381.855032 -31.22458) (xy 381.812652 -31.26696) (xy 381.765102 -31.303447)
			(xy 381.713196 -31.333414) (xy 381.657823 -31.35635) (xy 381.59993 -31.371863) (xy 381.540508 -31.379686)
			(xy 381.480572 -31.379686) (xy 381.42115 -31.371863) (xy 381.363257 -31.35635) (xy 381.307884 -31.333414)
			(xy 381.255978 -31.303447) (xy 381.208428 -31.26696) (xy 381.166048 -31.22458) (xy 381.129561 -31.17703)
			(xy 381.099594 -31.125124) (xy 381.076658 -31.069751) (xy 381.061145 -31.011858) (xy 381.053322 -30.952436)
			(xy 381.052832 -30.922468) (xy 370.705351 -30.922468) (xy 370.70489 -30.950674) (xy 370.697062 -31.01013)
			(xy 370.681541 -31.068055) (xy 370.658592 -31.123459) (xy 370.628608 -31.175393) (xy 370.592102 -31.222969)
			(xy 370.549697 -31.265374) (xy 370.502121 -31.30188) (xy 370.450187 -31.331864) (xy 370.394783 -31.354813)
			(xy 370.336858 -31.370334) (xy 370.277402 -31.378162) (xy 370.217434 -31.378162) (xy 370.157978 -31.370334)
			(xy 370.100053 -31.354813) (xy 370.044649 -31.331864) (xy 369.992715 -31.30188) (xy 369.945139 -31.265374)
			(xy 369.902734 -31.222969) (xy 369.866228 -31.175393) (xy 369.836244 -31.123459) (xy 369.813295 -31.068055)
			(xy 369.797774 -31.01013) (xy 369.789946 -30.950674) (xy 369.789456 -30.92069) (xy 355.9683 -30.92069)
			(xy 355.9683 -30.922468) (xy 355.96781 -30.952436) (xy 355.959987 -31.011858) (xy 355.944474 -31.069751)
			(xy 355.921538 -31.125124) (xy 355.891571 -31.17703) (xy 355.855084 -31.22458) (xy 355.812704 -31.26696)
			(xy 355.765154 -31.303447) (xy 355.713248 -31.333414) (xy 355.657875 -31.35635) (xy 355.599982 -31.371863)
			(xy 355.54056 -31.379686) (xy 355.480624 -31.379686) (xy 355.421202 -31.371863) (xy 355.363309 -31.35635)
			(xy 355.307936 -31.333414) (xy 355.25603 -31.303447) (xy 355.20848 -31.26696) (xy 355.1661 -31.22458)
			(xy 355.129613 -31.17703) (xy 355.099646 -31.125124) (xy 355.07671 -31.069751) (xy 355.061197 -31.011858)
			(xy 355.053374 -30.952436) (xy 355.052884 -30.922468) (xy 332.604843 -30.922468) (xy 332.604382 -30.950658)
			(xy 332.596559 -31.01008) (xy 332.581046 -31.067973) (xy 332.55811 -31.123346) (xy 332.528143 -31.175252)
			(xy 332.491656 -31.222802) (xy 332.449276 -31.265182) (xy 332.401726 -31.301669) (xy 332.34982 -31.331636)
			(xy 332.294447 -31.354572) (xy 332.236554 -31.370085) (xy 332.177132 -31.377908) (xy 332.117196 -31.377908)
			(xy 332.057774 -31.370085) (xy 331.999881 -31.354572) (xy 331.944508 -31.331636) (xy 331.892602 -31.301669)
			(xy 331.845052 -31.265182) (xy 331.802672 -31.222802) (xy 331.766185 -31.175252) (xy 331.736218 -31.123346)
			(xy 331.713282 -31.067973) (xy 331.697769 -31.01008) (xy 331.689946 -30.950658) (xy 331.689456 -30.92069)
			(xy 317.8683 -30.92069) (xy 317.8683 -30.922468) (xy 317.86781 -30.952452) (xy 317.859982 -31.011908)
			(xy 317.844461 -31.069833) (xy 317.821512 -31.125237) (xy 317.791528 -31.177171) (xy 317.755022 -31.224747)
			(xy 317.712617 -31.267152) (xy 317.665041 -31.303658) (xy 317.613107 -31.333642) (xy 317.557703 -31.356591)
			(xy 317.499778 -31.372112) (xy 317.440322 -31.37994) (xy 317.380354 -31.37994) (xy 317.320898 -31.372112)
			(xy 317.262973 -31.356591) (xy 317.207569 -31.333642) (xy 317.155635 -31.303658) (xy 317.108059 -31.267152)
			(xy 317.065654 -31.224747) (xy 317.029148 -31.177171) (xy 316.999164 -31.125237) (xy 316.976215 -31.069833)
			(xy 316.960694 -31.011908) (xy 316.952866 -30.952452) (xy 316.952376 -30.922468) (xy 306.604895 -30.922468)
			(xy 306.604434 -30.950658) (xy 306.596611 -31.01008) (xy 306.581098 -31.067973) (xy 306.558162 -31.123346)
			(xy 306.528195 -31.175252) (xy 306.491708 -31.222802) (xy 306.449328 -31.265182) (xy 306.401778 -31.301669)
			(xy 306.349872 -31.331636) (xy 306.294499 -31.354572) (xy 306.236606 -31.370085) (xy 306.177184 -31.377908)
			(xy 306.117248 -31.377908) (xy 306.057826 -31.370085) (xy 305.999933 -31.354572) (xy 305.94456 -31.331636)
			(xy 305.892654 -31.301669) (xy 305.845104 -31.265182) (xy 305.802724 -31.222802) (xy 305.766237 -31.175252)
			(xy 305.73627 -31.123346) (xy 305.713334 -31.067973) (xy 305.697821 -31.01008) (xy 305.689998 -30.950658)
			(xy 305.689508 -30.92069) (xy 291.868352 -30.92069) (xy 291.868352 -30.922468) (xy 291.867862 -30.952452)
			(xy 291.860034 -31.011908) (xy 291.844513 -31.069833) (xy 291.821564 -31.125237) (xy 291.79158 -31.177171)
			(xy 291.755074 -31.224747) (xy 291.712669 -31.267152) (xy 291.665093 -31.303658) (xy 291.613159 -31.333642)
			(xy 291.557755 -31.356591) (xy 291.49983 -31.372112) (xy 291.440374 -31.37994) (xy 291.380406 -31.37994)
			(xy 291.32095 -31.372112) (xy 291.263025 -31.356591) (xy 291.207621 -31.333642) (xy 291.155687 -31.303658)
			(xy 291.108111 -31.267152) (xy 291.065706 -31.224747) (xy 291.0292 -31.177171) (xy 290.999216 -31.125237)
			(xy 290.976267 -31.069833) (xy 290.960746 -31.011908) (xy 290.952918 -30.952452) (xy 290.952428 -30.922468)
			(xy 280.604947 -30.922468) (xy 280.604486 -30.950658) (xy 280.596663 -31.01008) (xy 280.58115 -31.067973)
			(xy 280.558214 -31.123346) (xy 280.528247 -31.175252) (xy 280.49176 -31.222802) (xy 280.44938 -31.265182)
			(xy 280.40183 -31.301669) (xy 280.349924 -31.331636) (xy 280.294551 -31.354572) (xy 280.236658 -31.370085)
			(xy 280.177236 -31.377908) (xy 280.1173 -31.377908) (xy 280.057878 -31.370085) (xy 279.999985 -31.354572)
			(xy 279.944612 -31.331636) (xy 279.892706 -31.301669) (xy 279.845156 -31.265182) (xy 279.802776 -31.222802)
			(xy 279.766289 -31.175252) (xy 279.736322 -31.123346) (xy 279.713386 -31.067973) (xy 279.697873 -31.01008)
			(xy 279.69005 -30.950658) (xy 279.68956 -30.92069) (xy 265.868404 -30.92069) (xy 265.868404 -30.922468)
			(xy 265.867914 -30.952452) (xy 265.860086 -31.011908) (xy 265.844565 -31.069833) (xy 265.821616 -31.125237)
			(xy 265.791632 -31.177171) (xy 265.755126 -31.224747) (xy 265.712721 -31.267152) (xy 265.665145 -31.303658)
			(xy 265.613211 -31.333642) (xy 265.557807 -31.356591) (xy 265.499882 -31.372112) (xy 265.440426 -31.37994)
			(xy 265.380458 -31.37994) (xy 265.321002 -31.372112) (xy 265.263077 -31.356591) (xy 265.207673 -31.333642)
			(xy 265.155739 -31.303658) (xy 265.108163 -31.267152) (xy 265.065758 -31.224747) (xy 265.029252 -31.177171)
			(xy 264.999268 -31.125237) (xy 264.976319 -31.069833) (xy 264.960798 -31.011908) (xy 264.95297 -30.952452)
			(xy 264.95248 -30.922468) (xy 254.604999 -30.922468) (xy 254.604538 -30.950658) (xy 254.596715 -31.01008)
			(xy 254.581202 -31.067973) (xy 254.558266 -31.123346) (xy 254.528299 -31.175252) (xy 254.491812 -31.222802)
			(xy 254.449432 -31.265182) (xy 254.401882 -31.301669) (xy 254.349976 -31.331636) (xy 254.294603 -31.354572)
			(xy 254.23671 -31.370085) (xy 254.177288 -31.377908) (xy 254.117352 -31.377908) (xy 254.05793 -31.370085)
			(xy 254.000037 -31.354572) (xy 253.944664 -31.331636) (xy 253.892758 -31.301669) (xy 253.845208 -31.265182)
			(xy 253.802828 -31.222802) (xy 253.766341 -31.175252) (xy 253.736374 -31.123346) (xy 253.713438 -31.067973)
			(xy 253.697925 -31.01008) (xy 253.690102 -30.950658) (xy 253.689612 -30.92069) (xy 239.868456 -30.92069)
			(xy 239.868456 -30.922468) (xy 239.867966 -30.952452) (xy 239.860138 -31.011908) (xy 239.844617 -31.069833)
			(xy 239.821668 -31.125237) (xy 239.791684 -31.177171) (xy 239.755178 -31.224747) (xy 239.712773 -31.267152)
			(xy 239.665197 -31.303658) (xy 239.613263 -31.333642) (xy 239.557859 -31.356591) (xy 239.499934 -31.372112)
			(xy 239.440478 -31.37994) (xy 239.38051 -31.37994) (xy 239.321054 -31.372112) (xy 239.263129 -31.356591)
			(xy 239.207725 -31.333642) (xy 239.155791 -31.303658) (xy 239.108215 -31.267152) (xy 239.06581 -31.224747)
			(xy 239.029304 -31.177171) (xy 238.99932 -31.125237) (xy 238.976371 -31.069833) (xy 238.96085 -31.011908)
			(xy 238.953022 -30.952452) (xy 238.952532 -30.922468) (xy 216.504999 -30.922468) (xy 216.504538 -30.950658)
			(xy 216.496715 -31.01008) (xy 216.481202 -31.067973) (xy 216.458266 -31.123346) (xy 216.428299 -31.175252)
			(xy 216.391812 -31.222802) (xy 216.349432 -31.265182) (xy 216.301882 -31.301669) (xy 216.249976 -31.331636)
			(xy 216.194603 -31.354572) (xy 216.13671 -31.370085) (xy 216.077288 -31.377908) (xy 216.017352 -31.377908)
			(xy 215.95793 -31.370085) (xy 215.900037 -31.354572) (xy 215.844664 -31.331636) (xy 215.792758 -31.301669)
			(xy 215.745208 -31.265182) (xy 215.702828 -31.222802) (xy 215.666341 -31.175252) (xy 215.636374 -31.123346)
			(xy 215.613438 -31.067973) (xy 215.597925 -31.01008) (xy 215.590102 -30.950658) (xy 215.589612 -30.92069)
			(xy 201.768456 -30.92069) (xy 201.768456 -30.922468) (xy 201.767966 -30.952452) (xy 201.760138 -31.011908)
			(xy 201.744617 -31.069833) (xy 201.721668 -31.125237) (xy 201.691684 -31.177171) (xy 201.655178 -31.224747)
			(xy 201.612773 -31.267152) (xy 201.565197 -31.303658) (xy 201.513263 -31.333642) (xy 201.457859 -31.356591)
			(xy 201.399934 -31.372112) (xy 201.340478 -31.37994) (xy 201.28051 -31.37994) (xy 201.221054 -31.372112)
			(xy 201.163129 -31.356591) (xy 201.107725 -31.333642) (xy 201.055791 -31.303658) (xy 201.008215 -31.267152)
			(xy 200.96581 -31.224747) (xy 200.929304 -31.177171) (xy 200.89932 -31.125237) (xy 200.876371 -31.069833)
			(xy 200.86085 -31.011908) (xy 200.853022 -30.952452) (xy 200.852532 -30.922468) (xy 190.505051 -30.922468)
			(xy 190.50459 -30.950658) (xy 190.496767 -31.01008) (xy 190.481254 -31.067973) (xy 190.458318 -31.123346)
			(xy 190.428351 -31.175252) (xy 190.391864 -31.222802) (xy 190.349484 -31.265182) (xy 190.301934 -31.301669)
			(xy 190.250028 -31.331636) (xy 190.194655 -31.354572) (xy 190.136762 -31.370085) (xy 190.07734 -31.377908)
			(xy 190.017404 -31.377908) (xy 189.957982 -31.370085) (xy 189.900089 -31.354572) (xy 189.844716 -31.331636)
			(xy 189.79281 -31.301669) (xy 189.74526 -31.265182) (xy 189.70288 -31.222802) (xy 189.666393 -31.175252)
			(xy 189.636426 -31.123346) (xy 189.61349 -31.067973) (xy 189.597977 -31.01008) (xy 189.590154 -30.950658)
			(xy 189.589664 -30.92069) (xy 175.768508 -30.92069) (xy 175.768508 -30.922468) (xy 175.768018 -30.952452)
			(xy 175.76019 -31.011908) (xy 175.744669 -31.069833) (xy 175.72172 -31.125237) (xy 175.691736 -31.177171)
			(xy 175.65523 -31.224747) (xy 175.612825 -31.267152) (xy 175.565249 -31.303658) (xy 175.513315 -31.333642)
			(xy 175.457911 -31.356591) (xy 175.399986 -31.372112) (xy 175.34053 -31.37994) (xy 175.280562 -31.37994)
			(xy 175.221106 -31.372112) (xy 175.163181 -31.356591) (xy 175.107777 -31.333642) (xy 175.055843 -31.303658)
			(xy 175.008267 -31.267152) (xy 174.965862 -31.224747) (xy 174.929356 -31.177171) (xy 174.899372 -31.125237)
			(xy 174.876423 -31.069833) (xy 174.860902 -31.011908) (xy 174.853074 -30.952452) (xy 174.852584 -30.922468)
			(xy 164.505103 -30.922468) (xy 164.504642 -30.950658) (xy 164.496819 -31.01008) (xy 164.481306 -31.067973)
			(xy 164.45837 -31.123346) (xy 164.428403 -31.175252) (xy 164.391916 -31.222802) (xy 164.349536 -31.265182)
			(xy 164.301986 -31.301669) (xy 164.25008 -31.331636) (xy 164.194707 -31.354572) (xy 164.136814 -31.370085)
			(xy 164.077392 -31.377908) (xy 164.017456 -31.377908) (xy 163.958034 -31.370085) (xy 163.900141 -31.354572)
			(xy 163.844768 -31.331636) (xy 163.792862 -31.301669) (xy 163.745312 -31.265182) (xy 163.702932 -31.222802)
			(xy 163.666445 -31.175252) (xy 163.636478 -31.123346) (xy 163.613542 -31.067973) (xy 163.598029 -31.01008)
			(xy 163.590206 -30.950658) (xy 163.589716 -30.92069) (xy 149.76856 -30.92069) (xy 149.76856 -30.922468)
			(xy 149.76807 -30.952452) (xy 149.760242 -31.011908) (xy 149.744721 -31.069833) (xy 149.721772 -31.125237)
			(xy 149.691788 -31.177171) (xy 149.655282 -31.224747) (xy 149.612877 -31.267152) (xy 149.565301 -31.303658)
			(xy 149.513367 -31.333642) (xy 149.457963 -31.356591) (xy 149.400038 -31.372112) (xy 149.340582 -31.37994)
			(xy 149.280614 -31.37994) (xy 149.221158 -31.372112) (xy 149.163233 -31.356591) (xy 149.107829 -31.333642)
			(xy 149.055895 -31.303658) (xy 149.008319 -31.267152) (xy 148.965914 -31.224747) (xy 148.929408 -31.177171)
			(xy 148.899424 -31.125237) (xy 148.876475 -31.069833) (xy 148.860954 -31.011908) (xy 148.853126 -30.952452)
			(xy 148.852636 -30.922468) (xy 138.505155 -30.922468) (xy 138.504694 -30.950658) (xy 138.496871 -31.01008)
			(xy 138.481358 -31.067973) (xy 138.458422 -31.123346) (xy 138.428455 -31.175252) (xy 138.391968 -31.222802)
			(xy 138.349588 -31.265182) (xy 138.302038 -31.301669) (xy 138.250132 -31.331636) (xy 138.194759 -31.354572)
			(xy 138.136866 -31.370085) (xy 138.077444 -31.377908) (xy 138.017508 -31.377908) (xy 137.958086 -31.370085)
			(xy 137.900193 -31.354572) (xy 137.84482 -31.331636) (xy 137.792914 -31.301669) (xy 137.745364 -31.265182)
			(xy 137.702984 -31.222802) (xy 137.666497 -31.175252) (xy 137.63653 -31.123346) (xy 137.613594 -31.067973)
			(xy 137.598081 -31.01008) (xy 137.590258 -30.950658) (xy 137.589768 -30.92069) (xy 123.768612 -30.92069)
			(xy 123.768612 -30.922468) (xy 123.768122 -30.952452) (xy 123.760294 -31.011908) (xy 123.744773 -31.069833)
			(xy 123.721824 -31.125237) (xy 123.69184 -31.177171) (xy 123.655334 -31.224747) (xy 123.612929 -31.267152)
			(xy 123.565353 -31.303658) (xy 123.513419 -31.333642) (xy 123.458015 -31.356591) (xy 123.40009 -31.372112)
			(xy 123.340634 -31.37994) (xy 123.280666 -31.37994) (xy 123.22121 -31.372112) (xy 123.163285 -31.356591)
			(xy 123.107881 -31.333642) (xy 123.055947 -31.303658) (xy 123.008371 -31.267152) (xy 122.965966 -31.224747)
			(xy 122.92946 -31.177171) (xy 122.899476 -31.125237) (xy 122.876527 -31.069833) (xy 122.861006 -31.011908)
			(xy 122.853178 -30.952452) (xy 122.852688 -30.922468) (xy 100.405155 -30.922468) (xy 100.404694 -30.950674)
			(xy 100.396866 -31.01013) (xy 100.381345 -31.068055) (xy 100.358396 -31.123459) (xy 100.328412 -31.175393)
			(xy 100.291906 -31.222969) (xy 100.249501 -31.265374) (xy 100.201925 -31.30188) (xy 100.149991 -31.331864)
			(xy 100.094587 -31.354813) (xy 100.036662 -31.370334) (xy 99.977206 -31.378162) (xy 99.917238 -31.378162)
			(xy 99.857782 -31.370334) (xy 99.799857 -31.354813) (xy 99.744453 -31.331864) (xy 99.692519 -31.30188)
			(xy 99.644943 -31.265374) (xy 99.602538 -31.222969) (xy 99.566032 -31.175393) (xy 99.536048 -31.123459)
			(xy 99.513099 -31.068055) (xy 99.497578 -31.01013) (xy 99.48975 -30.950674) (xy 99.48926 -30.92069)
			(xy 85.668104 -30.92069) (xy 85.668104 -30.922468) (xy 85.667614 -30.952436) (xy 85.659791 -31.011858)
			(xy 85.644278 -31.069751) (xy 85.621342 -31.125124) (xy 85.591375 -31.17703) (xy 85.554888 -31.22458)
			(xy 85.512508 -31.26696) (xy 85.464958 -31.303447) (xy 85.413052 -31.333414) (xy 85.357679 -31.35635)
			(xy 85.299786 -31.371863) (xy 85.240364 -31.379686) (xy 85.180428 -31.379686) (xy 85.121006 -31.371863)
			(xy 85.063113 -31.35635) (xy 85.00774 -31.333414) (xy 84.955834 -31.303447) (xy 84.908284 -31.26696)
			(xy 84.865904 -31.22458) (xy 84.829417 -31.17703) (xy 84.79945 -31.125124) (xy 84.776514 -31.069751)
			(xy 84.761001 -31.011858) (xy 84.753178 -30.952436) (xy 84.752688 -30.922468) (xy 74.405207 -30.922468)
			(xy 74.404746 -30.950674) (xy 74.396918 -31.01013) (xy 74.381397 -31.068055) (xy 74.358448 -31.123459)
			(xy 74.328464 -31.175393) (xy 74.291958 -31.222969) (xy 74.249553 -31.265374) (xy 74.201977 -31.30188)
			(xy 74.150043 -31.331864) (xy 74.094639 -31.354813) (xy 74.036714 -31.370334) (xy 73.977258 -31.378162)
			(xy 73.91729 -31.378162) (xy 73.857834 -31.370334) (xy 73.799909 -31.354813) (xy 73.744505 -31.331864)
			(xy 73.692571 -31.30188) (xy 73.644995 -31.265374) (xy 73.60259 -31.222969) (xy 73.566084 -31.175393)
			(xy 73.5361 -31.123459) (xy 73.513151 -31.068055) (xy 73.49763 -31.01013) (xy 73.489802 -30.950674)
			(xy 73.489312 -30.92069) (xy 59.668156 -30.92069) (xy 59.668156 -30.922468) (xy 59.667666 -30.952436)
			(xy 59.659843 -31.011858) (xy 59.64433 -31.069751) (xy 59.621394 -31.125124) (xy 59.591427 -31.17703)
			(xy 59.55494 -31.22458) (xy 59.51256 -31.26696) (xy 59.46501 -31.303447) (xy 59.413104 -31.333414)
			(xy 59.357731 -31.35635) (xy 59.299838 -31.371863) (xy 59.240416 -31.379686) (xy 59.18048 -31.379686)
			(xy 59.121058 -31.371863) (xy 59.063165 -31.35635) (xy 59.007792 -31.333414) (xy 58.955886 -31.303447)
			(xy 58.908336 -31.26696) (xy 58.865956 -31.22458) (xy 58.829469 -31.17703) (xy 58.799502 -31.125124)
			(xy 58.776566 -31.069751) (xy 58.761053 -31.011858) (xy 58.75323 -30.952436) (xy 58.75274 -30.922468)
			(xy 48.405259 -30.922468) (xy 48.404798 -30.950674) (xy 48.39697 -31.01013) (xy 48.381449 -31.068055)
			(xy 48.3585 -31.123459) (xy 48.328516 -31.175393) (xy 48.29201 -31.222969) (xy 48.249605 -31.265374)
			(xy 48.202029 -31.30188) (xy 48.150095 -31.331864) (xy 48.094691 -31.354813) (xy 48.036766 -31.370334)
			(xy 47.97731 -31.378162) (xy 47.917342 -31.378162) (xy 47.857886 -31.370334) (xy 47.799961 -31.354813)
			(xy 47.744557 -31.331864) (xy 47.692623 -31.30188) (xy 47.645047 -31.265374) (xy 47.602642 -31.222969)
			(xy 47.566136 -31.175393) (xy 47.536152 -31.123459) (xy 47.513203 -31.068055) (xy 47.497682 -31.01013)
			(xy 47.489854 -30.950674) (xy 47.489364 -30.92069) (xy 33.668208 -30.92069) (xy 33.668208 -30.922468)
			(xy 33.667718 -30.952436) (xy 33.659895 -31.011858) (xy 33.644382 -31.069751) (xy 33.621446 -31.125124)
			(xy 33.591479 -31.17703) (xy 33.554992 -31.22458) (xy 33.512612 -31.26696) (xy 33.465062 -31.303447)
			(xy 33.413156 -31.333414) (xy 33.357783 -31.35635) (xy 33.29989 -31.371863) (xy 33.240468 -31.379686)
			(xy 33.180532 -31.379686) (xy 33.12111 -31.371863) (xy 33.063217 -31.35635) (xy 33.007844 -31.333414)
			(xy 32.955938 -31.303447) (xy 32.908388 -31.26696) (xy 32.866008 -31.22458) (xy 32.829521 -31.17703)
			(xy 32.799554 -31.125124) (xy 32.776618 -31.069751) (xy 32.761105 -31.011858) (xy 32.753282 -30.952436)
			(xy 32.752792 -30.922468) (xy 22.405311 -30.922468) (xy 22.40485 -30.950674) (xy 22.397022 -31.01013)
			(xy 22.381501 -31.068055) (xy 22.358552 -31.123459) (xy 22.328568 -31.175393) (xy 22.292062 -31.222969)
			(xy 22.249657 -31.265374) (xy 22.202081 -31.30188) (xy 22.150147 -31.331864) (xy 22.094743 -31.354813)
			(xy 22.036818 -31.370334) (xy 21.977362 -31.378162) (xy 21.917394 -31.378162) (xy 21.857938 -31.370334)
			(xy 21.800013 -31.354813) (xy 21.744609 -31.331864) (xy 21.692675 -31.30188) (xy 21.645099 -31.265374)
			(xy 21.602694 -31.222969) (xy 21.566188 -31.175393) (xy 21.536204 -31.123459) (xy 21.513255 -31.068055)
			(xy 21.497734 -31.01013) (xy 21.489906 -30.950674) (xy 21.489416 -30.92069) (xy 7.66826 -30.92069)
			(xy 7.66826 -30.922468) (xy 7.66777 -30.952436) (xy 7.659947 -31.011858) (xy 7.644434 -31.069751)
			(xy 7.621498 -31.125124) (xy 7.591531 -31.17703) (xy 7.555044 -31.22458) (xy 7.512664 -31.26696)
			(xy 7.465114 -31.303447) (xy 7.413208 -31.333414) (xy 7.357835 -31.35635) (xy 7.299942 -31.371863)
			(xy 7.24052 -31.379686) (xy 7.180584 -31.379686) (xy 7.121162 -31.371863) (xy 7.063269 -31.35635)
			(xy 7.007896 -31.333414) (xy 6.95599 -31.303447) (xy 6.90844 -31.26696) (xy 6.86606 -31.22458) (xy 6.829573 -31.17703)
			(xy 6.799606 -31.125124) (xy 6.77667 -31.069751) (xy 6.761157 -31.011858) (xy 6.753334 -30.952436)
			(xy 6.752844 -30.922468) (xy 1.524 -30.922468) (xy 1.524 -32.722312) (xy 8.607044 -32.722312) (xy 8.607044 -31.858712)
			(xy 8.607534 -31.828744) (xy 8.615357 -31.769322) (xy 8.63087 -31.711429) (xy 8.653806 -31.656056)
			(xy 8.683773 -31.60415) (xy 8.72026 -31.5566) (xy 8.76264 -31.51422) (xy 8.81019 -31.477733) (xy 8.862096 -31.447766)
			(xy 8.917469 -31.42483) (xy 8.975362 -31.409317) (xy 9.034784 -31.401494) (xy 9.09472 -31.401494)
			(xy 9.154142 -31.409317) (xy 9.212035 -31.42483) (xy 9.267408 -31.447766) (xy 9.319314 -31.477733)
			(xy 9.366864 -31.51422) (xy 9.409244 -31.5566) (xy 9.445731 -31.60415) (xy 9.475698 -31.656056) (xy 9.498634 -31.711429)
			(xy 9.514147 -31.769322) (xy 9.52197 -31.828744) (xy 9.52246 -31.858712) (xy 9.52246 -32.714184)
			(xy 18.847308 -32.714184) (xy 18.847308 -31.850584) (xy 18.847798 -31.8206) (xy 18.855626 -31.761144)
			(xy 18.871147 -31.703219) (xy 18.894096 -31.647815) (xy 18.92408 -31.595881) (xy 18.960586 -31.548305)
			(xy 19.002991 -31.5059) (xy 19.050567 -31.469394) (xy 19.102501 -31.43941) (xy 19.157905 -31.416461)
			(xy 19.21583 -31.40094) (xy 19.275286 -31.393112) (xy 19.335254 -31.393112) (xy 19.39471 -31.40094)
			(xy 19.452635 -31.416461) (xy 19.508039 -31.43941) (xy 19.559973 -31.469394) (xy 19.607549 -31.5059)
			(xy 19.649954 -31.548305) (xy 19.68646 -31.595881) (xy 19.716444 -31.647815) (xy 19.739393 -31.703219)
			(xy 19.754914 -31.761144) (xy 19.762742 -31.8206) (xy 19.763232 -31.850584) (xy 19.763232 -32.714184)
			(xy 19.763099 -32.722312) (xy 34.606992 -32.722312) (xy 34.606992 -31.858712) (xy 34.607482 -31.828744)
			(xy 34.615305 -31.769322) (xy 34.630818 -31.711429) (xy 34.653754 -31.656056) (xy 34.683721 -31.60415)
			(xy 34.720208 -31.5566) (xy 34.762588 -31.51422) (xy 34.810138 -31.477733) (xy 34.862044 -31.447766)
			(xy 34.917417 -31.42483) (xy 34.97531 -31.409317) (xy 35.034732 -31.401494) (xy 35.094668 -31.401494)
			(xy 35.15409 -31.409317) (xy 35.211983 -31.42483) (xy 35.267356 -31.447766) (xy 35.319262 -31.477733)
			(xy 35.366812 -31.51422) (xy 35.409192 -31.5566) (xy 35.445679 -31.60415) (xy 35.475646 -31.656056)
			(xy 35.498582 -31.711429) (xy 35.514095 -31.769322) (xy 35.521918 -31.828744) (xy 35.522408 -31.858712)
			(xy 35.522408 -32.714184) (xy 44.847256 -32.714184) (xy 44.847256 -31.850584) (xy 44.847746 -31.8206)
			(xy 44.855574 -31.761144) (xy 44.871095 -31.703219) (xy 44.894044 -31.647815) (xy 44.924028 -31.595881)
			(xy 44.960534 -31.548305) (xy 45.002939 -31.5059) (xy 45.050515 -31.469394) (xy 45.102449 -31.43941)
			(xy 45.157853 -31.416461) (xy 45.215778 -31.40094) (xy 45.275234 -31.393112) (xy 45.335202 -31.393112)
			(xy 45.394658 -31.40094) (xy 45.452583 -31.416461) (xy 45.507987 -31.43941) (xy 45.559921 -31.469394)
			(xy 45.607497 -31.5059) (xy 45.649902 -31.548305) (xy 45.686408 -31.595881) (xy 45.716392 -31.647815)
			(xy 45.739341 -31.703219) (xy 45.754862 -31.761144) (xy 45.76269 -31.8206) (xy 45.76318 -31.850584)
			(xy 45.76318 -32.714184) (xy 45.763047 -32.722312) (xy 60.60694 -32.722312) (xy 60.60694 -31.858712)
			(xy 60.60743 -31.828744) (xy 60.615253 -31.769322) (xy 60.630766 -31.711429) (xy 60.653702 -31.656056)
			(xy 60.683669 -31.60415) (xy 60.720156 -31.5566) (xy 60.762536 -31.51422) (xy 60.810086 -31.477733)
			(xy 60.861992 -31.447766) (xy 60.917365 -31.42483) (xy 60.975258 -31.409317) (xy 61.03468 -31.401494)
			(xy 61.094616 -31.401494) (xy 61.154038 -31.409317) (xy 61.211931 -31.42483) (xy 61.267304 -31.447766)
			(xy 61.31921 -31.477733) (xy 61.36676 -31.51422) (xy 61.40914 -31.5566) (xy 61.445627 -31.60415)
			(xy 61.475594 -31.656056) (xy 61.49853 -31.711429) (xy 61.514043 -31.769322) (xy 61.521866 -31.828744)
			(xy 61.522356 -31.858712) (xy 61.522356 -32.714184) (xy 70.847204 -32.714184) (xy 70.847204 -31.850584)
			(xy 70.847694 -31.8206) (xy 70.855522 -31.761144) (xy 70.871043 -31.703219) (xy 70.893992 -31.647815)
			(xy 70.923976 -31.595881) (xy 70.960482 -31.548305) (xy 71.002887 -31.5059) (xy 71.050463 -31.469394)
			(xy 71.102397 -31.43941) (xy 71.157801 -31.416461) (xy 71.215726 -31.40094) (xy 71.275182 -31.393112)
			(xy 71.33515 -31.393112) (xy 71.394606 -31.40094) (xy 71.452531 -31.416461) (xy 71.507935 -31.43941)
			(xy 71.559869 -31.469394) (xy 71.607445 -31.5059) (xy 71.64985 -31.548305) (xy 71.686356 -31.595881)
			(xy 71.71634 -31.647815) (xy 71.739289 -31.703219) (xy 71.75481 -31.761144) (xy 71.762638 -31.8206)
			(xy 71.763128 -31.850584) (xy 71.763128 -32.714184) (xy 71.762995 -32.722312) (xy 86.606888 -32.722312)
			(xy 86.606888 -31.858712) (xy 86.607378 -31.828744) (xy 86.615201 -31.769322) (xy 86.630714 -31.711429)
			(xy 86.65365 -31.656056) (xy 86.683617 -31.60415) (xy 86.720104 -31.5566) (xy 86.762484 -31.51422)
			(xy 86.810034 -31.477733) (xy 86.86194 -31.447766) (xy 86.917313 -31.42483) (xy 86.975206 -31.409317)
			(xy 87.034628 -31.401494) (xy 87.094564 -31.401494) (xy 87.153986 -31.409317) (xy 87.211879 -31.42483)
			(xy 87.267252 -31.447766) (xy 87.319158 -31.477733) (xy 87.366708 -31.51422) (xy 87.409088 -31.5566)
			(xy 87.445575 -31.60415) (xy 87.475542 -31.656056) (xy 87.498478 -31.711429) (xy 87.513991 -31.769322)
			(xy 87.521814 -31.828744) (xy 87.522304 -31.858712) (xy 87.522304 -32.714184) (xy 96.847152 -32.714184)
			(xy 96.847152 -31.850584) (xy 96.847642 -31.8206) (xy 96.85547 -31.761144) (xy 96.870991 -31.703219)
			(xy 96.89394 -31.647815) (xy 96.923924 -31.595881) (xy 96.96043 -31.548305) (xy 97.002835 -31.5059)
			(xy 97.050411 -31.469394) (xy 97.102345 -31.43941) (xy 97.157749 -31.416461) (xy 97.215674 -31.40094)
			(xy 97.27513 -31.393112) (xy 97.335098 -31.393112) (xy 97.394554 -31.40094) (xy 97.452479 -31.416461)
			(xy 97.507883 -31.43941) (xy 97.559817 -31.469394) (xy 97.607393 -31.5059) (xy 97.649798 -31.548305)
			(xy 97.686304 -31.595881) (xy 97.716288 -31.647815) (xy 97.739237 -31.703219) (xy 97.754758 -31.761144)
			(xy 97.762586 -31.8206) (xy 97.763076 -31.850584) (xy 97.763076 -32.714184) (xy 97.762943 -32.722312)
			(xy 124.706888 -32.722312) (xy 124.706888 -31.858712) (xy 124.707378 -31.828728) (xy 124.715206 -31.769272)
			(xy 124.730727 -31.711347) (xy 124.753676 -31.655943) (xy 124.78366 -31.604009) (xy 124.820166 -31.556433)
			(xy 124.862571 -31.514028) (xy 124.910147 -31.477522) (xy 124.962081 -31.447538) (xy 125.017485 -31.424589)
			(xy 125.07541 -31.409068) (xy 125.134866 -31.40124) (xy 125.194834 -31.40124) (xy 125.25429 -31.409068)
			(xy 125.312215 -31.424589) (xy 125.367619 -31.447538) (xy 125.419553 -31.477522) (xy 125.467129 -31.514028)
			(xy 125.509534 -31.556433) (xy 125.54604 -31.604009) (xy 125.576024 -31.655943) (xy 125.598973 -31.711347)
			(xy 125.614494 -31.769272) (xy 125.622322 -31.828728) (xy 125.622812 -31.858712) (xy 125.622812 -32.714184)
			(xy 134.94766 -32.714184) (xy 134.94766 -31.850584) (xy 134.94815 -31.820616) (xy 134.955973 -31.761194)
			(xy 134.971486 -31.703301) (xy 134.994422 -31.647928) (xy 135.024389 -31.596022) (xy 135.060876 -31.548472)
			(xy 135.103256 -31.506092) (xy 135.150806 -31.469605) (xy 135.202712 -31.439638) (xy 135.258085 -31.416702)
			(xy 135.315978 -31.401189) (xy 135.3754 -31.393366) (xy 135.435336 -31.393366) (xy 135.494758 -31.401189)
			(xy 135.552651 -31.416702) (xy 135.608024 -31.439638) (xy 135.65993 -31.469605) (xy 135.70748 -31.506092)
			(xy 135.74986 -31.548472) (xy 135.786347 -31.596022) (xy 135.816314 -31.647928) (xy 135.83925 -31.703301)
			(xy 135.854763 -31.761194) (xy 135.862586 -31.820616) (xy 135.863076 -31.850584) (xy 135.863076 -32.714184)
			(xy 135.862943 -32.722312) (xy 150.706836 -32.722312) (xy 150.706836 -31.858712) (xy 150.707326 -31.828728)
			(xy 150.715154 -31.769272) (xy 150.730675 -31.711347) (xy 150.753624 -31.655943) (xy 150.783608 -31.604009)
			(xy 150.820114 -31.556433) (xy 150.862519 -31.514028) (xy 150.910095 -31.477522) (xy 150.962029 -31.447538)
			(xy 151.017433 -31.424589) (xy 151.075358 -31.409068) (xy 151.134814 -31.40124) (xy 151.194782 -31.40124)
			(xy 151.254238 -31.409068) (xy 151.312163 -31.424589) (xy 151.367567 -31.447538) (xy 151.419501 -31.477522)
			(xy 151.467077 -31.514028) (xy 151.509482 -31.556433) (xy 151.545988 -31.604009) (xy 151.575972 -31.655943)
			(xy 151.598921 -31.711347) (xy 151.614442 -31.769272) (xy 151.62227 -31.828728) (xy 151.62276 -31.858712)
			(xy 151.62276 -32.714184) (xy 160.947608 -32.714184) (xy 160.947608 -31.850584) (xy 160.948098 -31.820616)
			(xy 160.955921 -31.761194) (xy 160.971434 -31.703301) (xy 160.99437 -31.647928) (xy 161.024337 -31.596022)
			(xy 161.060824 -31.548472) (xy 161.103204 -31.506092) (xy 161.150754 -31.469605) (xy 161.20266 -31.439638)
			(xy 161.258033 -31.416702) (xy 161.315926 -31.401189) (xy 161.375348 -31.393366) (xy 161.435284 -31.393366)
			(xy 161.494706 -31.401189) (xy 161.552599 -31.416702) (xy 161.607972 -31.439638) (xy 161.659878 -31.469605)
			(xy 161.707428 -31.506092) (xy 161.749808 -31.548472) (xy 161.786295 -31.596022) (xy 161.816262 -31.647928)
			(xy 161.839198 -31.703301) (xy 161.854711 -31.761194) (xy 161.862534 -31.820616) (xy 161.863024 -31.850584)
			(xy 161.863024 -32.714184) (xy 161.862891 -32.722312) (xy 176.706784 -32.722312) (xy 176.706784 -31.858712)
			(xy 176.707274 -31.828728) (xy 176.715102 -31.769272) (xy 176.730623 -31.711347) (xy 176.753572 -31.655943)
			(xy 176.783556 -31.604009) (xy 176.820062 -31.556433) (xy 176.862467 -31.514028) (xy 176.910043 -31.477522)
			(xy 176.961977 -31.447538) (xy 177.017381 -31.424589) (xy 177.075306 -31.409068) (xy 177.134762 -31.40124)
			(xy 177.19473 -31.40124) (xy 177.254186 -31.409068) (xy 177.312111 -31.424589) (xy 177.367515 -31.447538)
			(xy 177.419449 -31.477522) (xy 177.467025 -31.514028) (xy 177.50943 -31.556433) (xy 177.545936 -31.604009)
			(xy 177.57592 -31.655943) (xy 177.598869 -31.711347) (xy 177.61439 -31.769272) (xy 177.622218 -31.828728)
			(xy 177.622708 -31.858712) (xy 177.622708 -32.714184) (xy 186.947556 -32.714184) (xy 186.947556 -31.850584)
			(xy 186.948046 -31.820616) (xy 186.955869 -31.761194) (xy 186.971382 -31.703301) (xy 186.994318 -31.647928)
			(xy 187.024285 -31.596022) (xy 187.060772 -31.548472) (xy 187.103152 -31.506092) (xy 187.150702 -31.469605)
			(xy 187.202608 -31.439638) (xy 187.257981 -31.416702) (xy 187.315874 -31.401189) (xy 187.375296 -31.393366)
			(xy 187.435232 -31.393366) (xy 187.494654 -31.401189) (xy 187.552547 -31.416702) (xy 187.60792 -31.439638)
			(xy 187.659826 -31.469605) (xy 187.707376 -31.506092) (xy 187.749756 -31.548472) (xy 187.786243 -31.596022)
			(xy 187.81621 -31.647928) (xy 187.839146 -31.703301) (xy 187.854659 -31.761194) (xy 187.862482 -31.820616)
			(xy 187.862972 -31.850584) (xy 187.862972 -32.714184) (xy 187.862839 -32.722312) (xy 202.706732 -32.722312)
			(xy 202.706732 -31.858712) (xy 202.707222 -31.828728) (xy 202.71505 -31.769272) (xy 202.730571 -31.711347)
			(xy 202.75352 -31.655943) (xy 202.783504 -31.604009) (xy 202.82001 -31.556433) (xy 202.862415 -31.514028)
			(xy 202.909991 -31.477522) (xy 202.961925 -31.447538) (xy 203.017329 -31.424589) (xy 203.075254 -31.409068)
			(xy 203.13471 -31.40124) (xy 203.194678 -31.40124) (xy 203.254134 -31.409068) (xy 203.312059 -31.424589)
			(xy 203.367463 -31.447538) (xy 203.419397 -31.477522) (xy 203.466973 -31.514028) (xy 203.509378 -31.556433)
			(xy 203.545884 -31.604009) (xy 203.575868 -31.655943) (xy 203.598817 -31.711347) (xy 203.614338 -31.769272)
			(xy 203.622166 -31.828728) (xy 203.622656 -31.858712) (xy 203.622656 -32.714184) (xy 212.947504 -32.714184)
			(xy 212.947504 -31.850584) (xy 212.947994 -31.820616) (xy 212.955817 -31.761194) (xy 212.97133 -31.703301)
			(xy 212.994266 -31.647928) (xy 213.024233 -31.596022) (xy 213.06072 -31.548472) (xy 213.1031 -31.506092)
			(xy 213.15065 -31.469605) (xy 213.202556 -31.439638) (xy 213.257929 -31.416702) (xy 213.315822 -31.401189)
			(xy 213.375244 -31.393366) (xy 213.43518 -31.393366) (xy 213.494602 -31.401189) (xy 213.552495 -31.416702)
			(xy 213.607868 -31.439638) (xy 213.659774 -31.469605) (xy 213.707324 -31.506092) (xy 213.749704 -31.548472)
			(xy 213.786191 -31.596022) (xy 213.816158 -31.647928) (xy 213.839094 -31.703301) (xy 213.854607 -31.761194)
			(xy 213.86243 -31.820616) (xy 213.86292 -31.850584) (xy 213.86292 -32.714184) (xy 213.862787 -32.722312)
			(xy 240.806732 -32.722312) (xy 240.806732 -31.858712) (xy 240.807222 -31.828728) (xy 240.81505 -31.769272)
			(xy 240.830571 -31.711347) (xy 240.85352 -31.655943) (xy 240.883504 -31.604009) (xy 240.92001 -31.556433)
			(xy 240.962415 -31.514028) (xy 241.009991 -31.477522) (xy 241.061925 -31.447538) (xy 241.117329 -31.424589)
			(xy 241.175254 -31.409068) (xy 241.23471 -31.40124) (xy 241.294678 -31.40124) (xy 241.354134 -31.409068)
			(xy 241.412059 -31.424589) (xy 241.467463 -31.447538) (xy 241.519397 -31.477522) (xy 241.566973 -31.514028)
			(xy 241.609378 -31.556433) (xy 241.645884 -31.604009) (xy 241.675868 -31.655943) (xy 241.698817 -31.711347)
			(xy 241.714338 -31.769272) (xy 241.722166 -31.828728) (xy 241.722656 -31.858712) (xy 241.722656 -32.714184)
			(xy 251.047504 -32.714184) (xy 251.047504 -31.850584) (xy 251.047994 -31.820616) (xy 251.055817 -31.761194)
			(xy 251.07133 -31.703301) (xy 251.094266 -31.647928) (xy 251.124233 -31.596022) (xy 251.16072 -31.548472)
			(xy 251.2031 -31.506092) (xy 251.25065 -31.469605) (xy 251.302556 -31.439638) (xy 251.357929 -31.416702)
			(xy 251.415822 -31.401189) (xy 251.475244 -31.393366) (xy 251.53518 -31.393366) (xy 251.594602 -31.401189)
			(xy 251.652495 -31.416702) (xy 251.707868 -31.439638) (xy 251.759774 -31.469605) (xy 251.807324 -31.506092)
			(xy 251.849704 -31.548472) (xy 251.886191 -31.596022) (xy 251.916158 -31.647928) (xy 251.939094 -31.703301)
			(xy 251.954607 -31.761194) (xy 251.96243 -31.820616) (xy 251.96292 -31.850584) (xy 251.96292 -32.714184)
			(xy 251.962787 -32.722312) (xy 266.80668 -32.722312) (xy 266.80668 -31.858712) (xy 266.80717 -31.828728)
			(xy 266.814998 -31.769272) (xy 266.830519 -31.711347) (xy 266.853468 -31.655943) (xy 266.883452 -31.604009)
			(xy 266.919958 -31.556433) (xy 266.962363 -31.514028) (xy 267.009939 -31.477522) (xy 267.061873 -31.447538)
			(xy 267.117277 -31.424589) (xy 267.175202 -31.409068) (xy 267.234658 -31.40124) (xy 267.294626 -31.40124)
			(xy 267.354082 -31.409068) (xy 267.412007 -31.424589) (xy 267.467411 -31.447538) (xy 267.519345 -31.477522)
			(xy 267.566921 -31.514028) (xy 267.609326 -31.556433) (xy 267.645832 -31.604009) (xy 267.675816 -31.655943)
			(xy 267.698765 -31.711347) (xy 267.714286 -31.769272) (xy 267.722114 -31.828728) (xy 267.722604 -31.858712)
			(xy 267.722604 -32.714184) (xy 277.047452 -32.714184) (xy 277.047452 -31.850584) (xy 277.047942 -31.820616)
			(xy 277.055765 -31.761194) (xy 277.071278 -31.703301) (xy 277.094214 -31.647928) (xy 277.124181 -31.596022)
			(xy 277.160668 -31.548472) (xy 277.203048 -31.506092) (xy 277.250598 -31.469605) (xy 277.302504 -31.439638)
			(xy 277.357877 -31.416702) (xy 277.41577 -31.401189) (xy 277.475192 -31.393366) (xy 277.535128 -31.393366)
			(xy 277.59455 -31.401189) (xy 277.652443 -31.416702) (xy 277.707816 -31.439638) (xy 277.759722 -31.469605)
			(xy 277.807272 -31.506092) (xy 277.849652 -31.548472) (xy 277.886139 -31.596022) (xy 277.916106 -31.647928)
			(xy 277.939042 -31.703301) (xy 277.954555 -31.761194) (xy 277.962378 -31.820616) (xy 277.962868 -31.850584)
			(xy 277.962868 -32.714184) (xy 277.962735 -32.722312) (xy 292.806628 -32.722312) (xy 292.806628 -31.858712)
			(xy 292.807118 -31.828728) (xy 292.814946 -31.769272) (xy 292.830467 -31.711347) (xy 292.853416 -31.655943)
			(xy 292.8834 -31.604009) (xy 292.919906 -31.556433) (xy 292.962311 -31.514028) (xy 293.009887 -31.477522)
			(xy 293.061821 -31.447538) (xy 293.117225 -31.424589) (xy 293.17515 -31.409068) (xy 293.234606 -31.40124)
			(xy 293.294574 -31.40124) (xy 293.35403 -31.409068) (xy 293.411955 -31.424589) (xy 293.467359 -31.447538)
			(xy 293.519293 -31.477522) (xy 293.566869 -31.514028) (xy 293.609274 -31.556433) (xy 293.64578 -31.604009)
			(xy 293.675764 -31.655943) (xy 293.698713 -31.711347) (xy 293.714234 -31.769272) (xy 293.722062 -31.828728)
			(xy 293.722552 -31.858712) (xy 293.722552 -32.714184) (xy 303.0474 -32.714184) (xy 303.0474 -31.850584)
			(xy 303.04789 -31.820616) (xy 303.055713 -31.761194) (xy 303.071226 -31.703301) (xy 303.094162 -31.647928)
			(xy 303.124129 -31.596022) (xy 303.160616 -31.548472) (xy 303.202996 -31.506092) (xy 303.250546 -31.469605)
			(xy 303.302452 -31.439638) (xy 303.357825 -31.416702) (xy 303.415718 -31.401189) (xy 303.47514 -31.393366)
			(xy 303.535076 -31.393366) (xy 303.594498 -31.401189) (xy 303.652391 -31.416702) (xy 303.707764 -31.439638)
			(xy 303.75967 -31.469605) (xy 303.80722 -31.506092) (xy 303.8496 -31.548472) (xy 303.886087 -31.596022)
			(xy 303.916054 -31.647928) (xy 303.93899 -31.703301) (xy 303.954503 -31.761194) (xy 303.962326 -31.820616)
			(xy 303.962816 -31.850584) (xy 303.962816 -32.714184) (xy 303.962683 -32.722312) (xy 318.806576 -32.722312)
			(xy 318.806576 -31.858712) (xy 318.807066 -31.828728) (xy 318.814894 -31.769272) (xy 318.830415 -31.711347)
			(xy 318.853364 -31.655943) (xy 318.883348 -31.604009) (xy 318.919854 -31.556433) (xy 318.962259 -31.514028)
			(xy 319.009835 -31.477522) (xy 319.061769 -31.447538) (xy 319.117173 -31.424589) (xy 319.175098 -31.409068)
			(xy 319.234554 -31.40124) (xy 319.294522 -31.40124) (xy 319.353978 -31.409068) (xy 319.411903 -31.424589)
			(xy 319.467307 -31.447538) (xy 319.519241 -31.477522) (xy 319.566817 -31.514028) (xy 319.609222 -31.556433)
			(xy 319.645728 -31.604009) (xy 319.675712 -31.655943) (xy 319.698661 -31.711347) (xy 319.714182 -31.769272)
			(xy 319.72201 -31.828728) (xy 319.7225 -31.858712) (xy 319.7225 -32.714184) (xy 329.047348 -32.714184)
			(xy 329.047348 -31.850584) (xy 329.047838 -31.820616) (xy 329.055661 -31.761194) (xy 329.071174 -31.703301)
			(xy 329.09411 -31.647928) (xy 329.124077 -31.596022) (xy 329.160564 -31.548472) (xy 329.202944 -31.506092)
			(xy 329.250494 -31.469605) (xy 329.3024 -31.439638) (xy 329.357773 -31.416702) (xy 329.415666 -31.401189)
			(xy 329.475088 -31.393366) (xy 329.535024 -31.393366) (xy 329.594446 -31.401189) (xy 329.652339 -31.416702)
			(xy 329.707712 -31.439638) (xy 329.759618 -31.469605) (xy 329.807168 -31.506092) (xy 329.849548 -31.548472)
			(xy 329.886035 -31.596022) (xy 329.916002 -31.647928) (xy 329.938938 -31.703301) (xy 329.954451 -31.761194)
			(xy 329.962274 -31.820616) (xy 329.962764 -31.850584) (xy 329.962764 -32.714184) (xy 329.962631 -32.722312)
			(xy 356.907084 -32.722312) (xy 356.907084 -31.858712) (xy 356.907574 -31.828744) (xy 356.915397 -31.769322)
			(xy 356.93091 -31.711429) (xy 356.953846 -31.656056) (xy 356.983813 -31.60415) (xy 357.0203 -31.5566)
			(xy 357.06268 -31.51422) (xy 357.11023 -31.477733) (xy 357.162136 -31.447766) (xy 357.217509 -31.42483)
			(xy 357.275402 -31.409317) (xy 357.334824 -31.401494) (xy 357.39476 -31.401494) (xy 357.454182 -31.409317)
			(xy 357.512075 -31.42483) (xy 357.567448 -31.447766) (xy 357.619354 -31.477733) (xy 357.666904 -31.51422)
			(xy 357.709284 -31.5566) (xy 357.745771 -31.60415) (xy 357.775738 -31.656056) (xy 357.798674 -31.711429)
			(xy 357.814187 -31.769322) (xy 357.82201 -31.828744) (xy 357.8225 -31.858712) (xy 357.8225 -32.714184)
			(xy 367.147348 -32.714184) (xy 367.147348 -31.850584) (xy 367.147838 -31.8206) (xy 367.155666 -31.761144)
			(xy 367.171187 -31.703219) (xy 367.194136 -31.647815) (xy 367.22412 -31.595881) (xy 367.260626 -31.548305)
			(xy 367.303031 -31.5059) (xy 367.350607 -31.469394) (xy 367.402541 -31.43941) (xy 367.457945 -31.416461)
			(xy 367.51587 -31.40094) (xy 367.575326 -31.393112) (xy 367.635294 -31.393112) (xy 367.69475 -31.40094)
			(xy 367.752675 -31.416461) (xy 367.808079 -31.43941) (xy 367.860013 -31.469394) (xy 367.907589 -31.5059)
			(xy 367.949994 -31.548305) (xy 367.9865 -31.595881) (xy 368.016484 -31.647815) (xy 368.039433 -31.703219)
			(xy 368.054954 -31.761144) (xy 368.062782 -31.8206) (xy 368.063272 -31.850584) (xy 368.063272 -32.714184)
			(xy 368.063139 -32.722312) (xy 382.907032 -32.722312) (xy 382.907032 -31.858712) (xy 382.907522 -31.828744)
			(xy 382.915345 -31.769322) (xy 382.930858 -31.711429) (xy 382.953794 -31.656056) (xy 382.983761 -31.60415)
			(xy 383.020248 -31.5566) (xy 383.062628 -31.51422) (xy 383.110178 -31.477733) (xy 383.162084 -31.447766)
			(xy 383.217457 -31.42483) (xy 383.27535 -31.409317) (xy 383.334772 -31.401494) (xy 383.394708 -31.401494)
			(xy 383.45413 -31.409317) (xy 383.512023 -31.42483) (xy 383.567396 -31.447766) (xy 383.619302 -31.477733)
			(xy 383.666852 -31.51422) (xy 383.709232 -31.5566) (xy 383.745719 -31.60415) (xy 383.775686 -31.656056)
			(xy 383.798622 -31.711429) (xy 383.814135 -31.769322) (xy 383.821958 -31.828744) (xy 383.822448 -31.858712)
			(xy 383.822448 -32.714184) (xy 393.147296 -32.714184) (xy 393.147296 -31.850584) (xy 393.147786 -31.8206)
			(xy 393.155614 -31.761144) (xy 393.171135 -31.703219) (xy 393.194084 -31.647815) (xy 393.224068 -31.595881)
			(xy 393.260574 -31.548305) (xy 393.302979 -31.5059) (xy 393.350555 -31.469394) (xy 393.402489 -31.43941)
			(xy 393.457893 -31.416461) (xy 393.515818 -31.40094) (xy 393.575274 -31.393112) (xy 393.635242 -31.393112)
			(xy 393.694698 -31.40094) (xy 393.752623 -31.416461) (xy 393.808027 -31.43941) (xy 393.859961 -31.469394)
			(xy 393.907537 -31.5059) (xy 393.949942 -31.548305) (xy 393.986448 -31.595881) (xy 394.016432 -31.647815)
			(xy 394.039381 -31.703219) (xy 394.054902 -31.761144) (xy 394.06273 -31.8206) (xy 394.06322 -31.850584)
			(xy 394.06322 -32.714184) (xy 394.063087 -32.722312) (xy 408.90698 -32.722312) (xy 408.90698 -31.858712)
			(xy 408.90747 -31.828744) (xy 408.915293 -31.769322) (xy 408.930806 -31.711429) (xy 408.953742 -31.656056)
			(xy 408.983709 -31.60415) (xy 409.020196 -31.5566) (xy 409.062576 -31.51422) (xy 409.110126 -31.477733)
			(xy 409.162032 -31.447766) (xy 409.217405 -31.42483) (xy 409.275298 -31.409317) (xy 409.33472 -31.401494)
			(xy 409.394656 -31.401494) (xy 409.454078 -31.409317) (xy 409.511971 -31.42483) (xy 409.567344 -31.447766)
			(xy 409.61925 -31.477733) (xy 409.6668 -31.51422) (xy 409.70918 -31.5566) (xy 409.745667 -31.60415)
			(xy 409.775634 -31.656056) (xy 409.79857 -31.711429) (xy 409.814083 -31.769322) (xy 409.821906 -31.828744)
			(xy 409.822396 -31.858712) (xy 409.822396 -32.714184) (xy 419.147244 -32.714184) (xy 419.147244 -31.850584)
			(xy 419.147734 -31.8206) (xy 419.155562 -31.761144) (xy 419.171083 -31.703219) (xy 419.194032 -31.647815)
			(xy 419.224016 -31.595881) (xy 419.260522 -31.548305) (xy 419.302927 -31.5059) (xy 419.350503 -31.469394)
			(xy 419.402437 -31.43941) (xy 419.457841 -31.416461) (xy 419.515766 -31.40094) (xy 419.575222 -31.393112)
			(xy 419.63519 -31.393112) (xy 419.694646 -31.40094) (xy 419.752571 -31.416461) (xy 419.807975 -31.43941)
			(xy 419.859909 -31.469394) (xy 419.907485 -31.5059) (xy 419.94989 -31.548305) (xy 419.986396 -31.595881)
			(xy 420.01638 -31.647815) (xy 420.039329 -31.703219) (xy 420.05485 -31.761144) (xy 420.062678 -31.8206)
			(xy 420.063168 -31.850584) (xy 420.063168 -32.714184) (xy 420.063035 -32.722312) (xy 434.906928 -32.722312)
			(xy 434.906928 -31.858712) (xy 434.907418 -31.828744) (xy 434.915241 -31.769322) (xy 434.930754 -31.711429)
			(xy 434.95369 -31.656056) (xy 434.983657 -31.60415) (xy 435.020144 -31.5566) (xy 435.062524 -31.51422)
			(xy 435.110074 -31.477733) (xy 435.16198 -31.447766) (xy 435.217353 -31.42483) (xy 435.275246 -31.409317)
			(xy 435.334668 -31.401494) (xy 435.394604 -31.401494) (xy 435.454026 -31.409317) (xy 435.511919 -31.42483)
			(xy 435.567292 -31.447766) (xy 435.619198 -31.477733) (xy 435.666748 -31.51422) (xy 435.709128 -31.5566)
			(xy 435.745615 -31.60415) (xy 435.775582 -31.656056) (xy 435.798518 -31.711429) (xy 435.814031 -31.769322)
			(xy 435.821854 -31.828744) (xy 435.822344 -31.858712) (xy 435.822344 -32.714184) (xy 445.147192 -32.714184)
			(xy 445.147192 -31.850584) (xy 445.147682 -31.8206) (xy 445.15551 -31.761144) (xy 445.171031 -31.703219)
			(xy 445.19398 -31.647815) (xy 445.223964 -31.595881) (xy 445.26047 -31.548305) (xy 445.302875 -31.5059)
			(xy 445.350451 -31.469394) (xy 445.402385 -31.43941) (xy 445.457789 -31.416461) (xy 445.515714 -31.40094)
			(xy 445.57517 -31.393112) (xy 445.635138 -31.393112) (xy 445.694594 -31.40094) (xy 445.752519 -31.416461)
			(xy 445.807923 -31.43941) (xy 445.859857 -31.469394) (xy 445.907433 -31.5059) (xy 445.949838 -31.548305)
			(xy 445.986344 -31.595881) (xy 446.016328 -31.647815) (xy 446.039277 -31.703219) (xy 446.054798 -31.761144)
			(xy 446.062626 -31.8206) (xy 446.063116 -31.850584) (xy 446.063116 -32.714184) (xy 446.062626 -32.744168)
			(xy 446.054798 -32.803624) (xy 446.039277 -32.861549) (xy 446.016328 -32.916953) (xy 445.986344 -32.968887)
			(xy 445.949838 -33.016463) (xy 445.907433 -33.058868) (xy 445.859857 -33.095374) (xy 445.807923 -33.125358)
			(xy 445.752519 -33.148307) (xy 445.694594 -33.163828) (xy 445.635138 -33.171656) (xy 445.57517 -33.171656)
			(xy 445.515714 -33.163828) (xy 445.457789 -33.148307) (xy 445.402385 -33.125358) (xy 445.350451 -33.095374)
			(xy 445.302875 -33.058868) (xy 445.26047 -33.016463) (xy 445.223964 -32.968887) (xy 445.19398 -32.916953)
			(xy 445.171031 -32.861549) (xy 445.15551 -32.803624) (xy 445.147682 -32.744168) (xy 445.147192 -32.714184)
			(xy 435.822344 -32.714184) (xy 435.822344 -32.722312) (xy 435.821854 -32.75228) (xy 435.814031 -32.811702)
			(xy 435.798518 -32.869595) (xy 435.775582 -32.924968) (xy 435.745615 -32.976874) (xy 435.709128 -33.024424)
			(xy 435.666748 -33.066804) (xy 435.619198 -33.103291) (xy 435.567292 -33.133258) (xy 435.511919 -33.156194)
			(xy 435.454026 -33.171707) (xy 435.394604 -33.17953) (xy 435.334668 -33.17953) (xy 435.275246 -33.171707)
			(xy 435.217353 -33.156194) (xy 435.16198 -33.133258) (xy 435.110074 -33.103291) (xy 435.062524 -33.066804)
			(xy 435.020144 -33.024424) (xy 434.983657 -32.976874) (xy 434.95369 -32.924968) (xy 434.930754 -32.869595)
			(xy 434.915241 -32.811702) (xy 434.907418 -32.75228) (xy 434.906928 -32.722312) (xy 420.063035 -32.722312)
			(xy 420.062678 -32.744168) (xy 420.05485 -32.803624) (xy 420.039329 -32.861549) (xy 420.01638 -32.916953)
			(xy 419.986396 -32.968887) (xy 419.94989 -33.016463) (xy 419.907485 -33.058868) (xy 419.859909 -33.095374)
			(xy 419.807975 -33.125358) (xy 419.752571 -33.148307) (xy 419.694646 -33.163828) (xy 419.63519 -33.171656)
			(xy 419.575222 -33.171656) (xy 419.515766 -33.163828) (xy 419.457841 -33.148307) (xy 419.402437 -33.125358)
			(xy 419.350503 -33.095374) (xy 419.302927 -33.058868) (xy 419.260522 -33.016463) (xy 419.224016 -32.968887)
			(xy 419.194032 -32.916953) (xy 419.171083 -32.861549) (xy 419.155562 -32.803624) (xy 419.147734 -32.744168)
			(xy 419.147244 -32.714184) (xy 409.822396 -32.714184) (xy 409.822396 -32.722312) (xy 409.821906 -32.75228)
			(xy 409.814083 -32.811702) (xy 409.79857 -32.869595) (xy 409.775634 -32.924968) (xy 409.745667 -32.976874)
			(xy 409.70918 -33.024424) (xy 409.6668 -33.066804) (xy 409.61925 -33.103291) (xy 409.567344 -33.133258)
			(xy 409.511971 -33.156194) (xy 409.454078 -33.171707) (xy 409.394656 -33.17953) (xy 409.33472 -33.17953)
			(xy 409.275298 -33.171707) (xy 409.217405 -33.156194) (xy 409.162032 -33.133258) (xy 409.110126 -33.103291)
			(xy 409.062576 -33.066804) (xy 409.020196 -33.024424) (xy 408.983709 -32.976874) (xy 408.953742 -32.924968)
			(xy 408.930806 -32.869595) (xy 408.915293 -32.811702) (xy 408.90747 -32.75228) (xy 408.90698 -32.722312)
			(xy 394.063087 -32.722312) (xy 394.06273 -32.744168) (xy 394.054902 -32.803624) (xy 394.039381 -32.861549)
			(xy 394.016432 -32.916953) (xy 393.986448 -32.968887) (xy 393.949942 -33.016463) (xy 393.907537 -33.058868)
			(xy 393.859961 -33.095374) (xy 393.808027 -33.125358) (xy 393.752623 -33.148307) (xy 393.694698 -33.163828)
			(xy 393.635242 -33.171656) (xy 393.575274 -33.171656) (xy 393.515818 -33.163828) (xy 393.457893 -33.148307)
			(xy 393.402489 -33.125358) (xy 393.350555 -33.095374) (xy 393.302979 -33.058868) (xy 393.260574 -33.016463)
			(xy 393.224068 -32.968887) (xy 393.194084 -32.916953) (xy 393.171135 -32.861549) (xy 393.155614 -32.803624)
			(xy 393.147786 -32.744168) (xy 393.147296 -32.714184) (xy 383.822448 -32.714184) (xy 383.822448 -32.722312)
			(xy 383.821958 -32.75228) (xy 383.814135 -32.811702) (xy 383.798622 -32.869595) (xy 383.775686 -32.924968)
			(xy 383.745719 -32.976874) (xy 383.709232 -33.024424) (xy 383.666852 -33.066804) (xy 383.619302 -33.103291)
			(xy 383.567396 -33.133258) (xy 383.512023 -33.156194) (xy 383.45413 -33.171707) (xy 383.394708 -33.17953)
			(xy 383.334772 -33.17953) (xy 383.27535 -33.171707) (xy 383.217457 -33.156194) (xy 383.162084 -33.133258)
			(xy 383.110178 -33.103291) (xy 383.062628 -33.066804) (xy 383.020248 -33.024424) (xy 382.983761 -32.976874)
			(xy 382.953794 -32.924968) (xy 382.930858 -32.869595) (xy 382.915345 -32.811702) (xy 382.907522 -32.75228)
			(xy 382.907032 -32.722312) (xy 368.063139 -32.722312) (xy 368.062782 -32.744168) (xy 368.054954 -32.803624)
			(xy 368.039433 -32.861549) (xy 368.016484 -32.916953) (xy 367.9865 -32.968887) (xy 367.949994 -33.016463)
			(xy 367.907589 -33.058868) (xy 367.860013 -33.095374) (xy 367.808079 -33.125358) (xy 367.752675 -33.148307)
			(xy 367.69475 -33.163828) (xy 367.635294 -33.171656) (xy 367.575326 -33.171656) (xy 367.51587 -33.163828)
			(xy 367.457945 -33.148307) (xy 367.402541 -33.125358) (xy 367.350607 -33.095374) (xy 367.303031 -33.058868)
			(xy 367.260626 -33.016463) (xy 367.22412 -32.968887) (xy 367.194136 -32.916953) (xy 367.171187 -32.861549)
			(xy 367.155666 -32.803624) (xy 367.147838 -32.744168) (xy 367.147348 -32.714184) (xy 357.8225 -32.714184)
			(xy 357.8225 -32.722312) (xy 357.82201 -32.75228) (xy 357.814187 -32.811702) (xy 357.798674 -32.869595)
			(xy 357.775738 -32.924968) (xy 357.745771 -32.976874) (xy 357.709284 -33.024424) (xy 357.666904 -33.066804)
			(xy 357.619354 -33.103291) (xy 357.567448 -33.133258) (xy 357.512075 -33.156194) (xy 357.454182 -33.171707)
			(xy 357.39476 -33.17953) (xy 357.334824 -33.17953) (xy 357.275402 -33.171707) (xy 357.217509 -33.156194)
			(xy 357.162136 -33.133258) (xy 357.11023 -33.103291) (xy 357.06268 -33.066804) (xy 357.0203 -33.024424)
			(xy 356.983813 -32.976874) (xy 356.953846 -32.924968) (xy 356.93091 -32.869595) (xy 356.915397 -32.811702)
			(xy 356.907574 -32.75228) (xy 356.907084 -32.722312) (xy 329.962631 -32.722312) (xy 329.962274 -32.744152)
			(xy 329.954451 -32.803574) (xy 329.938938 -32.861467) (xy 329.916002 -32.91684) (xy 329.886035 -32.968746)
			(xy 329.849548 -33.016296) (xy 329.807168 -33.058676) (xy 329.759618 -33.095163) (xy 329.707712 -33.12513)
			(xy 329.652339 -33.148066) (xy 329.594446 -33.163579) (xy 329.535024 -33.171402) (xy 329.475088 -33.171402)
			(xy 329.415666 -33.163579) (xy 329.357773 -33.148066) (xy 329.3024 -33.12513) (xy 329.250494 -33.095163)
			(xy 329.202944 -33.058676) (xy 329.160564 -33.016296) (xy 329.124077 -32.968746) (xy 329.09411 -32.91684)
			(xy 329.071174 -32.861467) (xy 329.055661 -32.803574) (xy 329.047838 -32.744152) (xy 329.047348 -32.714184)
			(xy 319.7225 -32.714184) (xy 319.7225 -32.722312) (xy 319.72201 -32.752296) (xy 319.714182 -32.811752)
			(xy 319.698661 -32.869677) (xy 319.675712 -32.925081) (xy 319.645728 -32.977015) (xy 319.609222 -33.024591)
			(xy 319.566817 -33.066996) (xy 319.519241 -33.103502) (xy 319.467307 -33.133486) (xy 319.411903 -33.156435)
			(xy 319.353978 -33.171956) (xy 319.294522 -33.179784) (xy 319.234554 -33.179784) (xy 319.175098 -33.171956)
			(xy 319.117173 -33.156435) (xy 319.061769 -33.133486) (xy 319.009835 -33.103502) (xy 318.962259 -33.066996)
			(xy 318.919854 -33.024591) (xy 318.883348 -32.977015) (xy 318.853364 -32.925081) (xy 318.830415 -32.869677)
			(xy 318.814894 -32.811752) (xy 318.807066 -32.752296) (xy 318.806576 -32.722312) (xy 303.962683 -32.722312)
			(xy 303.962326 -32.744152) (xy 303.954503 -32.803574) (xy 303.93899 -32.861467) (xy 303.916054 -32.91684)
			(xy 303.886087 -32.968746) (xy 303.8496 -33.016296) (xy 303.80722 -33.058676) (xy 303.75967 -33.095163)
			(xy 303.707764 -33.12513) (xy 303.652391 -33.148066) (xy 303.594498 -33.163579) (xy 303.535076 -33.171402)
			(xy 303.47514 -33.171402) (xy 303.415718 -33.163579) (xy 303.357825 -33.148066) (xy 303.302452 -33.12513)
			(xy 303.250546 -33.095163) (xy 303.202996 -33.058676) (xy 303.160616 -33.016296) (xy 303.124129 -32.968746)
			(xy 303.094162 -32.91684) (xy 303.071226 -32.861467) (xy 303.055713 -32.803574) (xy 303.04789 -32.744152)
			(xy 303.0474 -32.714184) (xy 293.722552 -32.714184) (xy 293.722552 -32.722312) (xy 293.722062 -32.752296)
			(xy 293.714234 -32.811752) (xy 293.698713 -32.869677) (xy 293.675764 -32.925081) (xy 293.64578 -32.977015)
			(xy 293.609274 -33.024591) (xy 293.566869 -33.066996) (xy 293.519293 -33.103502) (xy 293.467359 -33.133486)
			(xy 293.411955 -33.156435) (xy 293.35403 -33.171956) (xy 293.294574 -33.179784) (xy 293.234606 -33.179784)
			(xy 293.17515 -33.171956) (xy 293.117225 -33.156435) (xy 293.061821 -33.133486) (xy 293.009887 -33.103502)
			(xy 292.962311 -33.066996) (xy 292.919906 -33.024591) (xy 292.8834 -32.977015) (xy 292.853416 -32.925081)
			(xy 292.830467 -32.869677) (xy 292.814946 -32.811752) (xy 292.807118 -32.752296) (xy 292.806628 -32.722312)
			(xy 277.962735 -32.722312) (xy 277.962378 -32.744152) (xy 277.954555 -32.803574) (xy 277.939042 -32.861467)
			(xy 277.916106 -32.91684) (xy 277.886139 -32.968746) (xy 277.849652 -33.016296) (xy 277.807272 -33.058676)
			(xy 277.759722 -33.095163) (xy 277.707816 -33.12513) (xy 277.652443 -33.148066) (xy 277.59455 -33.163579)
			(xy 277.535128 -33.171402) (xy 277.475192 -33.171402) (xy 277.41577 -33.163579) (xy 277.357877 -33.148066)
			(xy 277.302504 -33.12513) (xy 277.250598 -33.095163) (xy 277.203048 -33.058676) (xy 277.160668 -33.016296)
			(xy 277.124181 -32.968746) (xy 277.094214 -32.91684) (xy 277.071278 -32.861467) (xy 277.055765 -32.803574)
			(xy 277.047942 -32.744152) (xy 277.047452 -32.714184) (xy 267.722604 -32.714184) (xy 267.722604 -32.722312)
			(xy 267.722114 -32.752296) (xy 267.714286 -32.811752) (xy 267.698765 -32.869677) (xy 267.675816 -32.925081)
			(xy 267.645832 -32.977015) (xy 267.609326 -33.024591) (xy 267.566921 -33.066996) (xy 267.519345 -33.103502)
			(xy 267.467411 -33.133486) (xy 267.412007 -33.156435) (xy 267.354082 -33.171956) (xy 267.294626 -33.179784)
			(xy 267.234658 -33.179784) (xy 267.175202 -33.171956) (xy 267.117277 -33.156435) (xy 267.061873 -33.133486)
			(xy 267.009939 -33.103502) (xy 266.962363 -33.066996) (xy 266.919958 -33.024591) (xy 266.883452 -32.977015)
			(xy 266.853468 -32.925081) (xy 266.830519 -32.869677) (xy 266.814998 -32.811752) (xy 266.80717 -32.752296)
			(xy 266.80668 -32.722312) (xy 251.962787 -32.722312) (xy 251.96243 -32.744152) (xy 251.954607 -32.803574)
			(xy 251.939094 -32.861467) (xy 251.916158 -32.91684) (xy 251.886191 -32.968746) (xy 251.849704 -33.016296)
			(xy 251.807324 -33.058676) (xy 251.759774 -33.095163) (xy 251.707868 -33.12513) (xy 251.652495 -33.148066)
			(xy 251.594602 -33.163579) (xy 251.53518 -33.171402) (xy 251.475244 -33.171402) (xy 251.415822 -33.163579)
			(xy 251.357929 -33.148066) (xy 251.302556 -33.12513) (xy 251.25065 -33.095163) (xy 251.2031 -33.058676)
			(xy 251.16072 -33.016296) (xy 251.124233 -32.968746) (xy 251.094266 -32.91684) (xy 251.07133 -32.861467)
			(xy 251.055817 -32.803574) (xy 251.047994 -32.744152) (xy 251.047504 -32.714184) (xy 241.722656 -32.714184)
			(xy 241.722656 -32.722312) (xy 241.722166 -32.752296) (xy 241.714338 -32.811752) (xy 241.698817 -32.869677)
			(xy 241.675868 -32.925081) (xy 241.645884 -32.977015) (xy 241.609378 -33.024591) (xy 241.566973 -33.066996)
			(xy 241.519397 -33.103502) (xy 241.467463 -33.133486) (xy 241.412059 -33.156435) (xy 241.354134 -33.171956)
			(xy 241.294678 -33.179784) (xy 241.23471 -33.179784) (xy 241.175254 -33.171956) (xy 241.117329 -33.156435)
			(xy 241.061925 -33.133486) (xy 241.009991 -33.103502) (xy 240.962415 -33.066996) (xy 240.92001 -33.024591)
			(xy 240.883504 -32.977015) (xy 240.85352 -32.925081) (xy 240.830571 -32.869677) (xy 240.81505 -32.811752)
			(xy 240.807222 -32.752296) (xy 240.806732 -32.722312) (xy 213.862787 -32.722312) (xy 213.86243 -32.744152)
			(xy 213.854607 -32.803574) (xy 213.839094 -32.861467) (xy 213.816158 -32.91684) (xy 213.786191 -32.968746)
			(xy 213.749704 -33.016296) (xy 213.707324 -33.058676) (xy 213.659774 -33.095163) (xy 213.607868 -33.12513)
			(xy 213.552495 -33.148066) (xy 213.494602 -33.163579) (xy 213.43518 -33.171402) (xy 213.375244 -33.171402)
			(xy 213.315822 -33.163579) (xy 213.257929 -33.148066) (xy 213.202556 -33.12513) (xy 213.15065 -33.095163)
			(xy 213.1031 -33.058676) (xy 213.06072 -33.016296) (xy 213.024233 -32.968746) (xy 212.994266 -32.91684)
			(xy 212.97133 -32.861467) (xy 212.955817 -32.803574) (xy 212.947994 -32.744152) (xy 212.947504 -32.714184)
			(xy 203.622656 -32.714184) (xy 203.622656 -32.722312) (xy 203.622166 -32.752296) (xy 203.614338 -32.811752)
			(xy 203.598817 -32.869677) (xy 203.575868 -32.925081) (xy 203.545884 -32.977015) (xy 203.509378 -33.024591)
			(xy 203.466973 -33.066996) (xy 203.419397 -33.103502) (xy 203.367463 -33.133486) (xy 203.312059 -33.156435)
			(xy 203.254134 -33.171956) (xy 203.194678 -33.179784) (xy 203.13471 -33.179784) (xy 203.075254 -33.171956)
			(xy 203.017329 -33.156435) (xy 202.961925 -33.133486) (xy 202.909991 -33.103502) (xy 202.862415 -33.066996)
			(xy 202.82001 -33.024591) (xy 202.783504 -32.977015) (xy 202.75352 -32.925081) (xy 202.730571 -32.869677)
			(xy 202.71505 -32.811752) (xy 202.707222 -32.752296) (xy 202.706732 -32.722312) (xy 187.862839 -32.722312)
			(xy 187.862482 -32.744152) (xy 187.854659 -32.803574) (xy 187.839146 -32.861467) (xy 187.81621 -32.91684)
			(xy 187.786243 -32.968746) (xy 187.749756 -33.016296) (xy 187.707376 -33.058676) (xy 187.659826 -33.095163)
			(xy 187.60792 -33.12513) (xy 187.552547 -33.148066) (xy 187.494654 -33.163579) (xy 187.435232 -33.171402)
			(xy 187.375296 -33.171402) (xy 187.315874 -33.163579) (xy 187.257981 -33.148066) (xy 187.202608 -33.12513)
			(xy 187.150702 -33.095163) (xy 187.103152 -33.058676) (xy 187.060772 -33.016296) (xy 187.024285 -32.968746)
			(xy 186.994318 -32.91684) (xy 186.971382 -32.861467) (xy 186.955869 -32.803574) (xy 186.948046 -32.744152)
			(xy 186.947556 -32.714184) (xy 177.622708 -32.714184) (xy 177.622708 -32.722312) (xy 177.622218 -32.752296)
			(xy 177.61439 -32.811752) (xy 177.598869 -32.869677) (xy 177.57592 -32.925081) (xy 177.545936 -32.977015)
			(xy 177.50943 -33.024591) (xy 177.467025 -33.066996) (xy 177.419449 -33.103502) (xy 177.367515 -33.133486)
			(xy 177.312111 -33.156435) (xy 177.254186 -33.171956) (xy 177.19473 -33.179784) (xy 177.134762 -33.179784)
			(xy 177.075306 -33.171956) (xy 177.017381 -33.156435) (xy 176.961977 -33.133486) (xy 176.910043 -33.103502)
			(xy 176.862467 -33.066996) (xy 176.820062 -33.024591) (xy 176.783556 -32.977015) (xy 176.753572 -32.925081)
			(xy 176.730623 -32.869677) (xy 176.715102 -32.811752) (xy 176.707274 -32.752296) (xy 176.706784 -32.722312)
			(xy 161.862891 -32.722312) (xy 161.862534 -32.744152) (xy 161.854711 -32.803574) (xy 161.839198 -32.861467)
			(xy 161.816262 -32.91684) (xy 161.786295 -32.968746) (xy 161.749808 -33.016296) (xy 161.707428 -33.058676)
			(xy 161.659878 -33.095163) (xy 161.607972 -33.12513) (xy 161.552599 -33.148066) (xy 161.494706 -33.163579)
			(xy 161.435284 -33.171402) (xy 161.375348 -33.171402) (xy 161.315926 -33.163579) (xy 161.258033 -33.148066)
			(xy 161.20266 -33.12513) (xy 161.150754 -33.095163) (xy 161.103204 -33.058676) (xy 161.060824 -33.016296)
			(xy 161.024337 -32.968746) (xy 160.99437 -32.91684) (xy 160.971434 -32.861467) (xy 160.955921 -32.803574)
			(xy 160.948098 -32.744152) (xy 160.947608 -32.714184) (xy 151.62276 -32.714184) (xy 151.62276 -32.722312)
			(xy 151.62227 -32.752296) (xy 151.614442 -32.811752) (xy 151.598921 -32.869677) (xy 151.575972 -32.925081)
			(xy 151.545988 -32.977015) (xy 151.509482 -33.024591) (xy 151.467077 -33.066996) (xy 151.419501 -33.103502)
			(xy 151.367567 -33.133486) (xy 151.312163 -33.156435) (xy 151.254238 -33.171956) (xy 151.194782 -33.179784)
			(xy 151.134814 -33.179784) (xy 151.075358 -33.171956) (xy 151.017433 -33.156435) (xy 150.962029 -33.133486)
			(xy 150.910095 -33.103502) (xy 150.862519 -33.066996) (xy 150.820114 -33.024591) (xy 150.783608 -32.977015)
			(xy 150.753624 -32.925081) (xy 150.730675 -32.869677) (xy 150.715154 -32.811752) (xy 150.707326 -32.752296)
			(xy 150.706836 -32.722312) (xy 135.862943 -32.722312) (xy 135.862586 -32.744152) (xy 135.854763 -32.803574)
			(xy 135.83925 -32.861467) (xy 135.816314 -32.91684) (xy 135.786347 -32.968746) (xy 135.74986 -33.016296)
			(xy 135.70748 -33.058676) (xy 135.65993 -33.095163) (xy 135.608024 -33.12513) (xy 135.552651 -33.148066)
			(xy 135.494758 -33.163579) (xy 135.435336 -33.171402) (xy 135.3754 -33.171402) (xy 135.315978 -33.163579)
			(xy 135.258085 -33.148066) (xy 135.202712 -33.12513) (xy 135.150806 -33.095163) (xy 135.103256 -33.058676)
			(xy 135.060876 -33.016296) (xy 135.024389 -32.968746) (xy 134.994422 -32.91684) (xy 134.971486 -32.861467)
			(xy 134.955973 -32.803574) (xy 134.94815 -32.744152) (xy 134.94766 -32.714184) (xy 125.622812 -32.714184)
			(xy 125.622812 -32.722312) (xy 125.622322 -32.752296) (xy 125.614494 -32.811752) (xy 125.598973 -32.869677)
			(xy 125.576024 -32.925081) (xy 125.54604 -32.977015) (xy 125.509534 -33.024591) (xy 125.467129 -33.066996)
			(xy 125.419553 -33.103502) (xy 125.367619 -33.133486) (xy 125.312215 -33.156435) (xy 125.25429 -33.171956)
			(xy 125.194834 -33.179784) (xy 125.134866 -33.179784) (xy 125.07541 -33.171956) (xy 125.017485 -33.156435)
			(xy 124.962081 -33.133486) (xy 124.910147 -33.103502) (xy 124.862571 -33.066996) (xy 124.820166 -33.024591)
			(xy 124.78366 -32.977015) (xy 124.753676 -32.925081) (xy 124.730727 -32.869677) (xy 124.715206 -32.811752)
			(xy 124.707378 -32.752296) (xy 124.706888 -32.722312) (xy 97.762943 -32.722312) (xy 97.762586 -32.744168)
			(xy 97.754758 -32.803624) (xy 97.739237 -32.861549) (xy 97.716288 -32.916953) (xy 97.686304 -32.968887)
			(xy 97.649798 -33.016463) (xy 97.607393 -33.058868) (xy 97.559817 -33.095374) (xy 97.507883 -33.125358)
			(xy 97.452479 -33.148307) (xy 97.394554 -33.163828) (xy 97.335098 -33.171656) (xy 97.27513 -33.171656)
			(xy 97.215674 -33.163828) (xy 97.157749 -33.148307) (xy 97.102345 -33.125358) (xy 97.050411 -33.095374)
			(xy 97.002835 -33.058868) (xy 96.96043 -33.016463) (xy 96.923924 -32.968887) (xy 96.89394 -32.916953)
			(xy 96.870991 -32.861549) (xy 96.85547 -32.803624) (xy 96.847642 -32.744168) (xy 96.847152 -32.714184)
			(xy 87.522304 -32.714184) (xy 87.522304 -32.722312) (xy 87.521814 -32.75228) (xy 87.513991 -32.811702)
			(xy 87.498478 -32.869595) (xy 87.475542 -32.924968) (xy 87.445575 -32.976874) (xy 87.409088 -33.024424)
			(xy 87.366708 -33.066804) (xy 87.319158 -33.103291) (xy 87.267252 -33.133258) (xy 87.211879 -33.156194)
			(xy 87.153986 -33.171707) (xy 87.094564 -33.17953) (xy 87.034628 -33.17953) (xy 86.975206 -33.171707)
			(xy 86.917313 -33.156194) (xy 86.86194 -33.133258) (xy 86.810034 -33.103291) (xy 86.762484 -33.066804)
			(xy 86.720104 -33.024424) (xy 86.683617 -32.976874) (xy 86.65365 -32.924968) (xy 86.630714 -32.869595)
			(xy 86.615201 -32.811702) (xy 86.607378 -32.75228) (xy 86.606888 -32.722312) (xy 71.762995 -32.722312)
			(xy 71.762638 -32.744168) (xy 71.75481 -32.803624) (xy 71.739289 -32.861549) (xy 71.71634 -32.916953)
			(xy 71.686356 -32.968887) (xy 71.64985 -33.016463) (xy 71.607445 -33.058868) (xy 71.559869 -33.095374)
			(xy 71.507935 -33.125358) (xy 71.452531 -33.148307) (xy 71.394606 -33.163828) (xy 71.33515 -33.171656)
			(xy 71.275182 -33.171656) (xy 71.215726 -33.163828) (xy 71.157801 -33.148307) (xy 71.102397 -33.125358)
			(xy 71.050463 -33.095374) (xy 71.002887 -33.058868) (xy 70.960482 -33.016463) (xy 70.923976 -32.968887)
			(xy 70.893992 -32.916953) (xy 70.871043 -32.861549) (xy 70.855522 -32.803624) (xy 70.847694 -32.744168)
			(xy 70.847204 -32.714184) (xy 61.522356 -32.714184) (xy 61.522356 -32.722312) (xy 61.521866 -32.75228)
			(xy 61.514043 -32.811702) (xy 61.49853 -32.869595) (xy 61.475594 -32.924968) (xy 61.445627 -32.976874)
			(xy 61.40914 -33.024424) (xy 61.36676 -33.066804) (xy 61.31921 -33.103291) (xy 61.267304 -33.133258)
			(xy 61.211931 -33.156194) (xy 61.154038 -33.171707) (xy 61.094616 -33.17953) (xy 61.03468 -33.17953)
			(xy 60.975258 -33.171707) (xy 60.917365 -33.156194) (xy 60.861992 -33.133258) (xy 60.810086 -33.103291)
			(xy 60.762536 -33.066804) (xy 60.720156 -33.024424) (xy 60.683669 -32.976874) (xy 60.653702 -32.924968)
			(xy 60.630766 -32.869595) (xy 60.615253 -32.811702) (xy 60.60743 -32.75228) (xy 60.60694 -32.722312)
			(xy 45.763047 -32.722312) (xy 45.76269 -32.744168) (xy 45.754862 -32.803624) (xy 45.739341 -32.861549)
			(xy 45.716392 -32.916953) (xy 45.686408 -32.968887) (xy 45.649902 -33.016463) (xy 45.607497 -33.058868)
			(xy 45.559921 -33.095374) (xy 45.507987 -33.125358) (xy 45.452583 -33.148307) (xy 45.394658 -33.163828)
			(xy 45.335202 -33.171656) (xy 45.275234 -33.171656) (xy 45.215778 -33.163828) (xy 45.157853 -33.148307)
			(xy 45.102449 -33.125358) (xy 45.050515 -33.095374) (xy 45.002939 -33.058868) (xy 44.960534 -33.016463)
			(xy 44.924028 -32.968887) (xy 44.894044 -32.916953) (xy 44.871095 -32.861549) (xy 44.855574 -32.803624)
			(xy 44.847746 -32.744168) (xy 44.847256 -32.714184) (xy 35.522408 -32.714184) (xy 35.522408 -32.722312)
			(xy 35.521918 -32.75228) (xy 35.514095 -32.811702) (xy 35.498582 -32.869595) (xy 35.475646 -32.924968)
			(xy 35.445679 -32.976874) (xy 35.409192 -33.024424) (xy 35.366812 -33.066804) (xy 35.319262 -33.103291)
			(xy 35.267356 -33.133258) (xy 35.211983 -33.156194) (xy 35.15409 -33.171707) (xy 35.094668 -33.17953)
			(xy 35.034732 -33.17953) (xy 34.97531 -33.171707) (xy 34.917417 -33.156194) (xy 34.862044 -33.133258)
			(xy 34.810138 -33.103291) (xy 34.762588 -33.066804) (xy 34.720208 -33.024424) (xy 34.683721 -32.976874)
			(xy 34.653754 -32.924968) (xy 34.630818 -32.869595) (xy 34.615305 -32.811702) (xy 34.607482 -32.75228)
			(xy 34.606992 -32.722312) (xy 19.763099 -32.722312) (xy 19.762742 -32.744168) (xy 19.754914 -32.803624)
			(xy 19.739393 -32.861549) (xy 19.716444 -32.916953) (xy 19.68646 -32.968887) (xy 19.649954 -33.016463)
			(xy 19.607549 -33.058868) (xy 19.559973 -33.095374) (xy 19.508039 -33.125358) (xy 19.452635 -33.148307)
			(xy 19.39471 -33.163828) (xy 19.335254 -33.171656) (xy 19.275286 -33.171656) (xy 19.21583 -33.163828)
			(xy 19.157905 -33.148307) (xy 19.102501 -33.125358) (xy 19.050567 -33.095374) (xy 19.002991 -33.058868)
			(xy 18.960586 -33.016463) (xy 18.92408 -32.968887) (xy 18.894096 -32.916953) (xy 18.871147 -32.861549)
			(xy 18.855626 -32.803624) (xy 18.847798 -32.744168) (xy 18.847308 -32.714184) (xy 9.52246 -32.714184)
			(xy 9.52246 -32.722312) (xy 9.52197 -32.75228) (xy 9.514147 -32.811702) (xy 9.498634 -32.869595)
			(xy 9.475698 -32.924968) (xy 9.445731 -32.976874) (xy 9.409244 -33.024424) (xy 9.366864 -33.066804)
			(xy 9.319314 -33.103291) (xy 9.267408 -33.133258) (xy 9.212035 -33.156194) (xy 9.154142 -33.171707)
			(xy 9.09472 -33.17953) (xy 9.034784 -33.17953) (xy 8.975362 -33.171707) (xy 8.917469 -33.156194)
			(xy 8.862096 -33.133258) (xy 8.81019 -33.103291) (xy 8.76264 -33.066804) (xy 8.72026 -33.024424)
			(xy 8.683773 -32.976874) (xy 8.653806 -32.924968) (xy 8.63087 -32.869595) (xy 8.615357 -32.811702)
			(xy 8.607534 -32.75228) (xy 8.607044 -32.722312) (xy 1.524 -32.722312) (xy 1.524 -34.52241) (xy 6.752844 -34.52241)
			(xy 6.752844 -33.65881) (xy 6.753334 -33.628842) (xy 6.761157 -33.56942) (xy 6.77667 -33.511527)
			(xy 6.799606 -33.456154) (xy 6.829573 -33.404248) (xy 6.86606 -33.356698) (xy 6.90844 -33.314318)
			(xy 6.95599 -33.277831) (xy 7.007896 -33.247864) (xy 7.063269 -33.224928) (xy 7.121162 -33.209415)
			(xy 7.180584 -33.201592) (xy 7.24052 -33.201592) (xy 7.299942 -33.209415) (xy 7.357835 -33.224928)
			(xy 7.413208 -33.247864) (xy 7.465114 -33.277831) (xy 7.512664 -33.314318) (xy 7.555044 -33.356698)
			(xy 7.591531 -33.404248) (xy 7.621498 -33.456154) (xy 7.644434 -33.511527) (xy 7.659947 -33.56942)
			(xy 7.66777 -33.628842) (xy 7.66826 -33.65881) (xy 7.66826 -34.520886) (xy 21.489416 -34.520886)
			(xy 21.489416 -33.657286) (xy 21.489906 -33.627302) (xy 21.497734 -33.567846) (xy 21.513255 -33.509921)
			(xy 21.536204 -33.454517) (xy 21.566188 -33.402583) (xy 21.602694 -33.355007) (xy 21.645099 -33.312602)
			(xy 21.692675 -33.276096) (xy 21.744609 -33.246112) (xy 21.800013 -33.223163) (xy 21.857938 -33.207642)
			(xy 21.917394 -33.199814) (xy 21.977362 -33.199814) (xy 22.036818 -33.207642) (xy 22.094743 -33.223163)
			(xy 22.150147 -33.246112) (xy 22.202081 -33.276096) (xy 22.249657 -33.312602) (xy 22.292062 -33.355007)
			(xy 22.328568 -33.402583) (xy 22.358552 -33.454517) (xy 22.381501 -33.509921) (xy 22.397022 -33.567846)
			(xy 22.40485 -33.627302) (xy 22.40534 -33.657286) (xy 22.40534 -34.520886) (xy 22.405315 -34.52241)
			(xy 32.752792 -34.52241) (xy 32.752792 -33.65881) (xy 32.753282 -33.628842) (xy 32.761105 -33.56942)
			(xy 32.776618 -33.511527) (xy 32.799554 -33.456154) (xy 32.829521 -33.404248) (xy 32.866008 -33.356698)
			(xy 32.908388 -33.314318) (xy 32.955938 -33.277831) (xy 33.007844 -33.247864) (xy 33.063217 -33.224928)
			(xy 33.12111 -33.209415) (xy 33.180532 -33.201592) (xy 33.240468 -33.201592) (xy 33.29989 -33.209415)
			(xy 33.357783 -33.224928) (xy 33.413156 -33.247864) (xy 33.465062 -33.277831) (xy 33.512612 -33.314318)
			(xy 33.554992 -33.356698) (xy 33.591479 -33.404248) (xy 33.621446 -33.456154) (xy 33.644382 -33.511527)
			(xy 33.659895 -33.56942) (xy 33.667718 -33.628842) (xy 33.668208 -33.65881) (xy 33.668208 -34.520886)
			(xy 47.489364 -34.520886) (xy 47.489364 -33.657286) (xy 47.489854 -33.627302) (xy 47.497682 -33.567846)
			(xy 47.513203 -33.509921) (xy 47.536152 -33.454517) (xy 47.566136 -33.402583) (xy 47.602642 -33.355007)
			(xy 47.645047 -33.312602) (xy 47.692623 -33.276096) (xy 47.744557 -33.246112) (xy 47.799961 -33.223163)
			(xy 47.857886 -33.207642) (xy 47.917342 -33.199814) (xy 47.97731 -33.199814) (xy 48.036766 -33.207642)
			(xy 48.094691 -33.223163) (xy 48.150095 -33.246112) (xy 48.202029 -33.276096) (xy 48.249605 -33.312602)
			(xy 48.29201 -33.355007) (xy 48.328516 -33.402583) (xy 48.3585 -33.454517) (xy 48.381449 -33.509921)
			(xy 48.39697 -33.567846) (xy 48.404798 -33.627302) (xy 48.405288 -33.657286) (xy 48.405288 -34.520886)
			(xy 48.405263 -34.52241) (xy 58.75274 -34.52241) (xy 58.75274 -33.65881) (xy 58.75323 -33.628842)
			(xy 58.761053 -33.56942) (xy 58.776566 -33.511527) (xy 58.799502 -33.456154) (xy 58.829469 -33.404248)
			(xy 58.865956 -33.356698) (xy 58.908336 -33.314318) (xy 58.955886 -33.277831) (xy 59.007792 -33.247864)
			(xy 59.063165 -33.224928) (xy 59.121058 -33.209415) (xy 59.18048 -33.201592) (xy 59.240416 -33.201592)
			(xy 59.299838 -33.209415) (xy 59.357731 -33.224928) (xy 59.413104 -33.247864) (xy 59.46501 -33.277831)
			(xy 59.51256 -33.314318) (xy 59.55494 -33.356698) (xy 59.591427 -33.404248) (xy 59.621394 -33.456154)
			(xy 59.64433 -33.511527) (xy 59.659843 -33.56942) (xy 59.667666 -33.628842) (xy 59.668156 -33.65881)
			(xy 59.668156 -34.520886) (xy 73.489312 -34.520886) (xy 73.489312 -33.657286) (xy 73.489802 -33.627302)
			(xy 73.49763 -33.567846) (xy 73.513151 -33.509921) (xy 73.5361 -33.454517) (xy 73.566084 -33.402583)
			(xy 73.60259 -33.355007) (xy 73.644995 -33.312602) (xy 73.692571 -33.276096) (xy 73.744505 -33.246112)
			(xy 73.799909 -33.223163) (xy 73.857834 -33.207642) (xy 73.91729 -33.199814) (xy 73.977258 -33.199814)
			(xy 74.036714 -33.207642) (xy 74.094639 -33.223163) (xy 74.150043 -33.246112) (xy 74.201977 -33.276096)
			(xy 74.249553 -33.312602) (xy 74.291958 -33.355007) (xy 74.328464 -33.402583) (xy 74.358448 -33.454517)
			(xy 74.381397 -33.509921) (xy 74.396918 -33.567846) (xy 74.404746 -33.627302) (xy 74.405236 -33.657286)
			(xy 74.405236 -34.520886) (xy 74.405211 -34.52241) (xy 84.752688 -34.52241) (xy 84.752688 -33.65881)
			(xy 84.753178 -33.628842) (xy 84.761001 -33.56942) (xy 84.776514 -33.511527) (xy 84.79945 -33.456154)
			(xy 84.829417 -33.404248) (xy 84.865904 -33.356698) (xy 84.908284 -33.314318) (xy 84.955834 -33.277831)
			(xy 85.00774 -33.247864) (xy 85.063113 -33.224928) (xy 85.121006 -33.209415) (xy 85.180428 -33.201592)
			(xy 85.240364 -33.201592) (xy 85.299786 -33.209415) (xy 85.357679 -33.224928) (xy 85.413052 -33.247864)
			(xy 85.464958 -33.277831) (xy 85.512508 -33.314318) (xy 85.554888 -33.356698) (xy 85.591375 -33.404248)
			(xy 85.621342 -33.456154) (xy 85.644278 -33.511527) (xy 85.659791 -33.56942) (xy 85.667614 -33.628842)
			(xy 85.668104 -33.65881) (xy 85.668104 -34.520886) (xy 99.48926 -34.520886) (xy 99.48926 -33.657286)
			(xy 99.48975 -33.627302) (xy 99.497578 -33.567846) (xy 99.513099 -33.509921) (xy 99.536048 -33.454517)
			(xy 99.566032 -33.402583) (xy 99.602538 -33.355007) (xy 99.644943 -33.312602) (xy 99.692519 -33.276096)
			(xy 99.744453 -33.246112) (xy 99.799857 -33.223163) (xy 99.857782 -33.207642) (xy 99.917238 -33.199814)
			(xy 99.977206 -33.199814) (xy 100.036662 -33.207642) (xy 100.094587 -33.223163) (xy 100.149991 -33.246112)
			(xy 100.201925 -33.276096) (xy 100.249501 -33.312602) (xy 100.291906 -33.355007) (xy 100.328412 -33.402583)
			(xy 100.358396 -33.454517) (xy 100.381345 -33.509921) (xy 100.396866 -33.567846) (xy 100.404694 -33.627302)
			(xy 100.405184 -33.657286) (xy 100.405184 -34.520886) (xy 100.405159 -34.52241) (xy 122.852688 -34.52241)
			(xy 122.852688 -33.65881) (xy 122.853178 -33.628826) (xy 122.861006 -33.56937) (xy 122.876527 -33.511445)
			(xy 122.899476 -33.456041) (xy 122.92946 -33.404107) (xy 122.965966 -33.356531) (xy 123.008371 -33.314126)
			(xy 123.055947 -33.27762) (xy 123.107881 -33.247636) (xy 123.163285 -33.224687) (xy 123.22121 -33.209166)
			(xy 123.280666 -33.201338) (xy 123.340634 -33.201338) (xy 123.40009 -33.209166) (xy 123.458015 -33.224687)
			(xy 123.513419 -33.247636) (xy 123.565353 -33.27762) (xy 123.612929 -33.314126) (xy 123.655334 -33.356531)
			(xy 123.69184 -33.404107) (xy 123.721824 -33.456041) (xy 123.744773 -33.511445) (xy 123.760294 -33.56937)
			(xy 123.768122 -33.628826) (xy 123.768612 -33.65881) (xy 123.768612 -34.520886) (xy 137.589768 -34.520886)
			(xy 137.589768 -33.657286) (xy 137.590258 -33.627318) (xy 137.598081 -33.567896) (xy 137.613594 -33.510003)
			(xy 137.63653 -33.45463) (xy 137.666497 -33.402724) (xy 137.702984 -33.355174) (xy 137.745364 -33.312794)
			(xy 137.792914 -33.276307) (xy 137.84482 -33.24634) (xy 137.900193 -33.223404) (xy 137.958086 -33.207891)
			(xy 138.017508 -33.200068) (xy 138.077444 -33.200068) (xy 138.136866 -33.207891) (xy 138.194759 -33.223404)
			(xy 138.250132 -33.24634) (xy 138.302038 -33.276307) (xy 138.349588 -33.312794) (xy 138.391968 -33.355174)
			(xy 138.428455 -33.402724) (xy 138.458422 -33.45463) (xy 138.481358 -33.510003) (xy 138.496871 -33.567896)
			(xy 138.504694 -33.627318) (xy 138.505184 -33.657286) (xy 138.505184 -34.520886) (xy 138.505159 -34.52241)
			(xy 148.852636 -34.52241) (xy 148.852636 -33.65881) (xy 148.853126 -33.628826) (xy 148.860954 -33.56937)
			(xy 148.876475 -33.511445) (xy 148.899424 -33.456041) (xy 148.929408 -33.404107) (xy 148.965914 -33.356531)
			(xy 149.008319 -33.314126) (xy 149.055895 -33.27762) (xy 149.107829 -33.247636) (xy 149.163233 -33.224687)
			(xy 149.221158 -33.209166) (xy 149.280614 -33.201338) (xy 149.340582 -33.201338) (xy 149.400038 -33.209166)
			(xy 149.457963 -33.224687) (xy 149.513367 -33.247636) (xy 149.565301 -33.27762) (xy 149.612877 -33.314126)
			(xy 149.655282 -33.356531) (xy 149.691788 -33.404107) (xy 149.721772 -33.456041) (xy 149.744721 -33.511445)
			(xy 149.760242 -33.56937) (xy 149.76807 -33.628826) (xy 149.76856 -33.65881) (xy 149.76856 -34.520886)
			(xy 163.589716 -34.520886) (xy 163.589716 -33.657286) (xy 163.590206 -33.627318) (xy 163.598029 -33.567896)
			(xy 163.613542 -33.510003) (xy 163.636478 -33.45463) (xy 163.666445 -33.402724) (xy 163.702932 -33.355174)
			(xy 163.745312 -33.312794) (xy 163.792862 -33.276307) (xy 163.844768 -33.24634) (xy 163.900141 -33.223404)
			(xy 163.958034 -33.207891) (xy 164.017456 -33.200068) (xy 164.077392 -33.200068) (xy 164.136814 -33.207891)
			(xy 164.194707 -33.223404) (xy 164.25008 -33.24634) (xy 164.301986 -33.276307) (xy 164.349536 -33.312794)
			(xy 164.391916 -33.355174) (xy 164.428403 -33.402724) (xy 164.45837 -33.45463) (xy 164.481306 -33.510003)
			(xy 164.496819 -33.567896) (xy 164.504642 -33.627318) (xy 164.505132 -33.657286) (xy 164.505132 -34.520886)
			(xy 164.505107 -34.52241) (xy 174.852584 -34.52241) (xy 174.852584 -33.65881) (xy 174.853074 -33.628826)
			(xy 174.860902 -33.56937) (xy 174.876423 -33.511445) (xy 174.899372 -33.456041) (xy 174.929356 -33.404107)
			(xy 174.965862 -33.356531) (xy 175.008267 -33.314126) (xy 175.055843 -33.27762) (xy 175.107777 -33.247636)
			(xy 175.163181 -33.224687) (xy 175.221106 -33.209166) (xy 175.280562 -33.201338) (xy 175.34053 -33.201338)
			(xy 175.399986 -33.209166) (xy 175.457911 -33.224687) (xy 175.513315 -33.247636) (xy 175.565249 -33.27762)
			(xy 175.612825 -33.314126) (xy 175.65523 -33.356531) (xy 175.691736 -33.404107) (xy 175.72172 -33.456041)
			(xy 175.744669 -33.511445) (xy 175.76019 -33.56937) (xy 175.768018 -33.628826) (xy 175.768508 -33.65881)
			(xy 175.768508 -34.520886) (xy 189.589664 -34.520886) (xy 189.589664 -33.657286) (xy 189.590154 -33.627318)
			(xy 189.597977 -33.567896) (xy 189.61349 -33.510003) (xy 189.636426 -33.45463) (xy 189.666393 -33.402724)
			(xy 189.70288 -33.355174) (xy 189.74526 -33.312794) (xy 189.79281 -33.276307) (xy 189.844716 -33.24634)
			(xy 189.900089 -33.223404) (xy 189.957982 -33.207891) (xy 190.017404 -33.200068) (xy 190.07734 -33.200068)
			(xy 190.136762 -33.207891) (xy 190.194655 -33.223404) (xy 190.250028 -33.24634) (xy 190.301934 -33.276307)
			(xy 190.349484 -33.312794) (xy 190.391864 -33.355174) (xy 190.428351 -33.402724) (xy 190.458318 -33.45463)
			(xy 190.481254 -33.510003) (xy 190.496767 -33.567896) (xy 190.50459 -33.627318) (xy 190.50508 -33.657286)
			(xy 190.50508 -34.520886) (xy 190.505055 -34.52241) (xy 200.852532 -34.52241) (xy 200.852532 -33.65881)
			(xy 200.853022 -33.628826) (xy 200.86085 -33.56937) (xy 200.876371 -33.511445) (xy 200.89932 -33.456041)
			(xy 200.929304 -33.404107) (xy 200.96581 -33.356531) (xy 201.008215 -33.314126) (xy 201.055791 -33.27762)
			(xy 201.107725 -33.247636) (xy 201.163129 -33.224687) (xy 201.221054 -33.209166) (xy 201.28051 -33.201338)
			(xy 201.340478 -33.201338) (xy 201.399934 -33.209166) (xy 201.457859 -33.224687) (xy 201.513263 -33.247636)
			(xy 201.565197 -33.27762) (xy 201.612773 -33.314126) (xy 201.655178 -33.356531) (xy 201.691684 -33.404107)
			(xy 201.721668 -33.456041) (xy 201.744617 -33.511445) (xy 201.760138 -33.56937) (xy 201.767966 -33.628826)
			(xy 201.768456 -33.65881) (xy 201.768456 -34.520886) (xy 215.589612 -34.520886) (xy 215.589612 -33.657286)
			(xy 215.590102 -33.627318) (xy 215.597925 -33.567896) (xy 215.613438 -33.510003) (xy 215.636374 -33.45463)
			(xy 215.666341 -33.402724) (xy 215.702828 -33.355174) (xy 215.745208 -33.312794) (xy 215.792758 -33.276307)
			(xy 215.844664 -33.24634) (xy 215.900037 -33.223404) (xy 215.95793 -33.207891) (xy 216.017352 -33.200068)
			(xy 216.077288 -33.200068) (xy 216.13671 -33.207891) (xy 216.194603 -33.223404) (xy 216.249976 -33.24634)
			(xy 216.301882 -33.276307) (xy 216.349432 -33.312794) (xy 216.391812 -33.355174) (xy 216.428299 -33.402724)
			(xy 216.458266 -33.45463) (xy 216.481202 -33.510003) (xy 216.496715 -33.567896) (xy 216.504538 -33.627318)
			(xy 216.505028 -33.657286) (xy 216.505028 -34.520886) (xy 216.505003 -34.52241) (xy 238.952532 -34.52241)
			(xy 238.952532 -33.65881) (xy 238.953022 -33.628826) (xy 238.96085 -33.56937) (xy 238.976371 -33.511445)
			(xy 238.99932 -33.456041) (xy 239.029304 -33.404107) (xy 239.06581 -33.356531) (xy 239.108215 -33.314126)
			(xy 239.155791 -33.27762) (xy 239.207725 -33.247636) (xy 239.263129 -33.224687) (xy 239.321054 -33.209166)
			(xy 239.38051 -33.201338) (xy 239.440478 -33.201338) (xy 239.499934 -33.209166) (xy 239.557859 -33.224687)
			(xy 239.613263 -33.247636) (xy 239.665197 -33.27762) (xy 239.712773 -33.314126) (xy 239.755178 -33.356531)
			(xy 239.791684 -33.404107) (xy 239.821668 -33.456041) (xy 239.844617 -33.511445) (xy 239.860138 -33.56937)
			(xy 239.867966 -33.628826) (xy 239.868456 -33.65881) (xy 239.868456 -34.520886) (xy 253.689612 -34.520886)
			(xy 253.689612 -33.657286) (xy 253.690102 -33.627318) (xy 253.697925 -33.567896) (xy 253.713438 -33.510003)
			(xy 253.736374 -33.45463) (xy 253.766341 -33.402724) (xy 253.802828 -33.355174) (xy 253.845208 -33.312794)
			(xy 253.892758 -33.276307) (xy 253.944664 -33.24634) (xy 254.000037 -33.223404) (xy 254.05793 -33.207891)
			(xy 254.117352 -33.200068) (xy 254.177288 -33.200068) (xy 254.23671 -33.207891) (xy 254.294603 -33.223404)
			(xy 254.349976 -33.24634) (xy 254.401882 -33.276307) (xy 254.449432 -33.312794) (xy 254.491812 -33.355174)
			(xy 254.528299 -33.402724) (xy 254.558266 -33.45463) (xy 254.581202 -33.510003) (xy 254.596715 -33.567896)
			(xy 254.604538 -33.627318) (xy 254.605028 -33.657286) (xy 254.605028 -34.520886) (xy 254.605003 -34.52241)
			(xy 264.95248 -34.52241) (xy 264.95248 -33.65881) (xy 264.95297 -33.628826) (xy 264.960798 -33.56937)
			(xy 264.976319 -33.511445) (xy 264.999268 -33.456041) (xy 265.029252 -33.404107) (xy 265.065758 -33.356531)
			(xy 265.108163 -33.314126) (xy 265.155739 -33.27762) (xy 265.207673 -33.247636) (xy 265.263077 -33.224687)
			(xy 265.321002 -33.209166) (xy 265.380458 -33.201338) (xy 265.440426 -33.201338) (xy 265.499882 -33.209166)
			(xy 265.557807 -33.224687) (xy 265.613211 -33.247636) (xy 265.665145 -33.27762) (xy 265.712721 -33.314126)
			(xy 265.755126 -33.356531) (xy 265.791632 -33.404107) (xy 265.821616 -33.456041) (xy 265.844565 -33.511445)
			(xy 265.860086 -33.56937) (xy 265.867914 -33.628826) (xy 265.868404 -33.65881) (xy 265.868404 -34.520886)
			(xy 279.68956 -34.520886) (xy 279.68956 -33.657286) (xy 279.69005 -33.627318) (xy 279.697873 -33.567896)
			(xy 279.713386 -33.510003) (xy 279.736322 -33.45463) (xy 279.766289 -33.402724) (xy 279.802776 -33.355174)
			(xy 279.845156 -33.312794) (xy 279.892706 -33.276307) (xy 279.944612 -33.24634) (xy 279.999985 -33.223404)
			(xy 280.057878 -33.207891) (xy 280.1173 -33.200068) (xy 280.177236 -33.200068) (xy 280.236658 -33.207891)
			(xy 280.294551 -33.223404) (xy 280.349924 -33.24634) (xy 280.40183 -33.276307) (xy 280.44938 -33.312794)
			(xy 280.49176 -33.355174) (xy 280.528247 -33.402724) (xy 280.558214 -33.45463) (xy 280.58115 -33.510003)
			(xy 280.596663 -33.567896) (xy 280.604486 -33.627318) (xy 280.604976 -33.657286) (xy 280.604976 -34.520886)
			(xy 280.604951 -34.52241) (xy 290.952428 -34.52241) (xy 290.952428 -33.65881) (xy 290.952918 -33.628826)
			(xy 290.960746 -33.56937) (xy 290.976267 -33.511445) (xy 290.999216 -33.456041) (xy 291.0292 -33.404107)
			(xy 291.065706 -33.356531) (xy 291.108111 -33.314126) (xy 291.155687 -33.27762) (xy 291.207621 -33.247636)
			(xy 291.263025 -33.224687) (xy 291.32095 -33.209166) (xy 291.380406 -33.201338) (xy 291.440374 -33.201338)
			(xy 291.49983 -33.209166) (xy 291.557755 -33.224687) (xy 291.613159 -33.247636) (xy 291.665093 -33.27762)
			(xy 291.712669 -33.314126) (xy 291.755074 -33.356531) (xy 291.79158 -33.404107) (xy 291.821564 -33.456041)
			(xy 291.844513 -33.511445) (xy 291.860034 -33.56937) (xy 291.867862 -33.628826) (xy 291.868352 -33.65881)
			(xy 291.868352 -34.520886) (xy 305.689508 -34.520886) (xy 305.689508 -33.657286) (xy 305.689998 -33.627318)
			(xy 305.697821 -33.567896) (xy 305.713334 -33.510003) (xy 305.73627 -33.45463) (xy 305.766237 -33.402724)
			(xy 305.802724 -33.355174) (xy 305.845104 -33.312794) (xy 305.892654 -33.276307) (xy 305.94456 -33.24634)
			(xy 305.999933 -33.223404) (xy 306.057826 -33.207891) (xy 306.117248 -33.200068) (xy 306.177184 -33.200068)
			(xy 306.236606 -33.207891) (xy 306.294499 -33.223404) (xy 306.349872 -33.24634) (xy 306.401778 -33.276307)
			(xy 306.449328 -33.312794) (xy 306.491708 -33.355174) (xy 306.528195 -33.402724) (xy 306.558162 -33.45463)
			(xy 306.581098 -33.510003) (xy 306.596611 -33.567896) (xy 306.604434 -33.627318) (xy 306.604924 -33.657286)
			(xy 306.604924 -34.520886) (xy 306.604899 -34.52241) (xy 316.952376 -34.52241) (xy 316.952376 -33.65881)
			(xy 316.952866 -33.628826) (xy 316.960694 -33.56937) (xy 316.976215 -33.511445) (xy 316.999164 -33.456041)
			(xy 317.029148 -33.404107) (xy 317.065654 -33.356531) (xy 317.108059 -33.314126) (xy 317.155635 -33.27762)
			(xy 317.207569 -33.247636) (xy 317.262973 -33.224687) (xy 317.320898 -33.209166) (xy 317.380354 -33.201338)
			(xy 317.440322 -33.201338) (xy 317.499778 -33.209166) (xy 317.557703 -33.224687) (xy 317.613107 -33.247636)
			(xy 317.665041 -33.27762) (xy 317.712617 -33.314126) (xy 317.755022 -33.356531) (xy 317.791528 -33.404107)
			(xy 317.821512 -33.456041) (xy 317.844461 -33.511445) (xy 317.859982 -33.56937) (xy 317.86781 -33.628826)
			(xy 317.8683 -33.65881) (xy 317.8683 -34.520886) (xy 331.689456 -34.520886) (xy 331.689456 -33.657286)
			(xy 331.689946 -33.627318) (xy 331.697769 -33.567896) (xy 331.713282 -33.510003) (xy 331.736218 -33.45463)
			(xy 331.766185 -33.402724) (xy 331.802672 -33.355174) (xy 331.845052 -33.312794) (xy 331.892602 -33.276307)
			(xy 331.944508 -33.24634) (xy 331.999881 -33.223404) (xy 332.057774 -33.207891) (xy 332.117196 -33.200068)
			(xy 332.177132 -33.200068) (xy 332.236554 -33.207891) (xy 332.294447 -33.223404) (xy 332.34982 -33.24634)
			(xy 332.401726 -33.276307) (xy 332.449276 -33.312794) (xy 332.491656 -33.355174) (xy 332.528143 -33.402724)
			(xy 332.55811 -33.45463) (xy 332.581046 -33.510003) (xy 332.596559 -33.567896) (xy 332.604382 -33.627318)
			(xy 332.604872 -33.657286) (xy 332.604872 -34.520886) (xy 332.604847 -34.52241) (xy 355.052884 -34.52241)
			(xy 355.052884 -33.65881) (xy 355.053374 -33.628842) (xy 355.061197 -33.56942) (xy 355.07671 -33.511527)
			(xy 355.099646 -33.456154) (xy 355.129613 -33.404248) (xy 355.1661 -33.356698) (xy 355.20848 -33.314318)
			(xy 355.25603 -33.277831) (xy 355.307936 -33.247864) (xy 355.363309 -33.224928) (xy 355.421202 -33.209415)
			(xy 355.480624 -33.201592) (xy 355.54056 -33.201592) (xy 355.599982 -33.209415) (xy 355.657875 -33.224928)
			(xy 355.713248 -33.247864) (xy 355.765154 -33.277831) (xy 355.812704 -33.314318) (xy 355.855084 -33.356698)
			(xy 355.891571 -33.404248) (xy 355.921538 -33.456154) (xy 355.944474 -33.511527) (xy 355.959987 -33.56942)
			(xy 355.96781 -33.628842) (xy 355.9683 -33.65881) (xy 355.9683 -34.520886) (xy 369.789456 -34.520886)
			(xy 369.789456 -33.657286) (xy 369.789946 -33.627302) (xy 369.797774 -33.567846) (xy 369.813295 -33.509921)
			(xy 369.836244 -33.454517) (xy 369.866228 -33.402583) (xy 369.902734 -33.355007) (xy 369.945139 -33.312602)
			(xy 369.992715 -33.276096) (xy 370.044649 -33.246112) (xy 370.100053 -33.223163) (xy 370.157978 -33.207642)
			(xy 370.217434 -33.199814) (xy 370.277402 -33.199814) (xy 370.336858 -33.207642) (xy 370.394783 -33.223163)
			(xy 370.450187 -33.246112) (xy 370.502121 -33.276096) (xy 370.549697 -33.312602) (xy 370.592102 -33.355007)
			(xy 370.628608 -33.402583) (xy 370.658592 -33.454517) (xy 370.681541 -33.509921) (xy 370.697062 -33.567846)
			(xy 370.70489 -33.627302) (xy 370.70538 -33.657286) (xy 370.70538 -34.520886) (xy 370.705355 -34.52241)
			(xy 381.052832 -34.52241) (xy 381.052832 -33.65881) (xy 381.053322 -33.628842) (xy 381.061145 -33.56942)
			(xy 381.076658 -33.511527) (xy 381.099594 -33.456154) (xy 381.129561 -33.404248) (xy 381.166048 -33.356698)
			(xy 381.208428 -33.314318) (xy 381.255978 -33.277831) (xy 381.307884 -33.247864) (xy 381.363257 -33.224928)
			(xy 381.42115 -33.209415) (xy 381.480572 -33.201592) (xy 381.540508 -33.201592) (xy 381.59993 -33.209415)
			(xy 381.657823 -33.224928) (xy 381.713196 -33.247864) (xy 381.765102 -33.277831) (xy 381.812652 -33.314318)
			(xy 381.855032 -33.356698) (xy 381.891519 -33.404248) (xy 381.921486 -33.456154) (xy 381.944422 -33.511527)
			(xy 381.959935 -33.56942) (xy 381.967758 -33.628842) (xy 381.968248 -33.65881) (xy 381.968248 -34.520886)
			(xy 395.789404 -34.520886) (xy 395.789404 -33.657286) (xy 395.789894 -33.627302) (xy 395.797722 -33.567846)
			(xy 395.813243 -33.509921) (xy 395.836192 -33.454517) (xy 395.866176 -33.402583) (xy 395.902682 -33.355007)
			(xy 395.945087 -33.312602) (xy 395.992663 -33.276096) (xy 396.044597 -33.246112) (xy 396.100001 -33.223163)
			(xy 396.157926 -33.207642) (xy 396.217382 -33.199814) (xy 396.27735 -33.199814) (xy 396.336806 -33.207642)
			(xy 396.394731 -33.223163) (xy 396.450135 -33.246112) (xy 396.502069 -33.276096) (xy 396.549645 -33.312602)
			(xy 396.59205 -33.355007) (xy 396.628556 -33.402583) (xy 396.65854 -33.454517) (xy 396.681489 -33.509921)
			(xy 396.69701 -33.567846) (xy 396.704838 -33.627302) (xy 396.705328 -33.657286) (xy 396.705328 -34.520886)
			(xy 396.705303 -34.52241) (xy 407.05278 -34.52241) (xy 407.05278 -33.65881) (xy 407.05327 -33.628842)
			(xy 407.061093 -33.56942) (xy 407.076606 -33.511527) (xy 407.099542 -33.456154) (xy 407.129509 -33.404248)
			(xy 407.165996 -33.356698) (xy 407.208376 -33.314318) (xy 407.255926 -33.277831) (xy 407.307832 -33.247864)
			(xy 407.363205 -33.224928) (xy 407.421098 -33.209415) (xy 407.48052 -33.201592) (xy 407.540456 -33.201592)
			(xy 407.599878 -33.209415) (xy 407.657771 -33.224928) (xy 407.713144 -33.247864) (xy 407.76505 -33.277831)
			(xy 407.8126 -33.314318) (xy 407.85498 -33.356698) (xy 407.891467 -33.404248) (xy 407.921434 -33.456154)
			(xy 407.94437 -33.511527) (xy 407.959883 -33.56942) (xy 407.967706 -33.628842) (xy 407.968196 -33.65881)
			(xy 407.968196 -34.520886) (xy 421.789352 -34.520886) (xy 421.789352 -33.657286) (xy 421.789842 -33.627302)
			(xy 421.79767 -33.567846) (xy 421.813191 -33.509921) (xy 421.83614 -33.454517) (xy 421.866124 -33.402583)
			(xy 421.90263 -33.355007) (xy 421.945035 -33.312602) (xy 421.992611 -33.276096) (xy 422.044545 -33.246112)
			(xy 422.099949 -33.223163) (xy 422.157874 -33.207642) (xy 422.21733 -33.199814) (xy 422.277298 -33.199814)
			(xy 422.336754 -33.207642) (xy 422.394679 -33.223163) (xy 422.450083 -33.246112) (xy 422.502017 -33.276096)
			(xy 422.549593 -33.312602) (xy 422.591998 -33.355007) (xy 422.628504 -33.402583) (xy 422.658488 -33.454517)
			(xy 422.681437 -33.509921) (xy 422.696958 -33.567846) (xy 422.704786 -33.627302) (xy 422.705276 -33.657286)
			(xy 422.705276 -34.520886) (xy 422.705251 -34.52241) (xy 433.052728 -34.52241) (xy 433.052728 -33.65881)
			(xy 433.053218 -33.628842) (xy 433.061041 -33.56942) (xy 433.076554 -33.511527) (xy 433.09949 -33.456154)
			(xy 433.129457 -33.404248) (xy 433.165944 -33.356698) (xy 433.208324 -33.314318) (xy 433.255874 -33.277831)
			(xy 433.30778 -33.247864) (xy 433.363153 -33.224928) (xy 433.421046 -33.209415) (xy 433.480468 -33.201592)
			(xy 433.540404 -33.201592) (xy 433.599826 -33.209415) (xy 433.657719 -33.224928) (xy 433.713092 -33.247864)
			(xy 433.764998 -33.277831) (xy 433.812548 -33.314318) (xy 433.854928 -33.356698) (xy 433.891415 -33.404248)
			(xy 433.921382 -33.456154) (xy 433.944318 -33.511527) (xy 433.959831 -33.56942) (xy 433.967654 -33.628842)
			(xy 433.968144 -33.65881) (xy 433.968144 -34.520886) (xy 447.7893 -34.520886) (xy 447.7893 -33.657286)
			(xy 447.78979 -33.627302) (xy 447.797618 -33.567846) (xy 447.813139 -33.509921) (xy 447.836088 -33.454517)
			(xy 447.866072 -33.402583) (xy 447.902578 -33.355007) (xy 447.944983 -33.312602) (xy 447.992559 -33.276096)
			(xy 448.044493 -33.246112) (xy 448.099897 -33.223163) (xy 448.157822 -33.207642) (xy 448.217278 -33.199814)
			(xy 448.277246 -33.199814) (xy 448.336702 -33.207642) (xy 448.394627 -33.223163) (xy 448.450031 -33.246112)
			(xy 448.501965 -33.276096) (xy 448.549541 -33.312602) (xy 448.591946 -33.355007) (xy 448.628452 -33.402583)
			(xy 448.658436 -33.454517) (xy 448.681385 -33.509921) (xy 448.696906 -33.567846) (xy 448.704734 -33.627302)
			(xy 448.705224 -33.657286) (xy 448.705224 -34.520886) (xy 448.704734 -34.55087) (xy 448.696906 -34.610326)
			(xy 448.681385 -34.668251) (xy 448.658436 -34.723655) (xy 448.628452 -34.775589) (xy 448.591946 -34.823165)
			(xy 448.549541 -34.86557) (xy 448.501965 -34.902076) (xy 448.450031 -34.93206) (xy 448.394627 -34.955009)
			(xy 448.336702 -34.97053) (xy 448.277246 -34.978358) (xy 448.217278 -34.978358) (xy 448.157822 -34.97053)
			(xy 448.099897 -34.955009) (xy 448.044493 -34.93206) (xy 447.992559 -34.902076) (xy 447.944983 -34.86557)
			(xy 447.902578 -34.823165) (xy 447.866072 -34.775589) (xy 447.836088 -34.723655) (xy 447.813139 -34.668251)
			(xy 447.797618 -34.610326) (xy 447.78979 -34.55087) (xy 447.7893 -34.520886) (xy 433.968144 -34.520886)
			(xy 433.968144 -34.52241) (xy 433.967654 -34.552378) (xy 433.959831 -34.6118) (xy 433.944318 -34.669693)
			(xy 433.921382 -34.725066) (xy 433.891415 -34.776972) (xy 433.854928 -34.824522) (xy 433.812548 -34.866902)
			(xy 433.764998 -34.903389) (xy 433.713092 -34.933356) (xy 433.657719 -34.956292) (xy 433.599826 -34.971805)
			(xy 433.540404 -34.979628) (xy 433.480468 -34.979628) (xy 433.421046 -34.971805) (xy 433.363153 -34.956292)
			(xy 433.30778 -34.933356) (xy 433.255874 -34.903389) (xy 433.208324 -34.866902) (xy 433.165944 -34.824522)
			(xy 433.129457 -34.776972) (xy 433.09949 -34.725066) (xy 433.076554 -34.669693) (xy 433.061041 -34.6118)
			(xy 433.053218 -34.552378) (xy 433.052728 -34.52241) (xy 422.705251 -34.52241) (xy 422.704786 -34.55087)
			(xy 422.696958 -34.610326) (xy 422.681437 -34.668251) (xy 422.658488 -34.723655) (xy 422.628504 -34.775589)
			(xy 422.591998 -34.823165) (xy 422.549593 -34.86557) (xy 422.502017 -34.902076) (xy 422.450083 -34.93206)
			(xy 422.394679 -34.955009) (xy 422.336754 -34.97053) (xy 422.277298 -34.978358) (xy 422.21733 -34.978358)
			(xy 422.157874 -34.97053) (xy 422.099949 -34.955009) (xy 422.044545 -34.93206) (xy 421.992611 -34.902076)
			(xy 421.945035 -34.86557) (xy 421.90263 -34.823165) (xy 421.866124 -34.775589) (xy 421.83614 -34.723655)
			(xy 421.813191 -34.668251) (xy 421.79767 -34.610326) (xy 421.789842 -34.55087) (xy 421.789352 -34.520886)
			(xy 407.968196 -34.520886) (xy 407.968196 -34.52241) (xy 407.967706 -34.552378) (xy 407.959883 -34.6118)
			(xy 407.94437 -34.669693) (xy 407.921434 -34.725066) (xy 407.891467 -34.776972) (xy 407.85498 -34.824522)
			(xy 407.8126 -34.866902) (xy 407.76505 -34.903389) (xy 407.713144 -34.933356) (xy 407.657771 -34.956292)
			(xy 407.599878 -34.971805) (xy 407.540456 -34.979628) (xy 407.48052 -34.979628) (xy 407.421098 -34.971805)
			(xy 407.363205 -34.956292) (xy 407.307832 -34.933356) (xy 407.255926 -34.903389) (xy 407.208376 -34.866902)
			(xy 407.165996 -34.824522) (xy 407.129509 -34.776972) (xy 407.099542 -34.725066) (xy 407.076606 -34.669693)
			(xy 407.061093 -34.6118) (xy 407.05327 -34.552378) (xy 407.05278 -34.52241) (xy 396.705303 -34.52241)
			(xy 396.704838 -34.55087) (xy 396.69701 -34.610326) (xy 396.681489 -34.668251) (xy 396.65854 -34.723655)
			(xy 396.628556 -34.775589) (xy 396.59205 -34.823165) (xy 396.549645 -34.86557) (xy 396.502069 -34.902076)
			(xy 396.450135 -34.93206) (xy 396.394731 -34.955009) (xy 396.336806 -34.97053) (xy 396.27735 -34.978358)
			(xy 396.217382 -34.978358) (xy 396.157926 -34.97053) (xy 396.100001 -34.955009) (xy 396.044597 -34.93206)
			(xy 395.992663 -34.902076) (xy 395.945087 -34.86557) (xy 395.902682 -34.823165) (xy 395.866176 -34.775589)
			(xy 395.836192 -34.723655) (xy 395.813243 -34.668251) (xy 395.797722 -34.610326) (xy 395.789894 -34.55087)
			(xy 395.789404 -34.520886) (xy 381.968248 -34.520886) (xy 381.968248 -34.52241) (xy 381.967758 -34.552378)
			(xy 381.959935 -34.6118) (xy 381.944422 -34.669693) (xy 381.921486 -34.725066) (xy 381.891519 -34.776972)
			(xy 381.855032 -34.824522) (xy 381.812652 -34.866902) (xy 381.765102 -34.903389) (xy 381.713196 -34.933356)
			(xy 381.657823 -34.956292) (xy 381.59993 -34.971805) (xy 381.540508 -34.979628) (xy 381.480572 -34.979628)
			(xy 381.42115 -34.971805) (xy 381.363257 -34.956292) (xy 381.307884 -34.933356) (xy 381.255978 -34.903389)
			(xy 381.208428 -34.866902) (xy 381.166048 -34.824522) (xy 381.129561 -34.776972) (xy 381.099594 -34.725066)
			(xy 381.076658 -34.669693) (xy 381.061145 -34.6118) (xy 381.053322 -34.552378) (xy 381.052832 -34.52241)
			(xy 370.705355 -34.52241) (xy 370.70489 -34.55087) (xy 370.697062 -34.610326) (xy 370.681541 -34.668251)
			(xy 370.658592 -34.723655) (xy 370.628608 -34.775589) (xy 370.592102 -34.823165) (xy 370.549697 -34.86557)
			(xy 370.502121 -34.902076) (xy 370.450187 -34.93206) (xy 370.394783 -34.955009) (xy 370.336858 -34.97053)
			(xy 370.277402 -34.978358) (xy 370.217434 -34.978358) (xy 370.157978 -34.97053) (xy 370.100053 -34.955009)
			(xy 370.044649 -34.93206) (xy 369.992715 -34.902076) (xy 369.945139 -34.86557) (xy 369.902734 -34.823165)
			(xy 369.866228 -34.775589) (xy 369.836244 -34.723655) (xy 369.813295 -34.668251) (xy 369.797774 -34.610326)
			(xy 369.789946 -34.55087) (xy 369.789456 -34.520886) (xy 355.9683 -34.520886) (xy 355.9683 -34.52241)
			(xy 355.96781 -34.552378) (xy 355.959987 -34.6118) (xy 355.944474 -34.669693) (xy 355.921538 -34.725066)
			(xy 355.891571 -34.776972) (xy 355.855084 -34.824522) (xy 355.812704 -34.866902) (xy 355.765154 -34.903389)
			(xy 355.713248 -34.933356) (xy 355.657875 -34.956292) (xy 355.599982 -34.971805) (xy 355.54056 -34.979628)
			(xy 355.480624 -34.979628) (xy 355.421202 -34.971805) (xy 355.363309 -34.956292) (xy 355.307936 -34.933356)
			(xy 355.25603 -34.903389) (xy 355.20848 -34.866902) (xy 355.1661 -34.824522) (xy 355.129613 -34.776972)
			(xy 355.099646 -34.725066) (xy 355.07671 -34.669693) (xy 355.061197 -34.6118) (xy 355.053374 -34.552378)
			(xy 355.052884 -34.52241) (xy 332.604847 -34.52241) (xy 332.604382 -34.550854) (xy 332.596559 -34.610276)
			(xy 332.581046 -34.668169) (xy 332.55811 -34.723542) (xy 332.528143 -34.775448) (xy 332.491656 -34.822998)
			(xy 332.449276 -34.865378) (xy 332.401726 -34.901865) (xy 332.34982 -34.931832) (xy 332.294447 -34.954768)
			(xy 332.236554 -34.970281) (xy 332.177132 -34.978104) (xy 332.117196 -34.978104) (xy 332.057774 -34.970281)
			(xy 331.999881 -34.954768) (xy 331.944508 -34.931832) (xy 331.892602 -34.901865) (xy 331.845052 -34.865378)
			(xy 331.802672 -34.822998) (xy 331.766185 -34.775448) (xy 331.736218 -34.723542) (xy 331.713282 -34.668169)
			(xy 331.697769 -34.610276) (xy 331.689946 -34.550854) (xy 331.689456 -34.520886) (xy 317.8683 -34.520886)
			(xy 317.8683 -34.52241) (xy 317.86781 -34.552394) (xy 317.859982 -34.61185) (xy 317.844461 -34.669775)
			(xy 317.821512 -34.725179) (xy 317.791528 -34.777113) (xy 317.755022 -34.824689) (xy 317.712617 -34.867094)
			(xy 317.665041 -34.9036) (xy 317.613107 -34.933584) (xy 317.557703 -34.956533) (xy 317.499778 -34.972054)
			(xy 317.440322 -34.979882) (xy 317.380354 -34.979882) (xy 317.320898 -34.972054) (xy 317.262973 -34.956533)
			(xy 317.207569 -34.933584) (xy 317.155635 -34.9036) (xy 317.108059 -34.867094) (xy 317.065654 -34.824689)
			(xy 317.029148 -34.777113) (xy 316.999164 -34.725179) (xy 316.976215 -34.669775) (xy 316.960694 -34.61185)
			(xy 316.952866 -34.552394) (xy 316.952376 -34.52241) (xy 306.604899 -34.52241) (xy 306.604434 -34.550854)
			(xy 306.596611 -34.610276) (xy 306.581098 -34.668169) (xy 306.558162 -34.723542) (xy 306.528195 -34.775448)
			(xy 306.491708 -34.822998) (xy 306.449328 -34.865378) (xy 306.401778 -34.901865) (xy 306.349872 -34.931832)
			(xy 306.294499 -34.954768) (xy 306.236606 -34.970281) (xy 306.177184 -34.978104) (xy 306.117248 -34.978104)
			(xy 306.057826 -34.970281) (xy 305.999933 -34.954768) (xy 305.94456 -34.931832) (xy 305.892654 -34.901865)
			(xy 305.845104 -34.865378) (xy 305.802724 -34.822998) (xy 305.766237 -34.775448) (xy 305.73627 -34.723542)
			(xy 305.713334 -34.668169) (xy 305.697821 -34.610276) (xy 305.689998 -34.550854) (xy 305.689508 -34.520886)
			(xy 291.868352 -34.520886) (xy 291.868352 -34.52241) (xy 291.867862 -34.552394) (xy 291.860034 -34.61185)
			(xy 291.844513 -34.669775) (xy 291.821564 -34.725179) (xy 291.79158 -34.777113) (xy 291.755074 -34.824689)
			(xy 291.712669 -34.867094) (xy 291.665093 -34.9036) (xy 291.613159 -34.933584) (xy 291.557755 -34.956533)
			(xy 291.49983 -34.972054) (xy 291.440374 -34.979882) (xy 291.380406 -34.979882) (xy 291.32095 -34.972054)
			(xy 291.263025 -34.956533) (xy 291.207621 -34.933584) (xy 291.155687 -34.9036) (xy 291.108111 -34.867094)
			(xy 291.065706 -34.824689) (xy 291.0292 -34.777113) (xy 290.999216 -34.725179) (xy 290.976267 -34.669775)
			(xy 290.960746 -34.61185) (xy 290.952918 -34.552394) (xy 290.952428 -34.52241) (xy 280.604951 -34.52241)
			(xy 280.604486 -34.550854) (xy 280.596663 -34.610276) (xy 280.58115 -34.668169) (xy 280.558214 -34.723542)
			(xy 280.528247 -34.775448) (xy 280.49176 -34.822998) (xy 280.44938 -34.865378) (xy 280.40183 -34.901865)
			(xy 280.349924 -34.931832) (xy 280.294551 -34.954768) (xy 280.236658 -34.970281) (xy 280.177236 -34.978104)
			(xy 280.1173 -34.978104) (xy 280.057878 -34.970281) (xy 279.999985 -34.954768) (xy 279.944612 -34.931832)
			(xy 279.892706 -34.901865) (xy 279.845156 -34.865378) (xy 279.802776 -34.822998) (xy 279.766289 -34.775448)
			(xy 279.736322 -34.723542) (xy 279.713386 -34.668169) (xy 279.697873 -34.610276) (xy 279.69005 -34.550854)
			(xy 279.68956 -34.520886) (xy 265.868404 -34.520886) (xy 265.868404 -34.52241) (xy 265.867914 -34.552394)
			(xy 265.860086 -34.61185) (xy 265.844565 -34.669775) (xy 265.821616 -34.725179) (xy 265.791632 -34.777113)
			(xy 265.755126 -34.824689) (xy 265.712721 -34.867094) (xy 265.665145 -34.9036) (xy 265.613211 -34.933584)
			(xy 265.557807 -34.956533) (xy 265.499882 -34.972054) (xy 265.440426 -34.979882) (xy 265.380458 -34.979882)
			(xy 265.321002 -34.972054) (xy 265.263077 -34.956533) (xy 265.207673 -34.933584) (xy 265.155739 -34.9036)
			(xy 265.108163 -34.867094) (xy 265.065758 -34.824689) (xy 265.029252 -34.777113) (xy 264.999268 -34.725179)
			(xy 264.976319 -34.669775) (xy 264.960798 -34.61185) (xy 264.95297 -34.552394) (xy 264.95248 -34.52241)
			(xy 254.605003 -34.52241) (xy 254.604538 -34.550854) (xy 254.596715 -34.610276) (xy 254.581202 -34.668169)
			(xy 254.558266 -34.723542) (xy 254.528299 -34.775448) (xy 254.491812 -34.822998) (xy 254.449432 -34.865378)
			(xy 254.401882 -34.901865) (xy 254.349976 -34.931832) (xy 254.294603 -34.954768) (xy 254.23671 -34.970281)
			(xy 254.177288 -34.978104) (xy 254.117352 -34.978104) (xy 254.05793 -34.970281) (xy 254.000037 -34.954768)
			(xy 253.944664 -34.931832) (xy 253.892758 -34.901865) (xy 253.845208 -34.865378) (xy 253.802828 -34.822998)
			(xy 253.766341 -34.775448) (xy 253.736374 -34.723542) (xy 253.713438 -34.668169) (xy 253.697925 -34.610276)
			(xy 253.690102 -34.550854) (xy 253.689612 -34.520886) (xy 239.868456 -34.520886) (xy 239.868456 -34.52241)
			(xy 239.867966 -34.552394) (xy 239.860138 -34.61185) (xy 239.844617 -34.669775) (xy 239.821668 -34.725179)
			(xy 239.791684 -34.777113) (xy 239.755178 -34.824689) (xy 239.712773 -34.867094) (xy 239.665197 -34.9036)
			(xy 239.613263 -34.933584) (xy 239.557859 -34.956533) (xy 239.499934 -34.972054) (xy 239.440478 -34.979882)
			(xy 239.38051 -34.979882) (xy 239.321054 -34.972054) (xy 239.263129 -34.956533) (xy 239.207725 -34.933584)
			(xy 239.155791 -34.9036) (xy 239.108215 -34.867094) (xy 239.06581 -34.824689) (xy 239.029304 -34.777113)
			(xy 238.99932 -34.725179) (xy 238.976371 -34.669775) (xy 238.96085 -34.61185) (xy 238.953022 -34.552394)
			(xy 238.952532 -34.52241) (xy 216.505003 -34.52241) (xy 216.504538 -34.550854) (xy 216.496715 -34.610276)
			(xy 216.481202 -34.668169) (xy 216.458266 -34.723542) (xy 216.428299 -34.775448) (xy 216.391812 -34.822998)
			(xy 216.349432 -34.865378) (xy 216.301882 -34.901865) (xy 216.249976 -34.931832) (xy 216.194603 -34.954768)
			(xy 216.13671 -34.970281) (xy 216.077288 -34.978104) (xy 216.017352 -34.978104) (xy 215.95793 -34.970281)
			(xy 215.900037 -34.954768) (xy 215.844664 -34.931832) (xy 215.792758 -34.901865) (xy 215.745208 -34.865378)
			(xy 215.702828 -34.822998) (xy 215.666341 -34.775448) (xy 215.636374 -34.723542) (xy 215.613438 -34.668169)
			(xy 215.597925 -34.610276) (xy 215.590102 -34.550854) (xy 215.589612 -34.520886) (xy 201.768456 -34.520886)
			(xy 201.768456 -34.52241) (xy 201.767966 -34.552394) (xy 201.760138 -34.61185) (xy 201.744617 -34.669775)
			(xy 201.721668 -34.725179) (xy 201.691684 -34.777113) (xy 201.655178 -34.824689) (xy 201.612773 -34.867094)
			(xy 201.565197 -34.9036) (xy 201.513263 -34.933584) (xy 201.457859 -34.956533) (xy 201.399934 -34.972054)
			(xy 201.340478 -34.979882) (xy 201.28051 -34.979882) (xy 201.221054 -34.972054) (xy 201.163129 -34.956533)
			(xy 201.107725 -34.933584) (xy 201.055791 -34.9036) (xy 201.008215 -34.867094) (xy 200.96581 -34.824689)
			(xy 200.929304 -34.777113) (xy 200.89932 -34.725179) (xy 200.876371 -34.669775) (xy 200.86085 -34.61185)
			(xy 200.853022 -34.552394) (xy 200.852532 -34.52241) (xy 190.505055 -34.52241) (xy 190.50459 -34.550854)
			(xy 190.496767 -34.610276) (xy 190.481254 -34.668169) (xy 190.458318 -34.723542) (xy 190.428351 -34.775448)
			(xy 190.391864 -34.822998) (xy 190.349484 -34.865378) (xy 190.301934 -34.901865) (xy 190.250028 -34.931832)
			(xy 190.194655 -34.954768) (xy 190.136762 -34.970281) (xy 190.07734 -34.978104) (xy 190.017404 -34.978104)
			(xy 189.957982 -34.970281) (xy 189.900089 -34.954768) (xy 189.844716 -34.931832) (xy 189.79281 -34.901865)
			(xy 189.74526 -34.865378) (xy 189.70288 -34.822998) (xy 189.666393 -34.775448) (xy 189.636426 -34.723542)
			(xy 189.61349 -34.668169) (xy 189.597977 -34.610276) (xy 189.590154 -34.550854) (xy 189.589664 -34.520886)
			(xy 175.768508 -34.520886) (xy 175.768508 -34.52241) (xy 175.768018 -34.552394) (xy 175.76019 -34.61185)
			(xy 175.744669 -34.669775) (xy 175.72172 -34.725179) (xy 175.691736 -34.777113) (xy 175.65523 -34.824689)
			(xy 175.612825 -34.867094) (xy 175.565249 -34.9036) (xy 175.513315 -34.933584) (xy 175.457911 -34.956533)
			(xy 175.399986 -34.972054) (xy 175.34053 -34.979882) (xy 175.280562 -34.979882) (xy 175.221106 -34.972054)
			(xy 175.163181 -34.956533) (xy 175.107777 -34.933584) (xy 175.055843 -34.9036) (xy 175.008267 -34.867094)
			(xy 174.965862 -34.824689) (xy 174.929356 -34.777113) (xy 174.899372 -34.725179) (xy 174.876423 -34.669775)
			(xy 174.860902 -34.61185) (xy 174.853074 -34.552394) (xy 174.852584 -34.52241) (xy 164.505107 -34.52241)
			(xy 164.504642 -34.550854) (xy 164.496819 -34.610276) (xy 164.481306 -34.668169) (xy 164.45837 -34.723542)
			(xy 164.428403 -34.775448) (xy 164.391916 -34.822998) (xy 164.349536 -34.865378) (xy 164.301986 -34.901865)
			(xy 164.25008 -34.931832) (xy 164.194707 -34.954768) (xy 164.136814 -34.970281) (xy 164.077392 -34.978104)
			(xy 164.017456 -34.978104) (xy 163.958034 -34.970281) (xy 163.900141 -34.954768) (xy 163.844768 -34.931832)
			(xy 163.792862 -34.901865) (xy 163.745312 -34.865378) (xy 163.702932 -34.822998) (xy 163.666445 -34.775448)
			(xy 163.636478 -34.723542) (xy 163.613542 -34.668169) (xy 163.598029 -34.610276) (xy 163.590206 -34.550854)
			(xy 163.589716 -34.520886) (xy 149.76856 -34.520886) (xy 149.76856 -34.52241) (xy 149.76807 -34.552394)
			(xy 149.760242 -34.61185) (xy 149.744721 -34.669775) (xy 149.721772 -34.725179) (xy 149.691788 -34.777113)
			(xy 149.655282 -34.824689) (xy 149.612877 -34.867094) (xy 149.565301 -34.9036) (xy 149.513367 -34.933584)
			(xy 149.457963 -34.956533) (xy 149.400038 -34.972054) (xy 149.340582 -34.979882) (xy 149.280614 -34.979882)
			(xy 149.221158 -34.972054) (xy 149.163233 -34.956533) (xy 149.107829 -34.933584) (xy 149.055895 -34.9036)
			(xy 149.008319 -34.867094) (xy 148.965914 -34.824689) (xy 148.929408 -34.777113) (xy 148.899424 -34.725179)
			(xy 148.876475 -34.669775) (xy 148.860954 -34.61185) (xy 148.853126 -34.552394) (xy 148.852636 -34.52241)
			(xy 138.505159 -34.52241) (xy 138.504694 -34.550854) (xy 138.496871 -34.610276) (xy 138.481358 -34.668169)
			(xy 138.458422 -34.723542) (xy 138.428455 -34.775448) (xy 138.391968 -34.822998) (xy 138.349588 -34.865378)
			(xy 138.302038 -34.901865) (xy 138.250132 -34.931832) (xy 138.194759 -34.954768) (xy 138.136866 -34.970281)
			(xy 138.077444 -34.978104) (xy 138.017508 -34.978104) (xy 137.958086 -34.970281) (xy 137.900193 -34.954768)
			(xy 137.84482 -34.931832) (xy 137.792914 -34.901865) (xy 137.745364 -34.865378) (xy 137.702984 -34.822998)
			(xy 137.666497 -34.775448) (xy 137.63653 -34.723542) (xy 137.613594 -34.668169) (xy 137.598081 -34.610276)
			(xy 137.590258 -34.550854) (xy 137.589768 -34.520886) (xy 123.768612 -34.520886) (xy 123.768612 -34.52241)
			(xy 123.768122 -34.552394) (xy 123.760294 -34.61185) (xy 123.744773 -34.669775) (xy 123.721824 -34.725179)
			(xy 123.69184 -34.777113) (xy 123.655334 -34.824689) (xy 123.612929 -34.867094) (xy 123.565353 -34.9036)
			(xy 123.513419 -34.933584) (xy 123.458015 -34.956533) (xy 123.40009 -34.972054) (xy 123.340634 -34.979882)
			(xy 123.280666 -34.979882) (xy 123.22121 -34.972054) (xy 123.163285 -34.956533) (xy 123.107881 -34.933584)
			(xy 123.055947 -34.9036) (xy 123.008371 -34.867094) (xy 122.965966 -34.824689) (xy 122.92946 -34.777113)
			(xy 122.899476 -34.725179) (xy 122.876527 -34.669775) (xy 122.861006 -34.61185) (xy 122.853178 -34.552394)
			(xy 122.852688 -34.52241) (xy 100.405159 -34.52241) (xy 100.404694 -34.55087) (xy 100.396866 -34.610326)
			(xy 100.381345 -34.668251) (xy 100.358396 -34.723655) (xy 100.328412 -34.775589) (xy 100.291906 -34.823165)
			(xy 100.249501 -34.86557) (xy 100.201925 -34.902076) (xy 100.149991 -34.93206) (xy 100.094587 -34.955009)
			(xy 100.036662 -34.97053) (xy 99.977206 -34.978358) (xy 99.917238 -34.978358) (xy 99.857782 -34.97053)
			(xy 99.799857 -34.955009) (xy 99.744453 -34.93206) (xy 99.692519 -34.902076) (xy 99.644943 -34.86557)
			(xy 99.602538 -34.823165) (xy 99.566032 -34.775589) (xy 99.536048 -34.723655) (xy 99.513099 -34.668251)
			(xy 99.497578 -34.610326) (xy 99.48975 -34.55087) (xy 99.48926 -34.520886) (xy 85.668104 -34.520886)
			(xy 85.668104 -34.52241) (xy 85.667614 -34.552378) (xy 85.659791 -34.6118) (xy 85.644278 -34.669693)
			(xy 85.621342 -34.725066) (xy 85.591375 -34.776972) (xy 85.554888 -34.824522) (xy 85.512508 -34.866902)
			(xy 85.464958 -34.903389) (xy 85.413052 -34.933356) (xy 85.357679 -34.956292) (xy 85.299786 -34.971805)
			(xy 85.240364 -34.979628) (xy 85.180428 -34.979628) (xy 85.121006 -34.971805) (xy 85.063113 -34.956292)
			(xy 85.00774 -34.933356) (xy 84.955834 -34.903389) (xy 84.908284 -34.866902) (xy 84.865904 -34.824522)
			(xy 84.829417 -34.776972) (xy 84.79945 -34.725066) (xy 84.776514 -34.669693) (xy 84.761001 -34.6118)
			(xy 84.753178 -34.552378) (xy 84.752688 -34.52241) (xy 74.405211 -34.52241) (xy 74.404746 -34.55087)
			(xy 74.396918 -34.610326) (xy 74.381397 -34.668251) (xy 74.358448 -34.723655) (xy 74.328464 -34.775589)
			(xy 74.291958 -34.823165) (xy 74.249553 -34.86557) (xy 74.201977 -34.902076) (xy 74.150043 -34.93206)
			(xy 74.094639 -34.955009) (xy 74.036714 -34.97053) (xy 73.977258 -34.978358) (xy 73.91729 -34.978358)
			(xy 73.857834 -34.97053) (xy 73.799909 -34.955009) (xy 73.744505 -34.93206) (xy 73.692571 -34.902076)
			(xy 73.644995 -34.86557) (xy 73.60259 -34.823165) (xy 73.566084 -34.775589) (xy 73.5361 -34.723655)
			(xy 73.513151 -34.668251) (xy 73.49763 -34.610326) (xy 73.489802 -34.55087) (xy 73.489312 -34.520886)
			(xy 59.668156 -34.520886) (xy 59.668156 -34.52241) (xy 59.667666 -34.552378) (xy 59.659843 -34.6118)
			(xy 59.64433 -34.669693) (xy 59.621394 -34.725066) (xy 59.591427 -34.776972) (xy 59.55494 -34.824522)
			(xy 59.51256 -34.866902) (xy 59.46501 -34.903389) (xy 59.413104 -34.933356) (xy 59.357731 -34.956292)
			(xy 59.299838 -34.971805) (xy 59.240416 -34.979628) (xy 59.18048 -34.979628) (xy 59.121058 -34.971805)
			(xy 59.063165 -34.956292) (xy 59.007792 -34.933356) (xy 58.955886 -34.903389) (xy 58.908336 -34.866902)
			(xy 58.865956 -34.824522) (xy 58.829469 -34.776972) (xy 58.799502 -34.725066) (xy 58.776566 -34.669693)
			(xy 58.761053 -34.6118) (xy 58.75323 -34.552378) (xy 58.75274 -34.52241) (xy 48.405263 -34.52241)
			(xy 48.404798 -34.55087) (xy 48.39697 -34.610326) (xy 48.381449 -34.668251) (xy 48.3585 -34.723655)
			(xy 48.328516 -34.775589) (xy 48.29201 -34.823165) (xy 48.249605 -34.86557) (xy 48.202029 -34.902076)
			(xy 48.150095 -34.93206) (xy 48.094691 -34.955009) (xy 48.036766 -34.97053) (xy 47.97731 -34.978358)
			(xy 47.917342 -34.978358) (xy 47.857886 -34.97053) (xy 47.799961 -34.955009) (xy 47.744557 -34.93206)
			(xy 47.692623 -34.902076) (xy 47.645047 -34.86557) (xy 47.602642 -34.823165) (xy 47.566136 -34.775589)
			(xy 47.536152 -34.723655) (xy 47.513203 -34.668251) (xy 47.497682 -34.610326) (xy 47.489854 -34.55087)
			(xy 47.489364 -34.520886) (xy 33.668208 -34.520886) (xy 33.668208 -34.52241) (xy 33.667718 -34.552378)
			(xy 33.659895 -34.6118) (xy 33.644382 -34.669693) (xy 33.621446 -34.725066) (xy 33.591479 -34.776972)
			(xy 33.554992 -34.824522) (xy 33.512612 -34.866902) (xy 33.465062 -34.903389) (xy 33.413156 -34.933356)
			(xy 33.357783 -34.956292) (xy 33.29989 -34.971805) (xy 33.240468 -34.979628) (xy 33.180532 -34.979628)
			(xy 33.12111 -34.971805) (xy 33.063217 -34.956292) (xy 33.007844 -34.933356) (xy 32.955938 -34.903389)
			(xy 32.908388 -34.866902) (xy 32.866008 -34.824522) (xy 32.829521 -34.776972) (xy 32.799554 -34.725066)
			(xy 32.776618 -34.669693) (xy 32.761105 -34.6118) (xy 32.753282 -34.552378) (xy 32.752792 -34.52241)
			(xy 22.405315 -34.52241) (xy 22.40485 -34.55087) (xy 22.397022 -34.610326) (xy 22.381501 -34.668251)
			(xy 22.358552 -34.723655) (xy 22.328568 -34.775589) (xy 22.292062 -34.823165) (xy 22.249657 -34.86557)
			(xy 22.202081 -34.902076) (xy 22.150147 -34.93206) (xy 22.094743 -34.955009) (xy 22.036818 -34.97053)
			(xy 21.977362 -34.978358) (xy 21.917394 -34.978358) (xy 21.857938 -34.97053) (xy 21.800013 -34.955009)
			(xy 21.744609 -34.93206) (xy 21.692675 -34.902076) (xy 21.645099 -34.86557) (xy 21.602694 -34.823165)
			(xy 21.566188 -34.775589) (xy 21.536204 -34.723655) (xy 21.513255 -34.668251) (xy 21.497734 -34.610326)
			(xy 21.489906 -34.55087) (xy 21.489416 -34.520886) (xy 7.66826 -34.520886) (xy 7.66826 -34.52241)
			(xy 7.66777 -34.552378) (xy 7.659947 -34.6118) (xy 7.644434 -34.669693) (xy 7.621498 -34.725066)
			(xy 7.591531 -34.776972) (xy 7.555044 -34.824522) (xy 7.512664 -34.866902) (xy 7.465114 -34.903389)
			(xy 7.413208 -34.933356) (xy 7.357835 -34.956292) (xy 7.299942 -34.971805) (xy 7.24052 -34.979628)
			(xy 7.180584 -34.979628) (xy 7.121162 -34.971805) (xy 7.063269 -34.956292) (xy 7.007896 -34.933356)
			(xy 6.95599 -34.903389) (xy 6.90844 -34.866902) (xy 6.86606 -34.824522) (xy 6.829573 -34.776972)
			(xy 6.799606 -34.725066) (xy 6.77667 -34.669693) (xy 6.761157 -34.6118) (xy 6.753334 -34.552378)
			(xy 6.752844 -34.52241) (xy 1.524 -34.52241) (xy 1.524 -36.60013) (xy 11.998459 -36.60013) (xy 12.002463 -36.512245)
			(xy 12.014443 -36.425088) (xy 12.034298 -36.339381) (xy 12.061865 -36.255836) (xy 12.096915 -36.175143)
			(xy 12.139157 -36.097971) (xy 12.188242 -36.024961) (xy 12.243763 -35.956717) (xy 12.30526 -35.893804)
			(xy 12.372222 -35.836744) (xy 12.444096 -35.78601) (xy 12.520286 -35.742022) (xy 12.60016 -35.705144)
			(xy 12.683057 -35.675683) (xy 12.768289 -35.653881) (xy 12.855151 -35.639921) (xy 12.942922 -35.633917)
			(xy 13.030876 -35.63592) (xy 13.118283 -35.645912) (xy 13.204419 -35.663812) (xy 13.288571 -35.68947)
			(xy 13.370041 -35.722674) (xy 13.448154 -35.763148) (xy 13.522262 -35.810559) (xy 13.591753 -35.864512)
			(xy 13.656049 -35.92456) (xy 13.714618 -35.990207) (xy 13.766975 -36.060907) (xy 13.812687 -36.136076)
			(xy 13.851373 -36.21509) (xy 13.882714 -36.297295) (xy 13.906449 -36.382009) (xy 13.922383 -36.46853)
			(xy 13.930383 -36.556142) (xy 13.930884 -36.60013) (xy 37.998407 -36.60013) (xy 38.002411 -36.512245)
			(xy 38.014391 -36.425088) (xy 38.034246 -36.339381) (xy 38.061813 -36.255836) (xy 38.096863 -36.175143)
			(xy 38.139105 -36.097971) (xy 38.18819 -36.024961) (xy 38.243711 -35.956717) (xy 38.305208 -35.893804)
			(xy 38.37217 -35.836744) (xy 38.444044 -35.78601) (xy 38.520234 -35.742022) (xy 38.600108 -35.705144)
			(xy 38.683005 -35.675683) (xy 38.768237 -35.653881) (xy 38.855099 -35.639921) (xy 38.94287 -35.633917)
			(xy 39.030824 -35.63592) (xy 39.118231 -35.645912) (xy 39.204367 -35.663812) (xy 39.288519 -35.68947)
			(xy 39.369989 -35.722674) (xy 39.448102 -35.763148) (xy 39.52221 -35.810559) (xy 39.591701 -35.864512)
			(xy 39.655997 -35.92456) (xy 39.714566 -35.990207) (xy 39.766923 -36.060907) (xy 39.812635 -36.136076)
			(xy 39.851321 -36.21509) (xy 39.882662 -36.297295) (xy 39.906397 -36.382009) (xy 39.922331 -36.46853)
			(xy 39.930331 -36.556142) (xy 39.930832 -36.60013) (xy 63.998355 -36.60013) (xy 64.002359 -36.512245)
			(xy 64.014339 -36.425088) (xy 64.034194 -36.339381) (xy 64.061761 -36.255836) (xy 64.096811 -36.175143)
			(xy 64.139053 -36.097971) (xy 64.188138 -36.024961) (xy 64.243659 -35.956717) (xy 64.305156 -35.893804)
			(xy 64.372118 -35.836744) (xy 64.443992 -35.78601) (xy 64.520182 -35.742022) (xy 64.600056 -35.705144)
			(xy 64.682953 -35.675683) (xy 64.768185 -35.653881) (xy 64.855047 -35.639921) (xy 64.942818 -35.633917)
			(xy 65.030772 -35.63592) (xy 65.118179 -35.645912) (xy 65.204315 -35.663812) (xy 65.288467 -35.68947)
			(xy 65.369937 -35.722674) (xy 65.44805 -35.763148) (xy 65.522158 -35.810559) (xy 65.591649 -35.864512)
			(xy 65.655945 -35.92456) (xy 65.714514 -35.990207) (xy 65.766871 -36.060907) (xy 65.812583 -36.136076)
			(xy 65.851269 -36.21509) (xy 65.88261 -36.297295) (xy 65.906345 -36.382009) (xy 65.922279 -36.46853)
			(xy 65.930279 -36.556142) (xy 65.93078 -36.60013) (xy 89.998303 -36.60013) (xy 90.002307 -36.512245)
			(xy 90.014287 -36.425088) (xy 90.034142 -36.339381) (xy 90.061709 -36.255836) (xy 90.096759 -36.175143)
			(xy 90.139001 -36.097971) (xy 90.188086 -36.024961) (xy 90.243607 -35.956717) (xy 90.305104 -35.893804)
			(xy 90.372066 -35.836744) (xy 90.44394 -35.78601) (xy 90.52013 -35.742022) (xy 90.600004 -35.705144)
			(xy 90.682901 -35.675683) (xy 90.768133 -35.653881) (xy 90.854995 -35.639921) (xy 90.942766 -35.633917)
			(xy 91.03072 -35.63592) (xy 91.118127 -35.645912) (xy 91.204263 -35.663812) (xy 91.288415 -35.68947)
			(xy 91.369885 -35.722674) (xy 91.447998 -35.763148) (xy 91.522106 -35.810559) (xy 91.591597 -35.864512)
			(xy 91.655893 -35.92456) (xy 91.714462 -35.990207) (xy 91.766819 -36.060907) (xy 91.812531 -36.136076)
			(xy 91.851217 -36.21509) (xy 91.882558 -36.297295) (xy 91.906293 -36.382009) (xy 91.922227 -36.46853)
			(xy 91.930227 -36.556142) (xy 91.930728 -36.60013) (xy 128.098557 -36.60013) (xy 128.102561 -36.512245)
			(xy 128.114541 -36.425088) (xy 128.134396 -36.339381) (xy 128.161963 -36.255836) (xy 128.197013 -36.175143)
			(xy 128.239255 -36.097971) (xy 128.28834 -36.024961) (xy 128.343861 -35.956717) (xy 128.405358 -35.893804)
			(xy 128.47232 -35.836744) (xy 128.544194 -35.78601) (xy 128.620384 -35.742022) (xy 128.700258 -35.705144)
			(xy 128.783155 -35.675683) (xy 128.868387 -35.653881) (xy 128.955249 -35.639921) (xy 129.04302 -35.633917)
			(xy 129.130974 -35.63592) (xy 129.218381 -35.645912) (xy 129.304517 -35.663812) (xy 129.388669 -35.68947)
			(xy 129.470139 -35.722674) (xy 129.548252 -35.763148) (xy 129.62236 -35.810559) (xy 129.691851 -35.864512)
			(xy 129.756147 -35.92456) (xy 129.814716 -35.990207) (xy 129.867073 -36.060907) (xy 129.912785 -36.136076)
			(xy 129.951471 -36.21509) (xy 129.982812 -36.297295) (xy 130.006547 -36.382009) (xy 130.022481 -36.46853)
			(xy 130.030481 -36.556142) (xy 130.030982 -36.60013) (xy 154.098505 -36.60013) (xy 154.102509 -36.512245)
			(xy 154.114489 -36.425088) (xy 154.134344 -36.339381) (xy 154.161911 -36.255836) (xy 154.196961 -36.175143)
			(xy 154.239203 -36.097971) (xy 154.288288 -36.024961) (xy 154.343809 -35.956717) (xy 154.405306 -35.893804)
			(xy 154.472268 -35.836744) (xy 154.544142 -35.78601) (xy 154.620332 -35.742022) (xy 154.700206 -35.705144)
			(xy 154.783103 -35.675683) (xy 154.868335 -35.653881) (xy 154.955197 -35.639921) (xy 155.042968 -35.633917)
			(xy 155.130922 -35.63592) (xy 155.218329 -35.645912) (xy 155.304465 -35.663812) (xy 155.388617 -35.68947)
			(xy 155.470087 -35.722674) (xy 155.5482 -35.763148) (xy 155.622308 -35.810559) (xy 155.691799 -35.864512)
			(xy 155.756095 -35.92456) (xy 155.814664 -35.990207) (xy 155.867021 -36.060907) (xy 155.912733 -36.136076)
			(xy 155.951419 -36.21509) (xy 155.98276 -36.297295) (xy 156.006495 -36.382009) (xy 156.022429 -36.46853)
			(xy 156.030429 -36.556142) (xy 156.03093 -36.60013) (xy 180.098453 -36.60013) (xy 180.102457 -36.512245)
			(xy 180.114437 -36.425088) (xy 180.134292 -36.339381) (xy 180.161859 -36.255836) (xy 180.196909 -36.175143)
			(xy 180.239151 -36.097971) (xy 180.288236 -36.024961) (xy 180.343757 -35.956717) (xy 180.405254 -35.893804)
			(xy 180.472216 -35.836744) (xy 180.54409 -35.78601) (xy 180.62028 -35.742022) (xy 180.700154 -35.705144)
			(xy 180.783051 -35.675683) (xy 180.868283 -35.653881) (xy 180.955145 -35.639921) (xy 181.042916 -35.633917)
			(xy 181.13087 -35.63592) (xy 181.218277 -35.645912) (xy 181.304413 -35.663812) (xy 181.388565 -35.68947)
			(xy 181.470035 -35.722674) (xy 181.548148 -35.763148) (xy 181.622256 -35.810559) (xy 181.691747 -35.864512)
			(xy 181.756043 -35.92456) (xy 181.814612 -35.990207) (xy 181.866969 -36.060907) (xy 181.912681 -36.136076)
			(xy 181.951367 -36.21509) (xy 181.982708 -36.297295) (xy 182.006443 -36.382009) (xy 182.022377 -36.46853)
			(xy 182.030377 -36.556142) (xy 182.030878 -36.60013) (xy 206.098655 -36.60013) (xy 206.102659 -36.512245)
			(xy 206.114639 -36.425088) (xy 206.134494 -36.339381) (xy 206.162061 -36.255836) (xy 206.197111 -36.175143)
			(xy 206.239353 -36.097971) (xy 206.288438 -36.024961) (xy 206.343959 -35.956717) (xy 206.405456 -35.893804)
			(xy 206.472418 -35.836744) (xy 206.544292 -35.78601) (xy 206.620482 -35.742022) (xy 206.700356 -35.705144)
			(xy 206.783253 -35.675683) (xy 206.868485 -35.653881) (xy 206.955347 -35.639921) (xy 207.043118 -35.633917)
			(xy 207.131072 -35.63592) (xy 207.218479 -35.645912) (xy 207.304615 -35.663812) (xy 207.388767 -35.68947)
			(xy 207.470237 -35.722674) (xy 207.54835 -35.763148) (xy 207.622458 -35.810559) (xy 207.691949 -35.864512)
			(xy 207.756245 -35.92456) (xy 207.814814 -35.990207) (xy 207.867171 -36.060907) (xy 207.912883 -36.136076)
			(xy 207.951569 -36.21509) (xy 207.98291 -36.297295) (xy 208.006645 -36.382009) (xy 208.022579 -36.46853)
			(xy 208.030579 -36.556142) (xy 208.03108 -36.60013) (xy 244.198655 -36.60013) (xy 244.202659 -36.512245)
			(xy 244.214639 -36.425088) (xy 244.234494 -36.339381) (xy 244.262061 -36.255836) (xy 244.297111 -36.175143)
			(xy 244.339353 -36.097971) (xy 244.388438 -36.024961) (xy 244.443959 -35.956717) (xy 244.505456 -35.893804)
			(xy 244.572418 -35.836744) (xy 244.644292 -35.78601) (xy 244.720482 -35.742022) (xy 244.800356 -35.705144)
			(xy 244.883253 -35.675683) (xy 244.968485 -35.653881) (xy 245.055347 -35.639921) (xy 245.143118 -35.633917)
			(xy 245.231072 -35.63592) (xy 245.318479 -35.645912) (xy 245.404615 -35.663812) (xy 245.488767 -35.68947)
			(xy 245.570237 -35.722674) (xy 245.64835 -35.763148) (xy 245.722458 -35.810559) (xy 245.791949 -35.864512)
			(xy 245.856245 -35.92456) (xy 245.914814 -35.990207) (xy 245.967171 -36.060907) (xy 246.012883 -36.136076)
			(xy 246.051569 -36.21509) (xy 246.08291 -36.297295) (xy 246.106645 -36.382009) (xy 246.122579 -36.46853)
			(xy 246.130579 -36.556142) (xy 246.13108 -36.60013) (xy 270.198603 -36.60013) (xy 270.202607 -36.512245)
			(xy 270.214587 -36.425088) (xy 270.234442 -36.339381) (xy 270.262009 -36.255836) (xy 270.297059 -36.175143)
			(xy 270.339301 -36.097971) (xy 270.388386 -36.024961) (xy 270.443907 -35.956717) (xy 270.505404 -35.893804)
			(xy 270.572366 -35.836744) (xy 270.64424 -35.78601) (xy 270.72043 -35.742022) (xy 270.800304 -35.705144)
			(xy 270.883201 -35.675683) (xy 270.968433 -35.653881) (xy 271.055295 -35.639921) (xy 271.143066 -35.633917)
			(xy 271.23102 -35.63592) (xy 271.318427 -35.645912) (xy 271.404563 -35.663812) (xy 271.488715 -35.68947)
			(xy 271.570185 -35.722674) (xy 271.648298 -35.763148) (xy 271.722406 -35.810559) (xy 271.791897 -35.864512)
			(xy 271.856193 -35.92456) (xy 271.914762 -35.990207) (xy 271.967119 -36.060907) (xy 272.012831 -36.136076)
			(xy 272.051517 -36.21509) (xy 272.082858 -36.297295) (xy 272.106593 -36.382009) (xy 272.122527 -36.46853)
			(xy 272.130527 -36.556142) (xy 272.131028 -36.60013) (xy 296.198551 -36.60013) (xy 296.202555 -36.512245)
			(xy 296.214535 -36.425088) (xy 296.23439 -36.339381) (xy 296.261957 -36.255836) (xy 296.297007 -36.175143)
			(xy 296.339249 -36.097971) (xy 296.388334 -36.024961) (xy 296.443855 -35.956717) (xy 296.505352 -35.893804)
			(xy 296.572314 -35.836744) (xy 296.644188 -35.78601) (xy 296.720378 -35.742022) (xy 296.800252 -35.705144)
			(xy 296.883149 -35.675683) (xy 296.968381 -35.653881) (xy 297.055243 -35.639921) (xy 297.143014 -35.633917)
			(xy 297.230968 -35.63592) (xy 297.318375 -35.645912) (xy 297.404511 -35.663812) (xy 297.488663 -35.68947)
			(xy 297.570133 -35.722674) (xy 297.648246 -35.763148) (xy 297.722354 -35.810559) (xy 297.791845 -35.864512)
			(xy 297.856141 -35.92456) (xy 297.91471 -35.990207) (xy 297.967067 -36.060907) (xy 298.012779 -36.136076)
			(xy 298.051465 -36.21509) (xy 298.082806 -36.297295) (xy 298.106541 -36.382009) (xy 298.122475 -36.46853)
			(xy 298.130475 -36.556142) (xy 298.130976 -36.60013) (xy 322.198245 -36.60013) (xy 322.202249 -36.512245)
			(xy 322.214229 -36.425088) (xy 322.234084 -36.339381) (xy 322.261651 -36.255836) (xy 322.296701 -36.175143)
			(xy 322.338943 -36.097971) (xy 322.388028 -36.024961) (xy 322.443549 -35.956717) (xy 322.505046 -35.893804)
			(xy 322.572008 -35.836744) (xy 322.643882 -35.78601) (xy 322.720072 -35.742022) (xy 322.799946 -35.705144)
			(xy 322.882843 -35.675683) (xy 322.968075 -35.653881) (xy 323.054937 -35.639921) (xy 323.142708 -35.633917)
			(xy 323.230662 -35.63592) (xy 323.318069 -35.645912) (xy 323.404205 -35.663812) (xy 323.488357 -35.68947)
			(xy 323.569827 -35.722674) (xy 323.64794 -35.763148) (xy 323.722048 -35.810559) (xy 323.791539 -35.864512)
			(xy 323.855835 -35.92456) (xy 323.914404 -35.990207) (xy 323.966761 -36.060907) (xy 324.012473 -36.136076)
			(xy 324.051159 -36.21509) (xy 324.0825 -36.297295) (xy 324.106235 -36.382009) (xy 324.122169 -36.46853)
			(xy 324.130169 -36.556142) (xy 324.13067 -36.60013) (xy 360.298499 -36.60013) (xy 360.302503 -36.512245)
			(xy 360.314483 -36.425088) (xy 360.334338 -36.339381) (xy 360.361905 -36.255836) (xy 360.396955 -36.175143)
			(xy 360.439197 -36.097971) (xy 360.488282 -36.024961) (xy 360.543803 -35.956717) (xy 360.6053 -35.893804)
			(xy 360.672262 -35.836744) (xy 360.744136 -35.78601) (xy 360.820326 -35.742022) (xy 360.9002 -35.705144)
			(xy 360.983097 -35.675683) (xy 361.068329 -35.653881) (xy 361.155191 -35.639921) (xy 361.242962 -35.633917)
			(xy 361.330916 -35.63592) (xy 361.418323 -35.645912) (xy 361.504459 -35.663812) (xy 361.588611 -35.68947)
			(xy 361.670081 -35.722674) (xy 361.748194 -35.763148) (xy 361.822302 -35.810559) (xy 361.891793 -35.864512)
			(xy 361.956089 -35.92456) (xy 362.014658 -35.990207) (xy 362.067015 -36.060907) (xy 362.112727 -36.136076)
			(xy 362.151413 -36.21509) (xy 362.182754 -36.297295) (xy 362.206489 -36.382009) (xy 362.222423 -36.46853)
			(xy 362.230423 -36.556142) (xy 362.230924 -36.60013) (xy 386.298447 -36.60013) (xy 386.302451 -36.512245)
			(xy 386.314431 -36.425088) (xy 386.334286 -36.339381) (xy 386.361853 -36.255836) (xy 386.396903 -36.175143)
			(xy 386.439145 -36.097971) (xy 386.48823 -36.024961) (xy 386.543751 -35.956717) (xy 386.605248 -35.893804)
			(xy 386.67221 -35.836744) (xy 386.744084 -35.78601) (xy 386.820274 -35.742022) (xy 386.900148 -35.705144)
			(xy 386.983045 -35.675683) (xy 387.068277 -35.653881) (xy 387.155139 -35.639921) (xy 387.24291 -35.633917)
			(xy 387.330864 -35.63592) (xy 387.418271 -35.645912) (xy 387.504407 -35.663812) (xy 387.588559 -35.68947)
			(xy 387.670029 -35.722674) (xy 387.748142 -35.763148) (xy 387.82225 -35.810559) (xy 387.891741 -35.864512)
			(xy 387.956037 -35.92456) (xy 388.014606 -35.990207) (xy 388.066963 -36.060907) (xy 388.112675 -36.136076)
			(xy 388.151361 -36.21509) (xy 388.182702 -36.297295) (xy 388.206437 -36.382009) (xy 388.222371 -36.46853)
			(xy 388.230371 -36.556142) (xy 388.230872 -36.60013) (xy 412.298649 -36.60013) (xy 412.302653 -36.512245)
			(xy 412.314633 -36.425088) (xy 412.334488 -36.339381) (xy 412.362055 -36.255836) (xy 412.397105 -36.175143)
			(xy 412.439347 -36.097971) (xy 412.488432 -36.024961) (xy 412.543953 -35.956717) (xy 412.60545 -35.893804)
			(xy 412.672412 -35.836744) (xy 412.744286 -35.78601) (xy 412.820476 -35.742022) (xy 412.90035 -35.705144)
			(xy 412.983247 -35.675683) (xy 413.068479 -35.653881) (xy 413.155341 -35.639921) (xy 413.243112 -35.633917)
			(xy 413.331066 -35.63592) (xy 413.418473 -35.645912) (xy 413.504609 -35.663812) (xy 413.588761 -35.68947)
			(xy 413.670231 -35.722674) (xy 413.748344 -35.763148) (xy 413.822452 -35.810559) (xy 413.891943 -35.864512)
			(xy 413.956239 -35.92456) (xy 414.014808 -35.990207) (xy 414.067165 -36.060907) (xy 414.112877 -36.136076)
			(xy 414.151563 -36.21509) (xy 414.182904 -36.297295) (xy 414.206639 -36.382009) (xy 414.222573 -36.46853)
			(xy 414.230573 -36.556142) (xy 414.231074 -36.60013) (xy 438.298597 -36.60013) (xy 438.302601 -36.512245)
			(xy 438.314581 -36.425088) (xy 438.334436 -36.339381) (xy 438.362003 -36.255836) (xy 438.397053 -36.175143)
			(xy 438.439295 -36.097971) (xy 438.48838 -36.024961) (xy 438.543901 -35.956717) (xy 438.605398 -35.893804)
			(xy 438.67236 -35.836744) (xy 438.744234 -35.78601) (xy 438.820424 -35.742022) (xy 438.900298 -35.705144)
			(xy 438.983195 -35.675683) (xy 439.068427 -35.653881) (xy 439.155289 -35.639921) (xy 439.24306 -35.633917)
			(xy 439.331014 -35.63592) (xy 439.418421 -35.645912) (xy 439.504557 -35.663812) (xy 439.588709 -35.68947)
			(xy 439.670179 -35.722674) (xy 439.748292 -35.763148) (xy 439.8224 -35.810559) (xy 439.891891 -35.864512)
			(xy 439.956187 -35.92456) (xy 440.014756 -35.990207) (xy 440.067113 -36.060907) (xy 440.112825 -36.136076)
			(xy 440.151511 -36.21509) (xy 440.182852 -36.297295) (xy 440.206587 -36.382009) (xy 440.222521 -36.46853)
			(xy 440.230521 -36.556142) (xy 440.231022 -36.60013) (xy 440.230521 -36.644118) (xy 440.222521 -36.73173)
			(xy 440.206587 -36.818251) (xy 440.182852 -36.902965) (xy 440.151511 -36.98517) (xy 440.112825 -37.064184)
			(xy 440.067113 -37.139353) (xy 440.014756 -37.210053) (xy 439.956187 -37.2757) (xy 439.891891 -37.335748)
			(xy 439.8224 -37.389701) (xy 439.748292 -37.437112) (xy 439.670179 -37.477586) (xy 439.588709 -37.51079)
			(xy 439.504557 -37.536448) (xy 439.418421 -37.554348) (xy 439.331014 -37.56434) (xy 439.24306 -37.566343)
			(xy 439.155289 -37.560339) (xy 439.068427 -37.546379) (xy 438.983195 -37.524577) (xy 438.900298 -37.495116)
			(xy 438.820424 -37.458238) (xy 438.744234 -37.41425) (xy 438.67236 -37.363516) (xy 438.605398 -37.306456)
			(xy 438.543901 -37.243543) (xy 438.48838 -37.175299) (xy 438.439295 -37.102289) (xy 438.397053 -37.025117)
			(xy 438.362003 -36.944424) (xy 438.334436 -36.860879) (xy 438.314581 -36.775172) (xy 438.302601 -36.688015)
			(xy 438.298597 -36.60013) (xy 414.231074 -36.60013) (xy 414.230573 -36.644118) (xy 414.222573 -36.73173)
			(xy 414.206639 -36.818251) (xy 414.182904 -36.902965) (xy 414.151563 -36.98517) (xy 414.112877 -37.064184)
			(xy 414.067165 -37.139353) (xy 414.014808 -37.210053) (xy 413.956239 -37.2757) (xy 413.891943 -37.335748)
			(xy 413.822452 -37.389701) (xy 413.748344 -37.437112) (xy 413.670231 -37.477586) (xy 413.588761 -37.51079)
			(xy 413.504609 -37.536448) (xy 413.418473 -37.554348) (xy 413.331066 -37.56434) (xy 413.243112 -37.566343)
			(xy 413.155341 -37.560339) (xy 413.068479 -37.546379) (xy 412.983247 -37.524577) (xy 412.90035 -37.495116)
			(xy 412.820476 -37.458238) (xy 412.744286 -37.41425) (xy 412.672412 -37.363516) (xy 412.60545 -37.306456)
			(xy 412.543953 -37.243543) (xy 412.488432 -37.175299) (xy 412.439347 -37.102289) (xy 412.397105 -37.025117)
			(xy 412.362055 -36.944424) (xy 412.334488 -36.860879) (xy 412.314633 -36.775172) (xy 412.302653 -36.688015)
			(xy 412.298649 -36.60013) (xy 388.230872 -36.60013) (xy 388.230371 -36.644118) (xy 388.222371 -36.73173)
			(xy 388.206437 -36.818251) (xy 388.182702 -36.902965) (xy 388.151361 -36.98517) (xy 388.112675 -37.064184)
			(xy 388.066963 -37.139353) (xy 388.014606 -37.210053) (xy 387.956037 -37.2757) (xy 387.891741 -37.335748)
			(xy 387.82225 -37.389701) (xy 387.748142 -37.437112) (xy 387.670029 -37.477586) (xy 387.588559 -37.51079)
			(xy 387.504407 -37.536448) (xy 387.418271 -37.554348) (xy 387.330864 -37.56434) (xy 387.24291 -37.566343)
			(xy 387.155139 -37.560339) (xy 387.068277 -37.546379) (xy 386.983045 -37.524577) (xy 386.900148 -37.495116)
			(xy 386.820274 -37.458238) (xy 386.744084 -37.41425) (xy 386.67221 -37.363516) (xy 386.605248 -37.306456)
			(xy 386.543751 -37.243543) (xy 386.48823 -37.175299) (xy 386.439145 -37.102289) (xy 386.396903 -37.025117)
			(xy 386.361853 -36.944424) (xy 386.334286 -36.860879) (xy 386.314431 -36.775172) (xy 386.302451 -36.688015)
			(xy 386.298447 -36.60013) (xy 362.230924 -36.60013) (xy 362.230423 -36.644118) (xy 362.222423 -36.73173)
			(xy 362.206489 -36.818251) (xy 362.182754 -36.902965) (xy 362.151413 -36.98517) (xy 362.112727 -37.064184)
			(xy 362.067015 -37.139353) (xy 362.014658 -37.210053) (xy 361.956089 -37.2757) (xy 361.891793 -37.335748)
			(xy 361.822302 -37.389701) (xy 361.748194 -37.437112) (xy 361.670081 -37.477586) (xy 361.588611 -37.51079)
			(xy 361.504459 -37.536448) (xy 361.418323 -37.554348) (xy 361.330916 -37.56434) (xy 361.242962 -37.566343)
			(xy 361.155191 -37.560339) (xy 361.068329 -37.546379) (xy 360.983097 -37.524577) (xy 360.9002 -37.495116)
			(xy 360.820326 -37.458238) (xy 360.744136 -37.41425) (xy 360.672262 -37.363516) (xy 360.6053 -37.306456)
			(xy 360.543803 -37.243543) (xy 360.488282 -37.175299) (xy 360.439197 -37.102289) (xy 360.396955 -37.025117)
			(xy 360.361905 -36.944424) (xy 360.334338 -36.860879) (xy 360.314483 -36.775172) (xy 360.302503 -36.688015)
			(xy 360.298499 -36.60013) (xy 324.13067 -36.60013) (xy 324.130169 -36.644118) (xy 324.122169 -36.73173)
			(xy 324.106235 -36.818251) (xy 324.0825 -36.902965) (xy 324.051159 -36.98517) (xy 324.012473 -37.064184)
			(xy 323.966761 -37.139353) (xy 323.914404 -37.210053) (xy 323.855835 -37.2757) (xy 323.791539 -37.335748)
			(xy 323.722048 -37.389701) (xy 323.64794 -37.437112) (xy 323.569827 -37.477586) (xy 323.488357 -37.51079)
			(xy 323.404205 -37.536448) (xy 323.318069 -37.554348) (xy 323.230662 -37.56434) (xy 323.142708 -37.566343)
			(xy 323.054937 -37.560339) (xy 322.968075 -37.546379) (xy 322.882843 -37.524577) (xy 322.799946 -37.495116)
			(xy 322.720072 -37.458238) (xy 322.643882 -37.41425) (xy 322.572008 -37.363516) (xy 322.505046 -37.306456)
			(xy 322.443549 -37.243543) (xy 322.388028 -37.175299) (xy 322.338943 -37.102289) (xy 322.296701 -37.025117)
			(xy 322.261651 -36.944424) (xy 322.234084 -36.860879) (xy 322.214229 -36.775172) (xy 322.202249 -36.688015)
			(xy 322.198245 -36.60013) (xy 298.130976 -36.60013) (xy 298.130475 -36.644118) (xy 298.122475 -36.73173)
			(xy 298.106541 -36.818251) (xy 298.082806 -36.902965) (xy 298.051465 -36.98517) (xy 298.012779 -37.064184)
			(xy 297.967067 -37.139353) (xy 297.91471 -37.210053) (xy 297.856141 -37.2757) (xy 297.791845 -37.335748)
			(xy 297.722354 -37.389701) (xy 297.648246 -37.437112) (xy 297.570133 -37.477586) (xy 297.488663 -37.51079)
			(xy 297.404511 -37.536448) (xy 297.318375 -37.554348) (xy 297.230968 -37.56434) (xy 297.143014 -37.566343)
			(xy 297.055243 -37.560339) (xy 296.968381 -37.546379) (xy 296.883149 -37.524577) (xy 296.800252 -37.495116)
			(xy 296.720378 -37.458238) (xy 296.644188 -37.41425) (xy 296.572314 -37.363516) (xy 296.505352 -37.306456)
			(xy 296.443855 -37.243543) (xy 296.388334 -37.175299) (xy 296.339249 -37.102289) (xy 296.297007 -37.025117)
			(xy 296.261957 -36.944424) (xy 296.23439 -36.860879) (xy 296.214535 -36.775172) (xy 296.202555 -36.688015)
			(xy 296.198551 -36.60013) (xy 272.131028 -36.60013) (xy 272.130527 -36.644118) (xy 272.122527 -36.73173)
			(xy 272.106593 -36.818251) (xy 272.082858 -36.902965) (xy 272.051517 -36.98517) (xy 272.012831 -37.064184)
			(xy 271.967119 -37.139353) (xy 271.914762 -37.210053) (xy 271.856193 -37.2757) (xy 271.791897 -37.335748)
			(xy 271.722406 -37.389701) (xy 271.648298 -37.437112) (xy 271.570185 -37.477586) (xy 271.488715 -37.51079)
			(xy 271.404563 -37.536448) (xy 271.318427 -37.554348) (xy 271.23102 -37.56434) (xy 271.143066 -37.566343)
			(xy 271.055295 -37.560339) (xy 270.968433 -37.546379) (xy 270.883201 -37.524577) (xy 270.800304 -37.495116)
			(xy 270.72043 -37.458238) (xy 270.64424 -37.41425) (xy 270.572366 -37.363516) (xy 270.505404 -37.306456)
			(xy 270.443907 -37.243543) (xy 270.388386 -37.175299) (xy 270.339301 -37.102289) (xy 270.297059 -37.025117)
			(xy 270.262009 -36.944424) (xy 270.234442 -36.860879) (xy 270.214587 -36.775172) (xy 270.202607 -36.688015)
			(xy 270.198603 -36.60013) (xy 246.13108 -36.60013) (xy 246.130579 -36.644118) (xy 246.122579 -36.73173)
			(xy 246.106645 -36.818251) (xy 246.08291 -36.902965) (xy 246.051569 -36.98517) (xy 246.012883 -37.064184)
			(xy 245.967171 -37.139353) (xy 245.914814 -37.210053) (xy 245.856245 -37.2757) (xy 245.791949 -37.335748)
			(xy 245.722458 -37.389701) (xy 245.64835 -37.437112) (xy 245.570237 -37.477586) (xy 245.488767 -37.51079)
			(xy 245.404615 -37.536448) (xy 245.318479 -37.554348) (xy 245.231072 -37.56434) (xy 245.143118 -37.566343)
			(xy 245.055347 -37.560339) (xy 244.968485 -37.546379) (xy 244.883253 -37.524577) (xy 244.800356 -37.495116)
			(xy 244.720482 -37.458238) (xy 244.644292 -37.41425) (xy 244.572418 -37.363516) (xy 244.505456 -37.306456)
			(xy 244.443959 -37.243543) (xy 244.388438 -37.175299) (xy 244.339353 -37.102289) (xy 244.297111 -37.025117)
			(xy 244.262061 -36.944424) (xy 244.234494 -36.860879) (xy 244.214639 -36.775172) (xy 244.202659 -36.688015)
			(xy 244.198655 -36.60013) (xy 208.03108 -36.60013) (xy 208.030579 -36.644118) (xy 208.022579 -36.73173)
			(xy 208.006645 -36.818251) (xy 207.98291 -36.902965) (xy 207.951569 -36.98517) (xy 207.912883 -37.064184)
			(xy 207.867171 -37.139353) (xy 207.814814 -37.210053) (xy 207.756245 -37.2757) (xy 207.691949 -37.335748)
			(xy 207.622458 -37.389701) (xy 207.54835 -37.437112) (xy 207.470237 -37.477586) (xy 207.388767 -37.51079)
			(xy 207.304615 -37.536448) (xy 207.218479 -37.554348) (xy 207.131072 -37.56434) (xy 207.043118 -37.566343)
			(xy 206.955347 -37.560339) (xy 206.868485 -37.546379) (xy 206.783253 -37.524577) (xy 206.700356 -37.495116)
			(xy 206.620482 -37.458238) (xy 206.544292 -37.41425) (xy 206.472418 -37.363516) (xy 206.405456 -37.306456)
			(xy 206.343959 -37.243543) (xy 206.288438 -37.175299) (xy 206.239353 -37.102289) (xy 206.197111 -37.025117)
			(xy 206.162061 -36.944424) (xy 206.134494 -36.860879) (xy 206.114639 -36.775172) (xy 206.102659 -36.688015)
			(xy 206.098655 -36.60013) (xy 182.030878 -36.60013) (xy 182.030377 -36.644118) (xy 182.022377 -36.73173)
			(xy 182.006443 -36.818251) (xy 181.982708 -36.902965) (xy 181.951367 -36.98517) (xy 181.912681 -37.064184)
			(xy 181.866969 -37.139353) (xy 181.814612 -37.210053) (xy 181.756043 -37.2757) (xy 181.691747 -37.335748)
			(xy 181.622256 -37.389701) (xy 181.548148 -37.437112) (xy 181.470035 -37.477586) (xy 181.388565 -37.51079)
			(xy 181.304413 -37.536448) (xy 181.218277 -37.554348) (xy 181.13087 -37.56434) (xy 181.042916 -37.566343)
			(xy 180.955145 -37.560339) (xy 180.868283 -37.546379) (xy 180.783051 -37.524577) (xy 180.700154 -37.495116)
			(xy 180.62028 -37.458238) (xy 180.54409 -37.41425) (xy 180.472216 -37.363516) (xy 180.405254 -37.306456)
			(xy 180.343757 -37.243543) (xy 180.288236 -37.175299) (xy 180.239151 -37.102289) (xy 180.196909 -37.025117)
			(xy 180.161859 -36.944424) (xy 180.134292 -36.860879) (xy 180.114437 -36.775172) (xy 180.102457 -36.688015)
			(xy 180.098453 -36.60013) (xy 156.03093 -36.60013) (xy 156.030429 -36.644118) (xy 156.022429 -36.73173)
			(xy 156.006495 -36.818251) (xy 155.98276 -36.902965) (xy 155.951419 -36.98517) (xy 155.912733 -37.064184)
			(xy 155.867021 -37.139353) (xy 155.814664 -37.210053) (xy 155.756095 -37.2757) (xy 155.691799 -37.335748)
			(xy 155.622308 -37.389701) (xy 155.5482 -37.437112) (xy 155.470087 -37.477586) (xy 155.388617 -37.51079)
			(xy 155.304465 -37.536448) (xy 155.218329 -37.554348) (xy 155.130922 -37.56434) (xy 155.042968 -37.566343)
			(xy 154.955197 -37.560339) (xy 154.868335 -37.546379) (xy 154.783103 -37.524577) (xy 154.700206 -37.495116)
			(xy 154.620332 -37.458238) (xy 154.544142 -37.41425) (xy 154.472268 -37.363516) (xy 154.405306 -37.306456)
			(xy 154.343809 -37.243543) (xy 154.288288 -37.175299) (xy 154.239203 -37.102289) (xy 154.196961 -37.025117)
			(xy 154.161911 -36.944424) (xy 154.134344 -36.860879) (xy 154.114489 -36.775172) (xy 154.102509 -36.688015)
			(xy 154.098505 -36.60013) (xy 130.030982 -36.60013) (xy 130.030481 -36.644118) (xy 130.022481 -36.73173)
			(xy 130.006547 -36.818251) (xy 129.982812 -36.902965) (xy 129.951471 -36.98517) (xy 129.912785 -37.064184)
			(xy 129.867073 -37.139353) (xy 129.814716 -37.210053) (xy 129.756147 -37.2757) (xy 129.691851 -37.335748)
			(xy 129.62236 -37.389701) (xy 129.548252 -37.437112) (xy 129.470139 -37.477586) (xy 129.388669 -37.51079)
			(xy 129.304517 -37.536448) (xy 129.218381 -37.554348) (xy 129.130974 -37.56434) (xy 129.04302 -37.566343)
			(xy 128.955249 -37.560339) (xy 128.868387 -37.546379) (xy 128.783155 -37.524577) (xy 128.700258 -37.495116)
			(xy 128.620384 -37.458238) (xy 128.544194 -37.41425) (xy 128.47232 -37.363516) (xy 128.405358 -37.306456)
			(xy 128.343861 -37.243543) (xy 128.28834 -37.175299) (xy 128.239255 -37.102289) (xy 128.197013 -37.025117)
			(xy 128.161963 -36.944424) (xy 128.134396 -36.860879) (xy 128.114541 -36.775172) (xy 128.102561 -36.688015)
			(xy 128.098557 -36.60013) (xy 91.930728 -36.60013) (xy 91.930227 -36.644118) (xy 91.922227 -36.73173)
			(xy 91.906293 -36.818251) (xy 91.882558 -36.902965) (xy 91.851217 -36.98517) (xy 91.812531 -37.064184)
			(xy 91.766819 -37.139353) (xy 91.714462 -37.210053) (xy 91.655893 -37.2757) (xy 91.591597 -37.335748)
			(xy 91.522106 -37.389701) (xy 91.447998 -37.437112) (xy 91.369885 -37.477586) (xy 91.288415 -37.51079)
			(xy 91.204263 -37.536448) (xy 91.118127 -37.554348) (xy 91.03072 -37.56434) (xy 90.942766 -37.566343)
			(xy 90.854995 -37.560339) (xy 90.768133 -37.546379) (xy 90.682901 -37.524577) (xy 90.600004 -37.495116)
			(xy 90.52013 -37.458238) (xy 90.44394 -37.41425) (xy 90.372066 -37.363516) (xy 90.305104 -37.306456)
			(xy 90.243607 -37.243543) (xy 90.188086 -37.175299) (xy 90.139001 -37.102289) (xy 90.096759 -37.025117)
			(xy 90.061709 -36.944424) (xy 90.034142 -36.860879) (xy 90.014287 -36.775172) (xy 90.002307 -36.688015)
			(xy 89.998303 -36.60013) (xy 65.93078 -36.60013) (xy 65.930279 -36.644118) (xy 65.922279 -36.73173)
			(xy 65.906345 -36.818251) (xy 65.88261 -36.902965) (xy 65.851269 -36.98517) (xy 65.812583 -37.064184)
			(xy 65.766871 -37.139353) (xy 65.714514 -37.210053) (xy 65.655945 -37.2757) (xy 65.591649 -37.335748)
			(xy 65.522158 -37.389701) (xy 65.44805 -37.437112) (xy 65.369937 -37.477586) (xy 65.288467 -37.51079)
			(xy 65.204315 -37.536448) (xy 65.118179 -37.554348) (xy 65.030772 -37.56434) (xy 64.942818 -37.566343)
			(xy 64.855047 -37.560339) (xy 64.768185 -37.546379) (xy 64.682953 -37.524577) (xy 64.600056 -37.495116)
			(xy 64.520182 -37.458238) (xy 64.443992 -37.41425) (xy 64.372118 -37.363516) (xy 64.305156 -37.306456)
			(xy 64.243659 -37.243543) (xy 64.188138 -37.175299) (xy 64.139053 -37.102289) (xy 64.096811 -37.025117)
			(xy 64.061761 -36.944424) (xy 64.034194 -36.860879) (xy 64.014339 -36.775172) (xy 64.002359 -36.688015)
			(xy 63.998355 -36.60013) (xy 39.930832 -36.60013) (xy 39.930331 -36.644118) (xy 39.922331 -36.73173)
			(xy 39.906397 -36.818251) (xy 39.882662 -36.902965) (xy 39.851321 -36.98517) (xy 39.812635 -37.064184)
			(xy 39.766923 -37.139353) (xy 39.714566 -37.210053) (xy 39.655997 -37.2757) (xy 39.591701 -37.335748)
			(xy 39.52221 -37.389701) (xy 39.448102 -37.437112) (xy 39.369989 -37.477586) (xy 39.288519 -37.51079)
			(xy 39.204367 -37.536448) (xy 39.118231 -37.554348) (xy 39.030824 -37.56434) (xy 38.94287 -37.566343)
			(xy 38.855099 -37.560339) (xy 38.768237 -37.546379) (xy 38.683005 -37.524577) (xy 38.600108 -37.495116)
			(xy 38.520234 -37.458238) (xy 38.444044 -37.41425) (xy 38.37217 -37.363516) (xy 38.305208 -37.306456)
			(xy 38.243711 -37.243543) (xy 38.18819 -37.175299) (xy 38.139105 -37.102289) (xy 38.096863 -37.025117)
			(xy 38.061813 -36.944424) (xy 38.034246 -36.860879) (xy 38.014391 -36.775172) (xy 38.002411 -36.688015)
			(xy 37.998407 -36.60013) (xy 13.930884 -36.60013) (xy 13.930383 -36.644118) (xy 13.922383 -36.73173)
			(xy 13.906449 -36.818251) (xy 13.882714 -36.902965) (xy 13.851373 -36.98517) (xy 13.812687 -37.064184)
			(xy 13.766975 -37.139353) (xy 13.714618 -37.210053) (xy 13.656049 -37.2757) (xy 13.591753 -37.335748)
			(xy 13.522262 -37.389701) (xy 13.448154 -37.437112) (xy 13.370041 -37.477586) (xy 13.288571 -37.51079)
			(xy 13.204419 -37.536448) (xy 13.118283 -37.554348) (xy 13.030876 -37.56434) (xy 12.942922 -37.566343)
			(xy 12.855151 -37.560339) (xy 12.768289 -37.546379) (xy 12.683057 -37.524577) (xy 12.60016 -37.495116)
			(xy 12.520286 -37.458238) (xy 12.444096 -37.41425) (xy 12.372222 -37.363516) (xy 12.30526 -37.306456)
			(xy 12.243763 -37.243543) (xy 12.188242 -37.175299) (xy 12.139157 -37.102289) (xy 12.096915 -37.025117)
			(xy 12.061865 -36.944424) (xy 12.034298 -36.860879) (xy 12.014443 -36.775172) (xy 12.002463 -36.688015)
			(xy 11.998459 -36.60013) (xy 1.524 -36.60013) (xy 1.524 -57.866534) (xy 1.524494 -57.876537) (xy 1.53216 -57.895017)
			(xy 1.546311 -57.909159) (xy 1.564797 -57.916813) (xy 1.5748 -57.917334)
		)
		(stroke
			(width 0)
			(type solid)
		)
		(fill yes)
		(layer "In2.Cu")
		(net "GND")
	)
	(gr_poly
		(pts
			(xy 53.023516 -417.065968) (xy 53.032744 -417.065564) (xy 53.049995 -417.059003) (xy 53.06379 -417.046743)
			(xy 53.072331 -417.030382) (xy 53.073808 -417.021264) (xy 53.073808 -394.27912) (xy 66.477388 -394.27912)
			(xy 66.525648 -394.32738) (xy 66.525648 -397.823885) (xy 71.348788 -397.823885) (xy 71.348792 -397.756458)
			(xy 71.356871 -397.689518) (xy 71.372911 -397.624026) (xy 71.396679 -397.560928) (xy 71.427833 -397.501131)
			(xy 71.465926 -397.445495) (xy 71.487792 -397.41983) (xy 71.4936 -397.412693) (xy 71.500108 -397.395496)
			(xy 71.500492 -397.386302) (xy 71.500492 -396.89405) (xy 71.50006 -396.884865) (xy 71.493562 -396.86768)
			(xy 71.487792 -396.860522) (xy 71.465918 -396.834865) (xy 71.427831 -396.779229) (xy 71.396681 -396.719431)
			(xy 71.372918 -396.656334) (xy 71.356883 -396.590844) (xy 71.348808 -396.523905) (xy 71.348809 -396.45648)
			(xy 71.356886 -396.389542) (xy 71.372922 -396.324052) (xy 71.396687 -396.260955) (xy 71.427838 -396.201158)
			(xy 71.465928 -396.145523) (xy 71.487792 -396.119858) (xy 71.493588 -396.112712) (xy 71.500103 -396.095522)
			(xy 71.500492 -396.08633) (xy 71.500492 -395.92885) (xy 71.501066 -395.918732) (xy 71.508769 -395.900021)
			(xy 71.523028 -395.885665) (xy 71.541686 -395.877836) (xy 71.5518 -395.877288) (xy 72.26808 -395.877288)
			(xy 72.278231 -395.877738) (xy 72.296981 -395.885524) (xy 72.311305 -395.899912) (xy 72.319007 -395.918697)
			(xy 72.319388 -395.92885) (xy 72.319388 -396.08633) (xy 72.319786 -396.095518) (xy 72.326308 -396.112703)
			(xy 72.332088 -396.119858) (xy 72.353943 -396.145531) (xy 72.392032 -396.201164) (xy 72.423184 -396.260959)
			(xy 72.446949 -396.324055) (xy 72.462986 -396.389543) (xy 72.471063 -396.456481) (xy 72.471064 -396.523904)
			(xy 72.462989 -396.590842) (xy 72.446954 -396.656331) (xy 72.42319 -396.719427) (xy 72.39204 -396.779223)
			(xy 72.353952 -396.834857) (xy 72.332088 -396.860522) (xy 72.326298 -396.867672) (xy 72.31978 -396.884859)
			(xy 72.319388 -396.89405) (xy 72.319388 -397.386302) (xy 72.3198 -397.395489) (xy 72.326313 -397.412673)
			(xy 72.332088 -397.41983) (xy 72.353915 -397.445526) (xy 72.392006 -397.501156) (xy 72.420766 -397.556355)
			(xy 73.54898 -397.556355) (xy 73.557023 -397.489534) (xy 73.572995 -397.424152) (xy 73.596666 -397.361148)
			(xy 73.627698 -397.301425) (xy 73.665645 -397.245838) (xy 73.687432 -397.220186) (xy 73.693221 -397.213036)
			(xy 73.69974 -397.195849) (xy 73.700132 -397.186658) (xy 73.700132 -397.028924) (xy 73.700542 -397.018767)
			(xy 73.708335 -397.000009) (xy 73.722736 -396.985684) (xy 73.741535 -396.977989) (xy 73.751694 -396.977616)
			(xy 74.467974 -396.977616) (xy 74.478096 -396.978147) (xy 74.496812 -396.985862) (xy 74.511169 -397.000134)
			(xy 74.518993 -397.018805) (xy 74.519536 -397.028924) (xy 74.519536 -397.186658) (xy 74.519981 -397.195841)
			(xy 74.526472 -397.213025) (xy 74.532236 -397.220186) (xy 74.554034 -397.24583) (xy 74.591984 -397.301417)
			(xy 74.623019 -397.361141) (xy 74.646692 -397.424147) (xy 74.662665 -397.48953) (xy 74.670709 -397.556354)
			(xy 74.670708 -397.623661) (xy 74.662662 -397.690484) (xy 74.646687 -397.755867) (xy 74.623012 -397.818872)
			(xy 74.620438 -397.823826) (xy 75.749084 -397.823826) (xy 75.749087 -397.756517) (xy 75.757136 -397.689691)
			(xy 75.773114 -397.624306) (xy 75.796793 -397.5613) (xy 75.827833 -397.501576) (xy 75.865789 -397.44599)
			(xy 75.88758 -397.420338) (xy 75.893383 -397.413197) (xy 75.899895 -397.396003) (xy 75.90028 -397.38681)
			(xy 75.90028 -396.893542) (xy 75.899854 -396.884356) (xy 75.893352 -396.867172) (xy 75.88758 -396.860014)
			(xy 75.865781 -396.83437) (xy 75.82783 -396.778784) (xy 75.796795 -396.719059) (xy 75.773121 -396.656054)
			(xy 75.757147 -396.59067) (xy 75.749104 -396.523846) (xy 75.749104 -396.456539) (xy 75.75715 -396.389715)
			(xy 75.773125 -396.324332) (xy 75.796801 -396.261327) (xy 75.827838 -396.201603) (xy 75.86579 -396.146018)
			(xy 75.88758 -396.120366) (xy 75.893371 -396.113217) (xy 75.89989 -396.096029) (xy 75.90028 -396.086838)
			(xy 75.90028 -395.92885) (xy 75.900706 -395.918676) (xy 75.908482 -395.899875) (xy 75.922868 -395.885487)
			(xy 75.941668 -395.877707) (xy 75.951842 -395.877288) (xy 76.668122 -395.877288) (xy 76.678301 -395.877647)
			(xy 76.697106 -395.885449) (xy 76.711492 -395.899855) (xy 76.719267 -395.91867) (xy 76.719684 -395.92885)
			(xy 76.719684 -396.086838) (xy 76.720079 -396.096027) (xy 76.726604 -396.113211) (xy 76.732384 -396.120366)
			(xy 76.754161 -396.146026) (xy 76.792109 -396.201612) (xy 76.823141 -396.261335) (xy 76.846814 -396.324338)
			(xy 76.862787 -396.389719) (xy 76.870831 -396.456541) (xy 76.870832 -396.523844) (xy 76.862789 -396.590666)
			(xy 76.846818 -396.656047) (xy 76.823147 -396.719051) (xy 76.792117 -396.778775) (xy 76.75417 -396.834362)
			(xy 76.732384 -396.860014) (xy 76.726597 -396.867166) (xy 76.720077 -396.884351) (xy 76.719684 -396.893542)
			(xy 76.719684 -397.38681) (xy 76.720093 -397.395997) (xy 76.726608 -397.413181) (xy 76.732384 -397.420338)
			(xy 76.754133 -397.446021) (xy 76.792082 -397.501604) (xy 76.820503 -397.556296) (xy 77.948748 -397.556296)
			(xy 77.956824 -397.489358) (xy 77.972859 -397.423869) (xy 77.996623 -397.360772) (xy 78.027774 -397.300977)
			(xy 78.065864 -397.245343) (xy 78.087728 -397.219678) (xy 78.09352 -397.21253) (xy 78.100037 -397.195341)
			(xy 78.100428 -397.18615) (xy 78.100428 -397.028924) (xy 78.100836 -397.0188) (xy 78.108582 -397.000091)
			(xy 78.122901 -396.985775) (xy 78.141611 -396.978034) (xy 78.151736 -396.977616) (xy 78.868016 -396.977616)
			(xy 78.878142 -396.978003) (xy 78.896849 -396.985759) (xy 78.911163 -397.000085) (xy 78.918905 -397.018798)
			(xy 78.919324 -397.028924) (xy 78.919324 -397.18615) (xy 78.919753 -397.195335) (xy 78.926253 -397.21252)
			(xy 78.932024 -397.219678) (xy 78.953897 -397.245336) (xy 78.991984 -397.300972) (xy 79.023133 -397.360769)
			(xy 79.046895 -397.423867) (xy 79.062929 -397.489357) (xy 79.071004 -397.556296) (xy 79.071003 -397.62372)
			(xy 79.062927 -397.690658) (xy 79.046891 -397.756147) (xy 79.023127 -397.819245) (xy 79.02071 -397.823885)
			(xy 80.148876 -397.823885) (xy 80.14888 -397.756458) (xy 80.156959 -397.689518) (xy 80.172998 -397.624027)
			(xy 80.196765 -397.560929) (xy 80.227919 -397.501131) (xy 80.266011 -397.445496) (xy 80.287876 -397.41983)
			(xy 80.293682 -397.412691) (xy 80.300192 -397.395496) (xy 80.300576 -397.386302) (xy 80.300576 -396.89405)
			(xy 80.300147 -396.884865) (xy 80.293647 -396.86768) (xy 80.287876 -396.860522) (xy 80.266003 -396.834864)
			(xy 80.227916 -396.779228) (xy 80.196767 -396.719431) (xy 80.173005 -396.656333) (xy 80.156971 -396.590843)
			(xy 80.148896 -396.523904) (xy 80.148897 -396.45648) (xy 80.156973 -396.389542) (xy 80.173009 -396.324053)
			(xy 80.196773 -396.260955) (xy 80.227924 -396.201159) (xy 80.266012 -396.145524) (xy 80.287876 -396.119858)
			(xy 80.29367 -396.112711) (xy 80.300187 -396.095522) (xy 80.300576 -396.08633) (xy 80.300576 -395.92885)
			(xy 80.301069 -395.918722) (xy 80.308787 -395.899995) (xy 80.323072 -395.885636) (xy 80.341759 -395.877821)
			(xy 80.351884 -395.877288) (xy 81.068164 -395.877288) (xy 81.078314 -395.877751) (xy 81.097063 -395.885532)
			(xy 81.111388 -395.899917) (xy 81.119091 -395.918698) (xy 81.119472 -395.92885) (xy 81.119472 -396.08633)
			(xy 81.119874 -396.095518) (xy 81.126394 -396.112702) (xy 81.132172 -396.119858) (xy 81.154027 -396.145531)
			(xy 81.192118 -396.201164) (xy 81.223271 -396.260959) (xy 81.247037 -396.324054) (xy 81.263074 -396.389543)
			(xy 81.271151 -396.456481) (xy 81.271152 -396.523904) (xy 81.263076 -396.590842) (xy 81.247041 -396.656331)
			(xy 81.223277 -396.719428) (xy 81.192126 -396.779223) (xy 81.154036 -396.834857) (xy 81.132172 -396.860522)
			(xy 81.12638 -396.86767) (xy 81.119863 -396.884859) (xy 81.119472 -396.89405) (xy 81.119472 -397.386302)
			(xy 81.119887 -397.395489) (xy 81.126398 -397.412673) (xy 81.132172 -397.41983) (xy 81.154 -397.445526)
			(xy 81.192091 -397.501155) (xy 81.220853 -397.556356) (xy 82.349068 -397.556356) (xy 82.357111 -397.489534)
			(xy 82.373082 -397.424153) (xy 82.396753 -397.361149) (xy 82.427783 -397.301425) (xy 82.46573 -397.245838)
			(xy 82.487516 -397.220186) (xy 82.493303 -397.213034) (xy 82.499823 -397.195849) (xy 82.500216 -397.186658)
			(xy 82.500216 -397.028924) (xy 82.500641 -397.018769) (xy 82.508432 -397.000014) (xy 82.522828 -396.98569)
			(xy 82.541621 -396.977992) (xy 82.551778 -396.977616) (xy 83.268058 -396.977616) (xy 83.278179 -396.97816)
			(xy 83.296895 -396.98587) (xy 83.311252 -397.000138) (xy 83.319076 -397.018806) (xy 83.31962 -397.028924)
			(xy 83.31962 -397.186658) (xy 83.320046 -397.195844) (xy 83.326548 -397.213028) (xy 83.33232 -397.220186)
			(xy 83.354119 -397.24583) (xy 83.39207 -397.301416) (xy 83.423105 -397.361141) (xy 83.446779 -397.424146)
			(xy 83.462753 -397.48953) (xy 83.470796 -397.556354) (xy 83.470796 -397.623661) (xy 83.46275 -397.690485)
			(xy 83.446775 -397.755868) (xy 83.423099 -397.818873) (xy 83.420495 -397.823884) (xy 84.548667 -397.823884)
			(xy 84.548671 -397.756458) (xy 84.55675 -397.689518) (xy 84.572788 -397.624028) (xy 84.596555 -397.560929)
			(xy 84.627708 -397.501132) (xy 84.665799 -397.445496) (xy 84.687664 -397.41983) (xy 84.693481 -397.412699)
			(xy 84.699982 -397.395497) (xy 84.700364 -397.386302) (xy 84.700364 -396.89405) (xy 84.699916 -396.884867)
			(xy 84.693427 -396.867683) (xy 84.687664 -396.860522) (xy 84.665791 -396.834864) (xy 84.627705 -396.779228)
			(xy 84.596557 -396.71943) (xy 84.572795 -396.656332) (xy 84.556761 -396.590843) (xy 84.548687 -396.523904)
			(xy 84.548688 -396.456481) (xy 84.556764 -396.389542) (xy 84.5728 -396.324053) (xy 84.596563 -396.260956)
			(xy 84.627713 -396.201159) (xy 84.665801 -396.145524) (xy 84.687664 -396.119858) (xy 84.693469 -396.112719)
			(xy 84.699977 -396.095523) (xy 84.700364 -396.08633) (xy 84.700364 -395.92885) (xy 84.700868 -395.918724)
			(xy 84.708584 -395.899999) (xy 84.722866 -395.88564) (xy 84.741548 -395.877823) (xy 84.751672 -395.877288)
			(xy 85.467952 -395.877288) (xy 85.478102 -395.877761) (xy 85.496851 -395.885538) (xy 85.511175 -395.899919)
			(xy 85.518879 -395.918699) (xy 85.51926 -395.92885) (xy 85.51926 -396.08633) (xy 85.519665 -396.095518)
			(xy 85.526183 -396.112701) (xy 85.53196 -396.119858) (xy 85.553816 -396.145531) (xy 85.591907 -396.201163)
			(xy 85.623061 -396.260958) (xy 85.646827 -396.324054) (xy 85.662864 -396.389543) (xy 85.670942 -396.456481)
			(xy 85.670943 -396.523904) (xy 85.662867 -396.590843) (xy 85.646832 -396.656332) (xy 85.623067 -396.719428)
			(xy 85.591915 -396.779224) (xy 85.553825 -396.834857) (xy 85.53196 -396.860522) (xy 85.526167 -396.867669)
			(xy 85.519651 -396.884858) (xy 85.51926 -396.89405) (xy 85.51926 -397.386302) (xy 85.519678 -397.395488)
			(xy 85.526187 -397.412672) (xy 85.53196 -397.41983) (xy 85.553788 -397.445525) (xy 85.591881 -397.501155)
			(xy 85.620612 -397.556296) (xy 86.748836 -397.556296) (xy 86.756911 -397.489358) (xy 86.772946 -397.423869)
			(xy 86.79671 -397.360773) (xy 86.82786 -397.300977) (xy 86.865948 -397.245343) (xy 86.887812 -397.219678)
			(xy 86.893602 -397.212528) (xy 86.90012 -397.195341) (xy 86.900512 -397.18615) (xy 86.900512 -397.028924)
			(xy 86.900936 -397.018802) (xy 86.908678 -397.000096) (xy 86.922993 -396.985781) (xy 86.941698 -396.978037)
			(xy 86.95182 -396.977616) (xy 87.6681 -396.977616) (xy 87.678224 -396.978016) (xy 87.696931 -396.985768)
			(xy 87.711246 -397.000089) (xy 87.718988 -397.018799) (xy 87.719408 -397.028924) (xy 87.719408 -397.18615)
			(xy 87.71984 -397.195335) (xy 87.726338 -397.21252) (xy 87.732108 -397.219678) (xy 87.753982 -397.245335)
			(xy 87.792069 -397.300971) (xy 87.823219 -397.360769) (xy 87.846982 -397.423866) (xy 87.863017 -397.489356)
			(xy 87.871092 -397.556295) (xy 87.871091 -397.62372) (xy 87.863014 -397.690658) (xy 87.846978 -397.756148)
			(xy 87.823213 -397.819245) (xy 87.820827 -397.823826) (xy 88.948962 -397.823826) (xy 88.948966 -397.756517)
			(xy 88.957014 -397.689692) (xy 88.972991 -397.624307) (xy 88.996669 -397.561301) (xy 89.027707 -397.501577)
			(xy 89.065661 -397.44599) (xy 89.087452 -397.420338) (xy 89.093264 -397.413204) (xy 89.099768 -397.396005)
			(xy 89.100152 -397.38681) (xy 89.100152 -396.893542) (xy 89.09971 -396.884358) (xy 89.093217 -396.867175)
			(xy 89.087452 -396.860014) (xy 89.065654 -396.83437) (xy 89.027704 -396.778783) (xy 88.996671 -396.719058)
			(xy 88.972998 -396.656053) (xy 88.957025 -396.590669) (xy 88.948982 -396.523846) (xy 88.948983 -396.456539)
			(xy 88.957028 -396.389716) (xy 88.973003 -396.324333) (xy 88.996677 -396.261328) (xy 89.027712 -396.201604)
			(xy 89.065663 -396.146018) (xy 89.087452 -396.120366) (xy 89.093252 -396.113223) (xy 89.099763 -396.096031)
			(xy 89.100152 -396.086838) (xy 89.100152 -395.92885) (xy 89.100605 -395.91868) (xy 89.108376 -395.899884)
			(xy 89.122753 -395.885496) (xy 89.141544 -395.877712) (xy 89.151714 -395.877288) (xy 89.867994 -395.877288)
			(xy 89.878171 -395.87767) (xy 89.896976 -395.885462) (xy 89.911362 -395.899861) (xy 89.919139 -395.918672)
			(xy 89.919556 -395.92885) (xy 89.919556 -396.086838) (xy 89.919958 -396.096026) (xy 89.926478 -396.11321)
			(xy 89.932256 -396.120366) (xy 89.954034 -396.146026) (xy 89.991983 -396.201611) (xy 90.023017 -396.261334)
			(xy 90.046691 -396.324337) (xy 90.062665 -396.389719) (xy 90.07071 -396.45654) (xy 90.070711 -396.523845)
			(xy 90.062667 -396.590667) (xy 90.046695 -396.656048) (xy 90.023023 -396.719052) (xy 89.991991 -396.778776)
			(xy 89.954043 -396.834362) (xy 89.932256 -396.860014) (xy 89.926465 -396.867163) (xy 89.919948 -396.884351)
			(xy 89.919556 -396.893542) (xy 89.919556 -397.38681) (xy 89.919971 -397.395996) (xy 89.926482 -397.41318)
			(xy 89.932256 -397.420338) (xy 89.954006 -397.446021) (xy 89.991957 -397.501603) (xy 90.020411 -397.556356)
			(xy 91.149156 -397.556356) (xy 91.157198 -397.489535) (xy 91.173169 -397.424153) (xy 91.196839 -397.361149)
			(xy 91.227869 -397.301426) (xy 91.265814 -397.245839) (xy 91.2876 -397.220186) (xy 91.293385 -397.213033)
			(xy 91.299907 -397.195848) (xy 91.3003 -397.186658) (xy 91.3003 -397.028924) (xy 91.300741 -397.018771)
			(xy 91.308529 -397.000019) (xy 91.32292 -396.985695) (xy 91.341708 -396.977995) (xy 91.351862 -396.977616)
			(xy 92.068142 -396.977616) (xy 92.078268 -396.978091) (xy 92.096986 -396.985829) (xy 92.11134 -397.000118)
			(xy 92.119162 -397.0188) (xy 92.119704 -397.028924) (xy 92.119704 -397.186658) (xy 92.120133 -397.195843)
			(xy 92.126634 -397.213028) (xy 92.132404 -397.220186) (xy 92.1542 -397.245831) (xy 92.192146 -397.301419)
			(xy 92.223176 -397.361144) (xy 92.246847 -397.42415) (xy 92.262818 -397.489532) (xy 92.27086 -397.556355)
			(xy 92.270859 -397.62366) (xy 92.262815 -397.690483) (xy 92.246842 -397.755865) (xy 92.22317 -397.81887)
			(xy 92.220595 -397.823825) (xy 115.349226 -397.823825) (xy 115.349229 -397.756518) (xy 115.357277 -397.689693)
			(xy 115.373253 -397.624309) (xy 115.396928 -397.561303) (xy 115.427964 -397.501578) (xy 115.465915 -397.445991)
			(xy 115.487704 -397.420338) (xy 115.49351 -397.413199) (xy 115.500019 -397.396004) (xy 115.500404 -397.38681)
			(xy 115.500404 -396.893542) (xy 115.499973 -396.884357) (xy 115.493474 -396.867173) (xy 115.487704 -396.860014)
			(xy 115.465908 -396.834369) (xy 115.427961 -396.778781) (xy 115.39693 -396.719056) (xy 115.37326 -396.656051)
			(xy 115.357288 -396.590668) (xy 115.349246 -396.523845) (xy 115.349247 -396.45654) (xy 115.357291 -396.389717)
			(xy 115.373264 -396.324335) (xy 115.396937 -396.26133) (xy 115.427969 -396.201606) (xy 115.465917 -396.146019)
			(xy 115.487704 -396.120366) (xy 115.493498 -396.113219) (xy 115.500014 -396.09603) (xy 115.500404 -396.086838)
			(xy 115.500404 -395.92885) (xy 115.500904 -395.918686) (xy 115.508666 -395.899899) (xy 115.523028 -395.885513)
			(xy 115.541803 -395.87772) (xy 115.551966 -395.877288) (xy 116.268246 -395.877288) (xy 116.278427 -395.877627)
			(xy 116.297232 -395.885437) (xy 116.311617 -395.899849) (xy 116.319392 -395.918668) (xy 116.319808 -395.92885)
			(xy 116.319808 -396.086838) (xy 116.320198 -396.096027) (xy 116.326725 -396.113212) (xy 116.332508 -396.120366)
			(xy 116.354288 -396.146026) (xy 116.39224 -396.20161) (xy 116.423277 -396.261332) (xy 116.446952 -396.324335)
			(xy 116.462928 -396.389717) (xy 116.470973 -396.45654) (xy 116.470974 -396.523845) (xy 116.46293 -396.590668)
			(xy 116.446957 -396.65605) (xy 116.423283 -396.719055) (xy 116.392248 -396.778777) (xy 116.354297 -396.834363)
			(xy 116.332508 -396.860014) (xy 116.326724 -396.867168) (xy 116.320202 -396.884352) (xy 116.319808 -396.893542)
			(xy 116.319808 -397.38681) (xy 116.320212 -397.395998) (xy 116.32673 -397.413182) (xy 116.332508 -397.420338)
			(xy 116.35426 -397.44602) (xy 116.392213 -397.501601) (xy 116.42064 -397.556296) (xy 117.548866 -397.556296)
			(xy 117.556942 -397.489357) (xy 117.572978 -397.423868) (xy 117.596743 -397.360771) (xy 117.627896 -397.300976)
			(xy 117.665987 -397.245342) (xy 117.687852 -397.219678) (xy 117.693647 -397.212532) (xy 117.700161 -397.195342)
			(xy 117.700552 -397.18615) (xy 117.700552 -397.028924) (xy 117.701103 -397.018823) (xy 117.708824 -397.000154)
			(xy 117.7231 -396.98586) (xy 117.741759 -396.978116) (xy 117.75186 -396.977616) (xy 118.46814 -396.977616)
			(xy 118.478253 -396.978053) (xy 118.496935 -396.985807) (xy 118.511229 -397.000118) (xy 118.51896 -397.01881)
			(xy 118.519448 -397.028924) (xy 118.519448 -397.18615) (xy 118.519894 -397.195333) (xy 118.526384 -397.212517)
			(xy 118.532148 -397.219678) (xy 118.554024 -397.245334) (xy 118.592115 -397.300969) (xy 118.623269 -397.360766)
			(xy 118.647035 -397.423864) (xy 118.663071 -397.489355) (xy 118.671147 -397.556295) (xy 118.671146 -397.62372)
			(xy 118.663068 -397.69066) (xy 118.64703 -397.75615) (xy 118.623262 -397.819248) (xy 118.620846 -397.823885)
			(xy 119.748994 -397.823885) (xy 119.748998 -397.756458) (xy 119.757077 -397.689517) (xy 119.773117 -397.624026)
			(xy 119.796885 -397.560928) (xy 119.828041 -397.50113) (xy 119.866134 -397.445495) (xy 119.888 -397.41983)
			(xy 119.893809 -397.412693) (xy 119.900316 -397.395496) (xy 119.9007 -397.386302) (xy 119.9007 -396.89405)
			(xy 119.900266 -396.884865) (xy 119.893769 -396.867681) (xy 119.888 -396.860522) (xy 119.866126 -396.834865)
			(xy 119.828038 -396.779229) (xy 119.796888 -396.719432) (xy 119.773124 -396.656334) (xy 119.757089 -396.590844)
			(xy 119.749014 -396.523905) (xy 119.749015 -396.45648) (xy 119.757092 -396.389541) (xy 119.773128 -396.324052)
			(xy 119.796894 -396.260954) (xy 119.828046 -396.201158) (xy 119.866135 -396.145523) (xy 119.888 -396.119858)
			(xy 119.893797 -396.112713) (xy 119.900311 -396.095522) (xy 119.9007 -396.08633) (xy 119.9007 -395.92885)
			(xy 119.901266 -395.918731) (xy 119.90897 -395.900019) (xy 119.923232 -395.885662) (xy 119.941893 -395.877834)
			(xy 119.952008 -395.877288) (xy 120.668288 -395.877288) (xy 120.67844 -395.877731) (xy 120.69719 -395.885521)
			(xy 120.711513 -395.899911) (xy 120.719215 -395.918696) (xy 120.719596 -395.92885) (xy 120.719596 -396.08633)
			(xy 120.719992 -396.095519) (xy 120.726516 -396.112703) (xy 120.732296 -396.119858) (xy 120.75415 -396.145531)
			(xy 120.79224 -396.201165) (xy 120.823391 -396.26096) (xy 120.847156 -396.324055) (xy 120.863192 -396.389544)
			(xy 120.871269 -396.456481) (xy 120.87127 -396.523904) (xy 120.863195 -396.590842) (xy 120.84716 -396.65633)
			(xy 120.823397 -396.719427) (xy 120.792247 -396.779223) (xy 120.75416 -396.834857) (xy 120.732296 -396.860522)
			(xy 120.726507 -396.867673) (xy 120.719988 -396.884859) (xy 120.719596 -396.89405) (xy 120.719596 -397.386302)
			(xy 120.720006 -397.395489) (xy 120.72652 -397.412673) (xy 120.732296 -397.41983) (xy 120.754123 -397.445526)
			(xy 120.792213 -397.501156) (xy 120.820972 -397.556355) (xy 121.949186 -397.556355) (xy 121.95723 -397.489533)
			(xy 121.973202 -397.424152) (xy 121.996873 -397.361148) (xy 122.027905 -397.301425) (xy 122.065853 -397.245838)
			(xy 122.08764 -397.220186) (xy 122.09343 -397.213036) (xy 122.099948 -397.195849) (xy 122.10034 -397.186658)
			(xy 122.10034 -397.028924) (xy 122.100742 -397.018766) (xy 122.108537 -397.000007) (xy 122.122941 -396.985681)
			(xy 122.141742 -396.977988) (xy 122.151902 -396.977616) (xy 122.868182 -396.977616) (xy 122.878305 -396.978141)
			(xy 122.897021 -396.985858) (xy 122.911377 -397.000132) (xy 122.919201 -397.018804) (xy 122.919744 -397.028924)
			(xy 122.919744 -397.186658) (xy 122.920187 -397.195841) (xy 122.926679 -397.213026) (xy 122.932444 -397.220186)
			(xy 122.954242 -397.24583) (xy 122.992192 -397.301417) (xy 123.023225 -397.361142) (xy 123.046898 -397.424147)
			(xy 123.062871 -397.489531) (xy 123.070915 -397.556354) (xy 123.070914 -397.623661) (xy 123.062868 -397.690484)
			(xy 123.046894 -397.755867) (xy 123.023219 -397.818872) (xy 123.020645 -397.823826) (xy 124.14929 -397.823826)
			(xy 124.149293 -397.756517) (xy 124.157342 -397.689691) (xy 124.17332 -397.624306) (xy 124.197 -397.5613)
			(xy 124.22804 -397.501575) (xy 124.265997 -397.44599) (xy 124.287788 -397.420338) (xy 124.293592 -397.413198)
			(xy 124.300103 -397.396004) (xy 124.300488 -397.38681) (xy 124.300488 -396.893542) (xy 124.30006 -396.884357)
			(xy 124.293559 -396.867172) (xy 124.287788 -396.860014) (xy 124.265989 -396.834371) (xy 124.228037 -396.778784)
			(xy 124.197002 -396.71906) (xy 124.173327 -396.656054) (xy 124.157354 -396.59067) (xy 124.14931 -396.523846)
			(xy 124.14931 -396.456539) (xy 124.157356 -396.389715) (xy 124.173332 -396.324332) (xy 124.197008 -396.261327)
			(xy 124.228045 -396.201603) (xy 124.265998 -396.146018) (xy 124.287788 -396.120366) (xy 124.29358 -396.113218)
			(xy 124.300098 -396.09603) (xy 124.300488 -396.086838) (xy 124.300488 -395.92885) (xy 124.300906 -395.918675)
			(xy 124.308684 -395.899872) (xy 124.323072 -395.885484) (xy 124.341875 -395.877706) (xy 124.35205 -395.877288)
			(xy 125.06833 -395.877288) (xy 125.07851 -395.87764) (xy 125.097315 -395.885445) (xy 125.1117 -395.899852)
			(xy 125.119475 -395.91867) (xy 125.119892 -395.92885) (xy 125.119892 -396.086838) (xy 125.120286 -396.096027)
			(xy 125.126811 -396.113211) (xy 125.132592 -396.120366) (xy 125.154369 -396.146027) (xy 125.192316 -396.201613)
			(xy 125.223348 -396.261335) (xy 125.24702 -396.324339) (xy 125.262993 -396.389719) (xy 125.271037 -396.456541)
			(xy 125.271038 -396.523844) (xy 125.262995 -396.590666) (xy 125.247025 -396.656047) (xy 125.223354 -396.719051)
			(xy 125.192324 -396.778774) (xy 125.154378 -396.834361) (xy 125.132592 -396.860014) (xy 125.126806 -396.867167)
			(xy 125.120285 -396.884351) (xy 125.119892 -396.893542) (xy 125.119892 -397.38681) (xy 125.120299 -397.395998)
			(xy 125.126815 -397.413182) (xy 125.132592 -397.420338) (xy 125.154341 -397.446021) (xy 125.192289 -397.501604)
			(xy 125.22071 -397.556296) (xy 126.348954 -397.556296) (xy 126.35703 -397.489357) (xy 126.373065 -397.423869)
			(xy 126.39683 -397.360772) (xy 126.427981 -397.300976) (xy 126.466071 -397.245343) (xy 126.487936 -397.219678)
			(xy 126.493729 -397.21253) (xy 126.500245 -397.195342) (xy 126.500636 -397.18615) (xy 126.500636 -397.028924)
			(xy 126.501036 -397.018799) (xy 126.508783 -397.000089) (xy 126.523105 -396.985772) (xy 126.541818 -396.978032)
			(xy 126.551944 -396.977616) (xy 127.268224 -396.977616) (xy 127.278336 -396.978066) (xy 127.297018 -396.985814)
			(xy 127.311313 -397.000122) (xy 127.319044 -397.018811) (xy 127.319532 -397.028924) (xy 127.319532 -397.18615)
			(xy 127.319981 -397.195333) (xy 127.326469 -397.212517) (xy 127.332232 -397.219678) (xy 127.354105 -397.245336)
			(xy 127.392191 -397.300972) (xy 127.423339 -397.36077) (xy 127.447102 -397.423867) (xy 127.463135 -397.489357)
			(xy 127.47121 -397.556296) (xy 127.471209 -397.623719) (xy 127.463133 -397.690658) (xy 127.447097 -397.756147)
			(xy 127.423333 -397.819244) (xy 127.420946 -397.823826) (xy 128.54908 -397.823826) (xy 128.549084 -397.756517)
			(xy 128.557132 -397.689691) (xy 128.57311 -397.624306) (xy 128.596789 -397.5613) (xy 128.627829 -397.501576)
			(xy 128.665785 -397.445989) (xy 128.687576 -397.420338) (xy 128.693379 -397.413197) (xy 128.69989 -397.396003)
			(xy 128.700276 -397.38681) (xy 128.700276 -396.893542) (xy 128.699851 -396.884356) (xy 128.693348 -396.867171)
			(xy 128.687576 -396.860014) (xy 128.665777 -396.83437) (xy 128.627826 -396.778784) (xy 128.596792 -396.719059)
			(xy 128.573118 -396.656053) (xy 128.557144 -396.59067) (xy 128.5491 -396.523846) (xy 128.549101 -396.456539)
			(xy 128.557147 -396.389715) (xy 128.573122 -396.324332) (xy 128.596798 -396.261327) (xy 128.627834 -396.201604)
			(xy 128.665787 -396.146018) (xy 128.687576 -396.120366) (xy 128.693367 -396.113216) (xy 128.699886 -396.096029)
			(xy 128.700276 -396.086838) (xy 128.700276 -395.92885) (xy 128.700706 -395.918677) (xy 128.708481 -395.899876)
			(xy 128.722866 -395.885488) (xy 128.741665 -395.877708) (xy 128.751838 -395.877288) (xy 129.468118 -395.877288)
			(xy 129.478297 -395.87765) (xy 129.497102 -395.885451) (xy 129.511487 -395.899856) (xy 129.519263 -395.91867)
			(xy 129.51968 -395.92885) (xy 129.51968 -396.086838) (xy 129.520076 -396.096027) (xy 129.5266 -396.113211)
			(xy 129.53238 -396.120366) (xy 129.554157 -396.146026) (xy 129.592105 -396.201612) (xy 129.623138 -396.261335)
			(xy 129.64681 -396.324338) (xy 129.662784 -396.389719) (xy 129.670828 -396.456541) (xy 129.670829 -396.523844)
			(xy 129.662786 -396.590666) (xy 129.646815 -396.656047) (xy 129.623144 -396.719051) (xy 129.592113 -396.778775)
			(xy 129.554167 -396.834362) (xy 129.53238 -396.860014) (xy 129.526593 -396.867166) (xy 129.520073 -396.884351)
			(xy 129.51968 -396.893542) (xy 129.51968 -397.38681) (xy 129.52009 -397.395997) (xy 129.526604 -397.413181)
			(xy 129.53238 -397.420338) (xy 129.55413 -397.446021) (xy 129.592078 -397.501604) (xy 129.620531 -397.556356)
			(xy 130.749274 -397.556356) (xy 130.757317 -397.489534) (xy 130.773288 -397.424152) (xy 130.796959 -397.361148)
			(xy 130.827991 -397.301425) (xy 130.865937 -397.245838) (xy 130.887724 -397.220186) (xy 130.893512 -397.213035)
			(xy 130.900031 -397.195849) (xy 130.900424 -397.186658) (xy 130.900424 -397.028924) (xy 130.900842 -397.018768)
			(xy 130.908634 -397.000012) (xy 130.923032 -396.985687) (xy 130.941828 -396.97799) (xy 130.951986 -396.977616)
			(xy 131.668266 -396.977616) (xy 131.678388 -396.978154) (xy 131.697103 -396.985866) (xy 131.71146 -397.000137)
			(xy 131.719284 -397.018806) (xy 131.719828 -397.028924) (xy 131.719828 -397.186658) (xy 131.720252 -397.195844)
			(xy 131.726756 -397.213029) (xy 131.732528 -397.220186) (xy 131.754326 -397.24583) (xy 131.792277 -397.301417)
			(xy 131.823312 -397.361141) (xy 131.846985 -397.424147) (xy 131.862959 -397.48953) (xy 131.871003 -397.556354)
			(xy 131.871002 -397.623661) (xy 131.862956 -397.690485) (xy 131.846981 -397.755868) (xy 131.823306 -397.818873)
			(xy 131.792269 -397.878596) (xy 131.754317 -397.934182) (xy 131.732528 -397.959834) (xy 131.726726 -397.966975)
			(xy 131.720217 -397.984169) (xy 131.719828 -397.993362) (xy 131.719828 -398.486884) (xy 131.720239 -398.496071)
			(xy 131.726751 -398.513256) (xy 131.732528 -398.520412) (xy 131.754352 -398.546034) (xy 131.792302 -398.601624)
			(xy 131.823336 -398.661352) (xy 131.847008 -398.72436) (xy 131.86298 -398.789746) (xy 131.871021 -398.856573)
			(xy 131.871018 -398.923881) (xy 131.86297 -398.990707) (xy 131.846992 -399.056092) (xy 131.823314 -399.119098)
			(xy 131.792274 -399.178822) (xy 131.754319 -399.234408) (xy 131.732528 -399.26006) (xy 131.726715 -399.267193)
			(xy 131.720212 -399.284393) (xy 131.719828 -399.293588) (xy 131.719828 -399.451576) (xy 131.719359 -399.461725)
			(xy 131.711577 -399.480472) (xy 131.697195 -399.494795) (xy 131.678417 -399.502501) (xy 131.668266 -399.502884)
			(xy 130.951986 -399.502884) (xy 130.941861 -399.502385) (xy 130.923145 -399.494657) (xy 130.90879 -399.480375)
			(xy 130.900967 -399.461698) (xy 130.900424 -399.451576) (xy 130.900424 -399.293588) (xy 130.900014 -399.284401)
			(xy 130.8935 -399.267217) (xy 130.887724 -399.26006) (xy 130.865972 -399.234378) (xy 130.828023 -399.178796)
			(xy 130.796989 -399.119076) (xy 130.773315 -399.056076) (xy 130.75734 -398.990697) (xy 130.749294 -398.923878)
			(xy 130.74929 -398.856576) (xy 130.757331 -398.789756) (xy 130.773299 -398.724376) (xy 130.796967 -398.661373)
			(xy 130.827996 -398.601651) (xy 130.865939 -398.546065) (xy 130.887724 -398.520412) (xy 130.893543 -398.513283)
			(xy 130.900044 -398.49608) (xy 130.900424 -398.486884) (xy 130.900424 -397.993362) (xy 130.900027 -397.984174)
			(xy 130.893504 -397.96699) (xy 130.887724 -397.959834) (xy 130.865946 -397.934174) (xy 130.827998 -397.878588)
			(xy 130.796965 -397.818865) (xy 130.773293 -397.755862) (xy 130.75732 -397.690481) (xy 130.749275 -397.62366)
			(xy 130.749274 -397.556356) (xy 129.620531 -397.556356) (xy 129.623112 -397.561323) (xy 129.646786 -397.624324)
			(xy 129.662761 -397.689702) (xy 129.670808 -397.756521) (xy 129.670811 -397.823822) (xy 129.662771 -397.890642)
			(xy 129.646803 -397.956022) (xy 129.623135 -398.019025) (xy 129.592108 -398.078747) (xy 129.554165 -398.134333)
			(xy 129.53238 -398.159986) (xy 129.526562 -398.167116) (xy 129.520061 -398.184318) (xy 129.51968 -398.193514)
			(xy 129.51968 -398.351502) (xy 129.519169 -398.361658) (xy 129.511397 -398.380423) (xy 129.497037 -398.394788)
			(xy 129.478274 -398.402565) (xy 129.468118 -398.403064) (xy 128.751838 -398.403064) (xy 128.741669 -398.402605)
			(xy 128.722876 -398.394833) (xy 128.70849 -398.380458) (xy 128.700703 -398.361671) (xy 128.700276 -398.351502)
			(xy 128.700276 -398.193514) (xy 128.699865 -398.184327) (xy 128.693352 -398.167142) (xy 128.687576 -398.159986)
			(xy 128.66575 -398.134365) (xy 128.627799 -398.078775) (xy 128.596766 -398.019048) (xy 128.573093 -397.956039)
			(xy 128.557122 -397.890652) (xy 128.54908 -397.823826) (xy 127.420946 -397.823826) (xy 127.392183 -397.879041)
			(xy 127.354095 -397.934676) (xy 127.332232 -397.960342) (xy 127.326427 -397.967481) (xy 127.319919 -397.984676)
			(xy 127.319532 -397.99387) (xy 127.319532 -398.486376) (xy 127.319969 -398.49556) (xy 127.326466 -398.512744)
			(xy 127.332232 -398.519904) (xy 127.35413 -398.545541) (xy 127.392216 -398.60118) (xy 127.423363 -398.66098)
			(xy 127.447124 -398.724081) (xy 127.463156 -398.789573) (xy 127.471228 -398.856514) (xy 127.471225 -398.92394)
			(xy 127.463146 -398.99088) (xy 127.447108 -399.056371) (xy 127.423341 -399.119469) (xy 127.392188 -399.179266)
			(xy 127.354097 -399.234902) (xy 127.332232 -399.260568) (xy 127.326416 -399.267699) (xy 127.319915 -399.284901)
			(xy 127.319532 -399.294096) (xy 127.319532 -399.451576) (xy 127.318996 -399.461679) (xy 127.311272 -399.480351)
			(xy 127.296991 -399.494645) (xy 127.278327 -399.502387) (xy 127.268224 -399.502884) (xy 126.551944 -399.502884)
			(xy 126.541822 -399.502447) (xy 126.523117 -399.494711) (xy 126.5088 -399.4804) (xy 126.501056 -399.461697)
			(xy 126.500636 -399.451576) (xy 126.500636 -399.294096) (xy 126.50022 -399.28491) (xy 126.49371 -399.267726)
			(xy 126.487936 -399.260568) (xy 126.466106 -399.234874) (xy 126.428014 -399.179245) (xy 126.39686 -399.119453)
			(xy 126.373092 -399.056359) (xy 126.357053 -398.990873) (xy 126.348974 -398.923938) (xy 126.34897 -398.856516)
			(xy 126.357043 -398.78958) (xy 126.373076 -398.724092) (xy 126.396838 -398.660997) (xy 126.427986 -398.601202)
			(xy 126.466073 -398.545569) (xy 126.487936 -398.519904) (xy 126.493718 -398.512749) (xy 126.50024 -398.495566)
			(xy 126.500636 -398.486376) (xy 126.500636 -397.99387) (xy 126.500232 -397.984682) (xy 126.493713 -397.967498)
			(xy 126.487936 -397.960342) (xy 126.466081 -397.934669) (xy 126.427989 -397.879037) (xy 126.396836 -397.819242)
			(xy 126.37307 -397.756146) (xy 126.357032 -397.690657) (xy 126.348955 -397.623719) (xy 126.348954 -397.556296)
			(xy 125.22071 -397.556296) (xy 125.223323 -397.561324) (xy 125.246996 -397.624324) (xy 125.262971 -397.689702)
			(xy 125.271018 -397.756521) (xy 125.271021 -397.823822) (xy 125.262981 -397.890642) (xy 125.247013 -397.956021)
			(xy 125.223346 -398.019024) (xy 125.192319 -398.078747) (xy 125.154377 -398.134334) (xy 125.132592 -398.159986)
			(xy 125.126775 -398.167117) (xy 125.120273 -398.184318) (xy 125.119892 -398.193514) (xy 125.119892 -398.351502)
			(xy 125.119369 -398.361656) (xy 125.111599 -398.38042) (xy 125.097243 -398.394784) (xy 125.078484 -398.402563)
			(xy 125.06833 -398.403064) (xy 124.35205 -398.403064) (xy 124.341882 -398.402595) (xy 124.323089 -398.394827)
			(xy 124.308702 -398.380455) (xy 124.300915 -398.36167) (xy 124.300488 -398.351502) (xy 124.300488 -398.193514)
			(xy 124.300074 -398.184327) (xy 124.293563 -398.167143) (xy 124.287788 -398.159986) (xy 124.265961 -398.134365)
			(xy 124.228011 -398.078775) (xy 124.196976 -398.019048) (xy 124.173304 -397.956039) (xy 124.157332 -397.890653)
			(xy 124.14929 -397.823826) (xy 123.020645 -397.823826) (xy 122.992184 -397.878596) (xy 122.954233 -397.934182)
			(xy 122.932444 -397.959834) (xy 122.926644 -397.966976) (xy 122.920133 -397.984169) (xy 122.919744 -397.993362)
			(xy 122.919744 -398.486884) (xy 122.920174 -398.496069) (xy 122.926675 -398.513253) (xy 122.932444 -398.520412)
			(xy 122.954268 -398.546035) (xy 122.992217 -398.601625) (xy 123.023249 -398.661352) (xy 123.046921 -398.724361)
			(xy 123.062892 -398.789747) (xy 123.070933 -398.856573) (xy 123.07093 -398.923881) (xy 123.062882 -398.990707)
			(xy 123.046905 -399.056091) (xy 123.023227 -399.119097) (xy 122.992189 -399.178822) (xy 122.954235 -399.234408)
			(xy 122.932444 -399.26006) (xy 122.926633 -399.267194) (xy 122.920128 -399.284393) (xy 122.919744 -399.293588)
			(xy 122.919744 -399.451576) (xy 122.91926 -399.461723) (xy 122.91148 -399.480467) (xy 122.897103 -399.494789)
			(xy 122.878331 -399.502498) (xy 122.868182 -399.502884) (xy 122.151902 -399.502884) (xy 122.141778 -399.502372)
			(xy 122.123062 -399.49465) (xy 122.108706 -399.480371) (xy 122.100883 -399.461697) (xy 122.10034 -399.451576)
			(xy 122.10034 -399.293588) (xy 122.099927 -399.284401) (xy 122.093414 -399.267217) (xy 122.08764 -399.26006)
			(xy 122.065888 -399.234379) (xy 122.027938 -399.178796) (xy 121.996903 -399.119077) (xy 121.973228 -399.056076)
			(xy 121.957253 -398.990698) (xy 121.949206 -398.923878) (xy 121.949202 -398.856576) (xy 121.957243 -398.789756)
			(xy 121.973212 -398.724376) (xy 121.996881 -398.661373) (xy 122.02791 -398.60165) (xy 122.065855 -398.546064)
			(xy 122.08764 -398.520412) (xy 122.093461 -398.513285) (xy 122.09996 -398.49608) (xy 122.10034 -398.486884)
			(xy 122.10034 -397.993362) (xy 122.099939 -397.984174) (xy 122.093418 -397.96699) (xy 122.08764 -397.959834)
			(xy 122.065862 -397.934174) (xy 122.027913 -397.878588) (xy 121.996879 -397.818866) (xy 121.973206 -397.755863)
			(xy 121.957232 -397.690481) (xy 121.949187 -397.62366) (xy 121.949186 -397.556355) (xy 120.820972 -397.556355)
			(xy 120.823365 -397.560948) (xy 120.847132 -397.624041) (xy 120.86317 -397.689526) (xy 120.871249 -397.756461)
			(xy 120.871253 -397.823882) (xy 120.86318 -397.890818) (xy 120.847149 -397.956305) (xy 120.823389 -398.0194)
			(xy 120.792242 -398.079195) (xy 120.754158 -398.134829) (xy 120.732296 -398.160494) (xy 120.726519 -398.167653)
			(xy 120.719993 -398.184833) (xy 120.719596 -398.194022) (xy 120.719596 -398.351502) (xy 120.719076 -398.361624)
			(xy 120.711354 -398.380339) (xy 120.697079 -398.394694) (xy 120.678408 -398.402519) (xy 120.668288 -398.403064)
			(xy 119.952008 -398.403064) (xy 119.94185 -398.402671) (xy 119.923091 -398.394871) (xy 119.908766 -398.380465)
			(xy 119.901072 -398.361662) (xy 119.9007 -398.351502) (xy 119.9007 -398.194022) (xy 119.900279 -398.184836)
			(xy 119.893773 -398.167651) (xy 119.888 -398.160494) (xy 119.866099 -398.13486) (xy 119.828011 -398.079221)
			(xy 119.796862 -398.01942) (xy 119.7731 -397.956319) (xy 119.757067 -397.890826) (xy 119.748994 -397.823885)
			(xy 118.620846 -397.823885) (xy 118.592108 -397.879044) (xy 118.554014 -397.934678) (xy 118.532148 -397.960342)
			(xy 118.526345 -397.967482) (xy 118.519835 -397.984677) (xy 118.519448 -397.99387) (xy 118.519448 -398.486376)
			(xy 118.519881 -398.495561) (xy 118.52638 -398.512745) (xy 118.532148 -398.519904) (xy 118.554049 -398.545539)
			(xy 118.59214 -398.601177) (xy 118.623292 -398.660977) (xy 118.647057 -398.724078) (xy 118.663091 -398.789571)
			(xy 118.671165 -398.856513) (xy 118.671162 -398.923941) (xy 118.663082 -398.990882) (xy 118.647041 -399.056374)
			(xy 118.62327 -399.119473) (xy 118.592112 -399.17927) (xy 118.554016 -399.234904) (xy 118.532148 -399.260568)
			(xy 118.526334 -399.2677) (xy 118.519831 -399.284901) (xy 118.519448 -399.294096) (xy 118.519448 -399.451576)
			(xy 118.518897 -399.461677) (xy 118.511176 -399.480346) (xy 118.4969 -399.49464) (xy 118.478241 -399.502384)
			(xy 118.46814 -399.502884) (xy 117.75186 -399.502884) (xy 117.741747 -399.502447) (xy 117.723065 -399.494693)
			(xy 117.708771 -399.480382) (xy 117.70104 -399.46169) (xy 117.700552 -399.451576) (xy 117.700552 -399.294096)
			(xy 117.700132 -399.28491) (xy 117.693624 -399.267726) (xy 117.687852 -399.260568) (xy 117.666022 -399.234874)
			(xy 117.627928 -399.179245) (xy 117.596773 -399.119453) (xy 117.573005 -399.05636) (xy 117.556965 -398.990874)
			(xy 117.548886 -398.923938) (xy 117.548882 -398.856516) (xy 117.556955 -398.789579) (xy 117.572989 -398.724092)
			(xy 117.596751 -398.660996) (xy 117.627901 -398.601201) (xy 117.665988 -398.545568) (xy 117.687852 -398.519904)
			(xy 117.693636 -398.51275) (xy 117.700157 -398.495566) (xy 117.700552 -398.486376) (xy 117.700552 -397.99387)
			(xy 117.700145 -397.984683) (xy 117.693628 -397.967499) (xy 117.687852 -397.960342) (xy 117.665996 -397.93467)
			(xy 117.627904 -397.879037) (xy 117.59675 -397.819243) (xy 117.572983 -397.756147) (xy 117.556945 -397.690658)
			(xy 117.548867 -397.623719) (xy 117.548866 -397.556296) (xy 116.42064 -397.556296) (xy 116.423251 -397.56132)
			(xy 116.446929 -397.624321) (xy 116.462906 -397.6897) (xy 116.470954 -397.75652) (xy 116.470957 -397.823823)
			(xy 116.462916 -397.890644) (xy 116.446945 -397.956025) (xy 116.423275 -398.019028) (xy 116.392243 -398.07875)
			(xy 116.354295 -398.134335) (xy 116.332508 -398.159986) (xy 116.326693 -398.167118) (xy 116.320189 -398.184319)
			(xy 116.319808 -398.193514) (xy 116.319808 -398.351502) (xy 116.319269 -398.361654) (xy 116.311503 -398.380415)
			(xy 116.297152 -398.394778) (xy 116.278398 -398.402561) (xy 116.268246 -398.403064) (xy 115.551966 -398.403064)
			(xy 115.541806 -398.402595) (xy 115.523037 -398.394809) (xy 115.508673 -398.380436) (xy 115.500899 -398.361662)
			(xy 115.500404 -398.351502) (xy 115.500404 -398.193514) (xy 115.499986 -398.184328) (xy 115.493478 -398.167143)
			(xy 115.487704 -398.159986) (xy 115.46588 -398.134364) (xy 115.427935 -398.078772) (xy 115.396905 -398.019044)
			(xy 115.373236 -397.956036) (xy 115.357267 -397.89065) (xy 115.349226 -397.823825) (xy 92.220595 -397.823825)
			(xy 92.192138 -397.878594) (xy 92.154191 -397.934181) (xy 92.132404 -397.959834) (xy 92.126611 -397.966982)
			(xy 92.120094 -397.98417) (xy 92.119704 -397.993362) (xy 92.119704 -398.486884) (xy 92.120121 -398.49607)
			(xy 92.12663 -398.513255) (xy 92.132404 -398.520412) (xy 92.154226 -398.546036) (xy 92.192171 -398.601627)
			(xy 92.2232 -398.661355) (xy 92.246869 -398.724363) (xy 92.262838 -398.789748) (xy 92.270879 -398.856574)
			(xy 92.270875 -398.923881) (xy 92.262828 -398.990705) (xy 92.246853 -399.056089) (xy 92.223178 -399.119094)
			(xy 92.192143 -399.178819) (xy 92.154193 -399.234407) (xy 92.132404 -399.26006) (xy 92.1266 -399.2672)
			(xy 92.12009 -399.284394) (xy 92.119704 -399.293588) (xy 92.119704 -399.451576) (xy 92.119259 -399.461728)
			(xy 92.111472 -399.480479) (xy 92.097082 -399.494803) (xy 92.078296 -399.502505) (xy 92.068142 -399.502884)
			(xy 91.351862 -399.502884) (xy 91.341736 -399.502405) (xy 91.323018 -399.494669) (xy 91.308664 -399.480381)
			(xy 91.300842 -399.4617) (xy 91.3003 -399.451576) (xy 91.3003 -399.293588) (xy 91.299895 -399.2844)
			(xy 91.293378 -399.267216) (xy 91.2876 -399.26006) (xy 91.265849 -399.234378) (xy 91.227901 -399.178795)
			(xy 91.196869 -399.119075) (xy 91.173196 -399.056075) (xy 91.157221 -398.990697) (xy 91.149175 -398.923878)
			(xy 91.149172 -398.856576) (xy 91.157212 -398.789757) (xy 91.17318 -398.724377) (xy 91.196847 -398.661374)
			(xy 91.227874 -398.601651) (xy 91.265816 -398.546065) (xy 91.2876 -398.520412) (xy 91.293416 -398.513281)
			(xy 91.299919 -398.49608) (xy 91.3003 -398.486884) (xy 91.3003 -397.993362) (xy 91.299908 -397.984173)
			(xy 91.293382 -397.966989) (xy 91.2876 -397.959834) (xy 91.265823 -397.934173) (xy 91.227877 -397.878587)
			(xy 91.196845 -397.818864) (xy 91.173174 -397.755861) (xy 91.157201 -397.69048) (xy 91.149157 -397.623659)
			(xy 91.149156 -397.556356) (xy 90.020411 -397.556356) (xy 90.022992 -397.561322) (xy 90.046667 -397.624323)
			(xy 90.062643 -397.689701) (xy 90.07069 -397.75652) (xy 90.070693 -397.823822) (xy 90.062653 -397.890643)
			(xy 90.046684 -397.956023) (xy 90.023015 -398.019026) (xy 89.991986 -398.078748) (xy 89.954041 -398.134334)
			(xy 89.932256 -398.159986) (xy 89.926435 -398.167114) (xy 89.919936 -398.184318) (xy 89.919556 -398.193514)
			(xy 89.919556 -398.351502) (xy 89.919138 -398.361674) (xy 89.911351 -398.38047) (xy 89.896964 -398.394855)
			(xy 89.878167 -398.402639) (xy 89.867994 -398.403064) (xy 89.151714 -398.403064) (xy 89.141544 -398.402625)
			(xy 89.122749 -398.394845) (xy 89.108364 -398.380464) (xy 89.100578 -398.361672) (xy 89.100152 -398.351502)
			(xy 89.100152 -398.193514) (xy 89.099724 -398.184329) (xy 89.093221 -398.167145) (xy 89.087452 -398.159986)
			(xy 89.065626 -398.134365) (xy 89.027678 -398.078774) (xy 88.996645 -398.019047) (xy 88.972974 -397.956038)
			(xy 88.957004 -397.890652) (xy 88.948962 -397.823826) (xy 87.820827 -397.823826) (xy 87.792062 -397.879042)
			(xy 87.753972 -397.934677) (xy 87.732108 -397.960342) (xy 87.726312 -397.967488) (xy 87.719797 -397.984678)
			(xy 87.719408 -397.99387) (xy 87.719408 -398.486376) (xy 87.719828 -398.495562) (xy 87.726335 -398.512747)
			(xy 87.732108 -398.519904) (xy 87.754007 -398.54554) (xy 87.792094 -398.601179) (xy 87.823243 -398.660979)
			(xy 87.847005 -398.72408) (xy 87.863037 -398.789573) (xy 87.87111 -398.856514) (xy 87.871107 -398.92394)
			(xy 87.863028 -398.990881) (xy 87.846989 -399.056372) (xy 87.823221 -399.11947) (xy 87.792066 -399.179267)
			(xy 87.753974 -399.234903) (xy 87.732108 -399.260568) (xy 87.726301 -399.267706) (xy 87.719792 -399.284902)
			(xy 87.719408 -399.294096) (xy 87.719408 -399.451576) (xy 87.718965 -399.461696) (xy 87.711226 -399.480398)
			(xy 87.696918 -399.494712) (xy 87.67822 -399.50246) (xy 87.6681 -399.502884) (xy 86.95182 -399.502884)
			(xy 86.941697 -399.502467) (xy 86.922991 -399.494723) (xy 86.908675 -399.480406) (xy 86.900932 -399.461699)
			(xy 86.900512 -399.451576) (xy 86.900512 -399.294096) (xy 86.900101 -399.284909) (xy 86.893587 -399.267725)
			(xy 86.887812 -399.260568) (xy 86.865983 -399.234874) (xy 86.827892 -399.179244) (xy 86.796739 -399.119452)
			(xy 86.772973 -399.056358) (xy 86.756934 -398.990873) (xy 86.748855 -398.923938) (xy 86.748852 -398.856516)
			(xy 86.756925 -398.78958) (xy 86.772957 -398.724093) (xy 86.796717 -398.660998) (xy 86.827865 -398.601203)
			(xy 86.86595 -398.545569) (xy 86.887812 -398.519904) (xy 86.893591 -398.512746) (xy 86.900116 -398.495565)
			(xy 86.900512 -398.486376) (xy 86.900512 -397.99387) (xy 86.900114 -397.984682) (xy 86.893592 -397.967497)
			(xy 86.887812 -397.960342) (xy 86.865957 -397.934669) (xy 86.827868 -397.879036) (xy 86.796716 -397.819241)
			(xy 86.772951 -397.756145) (xy 86.756914 -397.690657) (xy 86.748837 -397.623719) (xy 86.748836 -397.556296)
			(xy 85.620612 -397.556296) (xy 85.623035 -397.560946) (xy 85.646803 -397.624039) (xy 85.662842 -397.689525)
			(xy 85.670922 -397.756461) (xy 85.670925 -397.823882) (xy 85.662853 -397.890819) (xy 85.64682 -397.956306)
			(xy 85.623058 -398.019402) (xy 85.59191 -398.079196) (xy 85.553823 -398.134829) (xy 85.53196 -398.160494)
			(xy 85.526178 -398.16765) (xy 85.519656 -398.184832) (xy 85.51926 -398.194022) (xy 85.51926 -398.351502)
			(xy 85.518775 -398.361629) (xy 85.511047 -398.38035) (xy 85.49676 -398.394706) (xy 85.478076 -398.402525)
			(xy 85.467952 -398.403064) (xy 84.751672 -398.403064) (xy 84.741512 -398.402701) (xy 84.722752 -398.394889)
			(xy 84.708428 -398.380474) (xy 84.700736 -398.361665) (xy 84.700364 -398.351502) (xy 84.700364 -398.194022)
			(xy 84.699929 -398.184838) (xy 84.693431 -398.167654) (xy 84.687664 -398.160494) (xy 84.665764 -398.134859)
			(xy 84.627679 -398.079219) (xy 84.596532 -398.019419) (xy 84.572771 -397.956318) (xy 84.55674 -397.890825)
			(xy 84.548667 -397.823884) (xy 83.420495 -397.823884) (xy 83.392062 -397.878597) (xy 83.35411 -397.934182)
			(xy 83.33232 -397.959834) (xy 83.326529 -397.966983) (xy 83.32001 -397.984171) (xy 83.31962 -397.993362)
			(xy 83.31962 -398.486884) (xy 83.320033 -398.496071) (xy 83.326544 -398.513256) (xy 83.33232 -398.520412)
			(xy 83.354144 -398.546035) (xy 83.392095 -398.601624) (xy 83.423129 -398.661352) (xy 83.446801 -398.72436)
			(xy 83.462773 -398.789746) (xy 83.470815 -398.856573) (xy 83.470812 -398.923881) (xy 83.462763 -398.990707)
			(xy 83.446785 -399.056092) (xy 83.423107 -399.119098) (xy 83.392067 -399.178822) (xy 83.354111 -399.234408)
			(xy 83.33232 -399.26006) (xy 83.326518 -399.267201) (xy 83.320006 -399.284395) (xy 83.31962 -399.293588)
			(xy 83.31962 -399.451576) (xy 83.319159 -399.461726) (xy 83.311375 -399.480474) (xy 83.296991 -399.494798)
			(xy 83.27821 -399.502502) (xy 83.268058 -399.502884) (xy 82.551778 -399.502884) (xy 82.541653 -399.502392)
			(xy 82.522936 -399.494662) (xy 82.508581 -399.480378) (xy 82.500758 -399.461699) (xy 82.500216 -399.451576)
			(xy 82.500216 -399.293588) (xy 82.499808 -399.284401) (xy 82.493293 -399.267216) (xy 82.487516 -399.26006)
			(xy 82.465765 -399.234378) (xy 82.427816 -399.178795) (xy 82.396783 -399.119076) (xy 82.373109 -399.056075)
			(xy 82.357134 -398.990697) (xy 82.349088 -398.923878) (xy 82.349084 -398.856576) (xy 82.357125 -398.789756)
			(xy 82.373093 -398.724377) (xy 82.396761 -398.661374) (xy 82.427788 -398.601651) (xy 82.465731 -398.546065)
			(xy 82.487516 -398.520412) (xy 82.493334 -398.513282) (xy 82.499835 -398.49608) (xy 82.500216 -398.486884)
			(xy 82.500216 -397.993362) (xy 82.499821 -397.984173) (xy 82.493296 -397.966989) (xy 82.487516 -397.959834)
			(xy 82.465739 -397.934174) (xy 82.427791 -397.878588) (xy 82.396759 -397.818865) (xy 82.373086 -397.755862)
			(xy 82.357113 -397.690481) (xy 82.349069 -397.623659) (xy 82.349068 -397.556356) (xy 81.220853 -397.556356)
			(xy 81.223245 -397.560947) (xy 81.247013 -397.62404) (xy 81.263052 -397.689525) (xy 81.271131 -397.756461)
			(xy 81.271135 -397.823882) (xy 81.263062 -397.890818) (xy 81.24703 -397.956306) (xy 81.223269 -398.019401)
			(xy 81.192121 -398.079196) (xy 81.154035 -398.134829) (xy 81.132172 -398.160494) (xy 81.126392 -398.167651)
			(xy 81.119868 -398.184832) (xy 81.119472 -398.194022) (xy 81.119472 -398.351502) (xy 81.118975 -398.361627)
			(xy 81.111249 -398.380346) (xy 81.096966 -398.394702) (xy 81.078287 -398.402523) (xy 81.068164 -398.403064)
			(xy 80.351884 -398.403064) (xy 80.341724 -398.402691) (xy 80.322965 -398.394883) (xy 80.30864 -398.380471)
			(xy 80.300948 -398.361664) (xy 80.300576 -398.351502) (xy 80.300576 -398.194022) (xy 80.300161 -398.184835)
			(xy 80.293651 -398.16765) (xy 80.287876 -398.160494) (xy 80.265976 -398.134859) (xy 80.22789 -398.07922)
			(xy 80.196742 -398.019419) (xy 80.172981 -397.956318) (xy 80.156949 -397.890826) (xy 80.148876 -397.823885)
			(xy 79.02071 -397.823885) (xy 78.991976 -397.879041) (xy 78.953888 -397.934676) (xy 78.932024 -397.960342)
			(xy 78.92623 -397.967489) (xy 78.919713 -397.984678) (xy 78.919324 -397.99387) (xy 78.919324 -398.486376)
			(xy 78.91974 -398.495563) (xy 78.926249 -398.512747) (xy 78.932024 -398.519904) (xy 78.953922 -398.54554)
			(xy 78.992009 -398.60118) (xy 79.023156 -398.66098) (xy 79.046917 -398.724081) (xy 79.06295 -398.789573)
			(xy 79.071022 -398.856514) (xy 79.071019 -398.92394) (xy 79.06294 -398.99088) (xy 79.046901 -399.056371)
			(xy 79.023134 -399.119469) (xy 78.991981 -399.179267) (xy 78.953889 -399.234902) (xy 78.932024 -399.260568)
			(xy 78.926219 -399.267707) (xy 78.919709 -399.284902) (xy 78.919324 -399.294096) (xy 78.919324 -399.451576)
			(xy 78.918865 -399.461694) (xy 78.911129 -399.480393) (xy 78.896826 -399.494707) (xy 78.878134 -399.502457)
			(xy 78.868016 -399.502884) (xy 78.151736 -399.502884) (xy 78.141614 -399.502454) (xy 78.122908 -399.494715)
			(xy 78.108592 -399.480402) (xy 78.100848 -399.461698) (xy 78.100428 -399.451576) (xy 78.100428 -399.294096)
			(xy 78.100014 -399.284909) (xy 78.093502 -399.267725) (xy 78.087728 -399.260568) (xy 78.065898 -399.234874)
			(xy 78.027807 -399.179244) (xy 77.996653 -399.119452) (xy 77.972886 -399.056359) (xy 77.956847 -398.990873)
			(xy 77.948768 -398.923938) (xy 77.948764 -398.856516) (xy 77.956837 -398.78958) (xy 77.972869 -398.724093)
			(xy 77.996631 -398.660997) (xy 78.027779 -398.601202) (xy 78.065865 -398.545569) (xy 78.087728 -398.519904)
			(xy 78.093509 -398.512748) (xy 78.100032 -398.495566) (xy 78.100428 -398.486376) (xy 78.100428 -397.99387)
			(xy 78.100026 -397.984682) (xy 78.093506 -397.967498) (xy 78.087728 -397.960342) (xy 78.065873 -397.934669)
			(xy 78.027782 -397.879036) (xy 77.996629 -397.819241) (xy 77.972863 -397.756146) (xy 77.956826 -397.690657)
			(xy 77.948749 -397.623719) (xy 77.948748 -397.556296) (xy 76.820503 -397.556296) (xy 76.823115 -397.561323)
			(xy 76.846789 -397.624324) (xy 76.862764 -397.689702) (xy 76.870811 -397.756521) (xy 76.870814 -397.823822)
			(xy 76.862774 -397.890642) (xy 76.846806 -397.956022) (xy 76.823139 -398.019024) (xy 76.792111 -398.078747)
			(xy 76.754168 -398.134333) (xy 76.732384 -398.159986) (xy 76.726567 -398.167116) (xy 76.720065 -398.184318)
			(xy 76.719684 -398.193514) (xy 76.719684 -398.351502) (xy 76.719169 -398.361657) (xy 76.711398 -398.380422)
			(xy 76.697039 -398.394787) (xy 76.678277 -398.402565) (xy 76.668122 -398.403064) (xy 75.951842 -398.403064)
			(xy 75.941673 -398.402602) (xy 75.92288 -398.394831) (xy 75.908494 -398.380457) (xy 75.900707 -398.36167)
			(xy 75.90028 -398.351502) (xy 75.90028 -398.193514) (xy 75.899868 -398.184327) (xy 75.893356 -398.167142)
			(xy 75.88758 -398.159986) (xy 75.865754 -398.134365) (xy 75.827803 -398.078775) (xy 75.79677 -398.019048)
			(xy 75.773097 -397.956039) (xy 75.757126 -397.890653) (xy 75.749084 -397.823826) (xy 74.620438 -397.823826)
			(xy 74.591977 -397.878596) (xy 74.554025 -397.934182) (xy 74.532236 -397.959834) (xy 74.526435 -397.966975)
			(xy 74.519925 -397.984169) (xy 74.519536 -397.993362) (xy 74.519536 -398.486884) (xy 74.519968 -398.496069)
			(xy 74.526468 -398.513252) (xy 74.532236 -398.520412) (xy 74.55406 -398.546035) (xy 74.592009 -398.601625)
			(xy 74.623043 -398.661352) (xy 74.646714 -398.724361) (xy 74.662686 -398.789747) (xy 74.670727 -398.856573)
			(xy 74.670724 -398.923881) (xy 74.662676 -398.990707) (xy 74.646698 -399.056091) (xy 74.623021 -399.119097)
			(xy 74.591982 -399.178822) (xy 74.554027 -399.234408) (xy 74.532236 -399.26006) (xy 74.526424 -399.267194)
			(xy 74.51992 -399.284393) (xy 74.519536 -399.293588) (xy 74.519536 -399.451576) (xy 74.51906 -399.461724)
			(xy 74.511279 -399.480469) (xy 74.496899 -399.494792) (xy 74.478124 -399.502499) (xy 74.467974 -399.502884)
			(xy 73.751694 -399.502884) (xy 73.74157 -399.502379) (xy 73.722853 -399.494654) (xy 73.708498 -399.480373)
			(xy 73.700675 -399.461697) (xy 73.700132 -399.451576) (xy 73.700132 -399.293588) (xy 73.699721 -399.284401)
			(xy 73.693207 -399.267217) (xy 73.687432 -399.26006) (xy 73.66568 -399.234378) (xy 73.627731 -399.178796)
			(xy 73.596696 -399.119077) (xy 73.573022 -399.056076) (xy 73.557047 -398.990697) (xy 73.549 -398.923878)
			(xy 73.548996 -398.856576) (xy 73.557037 -398.789756) (xy 73.573006 -398.724376) (xy 73.596674 -398.661373)
			(xy 73.627703 -398.60165) (xy 73.665647 -398.546064) (xy 73.687432 -398.520412) (xy 73.693253 -398.513284)
			(xy 73.699752 -398.49608) (xy 73.700132 -398.486884) (xy 73.700132 -397.993362) (xy 73.699733 -397.984174)
			(xy 73.693211 -397.96699) (xy 73.687432 -397.959834) (xy 73.665654 -397.934174) (xy 73.627705 -397.878588)
			(xy 73.596672 -397.818866) (xy 73.572999 -397.755862) (xy 73.557026 -397.690481) (xy 73.548981 -397.62366)
			(xy 73.54898 -397.556355) (xy 72.420766 -397.556355) (xy 72.423159 -397.560948) (xy 72.446926 -397.62404)
			(xy 72.462964 -397.689526) (xy 72.471043 -397.756461) (xy 72.471047 -397.823882) (xy 72.462974 -397.890818)
			(xy 72.446942 -397.956305) (xy 72.423182 -398.0194) (xy 72.392035 -398.079195) (xy 72.35395 -398.134829)
			(xy 72.332088 -398.160494) (xy 72.32631 -398.167652) (xy 72.319785 -398.184833) (xy 72.319388 -398.194022)
			(xy 72.319388 -398.351502) (xy 72.318876 -398.361625) (xy 72.311153 -398.380341) (xy 72.296875 -398.394696)
			(xy 72.278201 -398.40252) (xy 72.26808 -398.403064) (xy 71.5518 -398.403064) (xy 71.541641 -398.402678)
			(xy 71.522882 -398.394875) (xy 71.508557 -398.380467) (xy 71.500864 -398.361663) (xy 71.500492 -398.351502)
			(xy 71.500492 -398.194022) (xy 71.500073 -398.184836) (xy 71.493566 -398.167651) (xy 71.487792 -398.160494)
			(xy 71.465891 -398.134859) (xy 71.427804 -398.07922) (xy 71.396655 -398.01942) (xy 71.372894 -397.956319)
			(xy 71.356861 -397.890826) (xy 71.348788 -397.823885) (xy 66.525648 -397.823885) (xy 66.525648 -401.723796)
			(xy 71.3488 -401.723796) (xy 71.348802 -401.656371) (xy 71.35688 -401.589431) (xy 71.372917 -401.523941)
			(xy 71.396683 -401.460843) (xy 71.427836 -401.401046) (xy 71.465927 -401.345411) (xy 71.487792 -401.319746)
			(xy 71.493593 -401.312604) (xy 71.500105 -401.295411) (xy 71.500492 -401.286218) (xy 71.500492 -400.793966)
			(xy 71.5001 -400.784777) (xy 71.493574 -400.767592) (xy 71.487792 -400.760438) (xy 71.465934 -400.734768)
			(xy 71.427846 -400.679134) (xy 71.396695 -400.619338) (xy 71.372931 -400.556242) (xy 71.356896 -400.490754)
			(xy 71.348819 -400.423816) (xy 71.348819 -400.356393) (xy 71.356894 -400.289455) (xy 71.372928 -400.223967)
			(xy 71.396692 -400.16087) (xy 71.427841 -400.101074) (xy 71.465929 -400.045439) (xy 71.487792 -400.019774)
			(xy 71.493581 -400.012623) (xy 71.500101 -399.995437) (xy 71.500492 -399.986246) (xy 71.500492 -399.828766)
			(xy 71.500997 -399.818643) (xy 71.508727 -399.79993) (xy 71.523007 -399.785577) (xy 71.54168 -399.77775)
			(xy 71.5518 -399.777204) (xy 72.26808 -399.777204) (xy 72.278233 -399.777638) (xy 72.296986 -399.785428)
			(xy 72.31131 -399.799821) (xy 72.31901 -399.818611) (xy 72.319388 -399.828766) (xy 72.319388 -399.986246)
			(xy 72.319827 -399.99543) (xy 72.326321 -400.012615) (xy 72.332088 -400.019774) (xy 72.353958 -400.045434)
			(xy 72.392048 -400.101069) (xy 72.423199 -400.160866) (xy 72.446963 -400.223963) (xy 72.462999 -400.289453)
			(xy 72.471074 -400.356392) (xy 72.471074 -400.423817) (xy 72.462997 -400.490756) (xy 72.44696 -400.556245)
			(xy 72.423195 -400.619342) (xy 72.392043 -400.679139) (xy 72.353953 -400.734773) (xy 72.332088 -400.760438)
			(xy 72.326291 -400.767583) (xy 72.319777 -400.784774) (xy 72.319388 -400.793966) (xy 72.319388 -401.286218)
			(xy 72.319792 -401.295406) (xy 72.32631 -401.31259) (xy 72.332088 -401.319746) (xy 72.353931 -401.345429)
			(xy 72.392021 -401.401061) (xy 72.423173 -401.460854) (xy 72.446939 -401.523949) (xy 72.462977 -401.589436)
			(xy 72.471054 -401.656372) (xy 72.471056 -401.723795) (xy 72.462982 -401.790732) (xy 72.446949 -401.85622)
			(xy 72.423187 -401.919316) (xy 72.392038 -401.979111) (xy 72.353951 -402.034745) (xy 72.332088 -402.06041)
			(xy 72.326303 -402.067564) (xy 72.319782 -402.084748) (xy 72.319388 -402.093938) (xy 72.319388 -402.251418)
			(xy 72.318889 -402.261542) (xy 72.311161 -402.280259) (xy 72.296879 -402.294614) (xy 72.278202 -402.302437)
			(xy 72.26808 -402.30298) (xy 71.5518 -402.30298) (xy 71.541643 -402.302578) (xy 71.522887 -402.294779)
			(xy 71.508563 -402.280376) (xy 71.500867 -402.261577) (xy 71.500492 -402.251418) (xy 71.500492 -402.093938)
			(xy 71.500065 -402.084753) (xy 71.493563 -402.067568) (xy 71.487792 -402.06041) (xy 71.465907 -402.034762)
			(xy 71.427819 -401.979125) (xy 71.39667 -401.919326) (xy 71.372907 -401.856227) (xy 71.356874 -401.790736)
			(xy 71.3488 -401.723796) (xy 66.525648 -401.723796) (xy 66.525648 -402.823818) (xy 73.54894 -402.823818)
			(xy 73.548944 -402.75651) (xy 73.556993 -402.689684) (xy 73.572971 -402.624299) (xy 73.596649 -402.561293)
			(xy 73.627687 -402.501568) (xy 73.665642 -402.44598) (xy 73.687432 -402.420328) (xy 73.693246 -402.413195)
			(xy 73.699749 -402.395995) (xy 73.700132 -402.3868) (xy 73.700132 -401.893532) (xy 73.699699 -401.884347)
			(xy 73.6932 -401.867163) (xy 73.687432 -401.860004) (xy 73.665625 -401.834368) (xy 73.627677 -401.778779)
			(xy 73.596645 -401.719053) (xy 73.572974 -401.656047) (xy 73.557002 -401.590662) (xy 73.54896 -401.523838)
			(xy 73.548962 -401.456532) (xy 73.557008 -401.389708) (xy 73.572982 -401.324325) (xy 73.596657 -401.261319)
			(xy 73.627692 -401.201595) (xy 73.665643 -401.146008) (xy 73.687432 -401.120356) (xy 73.693234 -401.113215)
			(xy 73.699745 -401.096021) (xy 73.700132 -401.086828) (xy 73.700132 -400.92884) (xy 73.700555 -400.918685)
			(xy 73.708343 -400.899927) (xy 73.722741 -400.885601) (xy 73.741537 -400.877906) (xy 73.751694 -400.877532)
			(xy 74.467974 -400.877532) (xy 74.478098 -400.878047) (xy 74.496817 -400.885765) (xy 74.511174 -400.900043)
			(xy 74.518996 -400.918719) (xy 74.519536 -400.92884) (xy 74.519536 -401.086828) (xy 74.519947 -401.096015)
			(xy 74.526462 -401.113198) (xy 74.532236 -401.120356) (xy 74.554005 -401.146024) (xy 74.591956 -401.201608)
			(xy 74.622991 -401.261329) (xy 74.646666 -401.324331) (xy 74.662641 -401.389712) (xy 74.670687 -401.456533)
			(xy 74.670689 -401.523837) (xy 74.662647 -401.590659) (xy 74.646675 -401.65604) (xy 74.623004 -401.719044)
			(xy 74.620565 -401.723737) (xy 75.749095 -401.723737) (xy 75.749097 -401.65643) (xy 75.757144 -401.589605)
			(xy 75.773121 -401.524221) (xy 75.796798 -401.461215) (xy 75.827836 -401.401492) (xy 75.86579 -401.345906)
			(xy 75.88758 -401.320254) (xy 75.893376 -401.313108) (xy 75.899892 -401.295918) (xy 75.90028 -401.286726)
			(xy 75.90028 -400.793458) (xy 75.899895 -400.784268) (xy 75.893364 -400.767084) (xy 75.88758 -400.75993)
			(xy 75.865797 -400.734274) (xy 75.827845 -400.678689) (xy 75.79681 -400.618966) (xy 75.773135 -400.555962)
			(xy 75.75716 -400.49058) (xy 75.749115 -400.423757) (xy 75.749114 -400.356452) (xy 75.757158 -400.289629)
			(xy 75.773132 -400.224247) (xy 75.796806 -400.161242) (xy 75.827841 -400.101519) (xy 75.865791 -400.045934)
			(xy 75.88758 -400.020282) (xy 75.893364 -400.013128) (xy 75.899887 -399.995944) (xy 75.90028 -399.986754)
			(xy 75.90028 -399.828766) (xy 75.900637 -399.818587) (xy 75.908441 -399.799783) (xy 75.922847 -399.785398)
			(xy 75.941662 -399.777622) (xy 75.951842 -399.777204) (xy 76.668122 -399.777204) (xy 76.678277 -399.777714)
			(xy 76.69704 -399.78549) (xy 76.711404 -399.79985) (xy 76.719183 -399.818611) (xy 76.719684 -399.828766)
			(xy 76.719684 -399.986754) (xy 76.72012 -399.995938) (xy 76.726616 -400.013123) (xy 76.732384 -400.020282)
			(xy 76.754177 -400.04593) (xy 76.792124 -400.101517) (xy 76.823156 -400.161242) (xy 76.846827 -400.224247)
			(xy 76.862799 -400.289629) (xy 76.870842 -400.356452) (xy 76.870842 -400.423757) (xy 76.862798 -400.49058)
			(xy 76.846825 -400.555962) (xy 76.823152 -400.618967) (xy 76.792119 -400.678691) (xy 76.754171 -400.734278)
			(xy 76.732384 -400.75993) (xy 76.72659 -400.767077) (xy 76.720074 -400.784266) (xy 76.719684 -400.793458)
			(xy 76.719684 -401.286726) (xy 76.720085 -401.295914) (xy 76.726605 -401.313098) (xy 76.732384 -401.320254)
			(xy 76.754149 -401.345924) (xy 76.792097 -401.401509) (xy 76.82313 -401.46123) (xy 76.846803 -401.524232)
			(xy 76.862777 -401.589612) (xy 76.870823 -401.656432) (xy 76.870825 -401.723735) (xy 76.862783 -401.790556)
			(xy 76.846813 -401.855936) (xy 76.823144 -401.91894) (xy 76.792114 -401.978663) (xy 76.75417 -402.03425)
			(xy 76.732384 -402.059902) (xy 76.726602 -402.067058) (xy 76.720079 -402.08424) (xy 76.719684 -402.09343)
			(xy 76.719684 -402.251418) (xy 76.719182 -402.261574) (xy 76.711406 -402.28034) (xy 76.697043 -402.294704)
			(xy 76.678278 -402.302481) (xy 76.668122 -402.30298) (xy 75.951842 -402.30298) (xy 75.941675 -402.302502)
			(xy 75.922885 -402.294734) (xy 75.908499 -402.280365) (xy 75.90071 -402.261584) (xy 75.90028 -402.251418)
			(xy 75.90028 -402.09343) (xy 75.89986 -402.084244) (xy 75.893354 -402.067059) (xy 75.88758 -402.059902)
			(xy 75.865769 -402.034268) (xy 75.827819 -401.97868) (xy 75.796784 -401.918954) (xy 75.773111 -401.855947)
			(xy 75.757138 -401.790562) (xy 75.749095 -401.723737) (xy 74.620565 -401.723737) (xy 74.591971 -401.778767)
			(xy 74.554023 -401.834352) (xy 74.532236 -401.860004) (xy 74.526447 -401.867155) (xy 74.51993 -401.884341)
			(xy 74.519536 -401.893532) (xy 74.519536 -402.3868) (xy 74.519961 -402.395985) (xy 74.526466 -402.413169)
			(xy 74.532236 -402.420328) (xy 74.553977 -402.446019) (xy 74.591929 -402.501599) (xy 74.622966 -402.561317)
			(xy 74.646642 -402.624317) (xy 74.662619 -402.689694) (xy 74.670668 -402.756513) (xy 74.670672 -402.823815)
			(xy 74.670664 -402.823878) (xy 77.948708 -402.823878) (xy 77.948713 -402.75645) (xy 77.956794 -402.689508)
			(xy 77.972835 -402.624016) (xy 77.996606 -402.560917) (xy 78.027764 -402.501119) (xy 78.06586 -402.445485)
			(xy 78.087728 -402.41982) (xy 78.093545 -402.412689) (xy 78.100047 -402.395488) (xy 78.100428 -402.386292)
			(xy 78.100428 -401.89404) (xy 78.099992 -401.884856) (xy 78.093496 -401.867671) (xy 78.087728 -401.860512)
			(xy 78.065843 -401.834863) (xy 78.027753 -401.779227) (xy 77.996602 -401.719429) (xy 77.972838 -401.65633)
			(xy 77.956803 -401.590838) (xy 77.948728 -401.523898) (xy 77.94873 -401.456472) (xy 77.956808 -401.389532)
			(xy 77.972847 -401.324041) (xy 77.996614 -401.260944) (xy 78.027769 -401.201147) (xy 78.065862 -401.145513)
			(xy 78.087728 -401.119848) (xy 78.093533 -401.112709) (xy 78.100042 -401.095514) (xy 78.100428 -401.08632)
			(xy 78.100428 -400.92884) (xy 78.10085 -400.918717) (xy 78.10859 -400.900009) (xy 78.122905 -400.885692)
			(xy 78.141613 -400.87795) (xy 78.151736 -400.877532) (xy 78.868016 -400.877532) (xy 78.878144 -400.877903)
			(xy 78.896854 -400.885663) (xy 78.911169 -400.899993) (xy 78.918908 -400.918712) (xy 78.919324 -400.92884)
			(xy 78.919324 -401.08632) (xy 78.919719 -401.095509) (xy 78.926243 -401.112693) (xy 78.932024 -401.119848)
			(xy 78.953867 -401.14553) (xy 78.991955 -401.201163) (xy 79.023105 -401.260957) (xy 79.04687 -401.324051)
			(xy 79.062906 -401.389538) (xy 79.070983 -401.456474) (xy 79.070985 -401.523896) (xy 79.062911 -401.590832)
			(xy 79.046879 -401.65632) (xy 79.023118 -401.719416) (xy 79.020837 -401.723796) (xy 80.148888 -401.723796)
			(xy 80.14889 -401.656371) (xy 80.156967 -401.589432) (xy 80.173004 -401.523942) (xy 80.19677 -401.460844)
			(xy 80.227922 -401.401047) (xy 80.266012 -401.345412) (xy 80.287876 -401.319746) (xy 80.293675 -401.312603)
			(xy 80.300189 -401.295411) (xy 80.300576 -401.286218) (xy 80.300576 -400.793966) (xy 80.300187 -400.784776)
			(xy 80.293659 -400.767592) (xy 80.287876 -400.760438) (xy 80.266019 -400.734767) (xy 80.227931 -400.679133)
			(xy 80.196782 -400.619337) (xy 80.173018 -400.556241) (xy 80.156983 -400.490753) (xy 80.148907 -400.423816)
			(xy 80.148907 -400.356393) (xy 80.156982 -400.289456) (xy 80.173016 -400.223967) (xy 80.196778 -400.160871)
			(xy 80.227927 -400.101075) (xy 80.266013 -400.04544) (xy 80.287876 -400.019774) (xy 80.293663 -400.012622)
			(xy 80.300184 -399.995437) (xy 80.300576 -399.986246) (xy 80.300576 -399.828766) (xy 80.301 -399.818633)
			(xy 80.308745 -399.799904) (xy 80.323051 -399.785548) (xy 80.341753 -399.777736) (xy 80.351884 -399.777204)
			(xy 81.068164 -399.777204) (xy 81.078316 -399.777651) (xy 81.097069 -399.785436) (xy 81.111393 -399.799825)
			(xy 81.119094 -399.818612) (xy 81.119472 -399.828766) (xy 81.119472 -399.986246) (xy 81.119914 -399.99543)
			(xy 81.126406 -400.012614) (xy 81.132172 -400.019774) (xy 81.154043 -400.045434) (xy 81.192133 -400.101069)
			(xy 81.223285 -400.160865) (xy 81.24705 -400.223963) (xy 81.263086 -400.289453) (xy 81.271162 -400.356392)
			(xy 81.271161 -400.423817) (xy 81.263085 -400.490756) (xy 81.247048 -400.556246) (xy 81.223282 -400.619343)
			(xy 81.192129 -400.679139) (xy 81.154037 -400.734773) (xy 81.132172 -400.760438) (xy 81.126373 -400.767581)
			(xy 81.11986 -400.784773) (xy 81.119472 -400.793966) (xy 81.119472 -401.286218) (xy 81.11988 -401.295405)
			(xy 81.126396 -401.312589) (xy 81.132172 -401.319746) (xy 81.154015 -401.345429) (xy 81.192107 -401.40106)
			(xy 81.22326 -401.460854) (xy 81.247026 -401.523948) (xy 81.263064 -401.589435) (xy 81.271142 -401.656372)
			(xy 81.271144 -401.723795) (xy 81.26307 -401.790732) (xy 81.247036 -401.85622) (xy 81.223273 -401.919316)
			(xy 81.192124 -401.979112) (xy 81.154036 -402.034745) (xy 81.132172 -402.06041) (xy 81.126385 -402.067562)
			(xy 81.119865 -402.084747) (xy 81.119472 -402.093938) (xy 81.119472 -402.251418) (xy 81.118989 -402.261544)
			(xy 81.111257 -402.280264) (xy 81.09697 -402.294619) (xy 81.078288 -402.30244) (xy 81.068164 -402.30298)
			(xy 80.351884 -402.30298) (xy 80.341726 -402.302591) (xy 80.32297 -402.294787) (xy 80.308646 -402.28038)
			(xy 80.30095 -402.261578) (xy 80.300576 -402.251418) (xy 80.300576 -402.093938) (xy 80.300153 -402.084752)
			(xy 80.293649 -402.067567) (xy 80.287876 -402.06041) (xy 80.265991 -402.034762) (xy 80.227905 -401.979125)
			(xy 80.196756 -401.919326) (xy 80.172994 -401.856227) (xy 80.156961 -401.790736) (xy 80.148888 -401.723796)
			(xy 79.020837 -401.723796) (xy 78.991971 -401.779212) (xy 78.953886 -401.834846) (xy 78.932024 -401.860512)
			(xy 78.926243 -401.867668) (xy 78.919718 -401.88485) (xy 78.919324 -401.89404) (xy 78.919324 -402.386292)
			(xy 78.919733 -402.395479) (xy 78.926247 -402.412664) (xy 78.932024 -402.41982) (xy 78.95384 -402.445525)
			(xy 78.991929 -402.501154) (xy 79.02308 -402.560945) (xy 79.046846 -402.624037) (xy 79.062884 -402.689521)
			(xy 79.070963 -402.756454) (xy 79.070968 -402.823818) (xy 82.349028 -402.823818) (xy 82.349032 -402.75651)
			(xy 82.357081 -402.689684) (xy 82.373058 -402.6243) (xy 82.396735 -402.561293) (xy 82.427773 -402.501568)
			(xy 82.465726 -402.44598) (xy 82.487516 -402.420328) (xy 82.493327 -402.413193) (xy 82.499833 -402.395995)
			(xy 82.500216 -402.3868) (xy 82.500216 -401.893532) (xy 82.499787 -401.884347) (xy 82.493286 -401.867163)
			(xy 82.487516 -401.860004) (xy 82.465709 -401.834368) (xy 82.427763 -401.778778) (xy 82.396731 -401.719052)
			(xy 82.373061 -401.656046) (xy 82.35709 -401.590662) (xy 82.349048 -401.523838) (xy 82.34905 -401.456532)
			(xy 82.357095 -401.389708) (xy 82.37307 -401.324325) (xy 82.396744 -401.26132) (xy 82.427778 -401.201596)
			(xy 82.465728 -401.146008) (xy 82.487516 -401.120356) (xy 82.493316 -401.113213) (xy 82.499828 -401.096021)
			(xy 82.500216 -401.086828) (xy 82.500216 -400.92884) (xy 82.500655 -400.918687) (xy 82.50844 -400.899932)
			(xy 82.522832 -400.885607) (xy 82.541623 -400.877908) (xy 82.551778 -400.877532) (xy 83.268058 -400.877532)
			(xy 83.278181 -400.878061) (xy 83.2969 -400.885773) (xy 83.311257 -400.900047) (xy 83.319079 -400.91872)
			(xy 83.31962 -400.92884) (xy 83.31962 -401.086828) (xy 83.320012 -401.096017) (xy 83.326538 -401.113202)
			(xy 83.33232 -401.120356) (xy 83.354089 -401.146024) (xy 83.392041 -401.201607) (xy 83.423078 -401.261328)
			(xy 83.446753 -401.324331) (xy 83.462729 -401.389711) (xy 83.470775 -401.456533) (xy 83.470777 -401.523837)
			(xy 83.462734 -401.590659) (xy 83.446762 -401.656041) (xy 83.42309 -401.719044) (xy 83.420621 -401.723796)
			(xy 84.548678 -401.723796) (xy 84.54868 -401.656371) (xy 84.556758 -401.589432) (xy 84.572795 -401.523942)
			(xy 84.59656 -401.460845) (xy 84.627711 -401.401047) (xy 84.6658 -401.345412) (xy 84.687664 -401.319746)
			(xy 84.693474 -401.312611) (xy 84.699979 -401.295412) (xy 84.700364 -401.286218) (xy 84.700364 -400.793966)
			(xy 84.699956 -400.784779) (xy 84.693439 -400.767595) (xy 84.687664 -400.760438) (xy 84.665807 -400.734767)
			(xy 84.627721 -400.679133) (xy 84.596572 -400.619337) (xy 84.572809 -400.556241) (xy 84.556774 -400.490753)
			(xy 84.548698 -400.423816) (xy 84.548698 -400.356393) (xy 84.556772 -400.289456) (xy 84.572806 -400.223968)
			(xy 84.596568 -400.160871) (xy 84.627716 -400.101075) (xy 84.665802 -400.04544) (xy 84.687664 -400.019774)
			(xy 84.693462 -400.01263) (xy 84.699974 -399.995438) (xy 84.700364 -399.986246) (xy 84.700364 -399.828766)
			(xy 84.700799 -399.818634) (xy 84.708543 -399.799908) (xy 84.722845 -399.785552) (xy 84.741542 -399.777738)
			(xy 84.751672 -399.777204) (xy 85.467952 -399.777204) (xy 85.478104 -399.777661) (xy 85.496856 -399.785442)
			(xy 85.511181 -399.799828) (xy 85.518881 -399.818613) (xy 85.51926 -399.828766) (xy 85.51926 -399.986246)
			(xy 85.519705 -399.995429) (xy 85.526196 -400.012613) (xy 85.53196 -400.019774) (xy 85.553831 -400.045434)
			(xy 85.591922 -400.101068) (xy 85.623075 -400.160865) (xy 85.646841 -400.223962) (xy 85.662877 -400.289453)
			(xy 85.670953 -400.356392) (xy 85.670952 -400.423817) (xy 85.662875 -400.490756) (xy 85.646838 -400.556246)
			(xy 85.623071 -400.619344) (xy 85.591918 -400.67914) (xy 85.553826 -400.734773) (xy 85.53196 -400.760438)
			(xy 85.52616 -400.76758) (xy 85.519648 -400.784773) (xy 85.51926 -400.793966) (xy 85.51926 -401.286218)
			(xy 85.51967 -401.295405) (xy 85.526185 -401.312589) (xy 85.53196 -401.319746) (xy 85.553804 -401.345428)
			(xy 85.591896 -401.40106) (xy 85.62305 -401.460853) (xy 85.646817 -401.523948) (xy 85.662855 -401.589435)
			(xy 85.670933 -401.656372) (xy 85.670935 -401.723795) (xy 85.662861 -401.790732) (xy 85.646827 -401.856221)
			(xy 85.623063 -401.919317) (xy 85.591913 -401.979112) (xy 85.553824 -402.034745) (xy 85.53196 -402.06041)
			(xy 85.526172 -402.067561) (xy 85.519653 -402.084747) (xy 85.51926 -402.093938) (xy 85.51926 -402.251418)
			(xy 85.518788 -402.261546) (xy 85.511055 -402.280268) (xy 85.496764 -402.294623) (xy 85.478078 -402.302442)
			(xy 85.467952 -402.30298) (xy 84.751672 -402.30298) (xy 84.741514 -402.302601) (xy 84.722757 -402.294792)
			(xy 84.708434 -402.280383) (xy 84.700738 -402.261579) (xy 84.700364 -402.251418) (xy 84.700364 -402.093938)
			(xy 84.699921 -402.084755) (xy 84.693429 -402.067571) (xy 84.687664 -402.06041) (xy 84.66578 -402.034762)
			(xy 84.627694 -401.979124) (xy 84.596546 -401.919325) (xy 84.572785 -401.856226) (xy 84.556752 -401.790735)
			(xy 84.548678 -401.723796) (xy 83.420621 -401.723796) (xy 83.392057 -401.778767) (xy 83.354108 -401.834352)
			(xy 83.33232 -401.860004) (xy 83.326542 -401.867162) (xy 83.320015 -401.884343) (xy 83.31962 -401.893532)
			(xy 83.31962 -402.3868) (xy 83.320026 -402.395988) (xy 83.326542 -402.413172) (xy 83.33232 -402.420328)
			(xy 83.354062 -402.446018) (xy 83.392015 -402.501598) (xy 83.423052 -402.561316) (xy 83.44673 -402.624316)
			(xy 83.462707 -402.689694) (xy 83.470756 -402.756513) (xy 83.47076 -402.823815) (xy 83.470752 -402.823878)
			(xy 86.748796 -402.823878) (xy 86.748801 -402.75645) (xy 86.756882 -402.689508) (xy 86.772922 -402.624016)
			(xy 86.796693 -402.560918) (xy 86.82785 -402.50112) (xy 86.865945 -402.445485) (xy 86.887812 -402.41982)
			(xy 86.893626 -402.412687) (xy 86.90013 -402.395487) (xy 86.900512 -402.386292) (xy 86.900512 -401.89404)
			(xy 86.90008 -401.884855) (xy 86.893581 -401.867671) (xy 86.887812 -401.860512) (xy 86.865928 -401.834863)
			(xy 86.827839 -401.779227) (xy 86.796689 -401.719428) (xy 86.772925 -401.656329) (xy 86.756891 -401.590838)
			(xy 86.748816 -401.523898) (xy 86.748818 -401.456472) (xy 86.756896 -401.389532) (xy 86.772934 -401.324042)
			(xy 86.796701 -401.260944) (xy 86.827855 -401.201148) (xy 86.865946 -401.145513) (xy 86.887812 -401.119848)
			(xy 86.893615 -401.112707) (xy 86.900125 -401.095513) (xy 86.900512 -401.08632) (xy 86.900512 -400.92884)
			(xy 86.900949 -400.918719) (xy 86.908686 -400.900014) (xy 86.922997 -400.885698) (xy 86.941699 -400.877953)
			(xy 86.95182 -400.877532) (xy 87.6681 -400.877532) (xy 87.678226 -400.877917) (xy 87.696936 -400.885671)
			(xy 87.711252 -400.899997) (xy 87.718991 -400.918713) (xy 87.719408 -400.92884) (xy 87.719408 -401.08632)
			(xy 87.719807 -401.095508) (xy 87.726328 -401.112693) (xy 87.732108 -401.119848) (xy 87.753952 -401.14553)
			(xy 87.792041 -401.201162) (xy 87.823192 -401.260956) (xy 87.846957 -401.324051) (xy 87.862994 -401.389538)
			(xy 87.871071 -401.456474) (xy 87.871073 -401.523896) (xy 87.862999 -401.590833) (xy 87.846966 -401.656321)
			(xy 87.823204 -401.719417) (xy 87.820954 -401.723737) (xy 115.349237 -401.723737) (xy 115.349239 -401.65643)
			(xy 115.357285 -401.589607) (xy 115.373259 -401.524224) (xy 115.396933 -401.461219) (xy 115.427967 -401.401494)
			(xy 115.465916 -401.345907) (xy 115.487704 -401.320254) (xy 115.493503 -401.313111) (xy 115.500016 -401.295919)
			(xy 115.500404 -401.286726) (xy 115.500404 -400.793458) (xy 115.500013 -400.784269) (xy 115.493486 -400.767085)
			(xy 115.487704 -400.75993) (xy 115.465923 -400.734273) (xy 115.427977 -400.678686) (xy 115.396945 -400.618963)
			(xy 115.373273 -400.555959) (xy 115.357301 -400.490578) (xy 115.349257 -400.423756) (xy 115.349256 -400.356453)
			(xy 115.357299 -400.289631) (xy 115.373271 -400.22425) (xy 115.396941 -400.161245) (xy 115.427972 -400.101522)
			(xy 115.465918 -400.045935) (xy 115.487704 -400.020282) (xy 115.493491 -400.01313) (xy 115.500011 -399.995945)
			(xy 115.500404 -399.986754) (xy 115.500404 -399.828766) (xy 115.500905 -399.81861) (xy 115.508684 -399.799847)
			(xy 115.523047 -399.785484) (xy 115.54181 -399.777705) (xy 115.551966 -399.777204) (xy 116.268246 -399.777204)
			(xy 116.278403 -399.777695) (xy 116.297166 -399.785478) (xy 116.311529 -399.799844) (xy 116.319307 -399.818609)
			(xy 116.319808 -399.828766) (xy 116.319808 -399.986754) (xy 116.320238 -399.995939) (xy 116.326738 -400.013124)
			(xy 116.332508 -400.020282) (xy 116.354303 -400.045929) (xy 116.392255 -400.101515) (xy 116.423291 -400.161238)
			(xy 116.446966 -400.224244) (xy 116.46294 -400.289627) (xy 116.470985 -400.356451) (xy 116.470984 -400.423758)
			(xy 116.462939 -400.490582) (xy 116.446963 -400.555965) (xy 116.423288 -400.61897) (xy 116.392251 -400.678693)
			(xy 116.354298 -400.734279) (xy 116.332508 -400.75993) (xy 116.326717 -400.767079) (xy 116.320199 -400.784267)
			(xy 116.319808 -400.793458) (xy 116.319808 -401.286726) (xy 116.320204 -401.295915) (xy 116.326727 -401.313099)
			(xy 116.332508 -401.320254) (xy 116.354276 -401.345923) (xy 116.392229 -401.401506) (xy 116.423266 -401.461227)
			(xy 116.446942 -401.524229) (xy 116.462918 -401.58961) (xy 116.470965 -401.656431) (xy 116.470967 -401.723736)
			(xy 116.462924 -401.790558) (xy 116.446952 -401.855939) (xy 116.423279 -401.918943) (xy 116.392246 -401.978666)
			(xy 116.354296 -402.034251) (xy 116.332508 -402.059902) (xy 116.326729 -402.06706) (xy 116.320204 -402.084241)
			(xy 116.319808 -402.09343) (xy 116.319808 -402.251418) (xy 116.319283 -402.261571) (xy 116.311511 -402.280332)
			(xy 116.297156 -402.294695) (xy 116.278399 -402.302477) (xy 116.268246 -402.30298) (xy 115.551966 -402.30298)
			(xy 115.541808 -402.302495) (xy 115.523042 -402.294713) (xy 115.508678 -402.280345) (xy 115.500902 -402.261576)
			(xy 115.500404 -402.251418) (xy 115.500404 -402.09343) (xy 115.499978 -402.084244) (xy 115.493475 -402.06706)
			(xy 115.487704 -402.059902) (xy 115.465896 -402.034267) (xy 115.42795 -401.978677) (xy 115.396919 -401.918951)
			(xy 115.373249 -401.855944) (xy 115.357279 -401.79056) (xy 115.349237 -401.723737) (xy 87.820954 -401.723737)
			(xy 87.792056 -401.779212) (xy 87.75397 -401.834847) (xy 87.732108 -401.860512) (xy 87.726325 -401.867667)
			(xy 87.719802 -401.88485) (xy 87.719408 -401.89404) (xy 87.719408 -402.386292) (xy 87.71982 -402.395479)
			(xy 87.726332 -402.412663) (xy 87.732108 -402.41982) (xy 87.753925 -402.445524) (xy 87.792014 -402.501153)
			(xy 87.823166 -402.560944) (xy 87.846933 -402.624036) (xy 87.862972 -402.68952) (xy 87.871051 -402.756454)
			(xy 87.871055 -402.823874) (xy 87.862984 -402.890809) (xy 87.846954 -402.956295) (xy 87.823196 -403.01939)
			(xy 87.792051 -403.079185) (xy 87.753969 -403.134819) (xy 87.732108 -403.160484) (xy 87.726294 -403.167617)
			(xy 87.71979 -403.184817) (xy 87.719408 -403.194012) (xy 87.719408 -403.351492) (xy 87.718978 -403.361613)
			(xy 87.711234 -403.380315) (xy 87.696922 -403.394629) (xy 87.678221 -403.402376) (xy 87.6681 -403.4028)
			(xy 86.95182 -403.4028) (xy 86.941699 -403.402368) (xy 86.922996 -403.394626) (xy 86.908681 -403.380315)
			(xy 86.900935 -403.361613) (xy 86.900512 -403.351492) (xy 86.900512 -403.194012) (xy 86.900093 -403.184826)
			(xy 86.893585 -403.167642) (xy 86.887812 -403.160484) (xy 86.8659 -403.134858) (xy 86.827812 -403.079218)
			(xy 86.796663 -403.019417) (xy 86.772901 -402.956315) (xy 86.756869 -402.890821) (xy 86.748796 -402.823878)
			(xy 83.470752 -402.823878) (xy 83.46272 -402.890635) (xy 83.446751 -402.956015) (xy 83.423082 -403.019018)
			(xy 83.392052 -403.07874) (xy 83.354106 -403.134324) (xy 83.33232 -403.159976) (xy 83.326511 -403.167113)
			(xy 83.320003 -403.18431) (xy 83.31962 -403.193504) (xy 83.31962 -403.351492) (xy 83.319172 -403.361643)
			(xy 83.311383 -403.380391) (xy 83.296995 -403.394714) (xy 83.278211 -403.402418) (xy 83.268058 -403.4028)
			(xy 82.551778 -403.4028) (xy 82.541655 -403.402293) (xy 82.522941 -403.394565) (xy 82.508586 -403.380286)
			(xy 82.500761 -403.361613) (xy 82.500216 -403.351492) (xy 82.500216 -403.193504) (xy 82.4998 -403.184318)
			(xy 82.49329 -403.167133) (xy 82.487516 -403.159976) (xy 82.465682 -403.134362) (xy 82.427736 -403.07877)
			(xy 82.396706 -403.019041) (xy 82.373037 -402.956031) (xy 82.357068 -402.890645) (xy 82.349028 -402.823818)
			(xy 79.070968 -402.823818) (xy 79.070968 -402.823874) (xy 79.062897 -402.890808) (xy 79.046867 -402.956294)
			(xy 79.023109 -403.019389) (xy 78.991966 -403.079184) (xy 78.953884 -403.134818) (xy 78.932024 -403.160484)
			(xy 78.926212 -403.167618) (xy 78.919706 -403.184817) (xy 78.919324 -403.194012) (xy 78.919324 -403.351492)
			(xy 78.918809 -403.361597) (xy 78.911078 -403.380271) (xy 78.896791 -403.394565) (xy 78.878121 -403.402304)
			(xy 78.868016 -403.4028) (xy 78.151736 -403.4028) (xy 78.141616 -403.402354) (xy 78.122913 -403.394618)
			(xy 78.108598 -403.38031) (xy 78.100851 -403.361612) (xy 78.100428 -403.351492) (xy 78.100428 -403.194012)
			(xy 78.100006 -403.184826) (xy 78.0935 -403.167642) (xy 78.087728 -403.160484) (xy 78.065816 -403.134858)
			(xy 78.027727 -403.079219) (xy 77.996577 -403.019417) (xy 77.972814 -402.956315) (xy 77.956781 -402.890821)
			(xy 77.948708 -402.823878) (xy 74.670664 -402.823878) (xy 74.662632 -402.890635) (xy 74.646664 -402.956014)
			(xy 74.622995 -403.019017) (xy 74.591966 -403.078739) (xy 74.554022 -403.134324) (xy 74.532236 -403.159976)
			(xy 74.526417 -403.167105) (xy 74.519917 -403.184308) (xy 74.519536 -403.193504) (xy 74.519536 -403.351492)
			(xy 74.519073 -403.361641) (xy 74.511286 -403.380386) (xy 74.496903 -403.394709) (xy 74.478125 -403.402415)
			(xy 74.467974 -403.4028) (xy 73.751694 -403.4028) (xy 73.741572 -403.402279) (xy 73.722858 -403.394557)
			(xy 73.708504 -403.380282) (xy 73.700678 -403.361611) (xy 73.700132 -403.351492) (xy 73.700132 -403.193504)
			(xy 73.699713 -403.184318) (xy 73.693205 -403.167134) (xy 73.687432 -403.159976) (xy 73.665597 -403.134363)
			(xy 73.62765 -403.07877) (xy 73.59662 -403.019041) (xy 73.57295 -402.956032) (xy 73.55698 -402.890645)
			(xy 73.54894 -402.823818) (xy 66.525648 -402.823818) (xy 66.525648 -405.623707) (xy 71.348811 -405.623707)
			(xy 71.348811 -405.556283) (xy 71.356888 -405.489345) (xy 71.372924 -405.423856) (xy 71.396688 -405.360759)
			(xy 71.427839 -405.300962) (xy 71.465928 -405.245327) (xy 71.487792 -405.219662) (xy 71.493586 -405.212515)
			(xy 71.500103 -405.195326) (xy 71.500492 -405.186134) (xy 71.500492 -404.693882) (xy 71.500092 -404.684694)
			(xy 71.493571 -404.667509) (xy 71.487792 -404.660354) (xy 71.46595 -404.634671) (xy 71.427861 -404.579039)
			(xy 71.39671 -404.519245) (xy 71.372945 -404.45615) (xy 71.356908 -404.390664) (xy 71.348831 -404.323727)
			(xy 71.348829 -404.256306) (xy 71.356902 -404.189369) (xy 71.372935 -404.123881) (xy 71.396696 -404.060785)
			(xy 71.427844 -404.00099) (xy 71.46593 -403.945355) (xy 71.487792 -403.91969) (xy 71.493574 -403.912535)
			(xy 71.500098 -403.895352) (xy 71.500492 -403.886162) (xy 71.500492 -403.728682) (xy 71.50101 -403.71856)
			(xy 71.508735 -403.699847) (xy 71.523011 -403.685493) (xy 71.541681 -403.677666) (xy 71.5518 -403.67712)
			(xy 72.26808 -403.67712) (xy 72.278235 -403.677538) (xy 72.296991 -403.685331) (xy 72.311316 -403.699729)
			(xy 72.319013 -403.718525) (xy 72.319388 -403.728682) (xy 72.319388 -403.886162) (xy 72.319819 -403.895347)
			(xy 72.326319 -403.912531) (xy 72.332088 -403.91969) (xy 72.353974 -403.945337) (xy 72.392063 -404.000974)
			(xy 72.423213 -404.060773) (xy 72.446977 -404.123872) (xy 72.463011 -404.189363) (xy 72.471085 -404.256304)
			(xy 72.471083 -404.323729) (xy 72.463005 -404.390669) (xy 72.446967 -404.45616) (xy 72.4232 -404.519258)
			(xy 72.392046 -404.579054) (xy 72.353954 -404.634689) (xy 72.332088 -404.660354) (xy 72.326285 -404.667494)
			(xy 72.319774 -404.684689) (xy 72.319388 -404.693882) (xy 72.319388 -405.186134) (xy 72.319784 -405.195323)
			(xy 72.326308 -405.212507) (xy 72.332088 -405.219662) (xy 72.353946 -405.245332) (xy 72.392036 -405.300965)
			(xy 72.423188 -405.360761) (xy 72.446953 -405.423857) (xy 72.462989 -405.489346) (xy 72.471066 -405.556284)
			(xy 72.471066 -405.623707) (xy 72.462991 -405.690645) (xy 72.446956 -405.756134) (xy 72.423191 -405.819231)
			(xy 72.392041 -405.879027) (xy 72.353952 -405.934661) (xy 72.332088 -405.960326) (xy 72.326297 -405.967475)
			(xy 72.319779 -405.984663) (xy 72.319388 -405.993854) (xy 72.319388 -406.151334) (xy 72.318902 -406.161459)
			(xy 72.311168 -406.180176) (xy 72.296883 -406.19453) (xy 72.278203 -406.202353) (xy 72.26808 -406.202896)
			(xy 71.5518 -406.202896) (xy 71.541645 -406.202478) (xy 71.522892 -406.194682) (xy 71.508569 -406.180284)
			(xy 71.50087 -406.161491) (xy 71.500492 -406.151334) (xy 71.500492 -405.993854) (xy 71.500058 -405.984669)
			(xy 71.493561 -405.967485) (xy 71.487792 -405.960326) (xy 71.465922 -405.934665) (xy 71.427834 -405.87903)
			(xy 71.396684 -405.819233) (xy 71.372921 -405.756136) (xy 71.356886 -405.690646) (xy 71.348811 -405.623707)
			(xy 66.525648 -405.623707) (xy 66.525648 -406.72373) (xy 73.548951 -406.72373) (xy 73.548954 -406.656422)
			(xy 73.557001 -406.589598) (xy 73.572978 -406.524214) (xy 73.596654 -406.461208) (xy 73.62769 -406.401483)
			(xy 73.665642 -406.345896) (xy 73.687432 -406.320244) (xy 73.693239 -406.313106) (xy 73.699747 -406.29591)
			(xy 73.700132 -406.286716) (xy 73.700132 -405.793448) (xy 73.699691 -405.784264) (xy 73.693198 -405.76708)
			(xy 73.687432 -405.75992) (xy 73.66564 -405.734271) (xy 73.627692 -405.678684) (xy 73.596659 -405.61896)
			(xy 73.572987 -405.555955) (xy 73.557015 -405.490572) (xy 73.548971 -405.42375) (xy 73.548971 -405.356444)
			(xy 73.557016 -405.289622) (xy 73.572989 -405.224239) (xy 73.596662 -405.161235) (xy 73.627695 -405.101511)
			(xy 73.665644 -405.045924) (xy 73.687432 -405.020272) (xy 73.693227 -405.013126) (xy 73.699742 -404.995936)
			(xy 73.700132 -404.986744) (xy 73.700132 -404.828756) (xy 73.700486 -404.818595) (xy 73.708302 -404.799836)
			(xy 73.72272 -404.785513) (xy 73.74153 -404.77782) (xy 73.751694 -404.777448) (xy 74.467974 -404.777448)
			(xy 74.4781 -404.777948) (xy 74.496822 -404.785669) (xy 74.51118 -404.799951) (xy 74.518998 -404.818633)
			(xy 74.519536 -404.828756) (xy 74.519536 -404.986744) (xy 74.519939 -404.995932) (xy 74.526459 -405.013115)
			(xy 74.532236 -405.020272) (xy 74.55402 -405.045927) (xy 74.591971 -405.101513) (xy 74.623006 -405.161235)
			(xy 74.64668 -405.22424) (xy 74.662654 -405.289622) (xy 74.670699 -405.356444) (xy 74.670699 -405.42375)
			(xy 74.662655 -405.490572) (xy 74.646682 -405.555955) (xy 74.623008 -405.618959) (xy 74.620571 -405.623649)
			(xy 75.749106 -405.623649) (xy 75.749107 -405.556342) (xy 75.757152 -405.489519) (xy 75.773127 -405.424136)
			(xy 75.796802 -405.361131) (xy 75.827839 -405.301407) (xy 75.865791 -405.245822) (xy 75.88758 -405.22017)
			(xy 75.893369 -405.21302) (xy 75.899889 -405.195833) (xy 75.90028 -405.186642) (xy 75.90028 -404.693374)
			(xy 75.899887 -404.684185) (xy 75.893362 -404.667001) (xy 75.88758 -404.659846) (xy 75.865813 -404.634177)
			(xy 75.827861 -404.578594) (xy 75.796824 -404.518873) (xy 75.773148 -404.45587) (xy 75.757173 -404.39049)
			(xy 75.749126 -404.323669) (xy 75.749124 -404.256365) (xy 75.757167 -404.189543) (xy 75.773138 -404.124161)
			(xy 75.796811 -404.061157) (xy 75.827844 -404.001435) (xy 75.865792 -403.94585) (xy 75.88758 -403.920198)
			(xy 75.893358 -403.913039) (xy 75.899884 -403.895859) (xy 75.90028 -403.88667) (xy 75.90028 -403.728682)
			(xy 75.90065 -403.718504) (xy 75.908449 -403.699701) (xy 75.922851 -403.685315) (xy 75.941664 -403.677538)
			(xy 75.951842 -403.67712) (xy 76.668122 -403.67712) (xy 76.678279 -403.677615) (xy 76.697045 -403.685393)
			(xy 76.711409 -403.699758) (xy 76.719186 -403.718525) (xy 76.719684 -403.728682) (xy 76.719684 -403.88667)
			(xy 76.720112 -403.895855) (xy 76.726614 -403.91304) (xy 76.732384 -403.920198) (xy 76.754193 -403.945833)
			(xy 76.792139 -404.001422) (xy 76.82317 -404.061148) (xy 76.846841 -404.124155) (xy 76.862812 -404.189539)
			(xy 76.870854 -404.256363) (xy 76.870852 -404.32367) (xy 76.862806 -404.390493) (xy 76.846831 -404.455877)
			(xy 76.823157 -404.518882) (xy 76.792122 -404.578606) (xy 76.754172 -404.634194) (xy 76.732384 -404.659846)
			(xy 76.726584 -404.666988) (xy 76.720072 -404.684181) (xy 76.719684 -404.693374) (xy 76.719684 -405.186642)
			(xy 76.720077 -405.195831) (xy 76.726603 -405.213015) (xy 76.732384 -405.22017) (xy 76.754165 -405.245827)
			(xy 76.792113 -405.301414) (xy 76.823145 -405.361137) (xy 76.846817 -405.42414) (xy 76.86279 -405.489522)
			(xy 76.870834 -405.556343) (xy 76.870835 -405.623648) (xy 76.862791 -405.690469) (xy 76.84682 -405.755851)
			(xy 76.823149 -405.818855) (xy 76.792117 -405.878579) (xy 76.754171 -405.934166) (xy 76.732384 -405.959818)
			(xy 76.726595 -405.966969) (xy 76.720077 -405.984155) (xy 76.719684 -405.993346) (xy 76.719684 -406.151334)
			(xy 76.719195 -406.161491) (xy 76.711414 -406.180257) (xy 76.697047 -406.19462) (xy 76.678279 -406.202397)
			(xy 76.668122 -406.202896) (xy 75.951842 -406.202896) (xy 75.941677 -406.202403) (xy 75.92289 -406.194638)
			(xy 75.908505 -406.180274) (xy 75.900712 -406.161498) (xy 75.90028 -406.151334) (xy 75.90028 -405.993346)
			(xy 75.899852 -405.984161) (xy 75.893351 -405.966976) (xy 75.88758 -405.959818) (xy 75.865785 -405.934171)
			(xy 75.827834 -405.878585) (xy 75.796799 -405.818861) (xy 75.773124 -405.755856) (xy 75.757151 -405.690472)
			(xy 75.749106 -405.623649) (xy 74.620571 -405.623649) (xy 74.591974 -405.678682) (xy 74.554024 -405.734268)
			(xy 74.532236 -405.75992) (xy 74.526441 -405.767066) (xy 74.519927 -405.784256) (xy 74.519536 -405.793448)
			(xy 74.519536 -406.286716) (xy 74.519953 -406.295902) (xy 74.526464 -406.313086) (xy 74.532236 -406.320244)
			(xy 74.553993 -406.345922) (xy 74.591944 -406.401504) (xy 74.62298 -406.461224) (xy 74.646656 -406.524225)
			(xy 74.662632 -406.589604) (xy 74.670679 -406.656424) (xy 74.670682 -406.723727) (xy 74.670675 -406.723789)
			(xy 77.94872 -406.723789) (xy 77.948723 -406.656363) (xy 77.956802 -406.589422) (xy 77.972842 -406.52393)
			(xy 77.996611 -406.460832) (xy 78.027767 -406.401035) (xy 78.065861 -406.345401) (xy 78.087728 -406.319736)
			(xy 78.093538 -406.3126) (xy 78.100044 -406.295402) (xy 78.100428 -406.286208) (xy 78.100428 -405.793956)
			(xy 78.100033 -405.784767) (xy 78.093508 -405.767584) (xy 78.087728 -405.760428) (xy 78.065859 -405.734766)
			(xy 78.027769 -405.679132) (xy 77.996617 -405.619336) (xy 77.972851 -405.556238) (xy 77.956815 -405.490748)
			(xy 77.948739 -405.423809) (xy 77.94874 -405.356385) (xy 77.956816 -405.289446) (xy 77.972853 -405.223956)
			(xy 77.996619 -405.160859) (xy 78.027772 -405.101063) (xy 78.065863 -405.045429) (xy 78.087728 -405.019764)
			(xy 78.093526 -405.01262) (xy 78.100039 -404.995428) (xy 78.100428 -404.986236) (xy 78.100428 -404.828756)
			(xy 78.10085 -404.818641) (xy 78.108607 -404.799956) (xy 78.122924 -404.785662) (xy 78.14162 -404.777934)
			(xy 78.151736 -404.777448) (xy 78.868016 -404.777448) (xy 78.878119 -404.777971) (xy 78.896788 -404.785704)
			(xy 78.91108 -404.799989) (xy 78.918823 -404.818653) (xy 78.919324 -404.828756) (xy 78.919324 -404.986236)
			(xy 78.919712 -404.995426) (xy 78.92624 -405.01261) (xy 78.932024 -405.019764) (xy 78.953883 -405.045433)
			(xy 78.99197 -405.101067) (xy 79.02312 -405.160863) (xy 79.046883 -405.22396) (xy 79.062918 -405.289448)
			(xy 79.070994 -405.356386) (xy 79.070995 -405.423808) (xy 79.062919 -405.490746) (xy 79.046885 -405.556235)
			(xy 79.023122 -405.619331) (xy 79.020843 -405.623707) (xy 80.148899 -405.623707) (xy 80.148899 -405.556284)
			(xy 80.156975 -405.489345) (xy 80.173011 -405.423856) (xy 80.196775 -405.360759) (xy 80.227925 -405.300963)
			(xy 80.266013 -405.245328) (xy 80.287876 -405.219662) (xy 80.293668 -405.212514) (xy 80.300186 -405.195326)
			(xy 80.300576 -405.186134) (xy 80.300576 -404.693882) (xy 80.30018 -404.684693) (xy 80.293657 -404.667509)
			(xy 80.287876 -404.660354) (xy 80.266034 -404.634671) (xy 80.227947 -404.579038) (xy 80.196796 -404.519244)
			(xy 80.173032 -404.45615) (xy 80.156996 -404.390663) (xy 80.148918 -404.323727) (xy 80.148917 -404.256306)
			(xy 80.15699 -404.189369) (xy 80.173022 -404.123882) (xy 80.196783 -404.060786) (xy 80.22793 -404.00099)
			(xy 80.266014 -403.945356) (xy 80.287876 -403.91969) (xy 80.293657 -403.912533) (xy 80.300182 -403.895352)
			(xy 80.300576 -403.886162) (xy 80.300576 -403.728682) (xy 80.301013 -403.71855) (xy 80.308753 -403.699821)
			(xy 80.323055 -403.685464) (xy 80.341754 -403.677652) (xy 80.351884 -403.67712) (xy 81.068164 -403.67712)
			(xy 81.078318 -403.677552) (xy 81.097074 -403.685339) (xy 81.111399 -403.699733) (xy 81.119096 -403.718526)
			(xy 81.119472 -403.728682) (xy 81.119472 -403.886162) (xy 81.119907 -403.895346) (xy 81.126404 -403.912531)
			(xy 81.132172 -403.91969) (xy 81.154059 -403.945337) (xy 81.192148 -404.000973) (xy 81.2233 -404.060772)
			(xy 81.247064 -404.123871) (xy 81.263099 -404.189363) (xy 81.271173 -404.256304) (xy 81.271171 -404.32373)
			(xy 81.263093 -404.39067) (xy 81.247054 -404.45616) (xy 81.223286 -404.519258) (xy 81.192131 -404.579055)
			(xy 81.154038 -404.634689) (xy 81.132172 -404.660354) (xy 81.126366 -404.667493) (xy 81.119858 -404.684688)
			(xy 81.119472 -404.693882) (xy 81.119472 -405.186134) (xy 81.119872 -405.195322) (xy 81.126393 -405.212506)
			(xy 81.132172 -405.219662) (xy 81.154031 -405.245332) (xy 81.192122 -405.300965) (xy 81.223274 -405.36076)
			(xy 81.24704 -405.423857) (xy 81.263077 -405.489345) (xy 81.271154 -405.556284) (xy 81.271154 -405.623707)
			(xy 81.263078 -405.690646) (xy 81.247043 -405.756135) (xy 81.223278 -405.819232) (xy 81.192126 -405.879027)
			(xy 81.154037 -405.934661) (xy 81.132172 -405.960326) (xy 81.126378 -405.967473) (xy 81.119862 -405.984662)
			(xy 81.119472 -405.993854) (xy 81.119472 -406.151334) (xy 81.119002 -406.161461) (xy 81.111265 -406.180181)
			(xy 81.096974 -406.194536) (xy 81.078289 -406.202356) (xy 81.068164 -406.202896) (xy 80.351884 -406.202896)
			(xy 80.341728 -406.202492) (xy 80.322975 -406.19469) (xy 80.308652 -406.180288) (xy 80.300953 -406.161492)
			(xy 80.300576 -406.151334) (xy 80.300576 -405.993854) (xy 80.300145 -405.984669) (xy 80.293646 -405.967484)
			(xy 80.287876 -405.960326) (xy 80.266007 -405.934665) (xy 80.22792 -405.879029) (xy 80.196771 -405.819232)
			(xy 80.173008 -405.756135) (xy 80.156974 -405.690646) (xy 80.148899 -405.623707) (xy 79.020843 -405.623707)
			(xy 78.991974 -405.679127) (xy 78.953887 -405.734762) (xy 78.932024 -405.760428) (xy 78.926236 -405.767579)
			(xy 78.919715 -405.784765) (xy 78.919324 -405.793956) (xy 78.919324 -406.286208) (xy 78.919725 -406.295396)
			(xy 78.926244 -406.312581) (xy 78.932024 -406.319736) (xy 78.953856 -406.345428) (xy 78.991944 -406.401059)
			(xy 79.023095 -406.460852) (xy 79.046859 -406.523945) (xy 79.062896 -406.589431) (xy 79.070974 -406.656366)
			(xy 79.070977 -406.72373) (xy 82.349039 -406.72373) (xy 82.349042 -406.656422) (xy 82.357089 -406.589598)
			(xy 82.373065 -406.524214) (xy 82.39674 -406.461209) (xy 82.427776 -406.401484) (xy 82.465727 -406.345896)
			(xy 82.487516 -406.320244) (xy 82.493321 -406.313105) (xy 82.49983 -406.29591) (xy 82.500216 -406.286716)
			(xy 82.500216 -405.793448) (xy 82.499779 -405.784264) (xy 82.493284 -405.767079) (xy 82.487516 -405.75992)
			(xy 82.465725 -405.734271) (xy 82.427778 -405.678683) (xy 82.396746 -405.618959) (xy 82.373074 -405.555954)
			(xy 82.357102 -405.490572) (xy 82.349059 -405.423749) (xy 82.349059 -405.356445) (xy 82.357103 -405.289622)
			(xy 82.373076 -405.22424) (xy 82.396748 -405.161235) (xy 82.427781 -405.101511) (xy 82.465729 -405.045924)
			(xy 82.487516 -405.020272) (xy 82.493309 -405.013124) (xy 82.499825 -404.995936) (xy 82.500216 -404.986744)
			(xy 82.500216 -404.828756) (xy 82.500586 -404.818597) (xy 82.508399 -404.799841) (xy 82.522811 -404.785518)
			(xy 82.541617 -404.777823) (xy 82.551778 -404.777448) (xy 83.268058 -404.777448) (xy 83.278183 -404.777961)
			(xy 83.296905 -404.785677) (xy 83.311263 -404.799955) (xy 83.319082 -404.818634) (xy 83.31962 -404.828756)
			(xy 83.31962 -404.986744) (xy 83.320004 -404.995934) (xy 83.326535 -405.013118) (xy 83.33232 -405.020272)
			(xy 83.354105 -405.045927) (xy 83.392057 -405.101512) (xy 83.423092 -405.161235) (xy 83.446767 -405.224239)
			(xy 83.462742 -405.289621) (xy 83.470787 -405.356444) (xy 83.470787 -405.42375) (xy 83.462743 -405.490573)
			(xy 83.446769 -405.555955) (xy 83.423095 -405.61896) (xy 83.420628 -405.623707) (xy 84.54869 -405.623707)
			(xy 84.54869 -405.556284) (xy 84.556766 -405.489346) (xy 84.572801 -405.423857) (xy 84.596564 -405.36076)
			(xy 84.627714 -405.300963) (xy 84.665801 -405.245328) (xy 84.687664 -405.219662) (xy 84.693467 -405.212522)
			(xy 84.699976 -405.195327) (xy 84.700364 -405.186134) (xy 84.700364 -404.693882) (xy 84.699948 -404.684696)
			(xy 84.693437 -404.667512) (xy 84.687664 -404.660354) (xy 84.665823 -404.63467) (xy 84.627736 -404.579038)
			(xy 84.596586 -404.519244) (xy 84.572822 -404.456149) (xy 84.556787 -404.390663) (xy 84.548709 -404.323727)
			(xy 84.548707 -404.256306) (xy 84.556781 -404.18937) (xy 84.572813 -404.123882) (xy 84.596573 -404.060787)
			(xy 84.627719 -404.000991) (xy 84.665803 -403.945356) (xy 84.687664 -403.91969) (xy 84.693455 -403.912541)
			(xy 84.699971 -403.895353) (xy 84.700364 -403.886162) (xy 84.700364 -403.728682) (xy 84.700812 -403.718551)
			(xy 84.70855 -403.699825) (xy 84.722849 -403.685468) (xy 84.741543 -403.677654) (xy 84.751672 -403.67712)
			(xy 85.467952 -403.67712) (xy 85.478105 -403.677561) (xy 85.496861 -403.685345) (xy 85.511186 -403.699736)
			(xy 85.518884 -403.718527) (xy 85.51926 -403.728682) (xy 85.51926 -403.886162) (xy 85.519698 -403.895346)
			(xy 85.526193 -403.91253) (xy 85.53196 -403.91969) (xy 85.553847 -403.945337) (xy 85.591938 -404.000973)
			(xy 85.62309 -404.060771) (xy 85.646854 -404.123871) (xy 85.66289 -404.189362) (xy 85.670964 -404.256303)
			(xy 85.670962 -404.32373) (xy 85.662884 -404.39067) (xy 85.646845 -404.456161) (xy 85.623076 -404.519259)
			(xy 85.591921 -404.579055) (xy 85.553827 -404.634689) (xy 85.53196 -404.660354) (xy 85.526153 -404.667492)
			(xy 85.519646 -404.684688) (xy 85.51926 -404.693882) (xy 85.51926 -405.186134) (xy 85.519663 -405.195322)
			(xy 85.526183 -405.212506) (xy 85.53196 -405.219662) (xy 85.553819 -405.245331) (xy 85.591911 -405.300964)
			(xy 85.623064 -405.36076) (xy 85.64683 -405.423856) (xy 85.662868 -405.489345) (xy 85.670945 -405.556284)
			(xy 85.670945 -405.623707) (xy 85.662869 -405.690646) (xy 85.646833 -405.756135) (xy 85.623068 -405.819232)
			(xy 85.591916 -405.879028) (xy 85.553825 -405.934661) (xy 85.53196 -405.960326) (xy 85.526165 -405.967472)
			(xy 85.51965 -405.984662) (xy 85.51926 -405.993854) (xy 85.51926 -406.151334) (xy 85.518801 -406.161463)
			(xy 85.511062 -406.180185) (xy 85.496768 -406.19454) (xy 85.478079 -406.202358) (xy 85.467952 -406.202896)
			(xy 84.751672 -406.202896) (xy 84.741516 -406.202501) (xy 84.722762 -406.194696) (xy 84.708439 -406.180291)
			(xy 84.700741 -406.161493) (xy 84.700364 -406.151334) (xy 84.700364 -405.993854) (xy 84.699914 -405.984671)
			(xy 84.693426 -405.967487) (xy 84.687664 -405.960326) (xy 84.665795 -405.934665) (xy 84.627709 -405.879029)
			(xy 84.596561 -405.819232) (xy 84.572799 -405.756135) (xy 84.556765 -405.690645) (xy 84.54869 -405.623707)
			(xy 83.420628 -405.623707) (xy 83.39206 -405.678683) (xy 83.354109 -405.734268) (xy 83.33232 -405.75992)
			(xy 83.326535 -405.767073) (xy 83.320013 -405.784258) (xy 83.31962 -405.793448) (xy 83.31962 -406.286716)
			(xy 83.320018 -406.295905) (xy 83.32654 -406.313089) (xy 83.33232 -406.320244) (xy 83.354077 -406.345921)
			(xy 83.39203 -406.401503) (xy 83.423067 -406.461223) (xy 83.446743 -406.524224) (xy 83.46272 -406.589604)
			(xy 83.470767 -406.656424) (xy 83.47077 -406.723728) (xy 83.470763 -406.723789) (xy 86.748808 -406.723789)
			(xy 86.748811 -406.656363) (xy 86.75689 -406.589422) (xy 86.772929 -406.523931) (xy 86.796697 -406.460833)
			(xy 86.827852 -406.401036) (xy 86.865946 -406.345401) (xy 86.887812 -406.319736) (xy 86.89362 -406.312599)
			(xy 86.900127 -406.295402) (xy 86.900512 -406.286208) (xy 86.900512 -405.793956) (xy 86.90012 -405.784767)
			(xy 86.893594 -405.767583) (xy 86.887812 -405.760428) (xy 86.865944 -405.734766) (xy 86.827854 -405.679131)
			(xy 86.796703 -405.619335) (xy 86.772939 -405.556238) (xy 86.756903 -405.490748) (xy 86.748827 -405.423809)
			(xy 86.748828 -405.356385) (xy 86.756904 -405.289446) (xy 86.77294 -405.223957) (xy 86.796706 -405.16086)
			(xy 86.827857 -405.101063) (xy 86.865947 -405.045429) (xy 86.887812 -405.019764) (xy 86.893608 -405.012618)
			(xy 86.900123 -404.995428) (xy 86.900512 -404.986236) (xy 86.900512 -404.828756) (xy 86.900949 -404.818643)
			(xy 86.908704 -404.799961) (xy 86.923015 -404.785668) (xy 86.941706 -404.777937) (xy 86.95182 -404.777448)
			(xy 87.6681 -404.777448) (xy 87.678202 -404.777984) (xy 87.696871 -404.785712) (xy 87.711163 -404.799993)
			(xy 87.718907 -404.818654) (xy 87.719408 -404.828756) (xy 87.719408 -404.986236) (xy 87.719799 -404.995425)
			(xy 87.726326 -405.01261) (xy 87.732108 -405.019764) (xy 87.753968 -405.045433) (xy 87.792056 -405.101067)
			(xy 87.823206 -405.160863) (xy 87.846971 -405.223959) (xy 87.863006 -405.289448) (xy 87.871082 -405.356385)
			(xy 87.871082 -405.423809) (xy 87.863007 -405.490746) (xy 87.846972 -405.556235) (xy 87.823209 -405.619332)
			(xy 87.792059 -405.679128) (xy 87.753971 -405.734763) (xy 87.732108 -405.760428) (xy 87.726318 -405.767578)
			(xy 87.719799 -405.784765) (xy 87.719408 -405.793956) (xy 87.719408 -406.286208) (xy 87.719813 -406.295396)
			(xy 87.72633 -406.31258) (xy 87.732108 -406.319736) (xy 87.75394 -406.345427) (xy 87.792029 -406.401058)
			(xy 87.823181 -406.460851) (xy 87.846947 -406.523944) (xy 87.862984 -406.58943) (xy 87.871062 -406.656365)
			(xy 87.871065 -406.723729) (xy 91.149127 -406.723729) (xy 91.14913 -406.656423) (xy 91.157177 -406.589598)
			(xy 91.173152 -406.524215) (xy 91.196827 -406.461209) (xy 91.227861 -406.401484) (xy 91.265812 -406.345897)
			(xy 91.2876 -406.320244) (xy 91.293403 -406.313103) (xy 91.299914 -406.295909) (xy 91.3003 -406.286716)
			(xy 91.3003 -405.793448) (xy 91.299867 -405.784263) (xy 91.293369 -405.767079) (xy 91.2876 -405.75992)
			(xy 91.26581 -405.734271) (xy 91.227863 -405.678683) (xy 91.196832 -405.618958) (xy 91.173162 -405.555954)
			(xy 91.15719 -405.490572) (xy 91.149147 -405.423749) (xy 91.149147 -405.356445) (xy 91.157191 -405.289622)
			(xy 91.173163 -405.224241) (xy 91.196835 -405.161236) (xy 91.227866 -405.101512) (xy 91.265813 -405.045925)
			(xy 91.2876 -405.020272) (xy 91.293391 -405.013123) (xy 91.299909 -404.995935) (xy 91.3003 -404.986744)
			(xy 91.3003 -404.828756) (xy 91.300686 -404.818599) (xy 91.308496 -404.799846) (xy 91.322903 -404.785524)
			(xy 91.341703 -404.777826) (xy 91.351862 -404.777448) (xy 92.068142 -404.777448) (xy 92.078272 -404.777892)
			(xy 92.096996 -404.785635) (xy 92.111351 -404.799934) (xy 92.119167 -404.818628) (xy 92.119704 -404.828756)
			(xy 92.119704 -404.986744) (xy 92.120092 -404.995934) (xy 92.126621 -405.013118) (xy 92.132404 -405.020272)
			(xy 92.154186 -405.045928) (xy 92.192133 -405.101515) (xy 92.223164 -405.161238) (xy 92.246835 -405.224242)
			(xy 92.262807 -405.289624) (xy 92.270851 -405.356445) (xy 92.270851 -405.423749) (xy 92.262808 -405.490571)
			(xy 92.246837 -405.555952) (xy 92.223166 -405.618956) (xy 92.192136 -405.67868) (xy 92.15419 -405.734267)
			(xy 92.132404 -405.75992) (xy 92.126617 -405.767072) (xy 92.120096 -405.784257) (xy 92.119704 -405.793448)
			(xy 92.119704 -406.286716) (xy 92.120106 -406.295904) (xy 92.126625 -406.313088) (xy 92.132404 -406.320244)
			(xy 92.154159 -406.345923) (xy 92.192106 -406.401506) (xy 92.223138 -406.461227) (xy 92.246811 -406.524228)
			(xy 92.262785 -406.589606) (xy 92.270831 -406.656425) (xy 92.270834 -406.723727) (xy 92.262793 -406.790546)
			(xy 92.246825 -406.855926) (xy 92.223158 -406.918929) (xy 92.192131 -406.978652) (xy 92.154188 -407.034239)
			(xy 92.132404 -407.059892) (xy 92.126629 -407.067052) (xy 92.120101 -407.084231) (xy 92.119704 -407.09342)
			(xy 92.119704 -407.251408) (xy 92.119285 -407.261562) (xy 92.111487 -407.280314) (xy 92.09709 -407.294637)
			(xy 92.078298 -407.302337) (xy 92.068142 -407.302716) (xy 91.351862 -407.302716) (xy 91.341727 -407.302303)
			(xy 91.322997 -407.294555) (xy 91.308641 -407.280246) (xy 91.30083 -407.261541) (xy 91.3003 -407.251408)
			(xy 91.3003 -407.09342) (xy 91.29988 -407.084234) (xy 91.293373 -407.067049) (xy 91.2876 -407.059892)
			(xy 91.265782 -407.034265) (xy 91.227837 -406.978674) (xy 91.196807 -406.918947) (xy 91.173138 -406.855939)
			(xy 91.157168 -406.790554) (xy 91.149127 -406.723729) (xy 87.871065 -406.723729) (xy 87.871065 -406.723786)
			(xy 87.862993 -406.790722) (xy 87.846961 -406.85621) (xy 87.823201 -406.919305) (xy 87.792054 -406.9791)
			(xy 87.75397 -407.034735) (xy 87.732108 -407.0604) (xy 87.72633 -407.067558) (xy 87.719804 -407.084739)
			(xy 87.719408 -407.093928) (xy 87.719408 -407.251408) (xy 87.718921 -407.261516) (xy 87.711183 -407.280193)
			(xy 87.696886 -407.294487) (xy 87.678208 -407.302223) (xy 87.6681 -407.302716) (xy 86.95182 -407.302716)
			(xy 86.941701 -407.302268) (xy 86.923001 -407.29453) (xy 86.908686 -407.280223) (xy 86.900937 -407.261527)
			(xy 86.900512 -407.251408) (xy 86.900512 -407.093928) (xy 86.900086 -407.084743) (xy 86.893583 -407.067558)
			(xy 86.887812 -407.0604) (xy 86.865916 -407.034761) (xy 86.827828 -406.979123) (xy 86.796678 -406.919323)
			(xy 86.772915 -406.856223) (xy 86.756881 -406.790731) (xy 86.748808 -406.723789) (xy 83.470763 -406.723789)
			(xy 83.462728 -406.790549) (xy 83.446757 -406.85593) (xy 83.423086 -406.918933) (xy 83.392055 -406.978655)
			(xy 83.354107 -407.03424) (xy 83.33232 -407.059892) (xy 83.326547 -407.067054) (xy 83.320017 -407.084231)
			(xy 83.31962 -407.09342) (xy 83.31962 -407.251408) (xy 83.319185 -407.26156) (xy 83.311391 -407.280309)
			(xy 83.296998 -407.294631) (xy 83.278212 -407.302334) (xy 83.268058 -407.302716) (xy 82.551778 -407.302716)
			(xy 82.541644 -407.30229) (xy 82.522914 -407.294547) (xy 82.508557 -407.280242) (xy 82.500747 -407.26154)
			(xy 82.500216 -407.251408) (xy 82.500216 -407.09342) (xy 82.499792 -407.084234) (xy 82.493288 -407.06705)
			(xy 82.487516 -407.059892) (xy 82.465698 -407.034265) (xy 82.427751 -406.978675) (xy 82.396721 -406.918947)
			(xy 82.373051 -406.85594) (xy 82.35708 -406.790555) (xy 82.349039 -406.72373) (xy 79.070977 -406.72373)
			(xy 79.070977 -406.723786) (xy 79.062905 -406.790722) (xy 79.046874 -406.856209) (xy 79.023114 -406.919304)
			(xy 78.991969 -406.9791) (xy 78.953885 -407.034734) (xy 78.932024 -407.0604) (xy 78.926248 -407.06756)
			(xy 78.91972 -407.084739) (xy 78.919324 -407.093928) (xy 78.919324 -407.251408) (xy 78.918822 -407.261514)
			(xy 78.911086 -407.280188) (xy 78.896795 -407.294482) (xy 78.878122 -407.30222) (xy 78.868016 -407.302716)
			(xy 78.151736 -407.302716) (xy 78.141618 -407.302255) (xy 78.122918 -407.294521) (xy 78.108603 -407.280219)
			(xy 78.100854 -407.261526) (xy 78.100428 -407.251408) (xy 78.100428 -407.093928) (xy 78.099998 -407.084743)
			(xy 78.093497 -407.067559) (xy 78.087728 -407.0604) (xy 78.065832 -407.034761) (xy 78.027742 -406.979124)
			(xy 77.996591 -406.919324) (xy 77.972828 -406.856224) (xy 77.956793 -406.790731) (xy 77.94872 -406.723789)
			(xy 74.670675 -406.723789) (xy 74.662641 -406.790548) (xy 74.64667 -406.855929) (xy 74.623 -406.918932)
			(xy 74.591969 -406.978655) (xy 74.554022 -407.03424) (xy 74.532236 -407.059892) (xy 74.526453 -407.067046)
			(xy 74.519932 -407.08423) (xy 74.519536 -407.09342) (xy 74.519536 -407.251408) (xy 74.519085 -407.261558)
			(xy 74.511294 -407.280304) (xy 74.496907 -407.294625) (xy 74.478126 -407.302331) (xy 74.467974 -407.302716)
			(xy 73.751694 -407.302716) (xy 73.741562 -407.302277) (xy 73.722832 -407.294539) (xy 73.708474 -407.280238)
			(xy 73.700663 -407.261538) (xy 73.700132 -407.251408) (xy 73.700132 -407.09342) (xy 73.699705 -407.084235)
			(xy 73.693202 -407.067051) (xy 73.687432 -407.059892) (xy 73.665613 -407.034266) (xy 73.627666 -406.978675)
			(xy 73.596634 -406.918948) (xy 73.572963 -406.85594) (xy 73.556993 -406.790555) (xy 73.548951 -406.72373)
			(xy 66.525648 -406.72373) (xy 66.525648 -409.523886) (xy 71.34879 -409.523886) (xy 71.348793 -409.45646)
			(xy 71.356872 -409.389519) (xy 71.372911 -409.324028) (xy 71.396679 -409.26093) (xy 71.427834 -409.201133)
			(xy 71.465926 -409.145497) (xy 71.487792 -409.119832) (xy 71.493599 -409.112694) (xy 71.500108 -409.095498)
			(xy 71.500492 -409.086304) (xy 71.500492 -408.594052) (xy 71.500059 -408.584867) (xy 71.493561 -408.567682)
			(xy 71.487792 -408.560524) (xy 71.46592 -408.534865) (xy 71.427833 -408.479229) (xy 71.396683 -408.419432)
			(xy 71.372919 -408.356335) (xy 71.356885 -408.290845) (xy 71.348809 -408.223906) (xy 71.34881 -408.156482)
			(xy 71.356887 -408.089543) (xy 71.372923 -408.024054) (xy 71.396688 -407.960957) (xy 71.427839 -407.90116)
			(xy 71.465928 -407.845525) (xy 71.487792 -407.81986) (xy 71.493587 -407.812714) (xy 71.500103 -407.795524)
			(xy 71.500492 -407.786332) (xy 71.500492 -407.628852) (xy 71.500946 -407.618741) (xy 71.508698 -407.600063)
			(xy 71.523004 -407.585771) (xy 71.541689 -407.578036) (xy 71.5518 -407.577544) (xy 72.26808 -407.577544)
			(xy 72.278181 -407.5781) (xy 72.296848 -407.585821) (xy 72.311141 -407.600095) (xy 72.318887 -407.618752)
			(xy 72.319388 -407.628852) (xy 72.319388 -407.786332) (xy 72.319785 -407.795521) (xy 72.326308 -407.812705)
			(xy 72.332088 -407.81986) (xy 72.353945 -407.845532) (xy 72.392034 -407.901165) (xy 72.423186 -407.96096)
			(xy 72.446951 -408.024056) (xy 72.462988 -408.089545) (xy 72.471064 -408.156482) (xy 72.471065 -408.223906)
			(xy 72.46299 -408.290844) (xy 72.446955 -408.356332) (xy 72.423191 -408.419429) (xy 72.39204 -408.479225)
			(xy 72.353952 -408.534859) (xy 72.332088 -408.560524) (xy 72.326297 -408.567673) (xy 72.31978 -408.584861)
			(xy 72.319388 -408.594052) (xy 72.319388 -409.086304) (xy 72.319799 -409.095491) (xy 72.326313 -409.112675)
			(xy 72.332088 -409.119832) (xy 72.353917 -409.145526) (xy 72.392008 -409.201156) (xy 72.423161 -409.260948)
			(xy 72.446927 -409.324042) (xy 72.462966 -409.389527) (xy 72.471045 -409.456462) (xy 72.471048 -409.523884)
			(xy 72.462975 -409.59082) (xy 72.446943 -409.656307) (xy 72.423183 -409.719402) (xy 72.392035 -409.779197)
			(xy 72.35395 -409.834831) (xy 72.332088 -409.860496) (xy 72.326309 -409.867654) (xy 72.319784 -409.884835)
			(xy 72.319388 -409.894024) (xy 72.319388 -410.051504) (xy 72.318987 -410.061628) (xy 72.311235 -410.080334)
			(xy 72.296914 -410.094649) (xy 72.278204 -410.102392) (xy 72.26808 -410.102812) (xy 71.5518 -410.102812)
			(xy 71.541693 -410.102315) (xy 71.523017 -410.09458) (xy 71.508723 -410.080286) (xy 71.500986 -410.061611)
			(xy 71.500492 -410.051504) (xy 71.500492 -409.894024) (xy 71.500072 -409.884838) (xy 71.493565 -409.867653)
			(xy 71.487792 -409.860496) (xy 71.465893 -409.83486) (xy 71.427806 -409.779221) (xy 71.396657 -409.719421)
			(xy 71.372895 -409.65632) (xy 71.356863 -409.590827) (xy 71.34879 -409.523886) (xy 66.525648 -409.523886)
			(xy 66.525648 -410.623641) (xy 73.548963 -410.623641) (xy 73.548964 -410.556335) (xy 73.55701 -410.489511)
			(xy 73.572984 -410.424128) (xy 73.596658 -410.361123) (xy 73.627693 -410.301399) (xy 73.665643 -410.245812)
			(xy 73.687432 -410.22016) (xy 73.693232 -410.213017) (xy 73.699744 -410.195825) (xy 73.700132 -410.186632)
			(xy 73.700132 -409.693364) (xy 73.699732 -409.684176) (xy 73.69321 -409.666992) (xy 73.687432 -409.659836)
			(xy 73.665656 -409.634174) (xy 73.627707 -409.578589) (xy 73.596674 -409.518867) (xy 73.573001 -409.455863)
			(xy 73.557027 -409.390482) (xy 73.548982 -409.323661) (xy 73.548981 -409.256357) (xy 73.557024 -409.189535)
			(xy 73.572995 -409.124154) (xy 73.596667 -409.06115) (xy 73.627698 -409.001427) (xy 73.665645 -408.94584)
			(xy 73.687432 -408.920188) (xy 73.69322 -408.913037) (xy 73.699739 -408.895851) (xy 73.700132 -408.88666)
			(xy 73.700132 -408.728672) (xy 73.700499 -408.718512) (xy 73.70831 -408.699753) (xy 73.722724 -408.685429)
			(xy 73.741532 -408.677736) (xy 73.751694 -408.677364) (xy 74.467974 -408.677364) (xy 74.478102 -408.677848)
			(xy 74.496827 -408.685572) (xy 74.511185 -408.69986) (xy 74.519001 -408.718546) (xy 74.519536 -408.728672)
			(xy 74.519536 -408.88666) (xy 74.51998 -408.895843) (xy 74.526472 -408.913027) (xy 74.532236 -408.920188)
			(xy 74.554036 -408.94583) (xy 74.591986 -409.001418) (xy 74.62302 -409.061142) (xy 74.646694 -409.124148)
			(xy 74.662666 -409.189532) (xy 74.67071 -409.256356) (xy 74.670709 -409.323662) (xy 74.662663 -409.390486)
			(xy 74.646688 -409.455869) (xy 74.623013 -409.518874) (xy 74.620439 -409.523827) (xy 75.749085 -409.523827)
			(xy 75.749088 -409.456519) (xy 75.757137 -409.389693) (xy 75.773115 -409.324308) (xy 75.796793 -409.261302)
			(xy 75.827833 -409.201578) (xy 75.865789 -409.145992) (xy 75.88758 -409.12034) (xy 75.893382 -409.113199)
			(xy 75.899894 -409.096005) (xy 75.90028 -409.086812) (xy 75.90028 -408.593544) (xy 75.899853 -408.584358)
			(xy 75.893352 -408.567174) (xy 75.88758 -408.560016) (xy 75.865783 -408.534371) (xy 75.827832 -408.478784)
			(xy 75.796797 -408.41906) (xy 75.773123 -408.356055) (xy 75.757149 -408.290671) (xy 75.749105 -408.223847)
			(xy 75.749106 -408.156541) (xy 75.757151 -408.089717) (xy 75.773126 -408.024334) (xy 75.796802 -407.961329)
			(xy 75.827838 -407.901605) (xy 75.865791 -407.84602) (xy 75.88758 -407.820368) (xy 75.89337 -407.813218)
			(xy 75.899889 -407.796031) (xy 75.90028 -407.78684) (xy 75.90028 -407.628852) (xy 75.900682 -407.618697)
			(xy 75.90849 -407.599948) (xy 75.922892 -407.585627) (xy 75.941685 -407.577925) (xy 75.951842 -407.577544)
			(xy 76.668122 -407.577544) (xy 76.678251 -407.578008) (xy 76.696973 -407.585744) (xy 76.711329 -407.600037)
			(xy 76.719147 -407.618726) (xy 76.719684 -407.628852) (xy 76.719684 -407.78684) (xy 76.720078 -407.796029)
			(xy 76.726603 -407.813213) (xy 76.732384 -407.820368) (xy 76.754163 -407.846027) (xy 76.792111 -407.901613)
			(xy 76.823143 -407.961336) (xy 76.846815 -408.024339) (xy 76.862788 -408.08972) (xy 76.870833 -408.156542)
			(xy 76.870833 -408.223846) (xy 76.86279 -408.290668) (xy 76.846819 -408.356049) (xy 76.823148 -408.419053)
			(xy 76.792117 -408.478777) (xy 76.754171 -408.534364) (xy 76.732384 -408.560016) (xy 76.726596 -408.567167)
			(xy 76.720077 -408.584353) (xy 76.719684 -408.593544) (xy 76.719684 -409.086812) (xy 76.720092 -409.095999)
			(xy 76.726607 -409.113184) (xy 76.732384 -409.12034) (xy 76.754135 -409.146022) (xy 76.792084 -409.201605)
			(xy 76.823117 -409.261324) (xy 76.846791 -409.324325) (xy 76.862766 -409.389703) (xy 76.870812 -409.456522)
			(xy 76.870816 -409.523824) (xy 76.862775 -409.590644) (xy 76.846807 -409.656023) (xy 76.823139 -409.719026)
			(xy 76.792112 -409.778749) (xy 76.754169 -409.834335) (xy 76.732384 -409.859988) (xy 76.726566 -409.867118)
			(xy 76.720065 -409.88432) (xy 76.719684 -409.893516) (xy 76.719684 -410.051504) (xy 76.719281 -410.06166)
			(xy 76.711481 -410.080416) (xy 76.697079 -410.09474) (xy 76.678281 -410.102436) (xy 76.668122 -410.102812)
			(xy 75.951842 -410.102812) (xy 75.941724 -410.10224) (xy 75.923014 -410.094536) (xy 75.908658 -410.080276)
			(xy 75.900828 -410.061618) (xy 75.90028 -410.051504) (xy 75.90028 -409.893516) (xy 75.899867 -409.884329)
			(xy 75.893356 -409.867144) (xy 75.88758 -409.859988) (xy 75.865756 -409.834365) (xy 75.827805 -409.778776)
			(xy 75.796771 -409.719048) (xy 75.773099 -409.65604) (xy 75.757127 -409.590654) (xy 75.749085 -409.523827)
			(xy 74.620439 -409.523827) (xy 74.591977 -409.578598) (xy 74.554025 -409.634184) (xy 74.532236 -409.659836)
			(xy 74.526434 -409.666977) (xy 74.519924 -409.684171) (xy 74.519536 -409.693364) (xy 74.519536 -410.186632)
			(xy 74.519945 -410.195819) (xy 74.526461 -410.213002) (xy 74.532236 -410.22016) (xy 74.554009 -410.245825)
			(xy 74.59196 -410.301409) (xy 74.622995 -410.36113) (xy 74.64667 -410.424133) (xy 74.662644 -410.489514)
			(xy 74.67069 -410.556336) (xy 74.670692 -410.62364) (xy 74.670685 -410.623701) (xy 77.948731 -410.623701)
			(xy 77.948732 -410.556275) (xy 77.95681 -410.489335) (xy 77.972848 -410.423845) (xy 77.996615 -410.360747)
			(xy 78.02777 -410.300951) (xy 78.065862 -410.245317) (xy 78.087728 -410.219652) (xy 78.093531 -410.212512)
			(xy 78.100041 -410.195317) (xy 78.100428 -410.186124) (xy 78.100428 -409.693872) (xy 78.100025 -409.684684)
			(xy 78.093506 -409.6675) (xy 78.087728 -409.660344) (xy 78.065875 -409.63467) (xy 78.027784 -409.579037)
			(xy 77.996631 -409.519242) (xy 77.972865 -409.456147) (xy 77.956828 -409.390658) (xy 77.948751 -409.323721)
			(xy 77.94875 -409.256297) (xy 77.956825 -409.189359) (xy 77.97286 -409.123871) (xy 77.996624 -409.060774)
			(xy 78.027775 -409.000979) (xy 78.065864 -408.945345) (xy 78.087728 -408.91968) (xy 78.093519 -408.912531)
			(xy 78.100036 -408.895343) (xy 78.100428 -408.886152) (xy 78.100428 -408.728672) (xy 78.100794 -408.718544)
			(xy 78.108556 -408.699835) (xy 78.122888 -408.68552) (xy 78.141608 -408.677781) (xy 78.151736 -408.677364)
			(xy 78.868016 -408.677364) (xy 78.878121 -408.677871) (xy 78.896793 -408.685608) (xy 78.911086 -408.699897)
			(xy 78.918826 -408.718567) (xy 78.919324 -408.728672) (xy 78.919324 -408.886152) (xy 78.919752 -408.895337)
			(xy 78.926253 -408.912522) (xy 78.932024 -408.91968) (xy 78.953899 -408.945336) (xy 78.991986 -409.000972)
			(xy 79.023135 -409.06077) (xy 79.046897 -409.123868) (xy 79.062931 -409.189358) (xy 79.071005 -409.256297)
			(xy 79.071004 -409.323721) (xy 79.062928 -409.39066) (xy 79.046892 -409.456149) (xy 79.023127 -409.519246)
			(xy 79.02071 -409.523886) (xy 80.148878 -409.523886) (xy 80.148881 -409.45646) (xy 80.15696 -409.38952)
			(xy 80.172999 -409.324029) (xy 80.196766 -409.260931) (xy 80.227919 -409.201133) (xy 80.266011 -409.145498)
			(xy 80.287876 -409.119832) (xy 80.293681 -409.112693) (xy 80.300191 -409.095498) (xy 80.300576 -409.086304)
			(xy 80.300576 -408.594052) (xy 80.300146 -408.584867) (xy 80.293647 -408.567682) (xy 80.287876 -408.560524)
			(xy 80.266005 -408.534865) (xy 80.227918 -408.479229) (xy 80.196769 -408.419432) (xy 80.173006 -408.356334)
			(xy 80.156972 -408.290844) (xy 80.148897 -408.223906) (xy 80.148898 -408.156482) (xy 80.156974 -408.089544)
			(xy 80.17301 -408.024055) (xy 80.196774 -407.960957) (xy 80.227924 -407.901161) (xy 80.266012 -407.845526)
			(xy 80.287876 -407.81986) (xy 80.293669 -407.812712) (xy 80.300187 -407.795524) (xy 80.300576 -407.786332)
			(xy 80.300576 -407.628852) (xy 80.301045 -407.618743) (xy 80.308794 -407.600069) (xy 80.323095 -407.585776)
			(xy 80.341775 -407.578039) (xy 80.351884 -407.577544) (xy 81.068164 -407.577544) (xy 81.078264 -407.578113)
			(xy 81.09693 -407.585829) (xy 81.111224 -407.600099) (xy 81.11897 -407.618753) (xy 81.119472 -407.628852)
			(xy 81.119472 -407.786332) (xy 81.119873 -407.79552) (xy 81.126394 -407.812704) (xy 81.132172 -407.81986)
			(xy 81.154029 -407.845531) (xy 81.19212 -407.901164) (xy 81.223273 -407.960959) (xy 81.247038 -408.024056)
			(xy 81.263075 -408.089544) (xy 81.271152 -408.156482) (xy 81.271153 -408.223906) (xy 81.263077 -408.290844)
			(xy 81.247042 -408.356333) (xy 81.223277 -408.41943) (xy 81.192126 -408.479225) (xy 81.154036 -408.534859)
			(xy 81.132172 -408.560524) (xy 81.126379 -408.567672) (xy 81.119863 -408.58486) (xy 81.119472 -408.594052)
			(xy 81.119472 -409.086304) (xy 81.119886 -409.095491) (xy 81.126398 -409.112675) (xy 81.132172 -409.119832)
			(xy 81.154002 -409.145526) (xy 81.192093 -409.201156) (xy 81.223247 -409.260948) (xy 81.247014 -409.324041)
			(xy 81.263053 -409.389527) (xy 81.271132 -409.456462) (xy 81.271136 -409.523884) (xy 81.263063 -409.59082)
			(xy 81.247031 -409.656307) (xy 81.223269 -409.719403) (xy 81.192121 -409.779198) (xy 81.154035 -409.834831)
			(xy 81.132172 -409.860496) (xy 81.126391 -409.867652) (xy 81.119868 -409.884834) (xy 81.119472 -409.894024)
			(xy 81.119472 -410.051504) (xy 81.119086 -410.06163) (xy 81.111332 -410.080339) (xy 81.097006 -410.094654)
			(xy 81.078291 -410.102394) (xy 81.068164 -410.102812) (xy 80.351884 -410.102812) (xy 80.341776 -410.102328)
			(xy 80.3231 -410.094587) (xy 80.308806 -410.08029) (xy 80.30107 -410.061612) (xy 80.300576 -410.051504)
			(xy 80.300576 -409.894024) (xy 80.30016 -409.884837) (xy 80.293651 -409.867653) (xy 80.287876 -409.860496)
			(xy 80.265978 -409.83486) (xy 80.227891 -409.77922) (xy 80.196744 -409.71942) (xy 80.172983 -409.656319)
			(xy 80.15695 -409.590827) (xy 80.148878 -409.523886) (xy 79.02071 -409.523886) (xy 78.991976 -409.579043)
			(xy 78.953888 -409.634678) (xy 78.932024 -409.660344) (xy 78.926229 -409.667491) (xy 78.919713 -409.68468)
			(xy 78.919324 -409.693872) (xy 78.919324 -410.186124) (xy 78.919717 -410.195313) (xy 78.926242 -410.212497)
			(xy 78.932024 -410.219652) (xy 78.953871 -410.245331) (xy 78.991959 -410.300964) (xy 79.023109 -410.360758)
			(xy 79.046873 -410.423853) (xy 79.062909 -410.489341) (xy 79.070986 -410.556277) (xy 79.070987 -410.623641)
			(xy 82.349051 -410.623641) (xy 82.349052 -410.556335) (xy 82.357097 -410.489512) (xy 82.373071 -410.424129)
			(xy 82.396745 -410.361124) (xy 82.427779 -410.3014) (xy 82.465728 -410.245812) (xy 82.487516 -410.22016)
			(xy 82.493314 -410.213016) (xy 82.499827 -410.195824) (xy 82.500216 -410.186632) (xy 82.500216 -409.693364)
			(xy 82.49982 -409.684175) (xy 82.493296 -409.666991) (xy 82.487516 -409.659836) (xy 82.465741 -409.634174)
			(xy 82.427793 -409.578588) (xy 82.39676 -409.518866) (xy 82.373088 -409.455863) (xy 82.357115 -409.390482)
			(xy 82.34907 -409.323661) (xy 82.349069 -409.256357) (xy 82.357112 -409.189536) (xy 82.373083 -409.124155)
			(xy 82.396753 -409.061151) (xy 82.427784 -409.001427) (xy 82.46573 -408.94584) (xy 82.487516 -408.920188)
			(xy 82.493302 -408.913035) (xy 82.499822 -408.89585) (xy 82.500216 -408.88666) (xy 82.500216 -408.728672)
			(xy 82.500599 -408.718514) (xy 82.508407 -408.699758) (xy 82.522815 -408.685435) (xy 82.541618 -408.677739)
			(xy 82.551778 -408.677364) (xy 83.268058 -408.677364) (xy 83.278185 -408.677862) (xy 83.29691 -408.68558)
			(xy 83.311268 -408.699864) (xy 83.319085 -408.718548) (xy 83.31962 -408.728672) (xy 83.31962 -408.88666)
			(xy 83.320045 -408.895846) (xy 83.326548 -408.913031) (xy 83.33232 -408.920188) (xy 83.354121 -408.94583)
			(xy 83.392072 -409.001417) (xy 83.423107 -409.061141) (xy 83.446781 -409.124147) (xy 83.462754 -409.189531)
			(xy 83.470798 -409.256356) (xy 83.470797 -409.323662) (xy 83.462751 -409.390487) (xy 83.446775 -409.45587)
			(xy 83.423099 -409.518875) (xy 83.420495 -409.523886) (xy 84.548669 -409.523886) (xy 84.548672 -409.45646)
			(xy 84.556751 -409.38952) (xy 84.572789 -409.324029) (xy 84.596556 -409.260931) (xy 84.627709 -409.201134)
			(xy 84.665799 -409.145498) (xy 84.687664 -409.119832) (xy 84.69348 -409.112701) (xy 84.699981 -409.095499)
			(xy 84.700364 -409.086304) (xy 84.700364 -408.594052) (xy 84.699915 -408.584869) (xy 84.693427 -408.567685)
			(xy 84.687664 -408.560524) (xy 84.665793 -408.534865) (xy 84.627707 -408.479228) (xy 84.596559 -408.419431)
			(xy 84.572797 -408.356334) (xy 84.556763 -408.290844) (xy 84.548688 -408.223906) (xy 84.548689 -408.156482)
			(xy 84.556765 -408.089544) (xy 84.5728 -408.024055) (xy 84.596564 -407.960958) (xy 84.627714 -407.901161)
			(xy 84.665801 -407.845526) (xy 84.687664 -407.81986) (xy 84.693468 -407.81272) (xy 84.699976 -407.795525)
			(xy 84.700364 -407.786332) (xy 84.700364 -407.628852) (xy 84.700845 -407.618745) (xy 84.708592 -407.600072)
			(xy 84.722889 -407.585781) (xy 84.741564 -407.578041) (xy 84.751672 -407.577544) (xy 85.467952 -407.577544)
			(xy 85.478051 -407.578123) (xy 85.496717 -407.585835) (xy 85.510806 -407.599896) (xy 98.75089 -407.599896)
			(xy 98.754894 -407.394708) (xy 98.766901 -407.189832) (xy 98.786892 -406.985581) (xy 98.814837 -406.782266)
			(xy 98.850693 -406.580195) (xy 98.894407 -406.379677) (xy 98.94591 -406.181018) (xy 99.005125 -405.984519)
			(xy 99.071961 -405.79048) (xy 99.146317 -405.599197) (xy 99.22808 -405.41096) (xy 99.317125 -405.226057)
			(xy 99.413316 -405.044769) (xy 99.516507 -404.867372) (xy 99.626541 -404.694135) (xy 99.74325 -404.525324)
			(xy 99.866456 -404.361195) (xy 99.995973 -404.201998) (xy 100.131602 -404.047976) (xy 100.273137 -403.899362)
			(xy 100.420362 -403.756384) (xy 100.573054 -403.619259) (xy 100.73098 -403.488195) (xy 100.893899 -403.363393)
			(xy 101.061564 -403.245043) (xy 101.233718 -403.133324) (xy 101.4101 -403.028407) (xy 101.590441 -402.930452)
			(xy 101.774467 -402.839608) (xy 101.961897 -402.756012) (xy 102.152446 -402.679793) (xy 102.345823 -402.611067)
			(xy 102.541735 -402.549938) (xy 102.739882 -402.496499) (xy 102.939964 -402.450832) (xy 103.141675 -402.413005)
			(xy 103.344708 -402.383078) (xy 103.548755 -402.361095) (xy 103.753504 -402.34709) (xy 103.958643 -402.341084)
			(xy 104.16386 -402.343086) (xy 104.368843 -402.353094) (xy 104.57328 -402.371091) (xy 104.776858 -402.397051)
			(xy 104.979269 -402.430934) (xy 105.180203 -402.472689) (xy 105.379356 -402.522252) (xy 105.576423 -402.579547)
			(xy 105.771105 -402.644487) (xy 105.963105 -402.716973) (xy 106.15213 -402.796896) (xy 106.209586 -402.823878)
			(xy 117.548826 -402.823878) (xy 117.548831 -402.75645) (xy 117.556912 -402.689507) (xy 117.572954 -402.624015)
			(xy 117.596726 -402.560916) (xy 117.627885 -402.501119) (xy 117.665983 -402.445484) (xy 117.687852 -402.41982)
			(xy 117.693671 -402.412691) (xy 117.700171 -402.395488) (xy 117.700552 -402.386292) (xy 117.700552 -401.89404)
			(xy 117.700111 -401.884856) (xy 117.693618 -401.867672) (xy 117.687852 -401.860512) (xy 117.665967 -401.834864)
			(xy 117.627875 -401.779228) (xy 117.596722 -401.71943) (xy 117.572957 -401.656331) (xy 117.556921 -401.590839)
			(xy 117.548846 -401.523898) (xy 117.548848 -401.456472) (xy 117.556927 -401.389531) (xy 117.572966 -401.32404)
			(xy 117.596735 -401.260943) (xy 117.627891 -401.201146) (xy 117.665985 -401.145512) (xy 117.687852 -401.119848)
			(xy 117.69366 -401.112711) (xy 117.700166 -401.095514) (xy 117.700552 -401.08632) (xy 117.700552 -400.92884)
			(xy 117.701117 -400.91874) (xy 117.708832 -400.900072) (xy 117.723105 -400.885777) (xy 117.741761 -400.878033)
			(xy 117.75186 -400.877532) (xy 118.46814 -400.877532) (xy 118.478255 -400.877953) (xy 118.49694 -400.88571)
			(xy 118.511235 -400.900027) (xy 118.518963 -400.918724) (xy 118.519448 -400.92884) (xy 118.519448 -401.08632)
			(xy 118.51986 -401.095507) (xy 118.526374 -401.11269) (xy 118.532148 -401.119848) (xy 118.553994 -401.145529)
			(xy 118.592087 -401.20116) (xy 118.623241 -401.260953) (xy 118.647009 -401.324048) (xy 118.663047 -401.389536)
			(xy 118.671126 -401.456473) (xy 118.671127 -401.523897) (xy 118.663053 -401.590834) (xy 118.647018 -401.656323)
			(xy 118.623254 -401.719419) (xy 118.620974 -401.723796) (xy 119.749006 -401.723796) (xy 119.749008 -401.656371)
			(xy 119.757086 -401.589431) (xy 119.773123 -401.523941) (xy 119.79689 -401.460843) (xy 119.828043 -401.401046)
			(xy 119.866135 -401.345411) (xy 119.888 -401.319746) (xy 119.893802 -401.312605) (xy 119.900313 -401.295411)
			(xy 119.9007 -401.286218) (xy 119.9007 -400.793966) (xy 119.900306 -400.784777) (xy 119.893781 -400.767593)
			(xy 119.888 -400.760438) (xy 119.866142 -400.734768) (xy 119.828053 -400.679134) (xy 119.796902 -400.619339)
			(xy 119.773138 -400.556242) (xy 119.757102 -400.490754) (xy 119.749025 -400.423816) (xy 119.749025 -400.356393)
			(xy 119.7571 -400.289455) (xy 119.773135 -400.223966) (xy 119.796898 -400.16087) (xy 119.828048 -400.101074)
			(xy 119.866136 -400.045439) (xy 119.888 -400.019774) (xy 119.89379 -400.012624) (xy 119.900309 -399.995437)
			(xy 119.9007 -399.986246) (xy 119.9007 -399.828766) (xy 119.901197 -399.818642) (xy 119.908929 -399.799928)
			(xy 119.923211 -399.785574) (xy 119.941887 -399.777749) (xy 119.952008 -399.777204) (xy 120.668288 -399.777204)
			(xy 120.678442 -399.777631) (xy 120.697195 -399.785424) (xy 120.711519 -399.799819) (xy 120.719218 -399.81861)
			(xy 120.719596 -399.828766) (xy 120.719596 -399.986246) (xy 120.720033 -399.99543) (xy 120.726528 -400.012615)
			(xy 120.732296 -400.019774) (xy 120.754166 -400.045434) (xy 120.792255 -400.101069) (xy 120.823405 -400.160866)
			(xy 120.847169 -400.223964) (xy 120.863205 -400.289454) (xy 120.87128 -400.356392) (xy 120.87128 -400.423817)
			(xy 120.863203 -400.490755) (xy 120.847167 -400.556245) (xy 120.823402 -400.619342) (xy 120.79225 -400.679138)
			(xy 120.75416 -400.734773) (xy 120.732296 -400.760438) (xy 120.7265 -400.767584) (xy 120.719985 -400.784774)
			(xy 120.719596 -400.793966) (xy 120.719596 -401.286218) (xy 120.719998 -401.295406) (xy 120.726517 -401.31259)
			(xy 120.732296 -401.319746) (xy 120.754138 -401.345429) (xy 120.792228 -401.401061) (xy 120.82338 -401.460855)
			(xy 120.847146 -401.523949) (xy 120.863183 -401.589436) (xy 120.87126 -401.656372) (xy 120.871262 -401.723794)
			(xy 120.863189 -401.790731) (xy 120.847155 -401.856219) (xy 120.823394 -401.919315) (xy 120.792245 -401.979111)
			(xy 120.754159 -402.034745) (xy 120.732296 -402.06041) (xy 120.726512 -402.067564) (xy 120.71999 -402.084748)
			(xy 120.719596 -402.093938) (xy 120.719596 -402.251418) (xy 120.719089 -402.261541) (xy 120.711362 -402.280256)
			(xy 120.697083 -402.294611) (xy 120.678409 -402.302436) (xy 120.668288 -402.30298) (xy 119.952008 -402.30298)
			(xy 119.941852 -402.302571) (xy 119.923096 -402.294775) (xy 119.908771 -402.280374) (xy 119.901075 -402.261576)
			(xy 119.9007 -402.251418) (xy 119.9007 -402.093938) (xy 119.900272 -402.084753) (xy 119.893771 -402.067568)
			(xy 119.888 -402.06041) (xy 119.866114 -402.034763) (xy 119.828026 -401.979126) (xy 119.796877 -401.919327)
			(xy 119.773114 -401.856228) (xy 119.75708 -401.790736) (xy 119.749006 -401.723796) (xy 118.620974 -401.723796)
			(xy 118.592102 -401.779215) (xy 118.554013 -401.834848) (xy 118.532148 -401.860512) (xy 118.526357 -401.867661)
			(xy 118.519841 -401.884849) (xy 118.519448 -401.89404) (xy 118.519448 -402.386292) (xy 118.519874 -402.395477)
			(xy 118.526378 -402.412661) (xy 118.532148 -402.41982) (xy 118.553967 -402.445523) (xy 118.59206 -402.501151)
			(xy 118.623216 -402.560942) (xy 118.646985 -402.624034) (xy 118.663025 -402.689519) (xy 118.671106 -402.756454)
			(xy 118.67111 -402.823818) (xy 121.949146 -402.823818) (xy 121.94915 -402.756509) (xy 121.957199 -402.689684)
			(xy 121.973177 -402.624299) (xy 121.996856 -402.561292) (xy 122.027895 -402.501567) (xy 122.065849 -402.44598)
			(xy 122.08764 -402.420328) (xy 122.093455 -402.413196) (xy 122.099958 -402.395995) (xy 122.10034 -402.3868)
			(xy 122.10034 -401.893532) (xy 122.099905 -401.884348) (xy 122.093408 -401.867164) (xy 122.08764 -401.860004)
			(xy 122.065832 -401.834368) (xy 122.027884 -401.778779) (xy 121.996852 -401.719054) (xy 121.97318 -401.656047)
			(xy 121.957208 -401.590663) (xy 121.949166 -401.523838) (xy 121.949168 -401.456532) (xy 121.957214 -401.389708)
			(xy 121.973189 -401.324324) (xy 121.996864 -401.261319) (xy 122.0279 -401.201595) (xy 122.065851 -401.146008)
			(xy 122.08764 -401.120356) (xy 122.093443 -401.113215) (xy 122.099953 -401.096021) (xy 122.10034 -401.086828)
			(xy 122.10034 -400.92884) (xy 122.100755 -400.918684) (xy 122.108545 -400.899924) (xy 122.122945 -400.885598)
			(xy 122.141743 -400.877904) (xy 122.151902 -400.877532) (xy 122.868182 -400.877532) (xy 122.878307 -400.878041)
			(xy 122.897026 -400.885761) (xy 122.911383 -400.900041) (xy 122.919204 -400.918718) (xy 122.919744 -400.92884)
			(xy 122.919744 -401.086828) (xy 122.920153 -401.096015) (xy 122.926669 -401.113199) (xy 122.932444 -401.120356)
			(xy 122.954212 -401.146024) (xy 122.992163 -401.201608) (xy 123.023198 -401.261329) (xy 123.046873 -401.324332)
			(xy 123.062848 -401.389712) (xy 123.070894 -401.456533) (xy 123.070895 -401.523837) (xy 123.062853 -401.590658)
			(xy 123.046882 -401.65604) (xy 123.02321 -401.719043) (xy 123.020771 -401.723737) (xy 124.149301 -401.723737)
			(xy 124.149303 -401.65643) (xy 124.15735 -401.589605) (xy 124.173327 -401.524221) (xy 124.197004 -401.461215)
			(xy 124.228043 -401.401491) (xy 124.265997 -401.345906) (xy 124.287788 -401.320254) (xy 124.293585 -401.313109)
			(xy 124.3001 -401.295918) (xy 124.300488 -401.286726) (xy 124.300488 -400.793458) (xy 124.300101 -400.784268)
			(xy 124.293572 -400.767084) (xy 124.287788 -400.75993) (xy 124.266005 -400.734274) (xy 124.228052 -400.678689)
			(xy 124.197016 -400.618966) (xy 124.173341 -400.555962) (xy 124.157366 -400.49058) (xy 124.149321 -400.423757)
			(xy 124.14932 -400.356452) (xy 124.157365 -400.289629) (xy 124.173338 -400.224246) (xy 124.197013 -400.161242)
			(xy 124.228048 -400.101519) (xy 124.265999 -400.045933) (xy 124.287788 -400.020282) (xy 124.293573 -400.013129)
			(xy 124.300095 -399.995944) (xy 124.300488 -399.986754) (xy 124.300488 -399.828766) (xy 124.300837 -399.818586)
			(xy 124.308643 -399.799781) (xy 124.323052 -399.785395) (xy 124.341869 -399.777621) (xy 124.35205 -399.777204)
			(xy 125.06833 -399.777204) (xy 125.078486 -399.777708) (xy 125.097249 -399.785486) (xy 125.111612 -399.799848)
			(xy 125.119391 -399.818611) (xy 125.119892 -399.828766) (xy 125.119892 -399.986754) (xy 125.120326 -399.995939)
			(xy 125.126823 -400.013123) (xy 125.132592 -400.020282) (xy 125.154385 -400.04593) (xy 125.192331 -400.101518)
			(xy 125.223363 -400.161242) (xy 125.247034 -400.224247) (xy 125.263005 -400.289629) (xy 125.271049 -400.356452)
			(xy 125.271048 -400.423757) (xy 125.263004 -400.490579) (xy 125.247031 -400.555962) (xy 125.223359 -400.618966)
			(xy 125.192327 -400.67869) (xy 125.154379 -400.734277) (xy 125.132592 -400.75993) (xy 125.126799 -400.767078)
			(xy 125.120283 -400.784266) (xy 125.119892 -400.793458) (xy 125.119892 -401.286726) (xy 125.120291 -401.295914)
			(xy 125.126813 -401.313099) (xy 125.132592 -401.320254) (xy 125.154357 -401.345924) (xy 125.192305 -401.401509)
			(xy 125.223337 -401.46123) (xy 125.24701 -401.524232) (xy 125.262983 -401.589612) (xy 125.271029 -401.656432)
			(xy 125.271031 -401.723735) (xy 125.262989 -401.790555) (xy 125.24702 -401.855936) (xy 125.223351 -401.918939)
			(xy 125.192322 -401.978663) (xy 125.154377 -402.034249) (xy 125.132592 -402.059902) (xy 125.126811 -402.067058)
			(xy 125.120287 -402.08424) (xy 125.119892 -402.09343) (xy 125.119892 -402.251418) (xy 125.119382 -402.261573)
			(xy 125.111608 -402.280337) (xy 125.097247 -402.294701) (xy 125.078485 -402.30248) (xy 125.06833 -402.30298)
			(xy 124.35205 -402.30298) (xy 124.341884 -402.302496) (xy 124.323094 -402.29473) (xy 124.308708 -402.280363)
			(xy 124.300918 -402.261584) (xy 124.300488 -402.251418) (xy 124.300488 -402.09343) (xy 124.300066 -402.084244)
			(xy 124.293561 -402.067059) (xy 124.287788 -402.059902) (xy 124.265977 -402.034268) (xy 124.228026 -401.97868)
			(xy 124.196991 -401.918955) (xy 124.173317 -401.855948) (xy 124.157344 -401.790563) (xy 124.149301 -401.723737)
			(xy 123.020771 -401.723737) (xy 122.992178 -401.778766) (xy 122.954231 -401.834352) (xy 122.932444 -401.860004)
			(xy 122.926656 -401.867155) (xy 122.920138 -401.884341) (xy 122.919744 -401.893532) (xy 122.919744 -402.3868)
			(xy 122.920167 -402.395986) (xy 122.926673 -402.413169) (xy 122.932444 -402.420328) (xy 122.954185 -402.446019)
			(xy 122.992136 -402.501599) (xy 123.023173 -402.561317) (xy 123.046849 -402.624317) (xy 123.062826 -402.689695)
			(xy 123.070874 -402.756513) (xy 123.070878 -402.823815) (xy 123.07087 -402.823878) (xy 126.348914 -402.823878)
			(xy 126.348919 -402.75645) (xy 126.357 -402.689508) (xy 126.373042 -402.624016) (xy 126.396813 -402.560916)
			(xy 126.427971 -402.501119) (xy 126.466068 -402.445485) (xy 126.487936 -402.41982) (xy 126.493754 -402.41269)
			(xy 126.500255 -402.395488) (xy 126.500636 -402.386292) (xy 126.500636 -401.89404) (xy 126.500198 -401.884856)
			(xy 126.493703 -401.867672) (xy 126.487936 -401.860512) (xy 126.466051 -401.834864) (xy 126.427961 -401.779227)
			(xy 126.396809 -401.719429) (xy 126.373044 -401.65633) (xy 126.357009 -401.590839) (xy 126.348934 -401.523898)
			(xy 126.348936 -401.456472) (xy 126.357014 -401.389532) (xy 126.373053 -401.324041) (xy 126.396821 -401.260943)
			(xy 126.427976 -401.201147) (xy 126.46607 -401.145513) (xy 126.487936 -401.119848) (xy 126.493742 -401.112709)
			(xy 126.50025 -401.095514) (xy 126.500636 -401.08632) (xy 126.500636 -400.92884) (xy 126.50105 -400.918716)
			(xy 126.508791 -400.900006) (xy 126.523109 -400.885689) (xy 126.54182 -400.877949) (xy 126.551944 -400.877532)
			(xy 127.268224 -400.877532) (xy 127.278352 -400.877897) (xy 127.297062 -400.885659) (xy 127.311377 -400.899991)
			(xy 127.319116 -400.918711) (xy 127.319532 -400.92884) (xy 127.319532 -401.08632) (xy 127.319948 -401.095506)
			(xy 127.326459 -401.11269) (xy 127.332232 -401.119848) (xy 127.354075 -401.14553) (xy 127.392162 -401.201163)
			(xy 127.423312 -401.260957) (xy 127.447076 -401.324052) (xy 127.463112 -401.389538) (xy 127.471189 -401.456474)
			(xy 127.471191 -401.523896) (xy 127.463117 -401.590832) (xy 127.447085 -401.65632) (xy 127.423324 -401.719415)
			(xy 127.421073 -401.723737) (xy 128.549092 -401.723737) (xy 128.549094 -401.65643) (xy 128.557141 -401.589605)
			(xy 128.573117 -401.524221) (xy 128.596794 -401.461216) (xy 128.627832 -401.401492) (xy 128.665786 -401.345906)
			(xy 128.687576 -401.320254) (xy 128.693372 -401.313108) (xy 128.699888 -401.295918) (xy 128.700276 -401.286726)
			(xy 128.700276 -400.793458) (xy 128.699891 -400.784268) (xy 128.69336 -400.767084) (xy 128.687576 -400.75993)
			(xy 128.665793 -400.734273) (xy 128.627842 -400.678688) (xy 128.596806 -400.618966) (xy 128.573131 -400.555962)
			(xy 128.557157 -400.49058) (xy 128.549112 -400.423757) (xy 128.549111 -400.356452) (xy 128.557155 -400.289629)
			(xy 128.573129 -400.224247) (xy 128.596802 -400.161242) (xy 128.627837 -400.101519) (xy 128.665788 -400.045934)
			(xy 128.687576 -400.020282) (xy 128.69336 -400.013128) (xy 128.699883 -399.995944) (xy 128.700276 -399.986754)
			(xy 128.700276 -399.828766) (xy 128.700637 -399.818587) (xy 128.70844 -399.799785) (xy 128.722845 -399.7854)
			(xy 128.741659 -399.777623) (xy 128.751838 -399.777204) (xy 129.468118 -399.777204) (xy 129.478273 -399.777718)
			(xy 129.497036 -399.785492) (xy 129.511399 -399.799851) (xy 129.519179 -399.818611) (xy 129.51968 -399.828766)
			(xy 129.51968 -399.986754) (xy 129.520117 -399.995938) (xy 129.526612 -400.013123) (xy 129.53238 -400.020282)
			(xy 129.554173 -400.045929) (xy 129.592121 -400.101517) (xy 129.623152 -400.161241) (xy 129.646824 -400.224247)
			(xy 129.662796 -400.289629) (xy 129.670839 -400.356452) (xy 129.670839 -400.423757) (xy 129.662794 -400.49058)
			(xy 129.646821 -400.555962) (xy 129.623149 -400.618967) (xy 129.592116 -400.678691) (xy 129.554168 -400.734278)
			(xy 129.53238 -400.75993) (xy 129.526586 -400.767077) (xy 129.52007 -400.784266) (xy 129.51968 -400.793458)
			(xy 129.51968 -401.286726) (xy 129.520082 -401.295914) (xy 129.526602 -401.313098) (xy 129.53238 -401.320254)
			(xy 129.554146 -401.345924) (xy 129.592094 -401.401508) (xy 129.623127 -401.46123) (xy 129.6468 -401.524232)
			(xy 129.662774 -401.589612) (xy 129.67082 -401.656432) (xy 129.670822 -401.723735) (xy 129.66278 -401.790556)
			(xy 129.64681 -401.855937) (xy 129.623141 -401.91894) (xy 129.592111 -401.978663) (xy 129.554166 -402.03425)
			(xy 129.53238 -402.059902) (xy 129.526598 -402.067057) (xy 129.520075 -402.08424) (xy 129.51968 -402.09343)
			(xy 129.51968 -402.251418) (xy 129.519182 -402.261575) (xy 129.511405 -402.280341) (xy 129.497041 -402.294705)
			(xy 129.478275 -402.302482) (xy 129.468118 -402.30298) (xy 128.751838 -402.30298) (xy 128.741671 -402.302505)
			(xy 128.722881 -402.294736) (xy 128.708495 -402.280366) (xy 128.700706 -402.261584) (xy 128.700276 -402.251418)
			(xy 128.700276 -402.09343) (xy 128.699857 -402.084244) (xy 128.69335 -402.067059) (xy 128.687576 -402.059902)
			(xy 128.665766 -402.034268) (xy 128.627815 -401.97868) (xy 128.596781 -401.918954) (xy 128.573108 -401.855947)
			(xy 128.557135 -401.790562) (xy 128.549092 -401.723737) (xy 127.421073 -401.723737) (xy 127.392178 -401.779211)
			(xy 127.354094 -401.834846) (xy 127.332232 -401.860512) (xy 127.32644 -401.86766) (xy 127.319924 -401.884849)
			(xy 127.319532 -401.89404) (xy 127.319532 -402.386292) (xy 127.319961 -402.395477) (xy 127.326463 -402.412661)
			(xy 127.332232 -402.41982) (xy 127.354048 -402.445525) (xy 127.392136 -402.501154) (xy 127.423287 -402.560945)
			(xy 127.447052 -402.624037) (xy 127.46309 -402.689521) (xy 127.471169 -402.756454) (xy 127.471174 -402.823818)
			(xy 130.749234 -402.823818) (xy 130.749238 -402.75651) (xy 130.757287 -402.689684) (xy 130.773265 -402.624299)
			(xy 130.796942 -402.561293) (xy 130.82798 -402.501568) (xy 130.865934 -402.44598) (xy 130.887724 -402.420328)
			(xy 130.893536 -402.413194) (xy 130.900041 -402.395995) (xy 130.900424 -402.3868) (xy 130.900424 -401.893532)
			(xy 130.899993 -401.884347) (xy 130.893493 -401.867163) (xy 130.887724 -401.860004) (xy 130.865917 -401.834368)
			(xy 130.82797 -401.778779) (xy 130.796938 -401.719053) (xy 130.773267 -401.656046) (xy 130.757296 -401.590662)
			(xy 130.749254 -401.523838) (xy 130.749256 -401.456532) (xy 130.757301 -401.389708) (xy 130.773276 -401.324325)
			(xy 130.79695 -401.26132) (xy 130.827985 -401.201595) (xy 130.865935 -401.146008) (xy 130.887724 -401.120356)
			(xy 130.893525 -401.113214) (xy 130.900036 -401.096021) (xy 130.900424 -401.086828) (xy 130.900424 -400.92884)
			(xy 130.900855 -400.918686) (xy 130.908642 -400.899929) (xy 130.923036 -400.885604) (xy 130.94183 -400.877907)
			(xy 130.951986 -400.877532) (xy 131.668266 -400.877532) (xy 131.67839 -400.878054) (xy 131.697108 -400.88577)
			(xy 131.711465 -400.900045) (xy 131.719287 -400.918719) (xy 131.719828 -400.92884) (xy 131.719828 -401.086828)
			(xy 131.720218 -401.096017) (xy 131.726745 -401.113202) (xy 131.732528 -401.120356) (xy 131.754297 -401.146024)
			(xy 131.792249 -401.201607) (xy 131.823285 -401.261328) (xy 131.84696 -401.324331) (xy 131.862935 -401.389712)
			(xy 131.870981 -401.456533) (xy 131.870983 -401.523837) (xy 131.862941 -401.590659) (xy 131.846969 -401.65604)
			(xy 131.823297 -401.719044) (xy 131.792264 -401.778767) (xy 131.754315 -401.834352) (xy 131.732528 -401.860004)
			(xy 131.726738 -401.867154) (xy 131.720222 -401.884341) (xy 131.719828 -401.893532) (xy 131.719828 -402.3868)
			(xy 131.720232 -402.395988) (xy 131.726749 -402.413173) (xy 131.732528 -402.420328) (xy 131.75427 -402.446019)
			(xy 131.792222 -402.501599) (xy 131.823259 -402.561317) (xy 131.846936 -402.624316) (xy 131.862913 -402.689694)
			(xy 131.870962 -402.756513) (xy 131.870966 -402.823815) (xy 131.862926 -402.890635) (xy 131.846957 -402.956015)
			(xy 131.823289 -403.019017) (xy 131.792259 -403.078739) (xy 131.754314 -403.134324) (xy 131.732528 -403.159976)
			(xy 131.726708 -403.167104) (xy 131.720209 -403.184308) (xy 131.719828 -403.193504) (xy 131.719828 -403.351492)
			(xy 131.719372 -403.361642) (xy 131.711585 -403.380389) (xy 131.697199 -403.394712) (xy 131.678418 -403.402417)
			(xy 131.668266 -403.4028) (xy 130.951986 -403.4028) (xy 130.941863 -403.402286) (xy 130.92315 -403.394561)
			(xy 130.908795 -403.380284) (xy 130.90097 -403.361612) (xy 130.900424 -403.351492) (xy 130.900424 -403.193504)
			(xy 130.900007 -403.184318) (xy 130.893498 -403.167133) (xy 130.887724 -403.159976) (xy 130.86589 -403.134362)
			(xy 130.827943 -403.07877) (xy 130.796913 -403.019041) (xy 130.773243 -402.956032) (xy 130.757274 -402.890645)
			(xy 130.749234 -402.823818) (xy 127.471174 -402.823818) (xy 127.471174 -402.823874) (xy 127.463103 -402.890808)
			(xy 127.447074 -402.956294) (xy 127.423316 -403.019389) (xy 127.392173 -403.079184) (xy 127.354092 -403.134818)
			(xy 127.332232 -403.160484) (xy 127.326409 -403.16761) (xy 127.319912 -403.184816) (xy 127.319532 -403.194012)
			(xy 127.319532 -403.351492) (xy 127.319009 -403.361596) (xy 127.31128 -403.380268) (xy 127.296995 -403.394562)
			(xy 127.278328 -403.402303) (xy 127.268224 -403.4028) (xy 126.551944 -403.4028) (xy 126.541824 -403.402348)
			(xy 126.523122 -403.394614) (xy 126.508806 -403.380308) (xy 126.501059 -403.361611) (xy 126.500636 -403.351492)
			(xy 126.500636 -403.194012) (xy 126.500212 -403.184826) (xy 126.493707 -403.167642) (xy 126.487936 -403.160484)
			(xy 126.466024 -403.134858) (xy 126.427934 -403.079219) (xy 126.396783 -403.019418) (xy 126.37302 -402.956315)
			(xy 126.356987 -402.890821) (xy 126.348914 -402.823878) (xy 123.07087 -402.823878) (xy 123.062839 -402.890634)
			(xy 123.04687 -402.956014) (xy 123.023202 -403.019017) (xy 122.992173 -403.078739) (xy 122.954229 -403.134324)
			(xy 122.932444 -403.159976) (xy 122.926626 -403.167106) (xy 122.920126 -403.184308) (xy 122.919744 -403.193504)
			(xy 122.919744 -403.351492) (xy 122.919273 -403.36164) (xy 122.911488 -403.380384) (xy 122.897107 -403.394706)
			(xy 122.878332 -403.402414) (xy 122.868182 -403.4028) (xy 122.151902 -403.4028) (xy 122.14178 -403.402273)
			(xy 122.123067 -403.394553) (xy 122.108712 -403.38028) (xy 122.100886 -403.361611) (xy 122.10034 -403.351492)
			(xy 122.10034 -403.193504) (xy 122.099919 -403.184318) (xy 122.093412 -403.167134) (xy 122.08764 -403.159976)
			(xy 122.065805 -403.134363) (xy 122.027857 -403.078771) (xy 121.996826 -403.019042) (xy 121.973156 -402.956032)
			(xy 121.957186 -402.890645) (xy 121.949146 -402.823818) (xy 118.67111 -402.823818) (xy 118.67111 -402.823874)
			(xy 118.663038 -402.89081) (xy 118.647006 -402.956297) (xy 118.623245 -403.019392) (xy 118.592097 -403.079187)
			(xy 118.554011 -403.13482) (xy 118.532148 -403.160484) (xy 118.526327 -403.167612) (xy 118.519828 -403.184816)
			(xy 118.519448 -403.194012) (xy 118.519448 -403.351492) (xy 118.51891 -403.361594) (xy 118.511183 -403.380263)
			(xy 118.496903 -403.394557) (xy 118.478242 -403.4023) (xy 118.46814 -403.4028) (xy 117.75186 -403.4028)
			(xy 117.741749 -403.402348) (xy 117.72307 -403.394597) (xy 117.708776 -403.38029) (xy 117.701043 -403.361604)
			(xy 117.700552 -403.351492) (xy 117.700552 -403.194012) (xy 117.700125 -403.184827) (xy 117.693622 -403.167643)
			(xy 117.687852 -403.160484) (xy 117.665939 -403.134859) (xy 117.627848 -403.07922) (xy 117.596697 -403.019418)
			(xy 117.572933 -402.956316) (xy 117.556899 -402.890822) (xy 117.548826 -402.823878) (xy 106.209586 -402.823878)
			(xy 106.337893 -402.884132) (xy 106.520111 -402.97855) (xy 106.698507 -403.080005) (xy 106.872808 -403.188344)
			(xy 107.04275 -403.3034) (xy 107.208073 -403.425) (xy 107.368526 -403.552957) (xy 107.523865 -403.687076)
			(xy 107.673852 -403.827155) (xy 107.81826 -403.972979) (xy 107.956868 -404.124325) (xy 108.089466 -404.280965)
			(xy 108.215852 -404.442659) (xy 108.335832 -404.609161) (xy 108.449225 -404.780217) (xy 108.555858 -404.955567)
			(xy 108.655568 -405.134944) (xy 108.748204 -405.318074) (xy 108.833624 -405.50468) (xy 108.882562 -405.623648)
			(xy 115.349248 -405.623648) (xy 115.349249 -405.556343) (xy 115.357293 -405.489521) (xy 115.373266 -405.424139)
			(xy 115.396938 -405.361134) (xy 115.42797 -405.30141) (xy 115.465917 -405.245823) (xy 115.487704 -405.22017)
			(xy 115.493496 -405.213022) (xy 115.500013 -405.195834) (xy 115.500404 -405.186642) (xy 115.500404 -404.693374)
			(xy 115.500006 -404.684186) (xy 115.493484 -404.667001) (xy 115.487704 -404.659846) (xy 115.465939 -404.634176)
			(xy 115.427992 -404.578591) (xy 115.396959 -404.51887) (xy 115.373287 -404.455868) (xy 115.357314 -404.390488)
			(xy 115.349268 -404.323668) (xy 115.349266 -404.256365) (xy 115.357308 -404.189545) (xy 115.373277 -404.124164)
			(xy 115.396946 -404.061161) (xy 115.427975 -404.001437) (xy 115.465919 -403.945851) (xy 115.487704 -403.920198)
			(xy 115.493484 -403.913041) (xy 115.500009 -403.89586) (xy 115.500404 -403.88667) (xy 115.500404 -403.728682)
			(xy 115.500918 -403.718527) (xy 115.508692 -403.699764) (xy 115.523051 -403.685401) (xy 115.541811 -403.677621)
			(xy 115.551966 -403.67712) (xy 116.268246 -403.67712) (xy 116.278404 -403.677595) (xy 116.297171 -403.685382)
			(xy 116.311534 -403.699752) (xy 116.31931 -403.718523) (xy 116.319808 -403.728682) (xy 116.319808 -403.88667)
			(xy 116.320231 -403.895856) (xy 116.326735 -403.91304) (xy 116.332508 -403.920198) (xy 116.354319 -403.945832)
			(xy 116.392271 -404.00142) (xy 116.423306 -404.061145) (xy 116.44698 -404.124152) (xy 116.462953 -404.189537)
			(xy 116.470996 -404.256363) (xy 116.470994 -404.32367) (xy 116.462947 -404.390495) (xy 116.44697 -404.455879)
			(xy 116.423292 -404.518885) (xy 116.392254 -404.578609) (xy 116.354299 -404.634195) (xy 116.332508 -404.659846)
			(xy 116.32671 -404.66699) (xy 116.320196 -404.684181) (xy 116.319808 -404.693374) (xy 116.319808 -405.186642)
			(xy 116.320196 -405.195832) (xy 116.326725 -405.213016) (xy 116.332508 -405.22017) (xy 116.354291 -405.245826)
			(xy 116.392244 -405.301411) (xy 116.42328 -405.361133) (xy 116.446956 -405.424137) (xy 116.462931 -405.48952)
			(xy 116.470976 -405.556343) (xy 116.470977 -405.623648) (xy 116.462932 -405.690471) (xy 116.446958 -405.755854)
			(xy 116.423284 -405.818858) (xy 116.392249 -405.878581) (xy 116.354297 -405.934167) (xy 116.332508 -405.959818)
			(xy 116.326722 -405.966971) (xy 116.320201 -405.984155) (xy 116.319808 -405.993346) (xy 116.319808 -406.151334)
			(xy 116.319296 -406.161488) (xy 116.311519 -406.180249) (xy 116.297159 -406.194612) (xy 116.2784 -406.202393)
			(xy 116.268246 -406.202896) (xy 115.551966 -406.202896) (xy 115.54181 -406.202395) (xy 115.523047 -406.194616)
			(xy 115.508684 -406.180253) (xy 115.500905 -406.16149) (xy 115.500404 -406.151334) (xy 115.500404 -405.993346)
			(xy 115.499971 -405.984161) (xy 115.493473 -405.966977) (xy 115.487704 -405.959818) (xy 115.465911 -405.93417)
			(xy 115.427965 -405.878582) (xy 115.396934 -405.818858) (xy 115.373263 -405.755853) (xy 115.357292 -405.69047)
			(xy 115.349248 -405.623648) (xy 108.882562 -405.623648) (xy 108.911698 -405.694476) (xy 108.982308 -405.887174)
			(xy 109.045345 -406.08248) (xy 109.100715 -406.280096) (xy 109.148332 -406.479723) (xy 109.188124 -406.681055)
			(xy 109.19485 -406.72379) (xy 117.548838 -406.72379) (xy 117.548841 -406.656362) (xy 117.55692 -406.589421)
			(xy 117.572961 -406.523929) (xy 117.596731 -406.460831) (xy 117.627888 -406.401034) (xy 117.665984 -406.3454)
			(xy 117.687852 -406.319736) (xy 117.693665 -406.312602) (xy 117.700168 -406.295403) (xy 117.700552 -406.286208)
			(xy 117.700552 -405.793956) (xy 117.700151 -405.784768) (xy 117.69363 -405.767585) (xy 117.687852 -405.760428)
			(xy 117.665982 -405.734767) (xy 117.62789 -405.679133) (xy 117.596737 -405.619337) (xy 117.572971 -405.556239)
			(xy 117.556934 -405.490749) (xy 117.548857 -405.42381) (xy 117.548858 -405.356384) (xy 117.556935 -405.289445)
			(xy 117.572972 -405.223955) (xy 117.596739 -405.160858) (xy 117.627893 -405.101062) (xy 117.665986 -405.045428)
			(xy 117.687852 -405.019764) (xy 117.693653 -405.012622) (xy 117.700164 -404.995429) (xy 117.700552 -404.986236)
			(xy 117.700552 -404.828756) (xy 117.701048 -404.81865) (xy 117.708791 -404.79998) (xy 117.723084 -404.785689)
			(xy 117.741754 -404.777947) (xy 117.75186 -404.777448) (xy 118.46814 -404.777448) (xy 118.478245 -404.777951)
			(xy 118.496914 -404.785692) (xy 118.511206 -404.799983) (xy 118.518948 -404.818651) (xy 118.519448 -404.828756)
			(xy 118.519448 -404.986236) (xy 118.519853 -404.995424) (xy 118.526372 -405.012607) (xy 118.532148 -405.019764)
			(xy 118.55401 -405.045432) (xy 118.592102 -405.101065) (xy 118.623256 -405.16086) (xy 118.647023 -405.223957)
			(xy 118.66306 -405.289446) (xy 118.671137 -405.356385) (xy 118.671137 -405.423809) (xy 118.663061 -405.490748)
			(xy 118.647024 -405.556238) (xy 118.623258 -405.619335) (xy 118.62098 -405.623708) (xy 119.749017 -405.623708)
			(xy 119.749017 -405.556283) (xy 119.757094 -405.489345) (xy 119.77313 -405.423855) (xy 119.796895 -405.360758)
			(xy 119.828046 -405.300962) (xy 119.866136 -405.245327) (xy 119.888 -405.219662) (xy 119.893795 -405.212516)
			(xy 119.900311 -405.195326) (xy 119.9007 -405.186134) (xy 119.9007 -404.693882) (xy 119.900298 -404.684694)
			(xy 119.893779 -404.66751) (xy 119.888 -404.660354) (xy 119.866158 -404.634671) (xy 119.828068 -404.579039)
			(xy 119.796917 -404.519245) (xy 119.773151 -404.456151) (xy 119.757114 -404.390664) (xy 119.749037 -404.323727)
			(xy 119.749035 -404.256306) (xy 119.757108 -404.189369) (xy 119.773141 -404.123881) (xy 119.796903 -404.060785)
			(xy 119.828051 -404.000989) (xy 119.866137 -403.945355) (xy 119.888 -403.91969) (xy 119.893783 -403.912535)
			(xy 119.900306 -403.895352) (xy 119.9007 -403.886162) (xy 119.9007 -403.728682) (xy 119.90121 -403.718559)
			(xy 119.908937 -403.699845) (xy 119.923215 -403.685491) (xy 119.941888 -403.677665) (xy 119.952008 -403.67712)
			(xy 120.668288 -403.67712) (xy 120.678444 -403.677532) (xy 120.6972 -403.685327) (xy 120.711524 -403.699727)
			(xy 120.719221 -403.718524) (xy 120.719596 -403.728682) (xy 120.719596 -403.886162) (xy 120.720025 -403.895347)
			(xy 120.726526 -403.912532) (xy 120.732296 -403.91969) (xy 120.754182 -403.945337) (xy 120.79227 -404.000974)
			(xy 120.82342 -404.060773) (xy 120.847183 -404.123872) (xy 120.863217 -404.189363) (xy 120.871291 -404.256304)
			(xy 120.871289 -404.323729) (xy 120.863211 -404.390669) (xy 120.847173 -404.456159) (xy 120.823407 -404.519257)
			(xy 120.792253 -404.579054) (xy 120.754161 -404.634689) (xy 120.732296 -404.660354) (xy 120.726494 -404.667495)
			(xy 120.719983 -404.684689) (xy 120.719596 -404.693882) (xy 120.719596 -405.186134) (xy 120.719991 -405.195323)
			(xy 120.726515 -405.212507) (xy 120.732296 -405.219662) (xy 120.754154 -405.245332) (xy 120.792243 -405.300966)
			(xy 120.823395 -405.360761) (xy 120.847159 -405.423858) (xy 120.863195 -405.489346) (xy 120.871272 -405.556284)
			(xy 120.871272 -405.623707) (xy 120.863197 -405.690645) (xy 120.847162 -405.756134) (xy 120.823398 -405.81923)
			(xy 120.792248 -405.879026) (xy 120.75416 -405.934661) (xy 120.732296 -405.960326) (xy 120.726505 -405.967475)
			(xy 120.719987 -405.984663) (xy 120.719596 -405.993854) (xy 120.719596 -406.151334) (xy 120.719102 -406.161458)
			(xy 120.71137 -406.180174) (xy 120.697087 -406.194527) (xy 120.67841 -406.202352) (xy 120.668288 -406.202896)
			(xy 119.952008 -406.202896) (xy 119.941854 -406.202472) (xy 119.923101 -406.194678) (xy 119.908777 -406.180282)
			(xy 119.901078 -406.16149) (xy 119.9007 -406.151334) (xy 119.9007 -405.993854) (xy 119.900264 -405.98467)
			(xy 119.893768 -405.967485) (xy 119.888 -405.960326) (xy 119.86613 -405.934666) (xy 119.828042 -405.87903)
			(xy 119.796891 -405.819234) (xy 119.773127 -405.756136) (xy 119.757092 -405.690646) (xy 119.749017 -405.623708)
			(xy 118.62098 -405.623708) (xy 118.592105 -405.67913) (xy 118.554014 -405.734764) (xy 118.532148 -405.760428)
			(xy 118.526351 -405.767572) (xy 118.519838 -405.784764) (xy 118.519448 -405.793956) (xy 118.519448 -406.286208)
			(xy 118.519866 -406.295394) (xy 118.526375 -406.312578) (xy 118.532148 -406.319736) (xy 118.553982 -406.345426)
			(xy 118.592075 -406.401056) (xy 118.62323 -406.460848) (xy 118.646999 -406.523942) (xy 118.663038 -406.589429)
			(xy 118.671117 -406.656365) (xy 118.67112 -406.72373) (xy 121.949157 -406.72373) (xy 121.94916 -406.656422)
			(xy 121.957208 -406.589597) (xy 121.973184 -406.524213) (xy 121.99686 -406.461207) (xy 122.027897 -406.401483)
			(xy 122.06585 -406.345896) (xy 122.08764 -406.320244) (xy 122.093448 -406.313107) (xy 122.099955 -406.29591)
			(xy 122.10034 -406.286716) (xy 122.10034 -405.793448) (xy 122.099898 -405.784264) (xy 122.093405 -405.76708)
			(xy 122.08764 -405.75992) (xy 122.065848 -405.734271) (xy 122.027899 -405.678684) (xy 121.996866 -405.61896)
			(xy 121.973194 -405.555955) (xy 121.957221 -405.490573) (xy 121.949177 -405.42375) (xy 121.949177 -405.356444)
			(xy 121.957222 -405.289621) (xy 121.973195 -405.224239) (xy 121.996869 -405.161234) (xy 122.027902 -405.101511)
			(xy 122.065852 -405.045924) (xy 122.08764 -405.020272) (xy 122.093436 -405.013127) (xy 122.09995 -404.995936)
			(xy 122.10034 -404.986744) (xy 122.10034 -404.828756) (xy 122.100686 -404.818594) (xy 122.108504 -404.799833)
			(xy 122.122924 -404.78551) (xy 122.141737 -404.777819) (xy 122.151902 -404.777448) (xy 122.868182 -404.777448)
			(xy 122.878309 -404.777941) (xy 122.897031 -404.785665) (xy 122.911388 -404.799949) (xy 122.919207 -404.818632)
			(xy 122.919744 -404.828756) (xy 122.919744 -404.986744) (xy 122.920145 -404.995932) (xy 122.926666 -405.013116)
			(xy 122.932444 -405.020272) (xy 122.954228 -405.045927) (xy 122.992178 -405.101513) (xy 123.023213 -405.161236)
			(xy 123.046886 -405.22424) (xy 123.06286 -405.289622) (xy 123.070905 -405.356444) (xy 123.070905 -405.42375)
			(xy 123.062861 -405.490572) (xy 123.046888 -405.555954) (xy 123.023215 -405.618959) (xy 123.020778 -405.623649)
			(xy 124.149312 -405.623649) (xy 124.149313 -405.556342) (xy 124.157358 -405.489518) (xy 124.173333 -405.424135)
			(xy 124.197009 -405.36113) (xy 124.228046 -405.301407) (xy 124.265998 -405.245822) (xy 124.287788 -405.22017)
			(xy 124.293578 -405.21302) (xy 124.300097 -405.195833) (xy 124.300488 -405.186642) (xy 124.300488 -404.693374)
			(xy 124.300093 -404.684185) (xy 124.293569 -404.667001) (xy 124.287788 -404.659846) (xy 124.26602 -404.634177)
			(xy 124.228068 -404.578594) (xy 124.197031 -404.518873) (xy 124.173355 -404.455871) (xy 124.157379 -404.39049)
			(xy 124.149332 -404.323669) (xy 124.14933 -404.256364) (xy 124.157373 -404.189542) (xy 124.173345 -404.124161)
			(xy 124.197017 -404.061157) (xy 124.228051 -404.001435) (xy 124.266 -403.945849) (xy 124.287788 -403.920198)
			(xy 124.293567 -403.91304) (xy 124.300092 -403.895859) (xy 124.300488 -403.88667) (xy 124.300488 -403.728682)
			(xy 124.30085 -403.718503) (xy 124.308651 -403.699698) (xy 124.323056 -403.685313) (xy 124.34187 -403.677537)
			(xy 124.35205 -403.67712) (xy 125.06833 -403.67712) (xy 125.078487 -403.677608) (xy 125.097254 -403.685389)
			(xy 125.111617 -403.699756) (xy 125.119394 -403.718524) (xy 125.119892 -403.728682) (xy 125.119892 -403.88667)
			(xy 125.120318 -403.895855) (xy 125.126821 -403.91304) (xy 125.132592 -403.920198) (xy 125.1544 -403.945833)
			(xy 125.192347 -404.001422) (xy 125.223377 -404.061149) (xy 125.247047 -404.124155) (xy 125.263018 -404.189539)
			(xy 125.27106 -404.256363) (xy 125.271058 -404.32367) (xy 125.263012 -404.390493) (xy 125.247038 -404.455876)
			(xy 125.223364 -404.518882) (xy 125.19233 -404.578606) (xy 125.15438 -404.634193) (xy 125.132592 -404.659846)
			(xy 125.126792 -404.666989) (xy 125.12028 -404.684181) (xy 125.119892 -404.693374) (xy 125.119892 -405.186642)
			(xy 125.120284 -405.195831) (xy 125.12681 -405.213015) (xy 125.132592 -405.22017) (xy 125.154373 -405.245827)
			(xy 125.19232 -405.301414) (xy 125.223352 -405.361137) (xy 125.247023 -405.424141) (xy 125.262996 -405.489522)
			(xy 125.27104 -405.556343) (xy 125.271041 -405.623647) (xy 125.262998 -405.690469) (xy 125.247026 -405.755851)
			(xy 125.223355 -405.818855) (xy 125.192325 -405.878578) (xy 125.154378 -405.934165) (xy 125.132592 -405.959818)
			(xy 125.126804 -405.96697) (xy 125.120285 -405.984155) (xy 125.119892 -405.993346) (xy 125.119892 -406.151334)
			(xy 125.119395 -406.16149) (xy 125.111615 -406.180254) (xy 125.097251 -406.194617) (xy 125.078486 -406.202396)
			(xy 125.06833 -406.202896) (xy 124.35205 -406.202896) (xy 124.341886 -406.202396) (xy 124.323099 -406.194634)
			(xy 124.308713 -406.180272) (xy 124.30092 -406.161497) (xy 124.300488 -406.151334) (xy 124.300488 -405.993346)
			(xy 124.300059 -405.984161) (xy 124.293559 -405.966976) (xy 124.287788 -405.959818) (xy 124.265993 -405.934171)
			(xy 124.228041 -405.878585) (xy 124.197005 -405.818861) (xy 124.173331 -405.755856) (xy 124.157357 -405.690473)
			(xy 124.149312 -405.623649) (xy 123.020778 -405.623649) (xy 122.992181 -405.678682) (xy 122.954232 -405.734268)
			(xy 122.932444 -405.75992) (xy 122.92665 -405.767066) (xy 122.920135 -405.784256) (xy 122.919744 -405.793448)
			(xy 122.919744 -406.286716) (xy 122.920159 -406.295902) (xy 122.926671 -406.313086) (xy 122.932444 -406.320244)
			(xy 122.954201 -406.345922) (xy 122.992152 -406.401504) (xy 123.023187 -406.461224) (xy 123.046862 -406.524225)
			(xy 123.062838 -406.589605) (xy 123.070885 -406.656425) (xy 123.070888 -406.723727) (xy 123.070881 -406.723789)
			(xy 126.348926 -406.723789) (xy 126.348929 -406.656363) (xy 126.357008 -406.589421) (xy 126.373048 -406.52393)
			(xy 126.396818 -406.460832) (xy 126.427974 -406.401035) (xy 126.466069 -406.345401) (xy 126.487936 -406.319736)
			(xy 126.493747 -406.312601) (xy 126.500252 -406.295403) (xy 126.500636 -406.286208) (xy 126.500636 -405.793956)
			(xy 126.500239 -405.784768) (xy 126.493715 -405.767584) (xy 126.487936 -405.760428) (xy 126.466067 -405.734767)
			(xy 126.427976 -405.679132) (xy 126.396823 -405.619336) (xy 126.373058 -405.556239) (xy 126.357022 -405.490749)
			(xy 126.348945 -405.423809) (xy 126.348946 -405.356385) (xy 126.357023 -405.289445) (xy 126.37306 -405.223956)
			(xy 126.396826 -405.160859) (xy 126.427979 -405.101062) (xy 126.466071 -405.045429) (xy 126.487936 -405.019764)
			(xy 126.493735 -405.012621) (xy 126.500247 -404.995429) (xy 126.500636 -404.986236) (xy 126.500636 -404.828756)
			(xy 126.50105 -404.81864) (xy 126.508809 -404.799954) (xy 126.523128 -404.785659) (xy 126.541827 -404.777933)
			(xy 126.551944 -404.777448) (xy 127.268224 -404.777448) (xy 127.278328 -404.777964) (xy 127.296997 -404.7857)
			(xy 127.311289 -404.799986) (xy 127.319032 -404.818652) (xy 127.319532 -404.828756) (xy 127.319532 -404.986236)
			(xy 127.31994 -404.995423) (xy 127.326457 -405.012607) (xy 127.332232 -405.019764) (xy 127.354091 -405.045433)
			(xy 127.392178 -405.101068) (xy 127.423327 -405.160864) (xy 127.44709 -405.22396) (xy 127.463125 -405.289448)
			(xy 127.4712 -405.356386) (xy 127.471201 -405.423808) (xy 127.463126 -405.490746) (xy 127.447092 -405.556234)
			(xy 127.423329 -405.619331) (xy 127.42108 -405.623649) (xy 128.549103 -405.623649) (xy 128.549104 -405.556342)
			(xy 128.557149 -405.489519) (xy 128.573124 -405.424136) (xy 128.596799 -405.361131) (xy 128.627835 -405.301407)
			(xy 128.665787 -405.245822) (xy 128.687576 -405.22017) (xy 128.693365 -405.213019) (xy 128.699885 -405.195833)
			(xy 128.700276 -405.186642) (xy 128.700276 -404.693374) (xy 128.699884 -404.684185) (xy 128.693358 -404.667)
			(xy 128.687576 -404.659846) (xy 128.665809 -404.634177) (xy 128.627857 -404.578593) (xy 128.596821 -404.518873)
			(xy 128.573145 -404.45587) (xy 128.557169 -404.39049) (xy 128.549123 -404.323669) (xy 128.549121 -404.256365)
			(xy 128.557164 -404.189543) (xy 128.573135 -404.124161) (xy 128.596807 -404.061158) (xy 128.62784 -404.001435)
			(xy 128.665789 -403.94585) (xy 128.687576 -403.920198) (xy 128.693353 -403.913039) (xy 128.69988 -403.895859)
			(xy 128.700276 -403.88667) (xy 128.700276 -403.728682) (xy 128.70065 -403.718505) (xy 128.708448 -403.699702)
			(xy 128.722849 -403.685317) (xy 128.74166 -403.677539) (xy 128.751838 -403.67712) (xy 129.468118 -403.67712)
			(xy 129.478275 -403.677618) (xy 129.497041 -403.685395) (xy 129.511405 -403.699759) (xy 129.519182 -403.718525)
			(xy 129.51968 -403.728682) (xy 129.51968 -403.88667) (xy 129.520109 -403.895855) (xy 129.52661 -403.913039)
			(xy 129.53238 -403.920198) (xy 129.554189 -403.945833) (xy 129.592136 -404.001422) (xy 129.623167 -404.061148)
			(xy 129.646838 -404.124155) (xy 129.662809 -404.189539) (xy 129.670851 -404.256363) (xy 129.670849 -404.32367)
			(xy 129.662803 -404.390494) (xy 129.646828 -404.455877) (xy 129.623154 -404.518882) (xy 129.592119 -404.578606)
			(xy 129.554169 -404.634194) (xy 129.53238 -404.659846) (xy 129.526579 -404.666988) (xy 129.520068 -404.684181)
			(xy 129.51968 -404.693374) (xy 129.51968 -405.186642) (xy 129.520074 -405.195831) (xy 129.5266 -405.213015)
			(xy 129.53238 -405.22017) (xy 129.554161 -405.245827) (xy 129.592109 -405.301413) (xy 129.623142 -405.361136)
			(xy 129.646814 -405.42414) (xy 129.662787 -405.489522) (xy 129.670831 -405.556343) (xy 129.670832 -405.623648)
			(xy 129.662788 -405.690469) (xy 129.646817 -405.755851) (xy 129.623145 -405.818855) (xy 129.592114 -405.878579)
			(xy 129.554167 -405.934166) (xy 129.53238 -405.959818) (xy 129.526591 -405.966968) (xy 129.520072 -405.984155)
			(xy 129.51968 -405.993346) (xy 129.51968 -406.151334) (xy 129.519195 -406.161492) (xy 129.511413 -406.180258)
			(xy 129.497045 -406.194622) (xy 129.478276 -406.202398) (xy 129.468118 -406.202896) (xy 128.751838 -406.202896)
			(xy 128.741673 -406.202406) (xy 128.722886 -406.19464) (xy 128.708501 -406.180275) (xy 128.700708 -406.161498)
			(xy 128.700276 -406.151334) (xy 128.700276 -405.993346) (xy 128.699849 -405.984161) (xy 128.693347 -405.966976)
			(xy 128.687576 -405.959818) (xy 128.665781 -405.934171) (xy 128.62783 -405.878585) (xy 128.596795 -405.818861)
			(xy 128.573121 -405.755856) (xy 128.557148 -405.690472) (xy 128.549103 -405.623649) (xy 127.42108 -405.623649)
			(xy 127.392181 -405.679127) (xy 127.354095 -405.734762) (xy 127.332232 -405.760428) (xy 127.326433 -405.767571)
			(xy 127.319922 -405.784763) (xy 127.319532 -405.793956) (xy 127.319532 -406.286208) (xy 127.319954 -406.295394)
			(xy 127.326461 -406.312577) (xy 127.332232 -406.319736) (xy 127.354063 -406.345428) (xy 127.392151 -406.401059)
			(xy 127.423301 -406.460852) (xy 127.447066 -406.523945) (xy 127.463103 -406.589431) (xy 127.471181 -406.656366)
			(xy 127.471183 -406.72373) (xy 130.749245 -406.72373) (xy 130.749248 -406.656422) (xy 130.757295 -406.589598)
			(xy 130.773271 -406.524214) (xy 130.796947 -406.461208) (xy 130.827983 -406.401484) (xy 130.865935 -406.345896)
			(xy 130.887724 -406.320244) (xy 130.89353 -406.313105) (xy 130.900038 -406.29591) (xy 130.900424 -406.286716)
			(xy 130.900424 -405.793448) (xy 130.899985 -405.784264) (xy 130.893491 -405.76708) (xy 130.887724 -405.75992)
			(xy 130.865933 -405.734271) (xy 130.827985 -405.678684) (xy 130.796953 -405.61896) (xy 130.773281 -405.555955)
			(xy 130.757309 -405.490572) (xy 130.749265 -405.42375) (xy 130.749265 -405.356444) (xy 130.75731 -405.289622)
			(xy 130.773283 -405.22424) (xy 130.796955 -405.161235) (xy 130.827988 -405.101511) (xy 130.865936 -405.045924)
			(xy 130.887724 -405.020272) (xy 130.893518 -405.013125) (xy 130.900033 -404.995936) (xy 130.900424 -404.986744)
			(xy 130.900424 -404.828756) (xy 130.900786 -404.818596) (xy 130.908601 -404.799838) (xy 130.923016 -404.785515)
			(xy 130.941823 -404.777822) (xy 130.951986 -404.777448) (xy 131.668266 -404.777448) (xy 131.678391 -404.777955)
			(xy 131.697113 -404.785673) (xy 131.711471 -404.799953) (xy 131.71929 -404.818633) (xy 131.719828 -404.828756)
			(xy 131.719828 -404.986744) (xy 131.720211 -404.995934) (xy 131.726743 -405.013119) (xy 131.732528 -405.020272)
			(xy 131.754313 -405.045927) (xy 131.792264 -405.101512) (xy 131.823299 -405.161235) (xy 131.846974 -405.224239)
			(xy 131.862948 -405.289622) (xy 131.870993 -405.356444) (xy 131.870993 -405.42375) (xy 131.862949 -405.490573)
			(xy 131.846975 -405.555955) (xy 131.823302 -405.618959) (xy 131.792267 -405.678683) (xy 131.754316 -405.734268)
			(xy 131.732528 -405.75992) (xy 131.726732 -405.767065) (xy 131.720219 -405.784256) (xy 131.719828 -405.793448)
			(xy 131.719828 -406.286716) (xy 131.720224 -406.295905) (xy 131.726747 -406.313089) (xy 131.732528 -406.320244)
			(xy 131.754285 -406.345922) (xy 131.792237 -406.401504) (xy 131.823274 -406.461223) (xy 131.84695 -406.524225)
			(xy 131.862926 -406.589604) (xy 131.870973 -406.656424) (xy 131.870976 -406.723728) (xy 131.862934 -406.790548)
			(xy 131.846964 -406.855929) (xy 131.823293 -406.918933) (xy 131.792262 -406.978655) (xy 131.754315 -407.03424)
			(xy 131.732528 -407.059892) (xy 131.726744 -407.067045) (xy 131.720224 -407.08423) (xy 131.719828 -407.09342)
			(xy 131.719828 -407.251408) (xy 131.719385 -407.261559) (xy 131.711592 -407.280306) (xy 131.697203 -407.294628)
			(xy 131.678419 -407.302333) (xy 131.668266 -407.302716) (xy 130.951986 -407.302716) (xy 130.941853 -407.302283)
			(xy 130.923123 -407.294543) (xy 130.908766 -407.28024) (xy 130.900955 -407.261539) (xy 130.900424 -407.251408)
			(xy 130.900424 -407.09342) (xy 130.899999 -407.084235) (xy 130.893495 -407.06705) (xy 130.887724 -407.059892)
			(xy 130.865905 -407.034266) (xy 130.827958 -406.978675) (xy 130.796927 -406.918948) (xy 130.773257 -406.85594)
			(xy 130.757287 -406.790555) (xy 130.749245 -406.72373) (xy 127.471183 -406.72373) (xy 127.471183 -406.723786)
			(xy 127.463111 -406.790722) (xy 127.44708 -406.856209) (xy 127.423321 -406.919304) (xy 127.392176 -406.9791)
			(xy 127.354093 -407.034734) (xy 127.332232 -407.0604) (xy 127.326445 -407.067551) (xy 127.319926 -407.084737)
			(xy 127.319532 -407.093928) (xy 127.319532 -407.251408) (xy 127.319022 -407.261513) (xy 127.311288 -407.280185)
			(xy 127.296999 -407.294479) (xy 127.278329 -407.302219) (xy 127.268224 -407.302716) (xy 126.551944 -407.302716)
			(xy 126.541826 -407.302248) (xy 126.523127 -407.294518) (xy 126.508812 -407.280217) (xy 126.501062 -407.261525)
			(xy 126.500636 -407.251408) (xy 126.500636 -407.093928) (xy 126.500204 -407.084743) (xy 126.493705 -407.067559)
			(xy 126.487936 -407.0604) (xy 126.466039 -407.034761) (xy 126.427949 -406.979124) (xy 126.396798 -406.919324)
			(xy 126.373034 -406.856224) (xy 126.357 -406.790731) (xy 126.348926 -406.723789) (xy 123.070881 -406.723789)
			(xy 123.062847 -406.790548) (xy 123.046877 -406.855929) (xy 123.023207 -406.918932) (xy 122.992176 -406.978654)
			(xy 122.95423 -407.03424) (xy 122.932444 -407.059892) (xy 122.926661 -407.067047) (xy 122.92014 -407.08423)
			(xy 122.919744 -407.09342) (xy 122.919744 -407.251408) (xy 122.919286 -407.261557) (xy 122.911496 -407.280301)
			(xy 122.897111 -407.294623) (xy 122.878333 -407.30233) (xy 122.868182 -407.302716) (xy 122.151902 -407.302716)
			(xy 122.14177 -407.30227) (xy 122.123041 -407.294535) (xy 122.108683 -407.280236) (xy 122.100871 -407.261538)
			(xy 122.10034 -407.251408) (xy 122.10034 -407.09342) (xy 122.099911 -407.084235) (xy 122.09341 -407.067051)
			(xy 122.08764 -407.059892) (xy 122.065821 -407.034266) (xy 122.027873 -406.978676) (xy 121.996841 -406.918949)
			(xy 121.97317 -406.855941) (xy 121.957199 -406.790555) (xy 121.949157 -406.72373) (xy 118.67112 -406.72373)
			(xy 118.67112 -406.723787) (xy 118.663047 -406.790724) (xy 118.647013 -406.856212) (xy 118.62325 -406.919308)
			(xy 118.5921 -406.979103) (xy 118.554012 -407.034736) (xy 118.532148 -407.0604) (xy 118.526362 -407.067553)
			(xy 118.519843 -407.084738) (xy 118.519448 -407.093928) (xy 118.519448 -407.251408) (xy 118.518922 -407.261511)
			(xy 118.511191 -407.28018) (xy 118.496907 -407.294473) (xy 118.478243 -407.302216) (xy 118.46814 -407.302716)
			(xy 117.75186 -407.302716) (xy 117.741751 -407.302248) (xy 117.723075 -407.2945) (xy 117.708782 -407.280198)
			(xy 117.701046 -407.261518) (xy 117.700552 -407.251408) (xy 117.700552 -407.093928) (xy 117.700117 -407.084744)
			(xy 117.693619 -407.06756) (xy 117.687852 -407.0604) (xy 117.665955 -407.034762) (xy 117.627864 -406.979124)
			(xy 117.596711 -406.919325) (xy 117.572947 -406.856225) (xy 117.556912 -406.790732) (xy 117.548838 -406.72379)
			(xy 109.19485 -406.72379) (xy 109.220031 -406.883787) (xy 109.244004 -407.087609) (xy 109.260006 -407.292212)
			(xy 109.268013 -407.497282) (xy 109.268514 -407.599896) (xy 109.268013 -407.70251) (xy 109.260006 -407.90758)
			(xy 109.244004 -408.112183) (xy 109.220031 -408.316005) (xy 109.188124 -408.518737) (xy 109.148332 -408.720069)
			(xy 109.100715 -408.919696) (xy 109.045345 -409.117312) (xy 108.982308 -409.312618) (xy 108.911698 -409.505316)
			(xy 108.904083 -409.523827) (xy 115.349227 -409.523827) (xy 115.349231 -409.456519) (xy 115.357278 -409.389695)
			(xy 115.373254 -409.324311) (xy 115.396929 -409.261305) (xy 115.427964 -409.20158) (xy 115.465915 -409.145993)
			(xy 115.487704 -409.12034) (xy 115.493509 -409.113201) (xy 115.500019 -409.096006) (xy 115.500404 -409.086812)
			(xy 115.500404 -408.593544) (xy 115.499972 -408.584359) (xy 115.493473 -408.567175) (xy 115.487704 -408.560016)
			(xy 115.465909 -408.53437) (xy 115.427963 -408.478782) (xy 115.396932 -408.419057) (xy 115.373261 -408.356052)
			(xy 115.35729 -408.290669) (xy 115.349247 -408.223846) (xy 115.349248 -408.156541) (xy 115.357292 -408.089719)
			(xy 115.373265 -408.024337) (xy 115.396937 -407.961332) (xy 115.427969 -407.901608) (xy 115.465917 -407.846021)
			(xy 115.487704 -407.820368) (xy 115.493497 -407.81322) (xy 115.500014 -407.796032) (xy 115.500404 -407.78684)
			(xy 115.500404 -407.628852) (xy 115.500783 -407.618694) (xy 115.508595 -407.59994) (xy 115.523004 -407.585618)
			(xy 115.541806 -407.577921) (xy 115.551966 -407.577544) (xy 116.268246 -407.577544) (xy 116.278376 -407.577989)
			(xy 116.297099 -407.585733) (xy 116.311454 -407.600031) (xy 116.319271 -407.618724) (xy 116.319808 -407.628852)
			(xy 116.319808 -407.78684) (xy 116.320197 -407.79603) (xy 116.326725 -407.813214) (xy 116.332508 -407.820368)
			(xy 116.354289 -407.846026) (xy 116.392242 -407.90161) (xy 116.423279 -407.961333) (xy 116.446954 -408.024336)
			(xy 116.462929 -408.089718) (xy 116.470975 -408.156541) (xy 116.470976 -408.223847) (xy 116.462931 -408.29067)
			(xy 116.446958 -408.356052) (xy 116.423283 -408.419056) (xy 116.392248 -408.478779) (xy 116.354297 -408.534365)
			(xy 116.332508 -408.560016) (xy 116.326723 -408.56717) (xy 116.320201 -408.584354) (xy 116.319808 -408.593544)
			(xy 116.319808 -409.086812) (xy 116.320211 -409.096) (xy 116.326729 -409.113184) (xy 116.332508 -409.12034)
			(xy 116.354262 -409.146021) (xy 116.392215 -409.201602) (xy 116.423253 -409.261321) (xy 116.44693 -409.324322)
			(xy 116.462907 -409.389701) (xy 116.470955 -409.456521) (xy 116.470958 -409.523825) (xy 116.462917 -409.590646)
			(xy 116.446946 -409.656026) (xy 116.423275 -409.71903) (xy 116.392243 -409.778752) (xy 116.354295 -409.834337)
			(xy 116.332508 -409.859988) (xy 116.326692 -409.86712) (xy 116.320189 -409.884321) (xy 116.319808 -409.893516)
			(xy 116.319808 -410.051504) (xy 116.319382 -410.061657) (xy 116.311586 -410.080408) (xy 116.297191 -410.094731)
			(xy 116.278401 -410.102432) (xy 116.268246 -410.102812) (xy 115.551966 -410.102812) (xy 115.541844 -410.102303)
			(xy 115.523131 -410.094574) (xy 115.508778 -410.080295) (xy 115.500951 -410.061624) (xy 115.500404 -410.051504)
			(xy 115.500404 -409.893516) (xy 115.499985 -409.88433) (xy 115.493477 -409.867145) (xy 115.487704 -409.859988)
			(xy 115.465882 -409.834364) (xy 115.427937 -409.778773) (xy 115.396907 -409.719045) (xy 115.373238 -409.656037)
			(xy 115.357268 -409.590652) (xy 115.349227 -409.523827) (xy 108.904083 -409.523827) (xy 108.833624 -409.695112)
			(xy 108.748204 -409.881718) (xy 108.655568 -410.064848) (xy 108.555858 -410.244225) (xy 108.449225 -410.419575)
			(xy 108.335832 -410.590631) (xy 108.312002 -410.623701) (xy 117.548849 -410.623701) (xy 117.54885 -410.556275)
			(xy 117.556929 -410.489335) (xy 117.572967 -410.423844) (xy 117.596736 -410.360746) (xy 117.627891 -410.30095)
			(xy 117.665985 -410.245316) (xy 117.687852 -410.219652) (xy 117.693658 -410.212514) (xy 117.700166 -410.195318)
			(xy 117.700552 -410.186124) (xy 117.700552 -409.693872) (xy 117.700144 -409.684685) (xy 117.693627 -409.667501)
			(xy 117.687852 -409.660344) (xy 117.665998 -409.63467) (xy 117.627906 -409.579038) (xy 117.596751 -409.519243)
			(xy 117.572984 -409.456148) (xy 117.556946 -409.390659) (xy 117.548869 -409.323721) (xy 117.548868 -409.256297)
			(xy 117.556943 -409.189359) (xy 117.572979 -409.12387) (xy 117.596744 -409.060773) (xy 117.627896 -409.000978)
			(xy 117.665987 -408.945344) (xy 117.687852 -408.91968) (xy 117.693646 -408.912533) (xy 117.700161 -408.895344)
			(xy 117.700552 -408.886152) (xy 117.700552 -408.728672) (xy 117.701061 -408.718567) (xy 117.708799 -408.699898)
			(xy 117.723088 -408.685606) (xy 117.741756 -408.677863) (xy 117.75186 -408.677364) (xy 118.46814 -408.677364)
			(xy 118.478247 -408.677852) (xy 118.496919 -408.685596) (xy 118.511211 -408.699891) (xy 118.518951 -408.718565)
			(xy 118.519448 -408.728672) (xy 118.519448 -408.886152) (xy 118.519893 -408.895335) (xy 118.526384 -408.912519)
			(xy 118.532148 -408.91968) (xy 118.554026 -408.945335) (xy 118.592117 -409.000969) (xy 118.62327 -409.060767)
			(xy 118.647036 -409.123865) (xy 118.663072 -409.189356) (xy 118.671148 -409.256296) (xy 118.671147 -409.323722)
			(xy 118.663069 -409.390662) (xy 118.647031 -409.456152) (xy 118.623263 -409.51925) (xy 118.620848 -409.523886)
			(xy 119.748996 -409.523886) (xy 119.748999 -409.45646) (xy 119.757078 -409.389519) (xy 119.773118 -409.324028)
			(xy 119.796886 -409.26093) (xy 119.828041 -409.201132) (xy 119.866134 -409.145497) (xy 119.888 -409.119832)
			(xy 119.893808 -409.112695) (xy 119.900316 -409.095498) (xy 119.9007 -409.086304) (xy 119.9007 -408.594052)
			(xy 119.900265 -408.584867) (xy 119.893769 -408.567683) (xy 119.888 -408.560524) (xy 119.866128 -408.534865)
			(xy 119.82804 -408.47923) (xy 119.796889 -408.419433) (xy 119.773126 -408.356335) (xy 119.757091 -408.290845)
			(xy 119.749015 -408.223906) (xy 119.749016 -408.156482) (xy 119.757093 -408.089543) (xy 119.773129 -408.024054)
			(xy 119.796894 -407.960956) (xy 119.828046 -407.90116) (xy 119.866136 -407.845525) (xy 119.888 -407.81986)
			(xy 119.893796 -407.812714) (xy 119.900311 -407.795524) (xy 119.9007 -407.786332) (xy 119.9007 -407.628852)
			(xy 119.901146 -407.61874) (xy 119.908899 -407.600061) (xy 119.923208 -407.585768) (xy 119.941896 -407.578035)
			(xy 119.952008 -407.577544) (xy 120.668288 -407.577544) (xy 120.678389 -407.578094) (xy 120.697056 -407.585817)
			(xy 120.71135 -407.600093) (xy 120.719095 -407.618752) (xy 120.719596 -407.628852) (xy 120.719596 -407.786332)
			(xy 120.719991 -407.795521) (xy 120.726515 -407.812705) (xy 120.732296 -407.81986) (xy 120.754152 -407.845532)
			(xy 120.792241 -407.901165) (xy 120.823393 -407.96096) (xy 120.847158 -408.024056) (xy 120.863194 -408.089545)
			(xy 120.87127 -408.156482) (xy 120.871271 -408.223906) (xy 120.863196 -408.290843) (xy 120.847161 -408.356332)
			(xy 120.823398 -408.419429) (xy 120.792248 -408.479225) (xy 120.75416 -408.534859) (xy 120.732296 -408.560524)
			(xy 120.726506 -408.567674) (xy 120.719988 -408.584861) (xy 120.719596 -408.594052) (xy 120.719596 -409.086304)
			(xy 120.720005 -409.095491) (xy 120.72652 -409.112675) (xy 120.732296 -409.119832) (xy 120.754125 -409.145526)
			(xy 120.792215 -409.201157) (xy 120.823367 -409.260949) (xy 120.847134 -409.324042) (xy 120.863172 -409.389527)
			(xy 120.871251 -409.456463) (xy 120.871254 -409.523883) (xy 120.863181 -409.590819) (xy 120.84715 -409.656306)
			(xy 120.823389 -409.719402) (xy 120.792243 -409.779197) (xy 120.754158 -409.834831) (xy 120.732296 -409.860496)
			(xy 120.726518 -409.867654) (xy 120.719992 -409.884835) (xy 120.719596 -409.894024) (xy 120.719596 -410.051504)
			(xy 120.719187 -410.061627) (xy 120.711437 -410.080332) (xy 120.697118 -410.094646) (xy 120.678411 -410.10239)
			(xy 120.668288 -410.102812) (xy 119.952008 -410.102812) (xy 119.941888 -410.102378) (xy 119.923186 -410.094634)
			(xy 119.908872 -410.080324) (xy 119.901125 -410.061624) (xy 119.9007 -410.051504) (xy 119.9007 -409.894024)
			(xy 119.900278 -409.884838) (xy 119.893773 -409.867654) (xy 119.888 -409.860496) (xy 119.866101 -409.83486)
			(xy 119.828013 -409.779221) (xy 119.796864 -409.719421) (xy 119.773102 -409.65632) (xy 119.757069 -409.590828)
			(xy 119.748996 -409.523886) (xy 118.620848 -409.523886) (xy 118.592108 -409.579046) (xy 118.554015 -409.63468)
			(xy 118.532148 -409.660344) (xy 118.526344 -409.667484) (xy 118.519835 -409.684679) (xy 118.519448 -409.693872)
			(xy 118.519448 -410.186124) (xy 118.519858 -410.195311) (xy 118.526373 -410.212495) (xy 118.532148 -410.219652)
			(xy 118.553998 -410.245329) (xy 118.592091 -410.300961) (xy 118.623245 -410.360755) (xy 118.647012 -410.42385)
			(xy 118.663051 -410.489338) (xy 118.671128 -410.556276) (xy 118.67113 -410.623641) (xy 121.949169 -410.623641)
			(xy 121.94917 -410.556335) (xy 121.957216 -410.489511) (xy 121.97319 -410.424128) (xy 121.996865 -410.361123)
			(xy 122.0279 -410.301399) (xy 122.065851 -410.245812) (xy 122.08764 -410.22016) (xy 122.093441 -410.213018)
			(xy 122.099952 -410.195825) (xy 122.10034 -410.186632) (xy 122.10034 -409.693364) (xy 122.099938 -409.684176)
			(xy 122.093418 -409.666992) (xy 122.08764 -409.659836) (xy 122.065864 -409.634174) (xy 122.027915 -409.578589)
			(xy 121.996881 -409.518867) (xy 121.973208 -409.455864) (xy 121.957234 -409.390483) (xy 121.949189 -409.323661)
			(xy 121.949188 -409.256357) (xy 121.957231 -409.189535) (xy 121.973202 -409.124154) (xy 121.996874 -409.06115)
			(xy 122.027906 -409.001427) (xy 122.065853 -408.94584) (xy 122.08764 -408.920188) (xy 122.093429 -408.913038)
			(xy 122.099947 -408.895851) (xy 122.10034 -408.88666) (xy 122.10034 -408.728672) (xy 122.100699 -408.718511)
			(xy 122.108512 -408.69975) (xy 122.122928 -408.685426) (xy 122.141738 -408.677735) (xy 122.151902 -408.677364)
			(xy 122.868182 -408.677364) (xy 122.878311 -408.677842) (xy 122.897036 -408.685568) (xy 122.911394 -408.699858)
			(xy 122.919209 -408.718546) (xy 122.919744 -408.728672) (xy 122.919744 -408.88666) (xy 122.920186 -408.895844)
			(xy 122.926679 -408.913028) (xy 122.932444 -408.920188) (xy 122.954244 -408.94583) (xy 122.992193 -409.001418)
			(xy 123.023227 -409.061143) (xy 123.0469 -409.124148) (xy 123.062873 -409.189532) (xy 123.070916 -409.256356)
			(xy 123.070915 -409.323662) (xy 123.062869 -409.390486) (xy 123.046895 -409.455869) (xy 123.02322 -409.518874)
			(xy 123.020646 -409.523827) (xy 124.149291 -409.523827) (xy 124.149295 -409.456519) (xy 124.157343 -409.389693)
			(xy 124.173321 -409.324308) (xy 124.197 -409.261302) (xy 124.22804 -409.201577) (xy 124.265997 -409.145992)
			(xy 124.287788 -409.12034) (xy 124.293591 -409.113199) (xy 124.300102 -409.096005) (xy 124.300488 -409.086812)
			(xy 124.300488 -408.593544) (xy 124.300059 -408.584359) (xy 124.293559 -408.567174) (xy 124.287788 -408.560016)
			(xy 124.265991 -408.534371) (xy 124.228039 -408.478785) (xy 124.197004 -408.419061) (xy 124.173329 -408.356055)
			(xy 124.157355 -408.290671) (xy 124.149311 -408.223847) (xy 124.149312 -408.156541) (xy 124.157357 -408.089717)
			(xy 124.173333 -408.024333) (xy 124.197008 -407.961328) (xy 124.228045 -407.901605) (xy 124.265998 -407.84602)
			(xy 124.287788 -407.820368) (xy 124.293579 -407.813219) (xy 124.300097 -407.796031) (xy 124.300488 -407.78684)
			(xy 124.300488 -407.628852) (xy 124.300882 -407.618696) (xy 124.308691 -407.599945) (xy 124.323096 -407.585624)
			(xy 124.341892 -407.577924) (xy 124.35205 -407.577544) (xy 125.06833 -407.577544) (xy 125.078459 -407.578002)
			(xy 125.097182 -407.58574) (xy 125.111537 -407.600035) (xy 125.119355 -407.618725) (xy 125.119892 -407.628852)
			(xy 125.119892 -407.78684) (xy 125.120285 -407.796029) (xy 125.126811 -407.813213) (xy 125.132592 -407.820368)
			(xy 125.154371 -407.846027) (xy 125.192318 -407.901613) (xy 125.22335 -407.961336) (xy 125.247022 -408.02434)
			(xy 125.262994 -408.089721) (xy 125.271039 -408.156542) (xy 125.271039 -408.223846) (xy 125.262997 -408.290667)
			(xy 125.247025 -408.356049) (xy 125.223355 -408.419053) (xy 125.192324 -408.478776) (xy 125.154378 -408.534363)
			(xy 125.132592 -408.560016) (xy 125.126805 -408.567168) (xy 125.120285 -408.584353) (xy 125.119892 -408.593544)
			(xy 125.119892 -409.086812) (xy 125.120298 -409.096) (xy 125.126815 -409.113184) (xy 125.132592 -409.12034)
			(xy 125.154343 -409.146022) (xy 125.192291 -409.201605) (xy 125.223324 -409.261324) (xy 125.246998 -409.324325)
			(xy 125.262972 -409.389703) (xy 125.271019 -409.456522) (xy 125.271022 -409.523824) (xy 125.262982 -409.590643)
			(xy 125.247014 -409.656023) (xy 125.223347 -409.719026) (xy 125.192319 -409.778749) (xy 125.154377 -409.834336)
			(xy 125.132592 -409.859988) (xy 125.126775 -409.867118) (xy 125.120273 -409.88432) (xy 125.119892 -409.893516)
			(xy 125.119892 -410.051504) (xy 125.119481 -410.061659) (xy 125.111683 -410.080413) (xy 125.097283 -410.094737)
			(xy 125.078487 -410.102435) (xy 125.06833 -410.102812) (xy 124.35205 -410.102812) (xy 124.341933 -410.102234)
			(xy 124.323223 -410.094532) (xy 124.308867 -410.080274) (xy 124.301036 -410.061618) (xy 124.300488 -410.051504)
			(xy 124.300488 -409.893516) (xy 124.300073 -409.884329) (xy 124.293563 -409.867145) (xy 124.287788 -409.859988)
			(xy 124.265963 -409.834366) (xy 124.228013 -409.778776) (xy 124.196978 -409.719049) (xy 124.173305 -409.65604)
			(xy 124.157333 -409.590654) (xy 124.149291 -409.523827) (xy 123.020646 -409.523827) (xy 122.992184 -409.578598)
			(xy 122.954233 -409.634184) (xy 122.932444 -409.659836) (xy 122.926643 -409.666978) (xy 122.920132 -409.684171)
			(xy 122.919744 -409.693364) (xy 122.919744 -410.186632) (xy 122.920151 -410.195819) (xy 122.926668 -410.213003)
			(xy 122.932444 -410.22016) (xy 122.954216 -410.245825) (xy 122.992167 -410.301409) (xy 123.023202 -410.361131)
			(xy 123.046876 -410.424134) (xy 123.062851 -410.489514) (xy 123.070896 -410.556336) (xy 123.070898 -410.62364)
			(xy 123.070891 -410.623701) (xy 126.348937 -410.623701) (xy 126.348938 -410.556275) (xy 126.357016 -410.489335)
			(xy 126.373055 -410.423845) (xy 126.396822 -410.360747) (xy 126.427977 -410.300951) (xy 126.46607 -410.245317)
			(xy 126.487936 -410.219652) (xy 126.49374 -410.212512) (xy 126.500249 -410.195317) (xy 126.500636 -410.186124)
			(xy 126.500636 -409.693872) (xy 126.500231 -409.684684) (xy 126.493713 -409.667501) (xy 126.487936 -409.660344)
			(xy 126.466083 -409.63467) (xy 126.427991 -409.579037) (xy 126.396838 -409.519243) (xy 126.373071 -409.456147)
			(xy 126.357034 -409.390659) (xy 126.348957 -409.323721) (xy 126.348956 -409.256297) (xy 126.357031 -409.189359)
			(xy 126.373066 -409.12387) (xy 126.396831 -409.060774) (xy 126.427982 -409.000978) (xy 126.466071 -408.945345)
			(xy 126.487936 -408.91968) (xy 126.493728 -408.912532) (xy 126.500245 -408.895343) (xy 126.500636 -408.886152)
			(xy 126.500636 -408.728672) (xy 126.500994 -408.718543) (xy 126.508758 -408.699832) (xy 126.523093 -408.685517)
			(xy 126.541815 -408.67778) (xy 126.551944 -408.677364) (xy 127.268224 -408.677364) (xy 127.27833 -408.677864)
			(xy 127.297002 -408.685603) (xy 127.311294 -408.699895) (xy 127.319035 -408.718566) (xy 127.319532 -408.728672)
			(xy 127.319532 -408.886152) (xy 127.31998 -408.895335) (xy 127.326469 -408.912519) (xy 127.332232 -408.91968)
			(xy 127.354107 -408.945336) (xy 127.392193 -409.000973) (xy 127.423341 -409.06077) (xy 127.447103 -409.123868)
			(xy 127.463137 -409.189358) (xy 127.471211 -409.256297) (xy 127.47121 -409.323721) (xy 127.463134 -409.39066)
			(xy 127.447098 -409.456149) (xy 127.423334 -409.519246) (xy 127.420948 -409.523827) (xy 128.549082 -409.523827)
			(xy 128.549085 -409.456519) (xy 128.557133 -409.389693) (xy 128.573111 -409.324308) (xy 128.59679 -409.261302)
			(xy 128.627829 -409.201578) (xy 128.665785 -409.145991) (xy 128.687576 -409.12034) (xy 128.693378 -409.113198)
			(xy 128.69989 -409.096005) (xy 128.700276 -409.086812) (xy 128.700276 -408.593544) (xy 128.69985 -408.584358)
			(xy 128.693348 -408.567174) (xy 128.687576 -408.560016) (xy 128.665779 -408.534371) (xy 128.627828 -408.478784)
			(xy 128.596793 -408.41906) (xy 128.573119 -408.356055) (xy 128.557146 -408.290671) (xy 128.549102 -408.223847)
			(xy 128.549103 -408.156541) (xy 128.557148 -408.089717) (xy 128.573123 -408.024334) (xy 128.596798 -407.961329)
			(xy 128.627835 -407.901605) (xy 128.665787 -407.84602) (xy 128.687576 -407.820368) (xy 128.693366 -407.813218)
			(xy 128.699885 -407.796031) (xy 128.700276 -407.78684) (xy 128.700276 -407.628852) (xy 128.700682 -407.618698)
			(xy 128.708489 -407.599949) (xy 128.72289 -407.585628) (xy 128.741682 -407.577926) (xy 128.751838 -407.577544)
			(xy 129.468118 -407.577544) (xy 129.478246 -407.578012) (xy 129.496969 -407.585746) (xy 129.511325 -407.600038)
			(xy 129.519143 -407.618726) (xy 129.51968 -407.628852) (xy 129.51968 -407.78684) (xy 129.520075 -407.796029)
			(xy 129.5266 -407.813213) (xy 129.53238 -407.820368) (xy 129.554159 -407.846027) (xy 129.592107 -407.901613)
			(xy 129.62314 -407.961336) (xy 129.646812 -408.024339) (xy 129.662785 -408.08972) (xy 129.67083 -408.156542)
			(xy 129.67083 -408.223846) (xy 129.662787 -408.290668) (xy 129.646816 -408.356049) (xy 129.623145 -408.419053)
			(xy 129.592113 -408.478777) (xy 129.554167 -408.534364) (xy 129.53238 -408.560016) (xy 129.526592 -408.567167)
			(xy 129.520073 -408.584353) (xy 129.51968 -408.593544) (xy 129.51968 -409.086812) (xy 129.520089 -409.095999)
			(xy 129.526604 -409.113183) (xy 129.53238 -409.12034) (xy 129.554131 -409.146022) (xy 129.59208 -409.201604)
			(xy 129.623114 -409.261324) (xy 129.646788 -409.324325) (xy 129.662763 -409.389703) (xy 129.670809 -409.456522)
			(xy 129.670813 -409.523824) (xy 129.662772 -409.590644) (xy 129.646804 -409.656024) (xy 129.623136 -409.719026)
			(xy 129.592108 -409.778749) (xy 129.554165 -409.834335) (xy 129.53238 -409.859988) (xy 129.526561 -409.867117)
			(xy 129.52006 -409.88432) (xy 129.51968 -409.893516) (xy 129.51968 -410.051504) (xy 129.519281 -410.061661)
			(xy 129.511481 -410.080417) (xy 129.497077 -410.094741) (xy 129.478277 -410.102437) (xy 129.468118 -410.102812)
			(xy 128.751838 -410.102812) (xy 128.74172 -410.102244) (xy 128.72301 -410.094538) (xy 128.708654 -410.080277)
			(xy 128.700824 -410.061618) (xy 128.700276 -410.051504) (xy 128.700276 -409.893516) (xy 128.699864 -409.884329)
			(xy 128.693352 -409.867144) (xy 128.687576 -409.859988) (xy 128.665751 -409.834366) (xy 128.627801 -409.778776)
			(xy 128.596768 -409.719048) (xy 128.573095 -409.65604) (xy 128.557124 -409.590654) (xy 128.549082 -409.523827)
			(xy 127.420948 -409.523827) (xy 127.392184 -409.579043) (xy 127.354096 -409.634678) (xy 127.332232 -409.660344)
			(xy 127.326426 -409.667482) (xy 127.319919 -409.684678) (xy 127.319532 -409.693872) (xy 127.319532 -410.186124)
			(xy 127.319946 -410.19531) (xy 127.326459 -410.212494) (xy 127.332232 -410.219652) (xy 127.354079 -410.245331)
			(xy 127.392166 -410.300964) (xy 127.423316 -410.360759) (xy 127.44708 -410.423854) (xy 127.463115 -410.489341)
			(xy 127.471192 -410.556277) (xy 127.471193 -410.623641) (xy 130.749257 -410.623641) (xy 130.749258 -410.556335)
			(xy 130.757303 -410.489512) (xy 130.773278 -410.424129) (xy 130.796952 -410.361123) (xy 130.827986 -410.301399)
			(xy 130.865936 -410.245812) (xy 130.887724 -410.22016) (xy 130.893523 -410.213017) (xy 130.900035 -410.195825)
			(xy 130.900424 -410.186632) (xy 130.900424 -409.693364) (xy 130.900026 -409.684176) (xy 130.893503 -409.666992)
			(xy 130.887724 -409.659836) (xy 130.865948 -409.634174) (xy 130.828 -409.578589) (xy 130.796967 -409.518866)
			(xy 130.773294 -409.455863) (xy 130.757321 -409.390482) (xy 130.749276 -409.323661) (xy 130.749275 -409.256357)
			(xy 130.757318 -409.189536) (xy 130.773289 -409.124154) (xy 130.79696 -409.06115) (xy 130.827991 -409.001427)
			(xy 130.865937 -408.94584) (xy 130.887724 -408.920188) (xy 130.893511 -408.913036) (xy 130.900031 -408.895851)
			(xy 130.900424 -408.88666) (xy 130.900424 -408.728672) (xy 130.900799 -408.718513) (xy 130.908608 -408.699755)
			(xy 130.92302 -408.685432) (xy 130.941825 -408.677738) (xy 130.951986 -408.677364) (xy 131.668266 -408.677364)
			(xy 131.678393 -408.677855) (xy 131.697118 -408.685576) (xy 131.711477 -408.699862) (xy 131.719293 -408.718547)
			(xy 131.719828 -408.728672) (xy 131.719828 -408.88666) (xy 131.720251 -408.895846) (xy 131.726755 -408.913031)
			(xy 131.732528 -408.920188) (xy 131.754328 -408.94583) (xy 131.792279 -409.001417) (xy 131.823314 -409.061142)
			(xy 131.846987 -409.124148) (xy 131.86296 -409.189532) (xy 131.871004 -409.256356) (xy 131.871003 -409.323662)
			(xy 131.862957 -409.390486) (xy 131.846982 -409.45587) (xy 131.823306 -409.518875) (xy 131.79227 -409.578598)
			(xy 131.754317 -409.634184) (xy 131.732528 -409.659836) (xy 131.726725 -409.666976) (xy 131.720216 -409.684171)
			(xy 131.719828 -409.693364) (xy 131.719828 -410.186632) (xy 131.720217 -410.195822) (xy 131.726745 -410.213006)
			(xy 131.732528 -410.22016) (xy 131.754301 -410.245825) (xy 131.792252 -410.301409) (xy 131.823288 -410.36113)
			(xy 131.846963 -410.424133) (xy 131.862938 -410.489514) (xy 131.870984 -410.556336) (xy 131.870986 -410.62364)
			(xy 131.862943 -410.690462) (xy 131.84697 -410.755844) (xy 131.823298 -410.818848) (xy 131.792265 -410.878571)
			(xy 131.754316 -410.934156) (xy 131.732528 -410.959808) (xy 131.726737 -410.966957) (xy 131.720221 -410.984145)
			(xy 131.719828 -410.993336) (xy 131.719828 -411.151324) (xy 131.719399 -411.161476) (xy 131.7116 -411.180224)
			(xy 131.697207 -411.194545) (xy 131.67842 -411.202249) (xy 131.668266 -411.202632) (xy 130.951986 -411.202632)
			(xy 130.941855 -411.202184) (xy 130.923128 -411.194446) (xy 130.908772 -411.180148) (xy 130.900958 -411.161453)
			(xy 130.900424 -411.151324) (xy 130.900424 -410.993336) (xy 130.899991 -410.984151) (xy 130.893493 -410.966967)
			(xy 130.887724 -410.959808) (xy 130.865921 -410.934169) (xy 130.827974 -410.87858) (xy 130.796942 -410.818855)
			(xy 130.773271 -410.755848) (xy 130.757299 -410.690465) (xy 130.749257 -410.623641) (xy 127.471193 -410.623641)
			(xy 127.471193 -410.623699) (xy 127.463119 -410.690635) (xy 127.447087 -410.756123) (xy 127.423326 -410.819219)
			(xy 127.392179 -410.879015) (xy 127.354094 -410.93465) (xy 127.332232 -410.960316) (xy 127.326438 -410.967463)
			(xy 127.319924 -410.984652) (xy 127.319532 -410.993844) (xy 127.319532 -411.151324) (xy 127.319035 -411.16143)
			(xy 127.311296 -411.180103) (xy 127.297003 -411.194396) (xy 127.27833 -411.202135) (xy 127.268224 -411.202632)
			(xy 126.551944 -411.202632) (xy 126.541828 -411.202149) (xy 126.523132 -411.194421) (xy 126.508817 -411.180125)
			(xy 126.501065 -411.161439) (xy 126.500636 -411.151324) (xy 126.500636 -410.993844) (xy 126.500196 -410.98466)
			(xy 126.493702 -410.967476) (xy 126.487936 -410.960316) (xy 126.466055 -410.934664) (xy 126.427964 -410.879029)
			(xy 126.396812 -410.819231) (xy 126.373048 -410.756132) (xy 126.357012 -410.690641) (xy 126.348937 -410.623701)
			(xy 123.070891 -410.623701) (xy 123.062855 -410.690462) (xy 123.046883 -410.755843) (xy 123.023211 -410.818847)
			(xy 122.992179 -410.87857) (xy 122.954231 -410.934156) (xy 122.932444 -410.959808) (xy 122.926655 -410.966958)
			(xy 122.920137 -410.984145) (xy 122.919744 -410.993336) (xy 122.919744 -411.151324) (xy 122.919299 -411.161474)
			(xy 122.911504 -411.180219) (xy 122.897115 -411.19454) (xy 122.878334 -411.202246) (xy 122.868182 -411.202632)
			(xy 122.151902 -411.202632) (xy 122.141772 -411.202171) (xy 122.123046 -411.194439) (xy 122.108688 -411.180144)
			(xy 122.100874 -411.161452) (xy 122.10034 -411.151324) (xy 122.10034 -410.993336) (xy 122.099903 -410.984152)
			(xy 122.093407 -410.966968) (xy 122.08764 -410.959808) (xy 122.065836 -410.934169) (xy 122.027888 -410.878581)
			(xy 121.996855 -410.818855) (xy 121.973183 -410.755849) (xy 121.957211 -410.690465) (xy 121.949169 -410.623641)
			(xy 118.67113 -410.623641) (xy 118.67113 -410.6237) (xy 118.663055 -410.690638) (xy 118.647019 -410.756127)
			(xy 118.623255 -410.819223) (xy 118.592103 -410.879018) (xy 118.554013 -410.934652) (xy 118.532148 -410.960316)
			(xy 118.526356 -410.967464) (xy 118.51984 -410.984653) (xy 118.519448 -410.993844) (xy 118.519448 -411.151324)
			(xy 118.518936 -411.161428) (xy 118.511199 -411.180098) (xy 118.496911 -411.19439) (xy 118.478244 -411.202133)
			(xy 118.46814 -411.202632) (xy 117.75186 -411.202632) (xy 117.741753 -411.202148) (xy 117.72308 -411.194404)
			(xy 117.708787 -411.180107) (xy 117.701048 -411.161431) (xy 117.700552 -411.151324) (xy 117.700552 -410.993844)
			(xy 117.700109 -410.984661) (xy 117.693617 -410.967477) (xy 117.687852 -410.960316) (xy 117.66597 -410.934665)
			(xy 117.627879 -410.879029) (xy 117.596726 -410.819232) (xy 117.57296 -410.756133) (xy 117.556924 -410.690642)
			(xy 117.548849 -410.623701) (xy 108.312002 -410.623701) (xy 108.215852 -410.757133) (xy 108.089466 -410.918827)
			(xy 107.956868 -411.075467) (xy 107.81826 -411.226813) (xy 107.673852 -411.372637) (xy 107.523865 -411.512716)
			(xy 107.368526 -411.646835) (xy 107.208073 -411.774792) (xy 107.04275 -411.896392) (xy 106.872808 -412.011448)
			(xy 106.698507 -412.119787) (xy 106.520111 -412.221242) (xy 106.337893 -412.31566) (xy 106.15213 -412.402896)
			(xy 105.963105 -412.482819) (xy 105.771105 -412.555305) (xy 105.576423 -412.620245) (xy 105.379356 -412.67754)
			(xy 105.180203 -412.727103) (xy 104.979269 -412.768858) (xy 104.776858 -412.802741) (xy 104.57328 -412.828701)
			(xy 104.368843 -412.846698) (xy 104.16386 -412.856706) (xy 103.958643 -412.858708) (xy 103.753504 -412.852702)
			(xy 103.548755 -412.838697) (xy 103.344708 -412.816714) (xy 103.141675 -412.786787) (xy 102.939964 -412.74896)
			(xy 102.739882 -412.703293) (xy 102.541735 -412.649854) (xy 102.345823 -412.588725) (xy 102.152446 -412.519999)
			(xy 101.961897 -412.44378) (xy 101.774467 -412.360184) (xy 101.590441 -412.26934) (xy 101.4101 -412.171385)
			(xy 101.233718 -412.066468) (xy 101.061564 -411.954749) (xy 100.893899 -411.836399) (xy 100.73098 -411.711597)
			(xy 100.573054 -411.580533) (xy 100.420362 -411.443408) (xy 100.273137 -411.30043) (xy 100.131602 -411.151816)
			(xy 99.995973 -410.997794) (xy 99.866456 -410.838597) (xy 99.74325 -410.674468) (xy 99.626541 -410.505657)
			(xy 99.516507 -410.33242) (xy 99.413316 -410.155023) (xy 99.317125 -409.973735) (xy 99.22808 -409.788832)
			(xy 99.146317 -409.600595) (xy 99.071961 -409.409312) (xy 99.005125 -409.215273) (xy 98.94591 -409.018774)
			(xy 98.894407 -408.820115) (xy 98.850693 -408.619597) (xy 98.814837 -408.417526) (xy 98.786892 -408.214211)
			(xy 98.766901 -408.00996) (xy 98.754894 -407.805084) (xy 98.75089 -407.599896) (xy 85.510806 -407.599896)
			(xy 85.511012 -407.600102) (xy 85.518758 -407.618754) (xy 85.51926 -407.628852) (xy 85.51926 -407.786332)
			(xy 85.519664 -407.79552) (xy 85.526183 -407.812703) (xy 85.53196 -407.81986) (xy 85.553818 -407.845531)
			(xy 85.591909 -407.901164) (xy 85.623062 -407.960959) (xy 85.646829 -408.024055) (xy 85.662866 -408.089544)
			(xy 85.670943 -408.156482) (xy 85.670944 -408.223906) (xy 85.662868 -408.290844) (xy 85.646832 -408.356333)
			(xy 85.623067 -408.41943) (xy 85.591915 -408.479226) (xy 85.553825 -408.534859) (xy 85.53196 -408.560524)
			(xy 85.526166 -408.567671) (xy 85.519651 -408.58486) (xy 85.51926 -408.594052) (xy 85.51926 -409.086304)
			(xy 85.519677 -409.09549) (xy 85.526187 -409.112674) (xy 85.53196 -409.119832) (xy 85.55379 -409.145526)
			(xy 85.591882 -409.201155) (xy 85.623037 -409.260947) (xy 85.646805 -409.32404) (xy 85.662844 -409.389526)
			(xy 85.670923 -409.456462) (xy 85.670927 -409.523884) (xy 85.662854 -409.59082) (xy 85.646821 -409.656308)
			(xy 85.623059 -409.719403) (xy 85.59191 -409.779198) (xy 85.553823 -409.834831) (xy 85.53196 -409.860496)
			(xy 85.526178 -409.867651) (xy 85.519655 -409.884834) (xy 85.51926 -409.894024) (xy 85.51926 -410.051504)
			(xy 85.518886 -410.061632) (xy 85.511129 -410.080343) (xy 85.496799 -410.094659) (xy 85.47808 -410.102396)
			(xy 85.467952 -410.102812) (xy 84.751672 -410.102812) (xy 84.741563 -410.102338) (xy 84.722886 -410.094594)
			(xy 84.708593 -410.080293) (xy 84.700857 -410.061613) (xy 84.700364 -410.051504) (xy 84.700364 -409.894024)
			(xy 84.699928 -409.88484) (xy 84.693431 -409.867656) (xy 84.687664 -409.860496) (xy 84.665766 -409.834859)
			(xy 84.627681 -409.77922) (xy 84.596534 -409.719419) (xy 84.572773 -409.656319) (xy 84.556741 -409.590827)
			(xy 84.548669 -409.523886) (xy 83.420495 -409.523886) (xy 83.392063 -409.578599) (xy 83.35411 -409.634184)
			(xy 83.33232 -409.659836) (xy 83.326528 -409.666985) (xy 83.32001 -409.684172) (xy 83.31962 -409.693364)
			(xy 83.31962 -410.186632) (xy 83.32001 -410.195821) (xy 83.326537 -410.213006) (xy 83.33232 -410.22016)
			(xy 83.354093 -410.245825) (xy 83.392045 -410.301408) (xy 83.423081 -410.36113) (xy 83.446757 -410.424133)
			(xy 83.462732 -410.489514) (xy 83.470778 -410.556336) (xy 83.47078 -410.62364) (xy 83.470773 -410.623701)
			(xy 86.748819 -410.623701) (xy 86.74882 -410.556275) (xy 86.756898 -410.489336) (xy 86.772936 -410.423846)
			(xy 86.796702 -410.360748) (xy 86.827855 -410.300952) (xy 86.865947 -410.245317) (xy 86.887812 -410.219652)
			(xy 86.893613 -410.21251) (xy 86.900125 -410.195317) (xy 86.900512 -410.186124) (xy 86.900512 -409.693872)
			(xy 86.900113 -409.684684) (xy 86.893591 -409.6675) (xy 86.887812 -409.660344) (xy 86.865959 -409.634669)
			(xy 86.82787 -409.579036) (xy 86.796718 -409.519242) (xy 86.772952 -409.456146) (xy 86.756916 -409.390658)
			(xy 86.748839 -409.32372) (xy 86.748837 -409.256298) (xy 86.756912 -409.18936) (xy 86.772947 -409.123871)
			(xy 86.79671 -409.060775) (xy 86.82786 -409.000979) (xy 86.865948 -408.945345) (xy 86.887812 -408.91968)
			(xy 86.893601 -408.912529) (xy 86.90012 -408.895343) (xy 86.900512 -408.886152) (xy 86.900512 -408.728672)
			(xy 86.900962 -408.71856) (xy 86.908711 -408.699879) (xy 86.923019 -408.685585) (xy 86.941708 -408.677853)
			(xy 86.95182 -408.677364) (xy 87.6681 -408.677364) (xy 87.678204 -408.677884) (xy 87.696876 -408.685615)
			(xy 87.711169 -408.699901) (xy 87.71891 -408.718568) (xy 87.719408 -408.728672) (xy 87.719408 -408.886152)
			(xy 87.719839 -408.895337) (xy 87.726338 -408.912522) (xy 87.732108 -408.91968) (xy 87.753983 -408.945336)
			(xy 87.792071 -409.000972) (xy 87.823221 -409.060769) (xy 87.846984 -409.123867) (xy 87.863019 -409.189358)
			(xy 87.871093 -409.256297) (xy 87.871092 -409.323721) (xy 87.863015 -409.39066) (xy 87.846979 -409.45615)
			(xy 87.823214 -409.519247) (xy 87.792062 -409.579044) (xy 87.753972 -409.634679) (xy 87.732108 -409.660344)
			(xy 87.726311 -409.667489) (xy 87.719796 -409.68468) (xy 87.719408 -409.693872) (xy 87.719408 -410.186124)
			(xy 87.719805 -410.195313) (xy 87.726328 -410.212497) (xy 87.732108 -410.219652) (xy 87.753956 -410.24533)
			(xy 87.792045 -410.300963) (xy 87.823196 -410.360758) (xy 87.84696 -410.423853) (xy 87.862997 -410.48934)
			(xy 87.871074 -410.556277) (xy 87.871075 -410.623641) (xy 91.149138 -410.623641) (xy 91.14914 -410.556335)
			(xy 91.157185 -410.489512) (xy 91.173158 -410.42413) (xy 91.196831 -410.361125) (xy 91.227864 -410.3014)
			(xy 91.265813 -410.245813) (xy 91.2876 -410.22016) (xy 91.293396 -410.213014) (xy 91.299911 -410.195824)
			(xy 91.3003 -410.186632) (xy 91.3003 -409.693364) (xy 91.299907 -409.684175) (xy 91.293382 -409.666991)
			(xy 91.2876 -409.659836) (xy 91.265825 -409.634174) (xy 91.227879 -409.578588) (xy 91.196847 -409.518865)
			(xy 91.173175 -409.455862) (xy 91.157203 -409.390482) (xy 91.149158 -409.323661) (xy 91.149157 -409.256357)
			(xy 91.157199 -409.189536) (xy 91.17317 -409.124155) (xy 91.19684 -409.061151) (xy 91.227869 -409.001428)
			(xy 91.265814 -408.945841) (xy 91.2876 -408.920188) (xy 91.293384 -408.913034) (xy 91.299906 -408.89585)
			(xy 91.3003 -408.88666) (xy 91.3003 -408.728672) (xy 91.300699 -408.718516) (xy 91.308503 -408.699763)
			(xy 91.322907 -408.685441) (xy 91.341704 -408.677742) (xy 91.351862 -408.677364) (xy 92.068142 -408.677364)
			(xy 92.078274 -408.677793) (xy 92.097001 -408.685539) (xy 92.111357 -408.699843) (xy 92.11917 -408.718542)
			(xy 92.119704 -408.728672) (xy 92.119704 -408.88666) (xy 92.120132 -408.895845) (xy 92.126633 -408.91303)
			(xy 92.132404 -408.920188) (xy 92.154202 -408.945831) (xy 92.192148 -409.00142) (xy 92.223178 -409.061145)
			(xy 92.246848 -409.124151) (xy 92.262819 -409.189534) (xy 92.270862 -409.256356) (xy 92.270861 -409.323662)
			(xy 92.262816 -409.390484) (xy 92.246843 -409.455867) (xy 92.223171 -409.518871) (xy 92.192139 -409.578596)
			(xy 92.154191 -409.634183) (xy 92.132404 -409.659836) (xy 92.12661 -409.666983) (xy 92.120094 -409.684172)
			(xy 92.119704 -409.693364) (xy 92.119704 -410.186632) (xy 92.120098 -410.195821) (xy 92.126623 -410.213005)
			(xy 92.132404 -410.22016) (xy 92.154175 -410.245826) (xy 92.192121 -410.301411) (xy 92.223153 -410.361133)
			(xy 92.246825 -410.424136) (xy 92.262797 -410.489516) (xy 92.270842 -410.556336) (xy 92.270844 -410.623639)
			(xy 92.262802 -410.69046) (xy 92.246832 -410.755841) (xy 92.223163 -410.818845) (xy 92.192134 -410.878568)
			(xy 92.154189 -410.934155) (xy 92.132404 -410.959808) (xy 92.126622 -410.966964) (xy 92.120098 -410.984146)
			(xy 92.119704 -410.993336) (xy 92.119704 -411.151324) (xy 92.119298 -411.161479) (xy 92.111495 -411.180231)
			(xy 92.097094 -411.194554) (xy 92.078299 -411.202253) (xy 92.068142 -411.202632) (xy 91.351862 -411.202632)
			(xy 91.341729 -411.202204) (xy 91.323002 -411.194458) (xy 91.308646 -411.180154) (xy 91.300833 -411.161455)
			(xy 91.3003 -411.151324) (xy 91.3003 -410.993336) (xy 91.299873 -410.984151) (xy 91.293371 -410.966966)
			(xy 91.2876 -410.959808) (xy 91.265798 -410.934168) (xy 91.227852 -410.878579) (xy 91.196822 -410.818853)
			(xy 91.173151 -410.755847) (xy 91.157181 -410.690464) (xy 91.149138 -410.623641) (xy 87.871075 -410.623641)
			(xy 87.871075 -410.623699) (xy 87.863001 -410.690636) (xy 87.846967 -410.756124) (xy 87.823205 -410.81922)
			(xy 87.792057 -410.879016) (xy 87.753971 -410.934651) (xy 87.732108 -410.960316) (xy 87.726323 -410.96747)
			(xy 87.719801 -410.984654) (xy 87.719408 -410.993844) (xy 87.719408 -411.151324) (xy 87.718935 -411.161433)
			(xy 87.711191 -411.180111) (xy 87.69689 -411.194404) (xy 87.67821 -411.20214) (xy 87.6681 -411.202632)
			(xy 86.95182 -411.202632) (xy 86.941716 -411.202099) (xy 86.923045 -411.194374) (xy 86.90875 -411.180092)
			(xy 86.901009 -411.161427) (xy 86.900512 -411.151324) (xy 86.900512 -410.993844) (xy 86.900078 -410.984659)
			(xy 86.893581 -410.967475) (xy 86.887812 -410.960316) (xy 86.865932 -410.934664) (xy 86.827843 -410.879028)
			(xy 86.796692 -410.81923) (xy 86.772928 -410.756131) (xy 86.756894 -410.69064) (xy 86.748819 -410.623701)
			(xy 83.470773 -410.623701) (xy 83.462736 -410.690462) (xy 83.446764 -410.755844) (xy 83.423091 -410.818848)
			(xy 83.392058 -410.878571) (xy 83.354108 -410.934156) (xy 83.33232 -410.959808) (xy 83.32654 -410.966965)
			(xy 83.320015 -410.984146) (xy 83.31962 -410.993336) (xy 83.31962 -411.151324) (xy 83.319199 -411.161477)
			(xy 83.311399 -411.180226) (xy 83.297003 -411.194548) (xy 83.278213 -411.202251) (xy 83.268058 -411.202632)
			(xy 82.551778 -411.202632) (xy 82.541646 -411.202191) (xy 82.522919 -411.194451) (xy 82.508563 -411.18015)
			(xy 82.500749 -411.161454) (xy 82.500216 -411.151324) (xy 82.500216 -410.993336) (xy 82.499785 -410.984151)
			(xy 82.493285 -410.966967) (xy 82.487516 -410.959808) (xy 82.465713 -410.934169) (xy 82.427766 -410.87858)
			(xy 82.396735 -410.818854) (xy 82.373064 -410.755848) (xy 82.357093 -410.690465) (xy 82.349051 -410.623641)
			(xy 79.070987 -410.623641) (xy 79.070987 -410.623699) (xy 79.062913 -410.690636) (xy 79.04688 -410.756124)
			(xy 79.023119 -410.81922) (xy 78.991971 -410.879016) (xy 78.953886 -410.93465) (xy 78.932024 -410.960316)
			(xy 78.926241 -410.967471) (xy 78.919717 -410.984654) (xy 78.919324 -410.993844) (xy 78.919324 -411.151324)
			(xy 78.918835 -411.161431) (xy 78.911094 -411.180106) (xy 78.896799 -411.194399) (xy 78.878123 -411.202137)
			(xy 78.868016 -411.202632) (xy 78.151736 -411.202632) (xy 78.14162 -411.202155) (xy 78.122923 -411.194425)
			(xy 78.108609 -411.180127) (xy 78.100857 -411.16144) (xy 78.100428 -411.151324) (xy 78.100428 -410.993844)
			(xy 78.09999 -410.98466) (xy 78.093495 -410.967476) (xy 78.087728 -410.960316) (xy 78.065847 -410.934664)
			(xy 78.027757 -410.879028) (xy 77.996606 -410.819231) (xy 77.972841 -410.756132) (xy 77.956806 -410.690641)
			(xy 77.948731 -410.623701) (xy 74.670685 -410.623701) (xy 74.662649 -410.690462) (xy 74.646677 -410.755844)
			(xy 74.623005 -410.818848) (xy 74.591972 -410.87857) (xy 74.554023 -410.934156) (xy 74.532236 -410.959808)
			(xy 74.526446 -410.966957) (xy 74.519929 -410.984145) (xy 74.519536 -410.993336) (xy 74.519536 -411.151324)
			(xy 74.519099 -411.161475) (xy 74.511302 -411.180221) (xy 74.496911 -411.194542) (xy 74.478127 -411.202248)
			(xy 74.467974 -411.202632) (xy 73.751694 -411.202632) (xy 73.741563 -411.202177) (xy 73.722837 -411.194442)
			(xy 73.70848 -411.180146) (xy 73.700666 -411.161452) (xy 73.700132 -411.151324) (xy 73.700132 -410.993336)
			(xy 73.699697 -410.984152) (xy 73.6932 -410.966967) (xy 73.687432 -410.959808) (xy 73.665629 -410.934169)
			(xy 73.627681 -410.87858) (xy 73.596649 -410.818855) (xy 73.572977 -410.755849) (xy 73.557005 -410.690465)
			(xy 73.548963 -410.623641) (xy 66.525648 -410.623641) (xy 66.525648 -417.018724) (xy 66.526774 -417.028227)
			(xy 66.535085 -417.04545) (xy 66.549098 -417.058464) (xy 66.566888 -417.065481) (xy 66.576448 -417.065968)
			(xy 140.97254 -417.065968) (xy 140.98212 -417.065577) (xy 140.999954 -417.058578) (xy 141.013983 -417.04553)
			(xy 141.022255 -417.02825) (xy 141.02334 -417.018724) (xy 141.02334 -394.305282) (xy 141.023816 -394.293169)
			(xy 141.031307 -394.270131) (xy 141.045549 -394.250535) (xy 141.065149 -394.236298) (xy 141.088189 -394.228813)
			(xy 141.100302 -394.22832) (xy 154.426158 -394.22832) (xy 154.57678 -394.378688) (xy 154.57678 -397.823825)
			(xy 159.349135 -397.823825) (xy 159.349138 -397.756518) (xy 159.357186 -397.689693) (xy 159.373162 -397.624309)
			(xy 159.396838 -397.561303) (xy 159.427875 -397.501578) (xy 159.465827 -397.44599) (xy 159.487616 -397.420338)
			(xy 159.493423 -397.4132) (xy 159.499931 -397.396004) (xy 159.500316 -397.38681) (xy 159.500316 -396.893542)
			(xy 159.499882 -396.884357) (xy 159.493384 -396.867173) (xy 159.487616 -396.860014) (xy 159.465819 -396.83437)
			(xy 159.427872 -396.778782) (xy 159.396841 -396.719057) (xy 159.373169 -396.656051) (xy 159.357198 -396.590668)
			(xy 159.349155 -396.523845) (xy 159.349156 -396.45654) (xy 159.3572 -396.389717) (xy 159.373174 -396.324334)
			(xy 159.396847 -396.26133) (xy 159.42788 -396.201606) (xy 159.465828 -396.146018) (xy 159.487616 -396.120366)
			(xy 159.493411 -396.11322) (xy 159.499926 -396.09603) (xy 159.500316 -396.086838) (xy 159.500316 -395.92885)
			(xy 159.500804 -395.918684) (xy 159.508569 -395.899895) (xy 159.522934 -395.885509) (xy 159.541713 -395.877718)
			(xy 159.551878 -395.877288) (xy 160.268158 -395.877288) (xy 160.278333 -395.877699) (xy 160.297136 -395.88548)
			(xy 160.311525 -395.89987) (xy 160.319302 -395.918675) (xy 160.31972 -395.92885) (xy 160.31972 -396.086838)
			(xy 160.320108 -396.096028) (xy 160.326637 -396.113212) (xy 160.33242 -396.120366) (xy 160.354199 -396.146026)
			(xy 160.392151 -396.20161) (xy 160.423187 -396.261332) (xy 160.446862 -396.324336) (xy 160.462837 -396.389718)
			(xy 160.470882 -396.45654) (xy 160.470883 -396.523845) (xy 160.46284 -396.590668) (xy 160.446866 -396.65605)
			(xy 160.423193 -396.719054) (xy 160.392159 -396.778777) (xy 160.354208 -396.834362) (xy 160.33242 -396.860014)
			(xy 160.326637 -396.867169) (xy 160.320114 -396.884352) (xy 160.31972 -396.893542) (xy 160.31972 -397.38681)
			(xy 160.320121 -397.395998) (xy 160.326641 -397.413183) (xy 160.33242 -397.420338) (xy 160.354172 -397.44602)
			(xy 160.392124 -397.501601) (xy 160.420549 -397.556296) (xy 161.5488 -397.556296) (xy 161.556874 -397.489359)
			(xy 161.572908 -397.423871) (xy 161.596669 -397.360775) (xy 161.627817 -397.300979) (xy 161.665902 -397.245344)
			(xy 161.687764 -397.219678) (xy 161.69356 -397.212533) (xy 161.700073 -397.195342) (xy 161.700464 -397.18615)
			(xy 161.700464 -397.028924) (xy 161.701004 -397.018821) (xy 161.708727 -397.00015) (xy 161.723007 -396.985856)
			(xy 161.74167 -396.978114) (xy 161.751772 -396.977616) (xy 162.468052 -396.977616) (xy 162.478173 -396.978056)
			(xy 162.496879 -396.985791) (xy 162.511195 -397.000101) (xy 162.51894 -397.018803) (xy 162.51936 -397.028924)
			(xy 162.51936 -397.18615) (xy 162.519803 -397.195333) (xy 162.526295 -397.212518) (xy 162.53206 -397.219678)
			(xy 162.553935 -397.245334) (xy 162.592026 -397.300969) (xy 162.623179 -397.360766) (xy 162.646944 -397.423864)
			(xy 162.66298 -397.489355) (xy 162.671056 -397.556295) (xy 162.671055 -397.62372) (xy 162.662977 -397.69066)
			(xy 162.64694 -397.75615) (xy 162.623173 -397.819247) (xy 162.620757 -397.823885) (xy 163.748903 -397.823885)
			(xy 163.748907 -397.756458) (xy 163.756987 -397.689517) (xy 163.773027 -397.624026) (xy 163.796796 -397.560927)
			(xy 163.827951 -397.50113) (xy 163.866045 -397.445495) (xy 163.887912 -397.41983) (xy 163.893722 -397.412694)
			(xy 163.900228 -397.395497) (xy 163.900612 -397.386302) (xy 163.900612 -396.89405) (xy 163.900175 -396.884866)
			(xy 163.89368 -396.867681) (xy 163.887912 -396.860522) (xy 163.866038 -396.834865) (xy 163.827949 -396.77923)
			(xy 163.796798 -396.719432) (xy 163.773034 -396.656334) (xy 163.756998 -396.590844) (xy 163.748923 -396.523905)
			(xy 163.748924 -396.45648) (xy 163.757001 -396.389541) (xy 163.773038 -396.324051) (xy 163.796804 -396.260954)
			(xy 163.827956 -396.201157) (xy 163.866047 -396.145523) (xy 163.887912 -396.119858) (xy 163.89371 -396.112714)
			(xy 163.900224 -396.095523) (xy 163.900612 -396.08633) (xy 163.900612 -395.92885) (xy 163.901167 -395.91873)
			(xy 163.908873 -395.900015) (xy 163.923138 -395.885658) (xy 163.941803 -395.877832) (xy 163.95192 -395.877288)
			(xy 164.6682 -395.877288) (xy 164.678353 -395.877721) (xy 164.697103 -395.885515) (xy 164.711426 -395.899908)
			(xy 164.719127 -395.918695) (xy 164.719508 -395.92885) (xy 164.719508 -396.08633) (xy 164.719902 -396.095519)
			(xy 164.726426 -396.112703) (xy 164.732208 -396.119858) (xy 164.754062 -396.145531) (xy 164.79215 -396.201165)
			(xy 164.823301 -396.26096) (xy 164.847065 -396.324056) (xy 164.863101 -396.389544) (xy 164.871178 -396.456481)
			(xy 164.871179 -396.523904) (xy 164.863104 -396.590841) (xy 164.84707 -396.65633) (xy 164.823307 -396.719426)
			(xy 164.792158 -396.779222) (xy 164.754071 -396.834857) (xy 164.732208 -396.860522) (xy 164.726421 -396.867674)
			(xy 164.7199 -396.884859) (xy 164.719508 -396.89405) (xy 164.719508 -397.386302) (xy 164.719915 -397.395489)
			(xy 164.726431 -397.412674) (xy 164.732208 -397.41983) (xy 164.754034 -397.445526) (xy 164.792124 -397.501156)
			(xy 164.823276 -397.560948) (xy 164.846898 -397.62366) (xy 165.949096 -397.62366) (xy 165.949096 -397.556355)
			(xy 165.957139 -397.489533) (xy 165.973111 -397.424151) (xy 165.996783 -397.361147) (xy 166.027816 -397.301424)
			(xy 166.065765 -397.245838) (xy 166.087552 -397.220186) (xy 166.093343 -397.213037) (xy 166.09986 -397.195849)
			(xy 166.100252 -397.186658) (xy 166.100252 -397.028924) (xy 166.10074 -397.018777) (xy 166.108519 -397.000035)
			(xy 166.122895 -396.985712) (xy 166.141666 -396.978003) (xy 166.151814 -396.977616) (xy 166.868094 -396.977616)
			(xy 166.878217 -396.978131) (xy 166.896934 -396.985852) (xy 166.911289 -397.000129) (xy 166.919113 -397.018803)
			(xy 166.919656 -397.028924) (xy 166.919656 -397.186658) (xy 166.920096 -397.195842) (xy 166.92659 -397.213026)
			(xy 166.932356 -397.220186) (xy 166.954154 -397.24583) (xy 166.992103 -397.301417) (xy 167.023136 -397.361142)
			(xy 167.046808 -397.424148) (xy 167.062781 -397.489531) (xy 167.070824 -397.556355) (xy 167.070823 -397.62366)
			(xy 167.062778 -397.690484) (xy 167.046804 -397.755867) (xy 167.02313 -397.818872) (xy 167.020556 -397.823825)
			(xy 168.149223 -397.823825) (xy 168.149226 -397.756518) (xy 168.157274 -397.689693) (xy 168.17325 -397.624309)
			(xy 168.196925 -397.561304) (xy 168.22796 -397.501579) (xy 168.265911 -397.445991) (xy 168.2877 -397.420338)
			(xy 168.293505 -397.413199) (xy 168.300015 -397.396004) (xy 168.3004 -397.38681) (xy 168.3004 -396.893542)
			(xy 168.29997 -396.884357) (xy 168.29347 -396.867172) (xy 168.2877 -396.860014) (xy 168.265904 -396.834369)
			(xy 168.227958 -396.778781) (xy 168.196927 -396.719056) (xy 168.173256 -396.656051) (xy 168.157285 -396.590668)
			(xy 168.149243 -396.523845) (xy 168.149244 -396.45654) (xy 168.157288 -396.389717) (xy 168.173261 -396.324335)
			(xy 168.196933 -396.26133) (xy 168.227965 -396.201606) (xy 168.265913 -396.146019) (xy 168.2877 -396.120366)
			(xy 168.293494 -396.113219) (xy 168.30001 -396.09603) (xy 168.3004 -396.086838) (xy 168.3004 -395.92885)
			(xy 168.300904 -395.918686) (xy 168.308665 -395.8999) (xy 168.323026 -395.885515) (xy 168.341799 -395.877721)
			(xy 168.351962 -395.877288) (xy 169.068242 -395.877288) (xy 169.078423 -395.877631) (xy 169.097228 -395.885439)
			(xy 169.111613 -395.89985) (xy 169.119388 -395.918669) (xy 169.119804 -395.92885) (xy 169.119804 -396.086838)
			(xy 169.120195 -396.096027) (xy 169.126722 -396.113212) (xy 169.132504 -396.120366) (xy 169.154281 -396.146027)
			(xy 169.192227 -396.201613) (xy 169.223258 -396.261336) (xy 169.24693 -396.324339) (xy 169.262902 -396.38972)
			(xy 169.270946 -396.456541) (xy 169.270947 -396.523844) (xy 169.262905 -396.590665) (xy 169.246934 -396.656047)
			(xy 169.223264 -396.71905) (xy 169.192235 -396.778774) (xy 169.15429 -396.834361) (xy 169.132504 -396.860014)
			(xy 169.126719 -396.867168) (xy 169.120197 -396.884352) (xy 169.119804 -396.893542) (xy 169.119804 -397.38681)
			(xy 169.120209 -397.395998) (xy 169.126726 -397.413182) (xy 169.132504 -397.420338) (xy 169.154253 -397.446021)
			(xy 169.1922 -397.501604) (xy 169.22062 -397.556296) (xy 170.348863 -397.556296) (xy 170.356939 -397.489357)
			(xy 170.372975 -397.423868) (xy 170.39674 -397.360771) (xy 170.427892 -397.300976) (xy 170.465983 -397.245342)
			(xy 170.487848 -397.219678) (xy 170.493642 -397.212531) (xy 170.500157 -397.195342) (xy 170.500548 -397.18615)
			(xy 170.500548 -397.028924) (xy 170.501103 -397.018823) (xy 170.508823 -397.000155) (xy 170.523098 -396.985862)
			(xy 170.541756 -396.978117) (xy 170.551856 -396.977616) (xy 171.268136 -396.977616) (xy 171.278249 -396.978056)
			(xy 171.296931 -396.985808) (xy 171.311225 -397.000119) (xy 171.318956 -397.01881) (xy 171.319444 -397.028924)
			(xy 171.319444 -397.18615) (xy 171.319891 -397.195333) (xy 171.326381 -397.212517) (xy 171.332144 -397.219678)
			(xy 171.35402 -397.245334) (xy 171.392112 -397.300969) (xy 171.423265 -397.360766) (xy 171.447031 -397.423864)
			(xy 171.463068 -397.489355) (xy 171.471144 -397.556295) (xy 171.471143 -397.62372) (xy 171.463065 -397.69066)
			(xy 171.447027 -397.756151) (xy 171.423259 -397.819248) (xy 171.420874 -397.823826) (xy 172.54899 -397.823826)
			(xy 172.548993 -397.756517) (xy 172.557042 -397.689691) (xy 172.57302 -397.624306) (xy 172.5967 -397.5613)
			(xy 172.62774 -397.501575) (xy 172.665697 -397.44599) (xy 172.687488 -397.420338) (xy 172.693292 -397.413198)
			(xy 172.699803 -397.396004) (xy 172.700188 -397.38681) (xy 172.700188 -396.893542) (xy 172.69976 -396.884357)
			(xy 172.693259 -396.867172) (xy 172.687488 -396.860014) (xy 172.665689 -396.834371) (xy 172.627737 -396.778784)
			(xy 172.596702 -396.71906) (xy 172.573027 -396.656054) (xy 172.557054 -396.59067) (xy 172.54901 -396.523846)
			(xy 172.54901 -396.456539) (xy 172.557056 -396.389715) (xy 172.573032 -396.324332) (xy 172.596708 -396.261327)
			(xy 172.627745 -396.201603) (xy 172.665698 -396.146018) (xy 172.687488 -396.120366) (xy 172.69328 -396.113218)
			(xy 172.699798 -396.09603) (xy 172.700188 -396.086838) (xy 172.700188 -395.92885) (xy 172.700606 -395.918675)
			(xy 172.708384 -395.899872) (xy 172.722772 -395.885484) (xy 172.741575 -395.877706) (xy 172.75175 -395.877288)
			(xy 173.46803 -395.877288) (xy 173.47821 -395.87764) (xy 173.497015 -395.885445) (xy 173.5114 -395.899852)
			(xy 173.519175 -395.91867) (xy 173.519592 -395.92885) (xy 173.519592 -396.086838) (xy 173.519986 -396.096027)
			(xy 173.526511 -396.113211) (xy 173.532292 -396.120366) (xy 173.554069 -396.146027) (xy 173.592016 -396.201613)
			(xy 173.623048 -396.261335) (xy 173.64672 -396.324339) (xy 173.662693 -396.389719) (xy 173.670737 -396.456541)
			(xy 173.670738 -396.523844) (xy 173.662695 -396.590666) (xy 173.646725 -396.656047) (xy 173.623054 -396.719051)
			(xy 173.592024 -396.778774) (xy 173.554078 -396.834361) (xy 173.532292 -396.860014) (xy 173.526506 -396.867167)
			(xy 173.519985 -396.884351) (xy 173.519592 -396.893542) (xy 173.519592 -397.38681) (xy 173.519999 -397.395998)
			(xy 173.526515 -397.413182) (xy 173.532292 -397.420338) (xy 173.554041 -397.446021) (xy 173.591989 -397.501604)
			(xy 173.620441 -397.556355) (xy 174.749183 -397.556355) (xy 174.757226 -397.489534) (xy 174.773198 -397.424152)
			(xy 174.796869 -397.361148) (xy 174.827901 -397.301424) (xy 174.865849 -397.245838) (xy 174.887636 -397.220186)
			(xy 174.893426 -397.213036) (xy 174.899944 -397.195849) (xy 174.900336 -397.186658) (xy 174.900336 -397.028924)
			(xy 174.900742 -397.018767) (xy 174.908536 -397.000008) (xy 174.922939 -396.985682) (xy 174.941739 -396.977988)
			(xy 174.951898 -396.977616) (xy 175.668178 -396.977616) (xy 175.6783 -396.978144) (xy 175.697017 -396.98586)
			(xy 175.711373 -397.000133) (xy 175.719197 -397.018805) (xy 175.71974 -397.028924) (xy 175.71974 -397.186658)
			(xy 175.720184 -397.195841) (xy 175.726675 -397.213025) (xy 175.73244 -397.220186) (xy 175.754238 -397.24583)
			(xy 175.792188 -397.301417) (xy 175.823222 -397.361142) (xy 175.846895 -397.424147) (xy 175.862868 -397.489531)
			(xy 175.870912 -397.556354) (xy 175.870911 -397.623661) (xy 175.862865 -397.690484) (xy 175.846891 -397.755867)
			(xy 175.823216 -397.818872) (xy 175.79218 -397.878596) (xy 175.754229 -397.934182) (xy 175.73244 -397.959834)
			(xy 175.726639 -397.966976) (xy 175.720129 -397.984169) (xy 175.71974 -397.993362) (xy 175.71974 -398.486884)
			(xy 175.720171 -398.496069) (xy 175.726672 -398.513253) (xy 175.73244 -398.520412) (xy 175.754264 -398.546035)
			(xy 175.792213 -398.601625) (xy 175.823246 -398.661352) (xy 175.846918 -398.724361) (xy 175.862889 -398.789747)
			(xy 175.87093 -398.856573) (xy 175.870927 -398.923881) (xy 175.862879 -398.990707) (xy 175.846902 -399.056091)
			(xy 175.823224 -399.119097) (xy 175.792185 -399.178822) (xy 175.754231 -399.234408) (xy 175.73244 -399.26006)
			(xy 175.726628 -399.267194) (xy 175.720124 -399.284393) (xy 175.71974 -399.293588) (xy 175.71974 -399.451576)
			(xy 175.71926 -399.461724) (xy 175.71148 -399.480468) (xy 175.697101 -399.494791) (xy 175.678327 -399.502498)
			(xy 175.668178 -399.502884) (xy 174.951898 -399.502884) (xy 174.941774 -399.502376) (xy 174.923058 -399.494652)
			(xy 174.908702 -399.480372) (xy 174.900879 -399.461697) (xy 174.900336 -399.451576) (xy 174.900336 -399.293588)
			(xy 174.899924 -399.284401) (xy 174.893411 -399.267217) (xy 174.887636 -399.26006) (xy 174.865884 -399.234379)
			(xy 174.827934 -399.178796) (xy 174.7969 -399.119077) (xy 174.773225 -399.056076) (xy 174.75725 -398.990697)
			(xy 174.749203 -398.923878) (xy 174.749199 -398.856576) (xy 174.75724 -398.789756) (xy 174.773209 -398.724376)
			(xy 174.796878 -398.661373) (xy 174.827906 -398.60165) (xy 174.865851 -398.546064) (xy 174.887636 -398.520412)
			(xy 174.893457 -398.513284) (xy 174.899956 -398.49608) (xy 174.900336 -398.486884) (xy 174.900336 -397.993362)
			(xy 174.899936 -397.984174) (xy 174.893414 -397.96699) (xy 174.887636 -397.959834) (xy 174.865858 -397.934174)
			(xy 174.827909 -397.878588) (xy 174.796876 -397.818866) (xy 174.773202 -397.755863) (xy 174.757229 -397.690481)
			(xy 174.749184 -397.62366) (xy 174.749183 -397.556355) (xy 173.620441 -397.556355) (xy 173.623023 -397.561324)
			(xy 173.646696 -397.624324) (xy 173.662671 -397.689702) (xy 173.670718 -397.756521) (xy 173.670721 -397.823822)
			(xy 173.662681 -397.890642) (xy 173.646713 -397.956021) (xy 173.623046 -398.019024) (xy 173.592019 -398.078747)
			(xy 173.554077 -398.134334) (xy 173.532292 -398.159986) (xy 173.526475 -398.167117) (xy 173.519973 -398.184318)
			(xy 173.519592 -398.193514) (xy 173.519592 -398.351502) (xy 173.519069 -398.361656) (xy 173.511299 -398.38042)
			(xy 173.496943 -398.394784) (xy 173.478184 -398.402563) (xy 173.46803 -398.403064) (xy 172.75175 -398.403064)
			(xy 172.741582 -398.402595) (xy 172.722789 -398.394827) (xy 172.708402 -398.380455) (xy 172.700615 -398.36167)
			(xy 172.700188 -398.351502) (xy 172.700188 -398.193514) (xy 172.699774 -398.184327) (xy 172.693263 -398.167143)
			(xy 172.687488 -398.159986) (xy 172.665661 -398.134365) (xy 172.627711 -398.078775) (xy 172.596676 -398.019048)
			(xy 172.573004 -397.956039) (xy 172.557032 -397.890653) (xy 172.54899 -397.823826) (xy 171.420874 -397.823826)
			(xy 171.392104 -397.879044) (xy 171.354011 -397.934678) (xy 171.332144 -397.960342) (xy 171.32634 -397.967482)
			(xy 171.319831 -397.984677) (xy 171.319444 -397.99387) (xy 171.319444 -398.486376) (xy 171.319878 -398.49556)
			(xy 171.326376 -398.512744) (xy 171.332144 -398.519904) (xy 171.354045 -398.545539) (xy 171.392137 -398.601177)
			(xy 171.423289 -398.660976) (xy 171.447054 -398.724077) (xy 171.463088 -398.789571) (xy 171.471162 -398.856513)
			(xy 171.471159 -398.923941) (xy 171.463078 -398.990883) (xy 171.447037 -399.056374) (xy 171.423267 -399.119473)
			(xy 171.392109 -399.17927) (xy 171.354012 -399.234904) (xy 171.332144 -399.260568) (xy 171.326329 -399.2677)
			(xy 171.319827 -399.284901) (xy 171.319444 -399.294096) (xy 171.319444 -399.451576) (xy 171.318896 -399.461678)
			(xy 171.311175 -399.480347) (xy 171.296897 -399.494641) (xy 171.278237 -399.502385) (xy 171.268136 -399.502884)
			(xy 170.551856 -399.502884) (xy 170.541742 -399.50245) (xy 170.52306 -399.494695) (xy 170.508766 -399.480383)
			(xy 170.501036 -399.46169) (xy 170.500548 -399.451576) (xy 170.500548 -399.294096) (xy 170.500129 -399.28491)
			(xy 170.49362 -399.267726) (xy 170.487848 -399.260568) (xy 170.466018 -399.234874) (xy 170.427925 -399.179245)
			(xy 170.39677 -399.119453) (xy 170.373001 -399.05636) (xy 170.356962 -398.990874) (xy 170.348883 -398.923938)
			(xy 170.348879 -398.856516) (xy 170.356952 -398.789579) (xy 170.372985 -398.724092) (xy 170.396748 -398.660996)
			(xy 170.427897 -398.601201) (xy 170.465984 -398.545568) (xy 170.487848 -398.519904) (xy 170.493631 -398.51275)
			(xy 170.500153 -398.495566) (xy 170.500548 -398.486376) (xy 170.500548 -397.99387) (xy 170.500141 -397.984683)
			(xy 170.493624 -397.967499) (xy 170.487848 -397.960342) (xy 170.465992 -397.934669) (xy 170.4279 -397.879037)
			(xy 170.396746 -397.819242) (xy 170.372979 -397.756146) (xy 170.356942 -397.690658) (xy 170.348864 -397.623719)
			(xy 170.348863 -397.556296) (xy 169.22062 -397.556296) (xy 169.223233 -397.561324) (xy 169.246906 -397.624324)
			(xy 169.26288 -397.689702) (xy 169.270927 -397.756521) (xy 169.27093 -397.823822) (xy 169.26289 -397.890641)
			(xy 169.246923 -397.956021) (xy 169.223256 -398.019024) (xy 169.19223 -398.078746) (xy 169.154288 -398.134333)
			(xy 169.132504 -398.159986) (xy 169.126689 -398.167118) (xy 169.120185 -398.184319) (xy 169.119804 -398.193514)
			(xy 169.119804 -398.351502) (xy 169.119269 -398.361655) (xy 169.111502 -398.380416) (xy 169.097149 -398.394779)
			(xy 169.078394 -398.402561) (xy 169.068242 -398.403064) (xy 168.351962 -398.403064) (xy 168.341802 -398.402598)
			(xy 168.323032 -398.394811) (xy 168.308669 -398.380437) (xy 168.300895 -398.361662) (xy 168.3004 -398.351502)
			(xy 168.3004 -398.193514) (xy 168.299983 -398.184328) (xy 168.293474 -398.167143) (xy 168.2877 -398.159986)
			(xy 168.265876 -398.134364) (xy 168.227931 -398.078772) (xy 168.196902 -398.019044) (xy 168.173233 -397.956036)
			(xy 168.157263 -397.89065) (xy 168.149223 -397.823825) (xy 167.020556 -397.823825) (xy 166.992095 -397.878596)
			(xy 166.954145 -397.934182) (xy 166.932356 -397.959834) (xy 166.926557 -397.966977) (xy 166.920045 -397.984169)
			(xy 166.919656 -397.993362) (xy 166.919656 -398.486884) (xy 166.920084 -398.496069) (xy 166.926586 -398.513253)
			(xy 166.932356 -398.520412) (xy 166.954179 -398.546035) (xy 166.992127 -398.601625) (xy 167.023159 -398.661353)
			(xy 167.04683 -398.724361) (xy 167.062801 -398.789747) (xy 167.070842 -398.856573) (xy 167.070839 -398.923881)
			(xy 167.062791 -398.990706) (xy 167.046814 -399.05609) (xy 167.023137 -399.119097) (xy 166.9921 -399.178821)
			(xy 166.954146 -399.234408) (xy 166.932356 -399.26006) (xy 166.926546 -399.267195) (xy 166.92004 -399.284394)
			(xy 166.919656 -399.293588) (xy 166.919656 -399.451576) (xy 166.91916 -399.461722) (xy 166.911383 -399.480463)
			(xy 166.89701 -399.494785) (xy 166.878241 -399.502496) (xy 166.868094 -399.502884) (xy 166.151814 -399.502884)
			(xy 166.141691 -399.502363) (xy 166.122975 -399.494644) (xy 166.108619 -399.480369) (xy 166.100795 -399.461696)
			(xy 166.100252 -399.451576) (xy 166.100252 -399.293588) (xy 166.099836 -399.284402) (xy 166.093325 -399.267218)
			(xy 166.087552 -399.26006) (xy 166.065799 -399.234379) (xy 166.027849 -399.178797) (xy 165.996813 -399.119077)
			(xy 165.973138 -399.056077) (xy 165.957162 -398.990698) (xy 165.949115 -398.923878) (xy 165.949111 -398.856576)
			(xy 165.957152 -398.789755) (xy 165.973122 -398.724375) (xy 165.996791 -398.661372) (xy 166.027821 -398.60165)
			(xy 166.065766 -398.546064) (xy 166.087552 -398.520412) (xy 166.093375 -398.513286) (xy 166.099872 -398.49608)
			(xy 166.100252 -398.486884) (xy 166.100252 -397.993362) (xy 166.099848 -397.984174) (xy 166.093329 -397.966991)
			(xy 166.087552 -397.959834) (xy 166.065774 -397.934174) (xy 166.027824 -397.878589) (xy 165.99679 -397.818866)
			(xy 165.973116 -397.755863) (xy 165.957142 -397.690482) (xy 165.949096 -397.62366) (xy 164.846898 -397.62366)
			(xy 164.847042 -397.624041) (xy 164.863079 -397.689526) (xy 164.871158 -397.756461) (xy 164.871162 -397.823882)
			(xy 164.86309 -397.890817) (xy 164.847058 -397.956304) (xy 164.823299 -398.019399) (xy 164.792153 -398.079195)
			(xy 164.754069 -398.134829) (xy 164.732208 -398.160494) (xy 164.726432 -398.167654) (xy 164.719905 -398.184833)
			(xy 164.719508 -398.194022) (xy 164.719508 -398.351502) (xy 164.718976 -398.361623) (xy 164.711257 -398.380335)
			(xy 164.696985 -398.394689) (xy 164.678318 -398.402517) (xy 164.6682 -398.403064) (xy 163.95192 -398.403064)
			(xy 163.941763 -398.402661) (xy 163.923004 -398.394866) (xy 163.908678 -398.380462) (xy 163.900984 -398.361662)
			(xy 163.900612 -398.351502) (xy 163.900612 -398.194022) (xy 163.900188 -398.184836) (xy 163.893684 -398.167652)
			(xy 163.887912 -398.160494) (xy 163.86601 -398.13486) (xy 163.827922 -398.079221) (xy 163.796772 -398.019421)
			(xy 163.77301 -397.95632) (xy 163.756976 -397.890827) (xy 163.748903 -397.823885) (xy 162.620757 -397.823885)
			(xy 162.592019 -397.879044) (xy 162.553926 -397.934677) (xy 162.53206 -397.960342) (xy 162.526258 -397.967483)
			(xy 162.519748 -397.984677) (xy 162.51936 -397.99387) (xy 162.51936 -398.486376) (xy 162.51979 -398.495561)
			(xy 162.526291 -398.512745) (xy 162.53206 -398.519904) (xy 162.553961 -398.545539) (xy 162.592051 -398.601177)
			(xy 162.623202 -398.660977) (xy 162.646966 -398.724078) (xy 162.663 -398.789571) (xy 162.671074 -398.856513)
			(xy 162.671071 -398.923941) (xy 162.662991 -398.990882) (xy 162.64695 -399.056374) (xy 162.62318 -399.119472)
			(xy 162.592023 -399.179269) (xy 162.553928 -399.234903) (xy 162.53206 -399.260568) (xy 162.526247 -399.267701)
			(xy 162.519743 -399.284901) (xy 162.51936 -399.294096) (xy 162.51936 -399.451576) (xy 162.518964 -399.461702)
			(xy 162.511216 -399.480413) (xy 162.496893 -399.494729) (xy 162.478178 -399.502468) (xy 162.468052 -399.502884)
			(xy 161.751772 -399.502884) (xy 161.741659 -399.502438) (xy 161.722978 -399.494688) (xy 161.708683 -399.480379)
			(xy 161.700952 -399.461689) (xy 161.700464 -399.451576) (xy 161.700464 -399.294096) (xy 161.700041 -399.28491)
			(xy 161.693535 -399.267727) (xy 161.687764 -399.260568) (xy 161.665937 -399.234873) (xy 161.627849 -399.179242)
			(xy 161.596699 -399.119449) (xy 161.572934 -399.056357) (xy 161.556897 -398.990871) (xy 161.548819 -398.923937)
			(xy 161.548816 -398.856517) (xy 161.556888 -398.789582) (xy 161.572918 -398.724095) (xy 161.596677 -398.661)
			(xy 161.627821 -398.601205) (xy 161.665903 -398.54557) (xy 161.687764 -398.519904) (xy 161.693549 -398.512751)
			(xy 161.700069 -398.495566) (xy 161.700464 -398.486376) (xy 161.700464 -397.99387) (xy 161.700054 -397.984683)
			(xy 161.693538 -397.9675) (xy 161.687764 -397.960342) (xy 161.665911 -397.934668) (xy 161.627824 -397.879034)
			(xy 161.596675 -397.819239) (xy 161.572912 -397.756143) (xy 161.556877 -397.690655) (xy 161.548801 -397.623719)
			(xy 161.5488 -397.556296) (xy 160.420549 -397.556296) (xy 160.423161 -397.561321) (xy 160.446838 -397.624321)
			(xy 160.462815 -397.6897) (xy 160.470863 -397.75652) (xy 160.470866 -397.823823) (xy 160.462825 -397.890644)
			(xy 160.446855 -397.956024) (xy 160.423185 -398.019027) (xy 160.392154 -398.078749) (xy 160.354207 -398.134334)
			(xy 160.33242 -398.159986) (xy 160.326607 -398.16712) (xy 160.320101 -398.184319) (xy 160.31972 -398.193514)
			(xy 160.31972 -398.351502) (xy 160.319337 -398.361679) (xy 160.311543 -398.380482) (xy 160.297145 -398.394868)
			(xy 160.278335 -398.402645) (xy 160.268158 -398.403064) (xy 159.551878 -398.403064) (xy 159.541719 -398.402585)
			(xy 159.52295 -398.394804) (xy 159.508585 -398.380433) (xy 159.500811 -398.361661) (xy 159.500316 -398.351502)
			(xy 159.500316 -398.193514) (xy 159.499895 -398.184328) (xy 159.493388 -398.167144) (xy 159.487616 -398.159986)
			(xy 159.465792 -398.134364) (xy 159.427845 -398.078773) (xy 159.396815 -398.019045) (xy 159.373145 -397.956036)
			(xy 159.357176 -397.890651) (xy 159.349135 -397.823825) (xy 154.57678 -397.823825) (xy 154.57678 -401.723737)
			(xy 159.349146 -401.723737) (xy 159.349148 -401.65643) (xy 159.357194 -401.589607) (xy 159.373169 -401.524223)
			(xy 159.396843 -401.461218) (xy 159.427878 -401.401494) (xy 159.465828 -401.345906) (xy 159.487616 -401.320254)
			(xy 159.493416 -401.313112) (xy 159.499928 -401.295919) (xy 159.500316 -401.286726) (xy 159.500316 -400.793458)
			(xy 159.499923 -400.784269) (xy 159.493397 -400.767085) (xy 159.487616 -400.75993) (xy 159.465835 -400.734273)
			(xy 159.427887 -400.678686) (xy 159.396855 -400.618963) (xy 159.373183 -400.55596) (xy 159.35721 -400.490578)
			(xy 159.349166 -400.423757) (xy 159.349165 -400.356452) (xy 159.357209 -400.289631) (xy 159.37318 -400.224249)
			(xy 159.396851 -400.161245) (xy 159.427883 -400.101521) (xy 159.465829 -400.045934) (xy 159.487616 -400.020282)
			(xy 159.493405 -400.013131) (xy 159.499923 -399.995945) (xy 159.500316 -399.986754) (xy 159.500316 -399.828766)
			(xy 159.500805 -399.818609) (xy 159.508586 -399.799843) (xy 159.522953 -399.78548) (xy 159.541721 -399.777703)
			(xy 159.551878 -399.777204) (xy 160.268158 -399.777204) (xy 160.278323 -399.777697) (xy 160.29711 -399.785462)
			(xy 160.311495 -399.799826) (xy 160.319288 -399.818602) (xy 160.31972 -399.828766) (xy 160.31972 -399.986754)
			(xy 160.320148 -399.995939) (xy 160.326649 -400.013124) (xy 160.33242 -400.020282) (xy 160.354215 -400.045929)
			(xy 160.392166 -400.101515) (xy 160.423201 -400.161239) (xy 160.446876 -400.224244) (xy 160.462849 -400.289628)
			(xy 160.470894 -400.356451) (xy 160.470893 -400.423758) (xy 160.462848 -400.490581) (xy 160.446873 -400.555964)
			(xy 160.423198 -400.618969) (xy 160.392161 -400.678693) (xy 160.354209 -400.734278) (xy 160.33242 -400.75993)
			(xy 160.326631 -400.76708) (xy 160.320111 -400.784267) (xy 160.31972 -400.793458) (xy 160.31972 -401.286726)
			(xy 160.320113 -401.295915) (xy 160.326638 -401.313099) (xy 160.33242 -401.320254) (xy 160.354187 -401.345923)
			(xy 160.392139 -401.401506) (xy 160.423176 -401.461227) (xy 160.446852 -401.52423) (xy 160.462827 -401.58961)
			(xy 160.470874 -401.656431) (xy 160.470876 -401.723735) (xy 160.462833 -401.790557) (xy 160.446862 -401.855939)
			(xy 160.423189 -401.918943) (xy 160.392156 -401.978665) (xy 160.354208 -402.03425) (xy 160.33242 -402.059902)
			(xy 160.326642 -402.067061) (xy 160.320116 -402.084241) (xy 160.31972 -402.09343) (xy 160.31972 -402.251418)
			(xy 160.31935 -402.261596) (xy 160.311551 -402.280399) (xy 160.297149 -402.294785) (xy 160.278336 -402.302562)
			(xy 160.268158 -402.30298) (xy 159.551878 -402.30298) (xy 159.541721 -402.302485) (xy 159.522955 -402.294707)
			(xy 159.508591 -402.280342) (xy 159.500814 -402.261575) (xy 159.500316 -402.251418) (xy 159.500316 -402.09343)
			(xy 159.499888 -402.084245) (xy 159.493386 -402.06706) (xy 159.487616 -402.059902) (xy 159.465807 -402.034267)
			(xy 159.427861 -401.978678) (xy 159.39683 -401.918952) (xy 159.373159 -401.855945) (xy 159.357188 -401.790561)
			(xy 159.349146 -401.723737) (xy 154.57678 -401.723737) (xy 154.57678 -402.823877) (xy 161.54876 -402.823877)
			(xy 161.548765 -402.756451) (xy 161.556845 -402.68951) (xy 161.572884 -402.624018) (xy 161.596652 -402.56092)
			(xy 161.627806 -402.501122) (xy 161.665898 -402.445486) (xy 161.687764 -402.41982) (xy 161.693585 -402.412692)
			(xy 161.700083 -402.395488) (xy 161.700464 -402.386292) (xy 161.700464 -401.89404) (xy 161.70002 -401.884857)
			(xy 161.693528 -401.867673) (xy 161.687764 -401.860512) (xy 161.665882 -401.834862) (xy 161.627796 -401.779225)
			(xy 161.596648 -401.719426) (xy 161.572887 -401.656327) (xy 161.556854 -401.590837) (xy 161.54878 -401.523897)
			(xy 161.548782 -401.456473) (xy 161.556859 -401.389534) (xy 161.572896 -401.324044) (xy 161.59666 -401.260946)
			(xy 161.627811 -401.201149) (xy 161.6659 -401.145514) (xy 161.687764 -401.119848) (xy 161.693573 -401.112712)
			(xy 161.700078 -401.095514) (xy 161.700464 -401.08632) (xy 161.700464 -400.92884) (xy 161.700948 -400.918725)
			(xy 161.708676 -400.900029) (xy 161.722972 -400.885714) (xy 161.741657 -400.877961) (xy 161.751772 -400.877532)
			(xy 162.468052 -400.877532) (xy 162.478175 -400.877956) (xy 162.496884 -400.885694) (xy 162.511201 -400.900009)
			(xy 162.518942 -400.918717) (xy 162.51936 -400.92884) (xy 162.51936 -401.08632) (xy 162.519769 -401.095507)
			(xy 162.526285 -401.112691) (xy 162.53206 -401.119848) (xy 162.553906 -401.145529) (xy 162.591998 -401.20116)
			(xy 162.623151 -401.260954) (xy 162.646919 -401.324049) (xy 162.662957 -401.389536) (xy 162.671035 -401.456474)
			(xy 162.671037 -401.523896) (xy 162.662962 -401.590834) (xy 162.646927 -401.656323) (xy 162.623164 -401.719419)
			(xy 162.620884 -401.723796) (xy 163.748915 -401.723796) (xy 163.748917 -401.656371) (xy 163.756995 -401.589431)
			(xy 163.773033 -401.52394) (xy 163.7968 -401.460842) (xy 163.827954 -401.401046) (xy 163.866046 -401.345411)
			(xy 163.887912 -401.319746) (xy 163.893715 -401.312606) (xy 163.900226 -401.295411) (xy 163.900612 -401.286218)
			(xy 163.900612 -400.793966) (xy 163.900216 -400.784777) (xy 163.893692 -400.767593) (xy 163.887912 -400.760438)
			(xy 163.866054 -400.734768) (xy 163.827964 -400.679135) (xy 163.796812 -400.619339) (xy 163.773047 -400.556243)
			(xy 163.757011 -400.490754) (xy 163.748934 -400.423816) (xy 163.748934 -400.356393) (xy 163.757009 -400.289455)
			(xy 163.773044 -400.223966) (xy 163.796809 -400.160869) (xy 163.827959 -400.101073) (xy 163.866048 -400.045439)
			(xy 163.887912 -400.019774) (xy 163.893703 -400.012625) (xy 163.900221 -399.995437) (xy 163.900612 -399.986246)
			(xy 163.900612 -399.828766) (xy 163.901098 -399.818641) (xy 163.908832 -399.799924) (xy 163.923117 -399.78557)
			(xy 163.941797 -399.777747) (xy 163.95192 -399.777204) (xy 164.6682 -399.777204) (xy 164.678355 -399.777622)
			(xy 164.697108 -399.785418) (xy 164.711431 -399.799816) (xy 164.71913 -399.818609) (xy 164.719508 -399.828766)
			(xy 164.719508 -399.986246) (xy 164.719942 -399.995431) (xy 164.726439 -400.012615) (xy 164.732208 -400.019774)
			(xy 164.754078 -400.045435) (xy 164.792166 -400.10107) (xy 164.823316 -400.160867) (xy 164.847079 -400.223964)
			(xy 164.863114 -400.289454) (xy 164.871189 -400.356393) (xy 164.871189 -400.423817) (xy 164.863112 -400.490755)
			(xy 164.847076 -400.556244) (xy 164.823312 -400.619341) (xy 164.792161 -400.679138) (xy 164.754072 -400.734773)
			(xy 164.732208 -400.760438) (xy 164.726414 -400.767585) (xy 164.719897 -400.784774) (xy 164.719508 -400.793966)
			(xy 164.719508 -401.286218) (xy 164.719908 -401.295406) (xy 164.726429 -401.312591) (xy 164.732208 -401.319746)
			(xy 164.75405 -401.345429) (xy 164.792139 -401.401061) (xy 164.82329 -401.460855) (xy 164.847055 -401.52395)
			(xy 164.863092 -401.589436) (xy 164.871169 -401.656373) (xy 164.871171 -401.723794) (xy 164.863098 -401.790731)
			(xy 164.847065 -401.856219) (xy 164.823304 -401.919315) (xy 164.792156 -401.97911) (xy 164.75407 -402.034745)
			(xy 164.732208 -402.06041) (xy 164.726426 -402.067565) (xy 164.719902 -402.084748) (xy 164.719508 -402.093938)
			(xy 164.719508 -402.251418) (xy 164.71899 -402.26154) (xy 164.711265 -402.280253) (xy 164.696989 -402.294607)
			(xy 164.678319 -402.302434) (xy 164.6682 -402.30298) (xy 163.95192 -402.30298) (xy 163.941765 -402.302562)
			(xy 163.923009 -402.294769) (xy 163.908684 -402.280371) (xy 163.900987 -402.261575) (xy 163.900612 -402.251418)
			(xy 163.900612 -402.093938) (xy 163.900181 -402.084753) (xy 163.893681 -402.067569) (xy 163.887912 -402.06041)
			(xy 163.866026 -402.034763) (xy 163.827937 -401.979126) (xy 163.796787 -401.919327) (xy 163.773023 -401.856228)
			(xy 163.756989 -401.790737) (xy 163.748915 -401.723796) (xy 162.620884 -401.723796) (xy 162.592013 -401.779214)
			(xy 162.553924 -401.834847) (xy 162.53206 -401.860512) (xy 162.526271 -401.867662) (xy 162.519753 -401.884849)
			(xy 162.51936 -401.89404) (xy 162.51936 -402.386292) (xy 162.519783 -402.395478) (xy 162.526289 -402.412662)
			(xy 162.53206 -402.41982) (xy 162.553878 -402.445523) (xy 162.591971 -402.501152) (xy 162.623126 -402.560942)
			(xy 162.646895 -402.624034) (xy 162.662935 -402.689519) (xy 162.671015 -402.756454) (xy 162.671019 -402.823818)
			(xy 165.949055 -402.823818) (xy 165.94906 -402.756509) (xy 165.957109 -402.689683) (xy 165.973087 -402.624298)
			(xy 165.996766 -402.561292) (xy 166.027805 -402.501567) (xy 166.065761 -402.44598) (xy 166.087552 -402.420328)
			(xy 166.093368 -402.413197) (xy 166.09987 -402.395995) (xy 166.100252 -402.3868) (xy 166.100252 -401.893532)
			(xy 166.099815 -401.884348) (xy 166.093319 -401.867164) (xy 166.087552 -401.860004) (xy 166.065744 -401.834368)
			(xy 166.027795 -401.77878) (xy 165.996762 -401.719054) (xy 165.97309 -401.656047) (xy 165.957118 -401.590663)
			(xy 165.949075 -401.523838) (xy 165.949077 -401.456532) (xy 165.957123 -401.389707) (xy 165.973098 -401.324324)
			(xy 165.996774 -401.261318) (xy 166.02781 -401.201594) (xy 166.065762 -401.146008) (xy 166.087552 -401.120356)
			(xy 166.093356 -401.113216) (xy 166.099865 -401.096021) (xy 166.100252 -401.086828) (xy 166.100252 -400.92884)
			(xy 166.100754 -400.918694) (xy 166.108527 -400.899952) (xy 166.122899 -400.885629) (xy 166.141667 -400.87792)
			(xy 166.151814 -400.877532) (xy 166.868094 -400.877532) (xy 166.878219 -400.878031) (xy 166.896939 -400.885756)
			(xy 166.911295 -400.900038) (xy 166.919116 -400.918717) (xy 166.919656 -400.92884) (xy 166.919656 -401.086828)
			(xy 166.920063 -401.096015) (xy 166.92658 -401.113199) (xy 166.932356 -401.120356) (xy 166.954124 -401.146024)
			(xy 166.992074 -401.201608) (xy 167.023108 -401.26133) (xy 167.046782 -401.324332) (xy 167.062757 -401.389712)
			(xy 167.070803 -401.456533) (xy 167.070804 -401.523837) (xy 167.062762 -401.590658) (xy 167.046791 -401.656039)
			(xy 167.02312 -401.719043) (xy 167.020682 -401.723736) (xy 168.149234 -401.723736) (xy 168.149236 -401.65643)
			(xy 168.157282 -401.589607) (xy 168.173256 -401.524224) (xy 168.19693 -401.461219) (xy 168.227963 -401.401494)
			(xy 168.265912 -401.345907) (xy 168.2877 -401.320254) (xy 168.293499 -401.31311) (xy 168.300012 -401.295919)
			(xy 168.3004 -401.286726) (xy 168.3004 -400.793458) (xy 168.30001 -400.784269) (xy 168.293482 -400.767084)
			(xy 168.2877 -400.75993) (xy 168.265919 -400.734272) (xy 168.227973 -400.678686) (xy 168.196942 -400.618963)
			(xy 168.17327 -400.555959) (xy 168.157298 -400.490578) (xy 168.149254 -400.423756) (xy 168.149253 -400.356453)
			(xy 168.157296 -400.289631) (xy 168.173267 -400.22425) (xy 168.196938 -400.161246) (xy 168.227968 -400.101522)
			(xy 168.265914 -400.045935) (xy 168.2877 -400.020282) (xy 168.293487 -400.01313) (xy 168.300007 -399.995945)
			(xy 168.3004 -399.986754) (xy 168.3004 -399.828766) (xy 168.300905 -399.818611) (xy 168.308683 -399.799848)
			(xy 168.323045 -399.785485) (xy 168.341807 -399.777705) (xy 168.351962 -399.777204) (xy 169.068242 -399.777204)
			(xy 169.078398 -399.777698) (xy 169.097162 -399.78548) (xy 169.111524 -399.799845) (xy 169.119303 -399.81861)
			(xy 169.119804 -399.828766) (xy 169.119804 -399.986754) (xy 169.120235 -399.995939) (xy 169.126734 -400.013124)
			(xy 169.132504 -400.020282) (xy 169.154296 -400.04593) (xy 169.192242 -400.101518) (xy 169.223273 -400.161243)
			(xy 169.246943 -400.224248) (xy 169.262915 -400.28963) (xy 169.270958 -400.356452) (xy 169.270957 -400.423757)
			(xy 169.262913 -400.490579) (xy 169.246941 -400.555961) (xy 169.223269 -400.618966) (xy 169.192237 -400.67869)
			(xy 169.154291 -400.734277) (xy 169.132504 -400.75993) (xy 169.126713 -400.767079) (xy 169.120195 -400.784267)
			(xy 169.119804 -400.793458) (xy 169.119804 -401.286726) (xy 169.1202 -401.295915) (xy 169.126723 -401.313099)
			(xy 169.132504 -401.320254) (xy 169.154269 -401.345925) (xy 169.192215 -401.401509) (xy 169.223247 -401.461231)
			(xy 169.246919 -401.524233) (xy 169.262893 -401.589612) (xy 169.270938 -401.656432) (xy 169.27094 -401.723735)
			(xy 169.262899 -401.790555) (xy 169.246929 -401.855936) (xy 169.223261 -401.918939) (xy 169.192232 -401.978662)
			(xy 169.154289 -402.034249) (xy 169.132504 -402.059902) (xy 169.126725 -402.067059) (xy 169.1202 -402.084241)
			(xy 169.119804 -402.09343) (xy 169.119804 -402.251418) (xy 169.119283 -402.261572) (xy 169.11151 -402.280333)
			(xy 169.097154 -402.294697) (xy 169.078396 -402.302478) (xy 169.068242 -402.30298) (xy 168.351962 -402.30298)
			(xy 168.341804 -402.302498) (xy 168.323037 -402.294715) (xy 168.308674 -402.280346) (xy 168.300898 -402.261576)
			(xy 168.3004 -402.251418) (xy 168.3004 -402.09343) (xy 168.299975 -402.084244) (xy 168.293472 -402.06706)
			(xy 168.2877 -402.059902) (xy 168.265892 -402.034267) (xy 168.227946 -401.978677) (xy 168.196916 -401.918951)
			(xy 168.173246 -401.855944) (xy 168.157276 -401.79056) (xy 168.149234 -401.723736) (xy 167.020682 -401.723736)
			(xy 166.992089 -401.778766) (xy 166.954142 -401.834352) (xy 166.932356 -401.860004) (xy 166.92657 -401.867156)
			(xy 166.92005 -401.884342) (xy 166.919656 -401.893532) (xy 166.919656 -402.3868) (xy 166.920076 -402.395986)
			(xy 166.926584 -402.41317) (xy 166.932356 -402.420328) (xy 166.954097 -402.446019) (xy 166.992047 -402.5016)
			(xy 167.023083 -402.561318) (xy 167.046758 -402.624317) (xy 167.062735 -402.689695) (xy 167.070783 -402.756513)
			(xy 167.070787 -402.823815) (xy 167.070779 -402.823878) (xy 170.348823 -402.823878) (xy 170.348828 -402.75645)
			(xy 170.356909 -402.689507) (xy 170.372951 -402.624015) (xy 170.396723 -402.560916) (xy 170.427882 -402.501119)
			(xy 170.465979 -402.445484) (xy 170.487848 -402.41982) (xy 170.493667 -402.412691) (xy 170.500167 -402.395488)
			(xy 170.500548 -402.386292) (xy 170.500548 -401.89404) (xy 170.500108 -401.884856) (xy 170.493614 -401.867672)
			(xy 170.487848 -401.860512) (xy 170.465963 -401.834864) (xy 170.427871 -401.779228) (xy 170.396719 -401.71943)
			(xy 170.372954 -401.656331) (xy 170.356918 -401.590839) (xy 170.348843 -401.523898) (xy 170.348845 -401.456472)
			(xy 170.356924 -401.389531) (xy 170.372963 -401.324041) (xy 170.396731 -401.260943) (xy 170.427887 -401.201146)
			(xy 170.465981 -401.145512) (xy 170.487848 -401.119848) (xy 170.493655 -401.112711) (xy 170.500162 -401.095514)
			(xy 170.500548 -401.08632) (xy 170.500548 -400.92884) (xy 170.501117 -400.91874) (xy 170.508832 -400.900073)
			(xy 170.523102 -400.885779) (xy 170.541757 -400.878033) (xy 170.551856 -400.877532) (xy 171.268136 -400.877532)
			(xy 171.278265 -400.877887) (xy 171.296975 -400.885653) (xy 171.311289 -400.899989) (xy 171.319028 -400.918711)
			(xy 171.319444 -400.92884) (xy 171.319444 -401.08632) (xy 171.319857 -401.095507) (xy 171.32637 -401.11269)
			(xy 171.332144 -401.119848) (xy 171.35399 -401.145528) (xy 171.392083 -401.20116) (xy 171.423238 -401.260953)
			(xy 171.447006 -401.324048) (xy 171.463044 -401.389536) (xy 171.471123 -401.456473) (xy 171.471124 -401.523897)
			(xy 171.46305 -401.590834) (xy 171.447015 -401.656323) (xy 171.42325 -401.719419) (xy 171.421001 -401.723737)
			(xy 172.549001 -401.723737) (xy 172.549003 -401.65643) (xy 172.55705 -401.589605) (xy 172.573027 -401.524221)
			(xy 172.596704 -401.461215) (xy 172.627743 -401.401491) (xy 172.665697 -401.345906) (xy 172.687488 -401.320254)
			(xy 172.693285 -401.313109) (xy 172.6998 -401.295918) (xy 172.700188 -401.286726) (xy 172.700188 -400.793458)
			(xy 172.699801 -400.784268) (xy 172.693272 -400.767084) (xy 172.687488 -400.75993) (xy 172.665705 -400.734274)
			(xy 172.627752 -400.678689) (xy 172.596716 -400.618966) (xy 172.573041 -400.555962) (xy 172.557066 -400.49058)
			(xy 172.549021 -400.423757) (xy 172.54902 -400.356452) (xy 172.557065 -400.289629) (xy 172.573038 -400.224246)
			(xy 172.596713 -400.161242) (xy 172.627748 -400.101519) (xy 172.665699 -400.045933) (xy 172.687488 -400.020282)
			(xy 172.693273 -400.013129) (xy 172.699795 -399.995944) (xy 172.700188 -399.986754) (xy 172.700188 -399.828766)
			(xy 172.700537 -399.818586) (xy 172.708343 -399.799781) (xy 172.722752 -399.785395) (xy 172.741569 -399.777621)
			(xy 172.75175 -399.777204) (xy 173.46803 -399.777204) (xy 173.478186 -399.777708) (xy 173.496949 -399.785486)
			(xy 173.511312 -399.799848) (xy 173.519091 -399.818611) (xy 173.519592 -399.828766) (xy 173.519592 -399.986754)
			(xy 173.520026 -399.995939) (xy 173.526523 -400.013123) (xy 173.532292 -400.020282) (xy 173.554085 -400.04593)
			(xy 173.592031 -400.101518) (xy 173.623063 -400.161242) (xy 173.646734 -400.224247) (xy 173.662705 -400.289629)
			(xy 173.670749 -400.356452) (xy 173.670748 -400.423757) (xy 173.662704 -400.490579) (xy 173.646731 -400.555962)
			(xy 173.623059 -400.618966) (xy 173.592027 -400.67869) (xy 173.554079 -400.734277) (xy 173.532292 -400.75993)
			(xy 173.526499 -400.767078) (xy 173.519983 -400.784266) (xy 173.519592 -400.793458) (xy 173.519592 -401.286726)
			(xy 173.519991 -401.295914) (xy 173.526513 -401.313099) (xy 173.532292 -401.320254) (xy 173.554057 -401.345924)
			(xy 173.592005 -401.401509) (xy 173.623037 -401.46123) (xy 173.64671 -401.524232) (xy 173.662683 -401.589612)
			(xy 173.670729 -401.656432) (xy 173.670731 -401.723735) (xy 173.662689 -401.790555) (xy 173.64672 -401.855936)
			(xy 173.623051 -401.918939) (xy 173.592022 -401.978663) (xy 173.554077 -402.034249) (xy 173.532292 -402.059902)
			(xy 173.526511 -402.067058) (xy 173.519987 -402.08424) (xy 173.519592 -402.09343) (xy 173.519592 -402.251418)
			(xy 173.519082 -402.261573) (xy 173.511308 -402.280337) (xy 173.496947 -402.294701) (xy 173.478185 -402.30248)
			(xy 173.46803 -402.30298) (xy 172.75175 -402.30298) (xy 172.741584 -402.302496) (xy 172.722794 -402.29473)
			(xy 172.708408 -402.280363) (xy 172.700618 -402.261584) (xy 172.700188 -402.251418) (xy 172.700188 -402.09343)
			(xy 172.699766 -402.084244) (xy 172.693261 -402.067059) (xy 172.687488 -402.059902) (xy 172.665677 -402.034268)
			(xy 172.627726 -401.97868) (xy 172.596691 -401.918955) (xy 172.573017 -401.855948) (xy 172.557044 -401.790563)
			(xy 172.549001 -401.723737) (xy 171.421001 -401.723737) (xy 171.392099 -401.779215) (xy 171.354009 -401.834848)
			(xy 171.332144 -401.860512) (xy 171.326353 -401.867661) (xy 171.319836 -401.884849) (xy 171.319444 -401.89404)
			(xy 171.319444 -402.386292) (xy 171.31987 -402.395477) (xy 171.326374 -402.412661) (xy 171.332144 -402.41982)
			(xy 171.353963 -402.445523) (xy 171.392057 -402.501151) (xy 171.423213 -402.560941) (xy 171.446982 -402.624033)
			(xy 171.463022 -402.689518) (xy 171.471103 -402.756453) (xy 171.471107 -402.823818) (xy 174.749143 -402.823818)
			(xy 174.749147 -402.75651) (xy 174.757196 -402.689684) (xy 174.773174 -402.624299) (xy 174.796852 -402.561292)
			(xy 174.827891 -402.501567) (xy 174.865845 -402.44598) (xy 174.887636 -402.420328) (xy 174.89345 -402.413195)
			(xy 174.899953 -402.395995) (xy 174.900336 -402.3868) (xy 174.900336 -401.893532) (xy 174.899902 -401.884348)
			(xy 174.893404 -401.867163) (xy 174.887636 -401.860004) (xy 174.865829 -401.834368) (xy 174.827881 -401.778779)
			(xy 174.796848 -401.719053) (xy 174.773177 -401.656047) (xy 174.757205 -401.590663) (xy 174.749163 -401.523838)
			(xy 174.749165 -401.456532) (xy 174.757211 -401.389708) (xy 174.773186 -401.324324) (xy 174.796861 -401.261319)
			(xy 174.827896 -401.201595) (xy 174.865847 -401.146008) (xy 174.887636 -401.120356) (xy 174.893438 -401.113215)
			(xy 174.899949 -401.096021) (xy 174.900336 -401.086828) (xy 174.900336 -400.92884) (xy 174.900755 -400.918684)
			(xy 174.908544 -400.899926) (xy 174.922943 -400.8856) (xy 174.94174 -400.877905) (xy 174.951898 -400.877532)
			(xy 175.668178 -400.877532) (xy 175.678302 -400.878044) (xy 175.697022 -400.885763) (xy 175.711378 -400.900042)
			(xy 175.7192 -400.918718) (xy 175.71974 -400.92884) (xy 175.71974 -401.086828) (xy 175.72015 -401.096015)
			(xy 175.726665 -401.113198) (xy 175.73244 -401.120356) (xy 175.754209 -401.146024) (xy 175.792159 -401.201608)
			(xy 175.823195 -401.261329) (xy 175.846869 -401.324331) (xy 175.862844 -401.389712) (xy 175.870891 -401.456533)
			(xy 175.870892 -401.523837) (xy 175.86285 -401.590658) (xy 175.846878 -401.65604) (xy 175.823207 -401.719044)
			(xy 175.792175 -401.778766) (xy 175.754227 -401.834352) (xy 175.73244 -401.860004) (xy 175.726652 -401.867155)
			(xy 175.720134 -401.884341) (xy 175.71974 -401.893532) (xy 175.71974 -402.3868) (xy 175.720164 -402.395985)
			(xy 175.726669 -402.413169) (xy 175.73244 -402.420328) (xy 175.754181 -402.446019) (xy 175.792133 -402.501599)
			(xy 175.823169 -402.561317) (xy 175.846846 -402.624317) (xy 175.862823 -402.689694) (xy 175.870871 -402.756513)
			(xy 175.870875 -402.823815) (xy 175.862835 -402.890634) (xy 175.846867 -402.956014) (xy 175.823199 -403.019017)
			(xy 175.79217 -403.078739) (xy 175.754225 -403.134324) (xy 175.73244 -403.159976) (xy 175.726621 -403.167105)
			(xy 175.720122 -403.184308) (xy 175.71974 -403.193504) (xy 175.71974 -403.351492) (xy 175.719273 -403.361641)
			(xy 175.711487 -403.380385) (xy 175.697105 -403.394707) (xy 175.678328 -403.402415) (xy 175.668178 -403.4028)
			(xy 174.951898 -403.4028) (xy 174.941776 -403.402276) (xy 174.923063 -403.394555) (xy 174.908708 -403.380281)
			(xy 174.900882 -403.361611) (xy 174.900336 -403.351492) (xy 174.900336 -403.193504) (xy 174.899916 -403.184318)
			(xy 174.893408 -403.167134) (xy 174.887636 -403.159976) (xy 174.865801 -403.134363) (xy 174.827854 -403.078771)
			(xy 174.796823 -403.019042) (xy 174.773153 -402.956032) (xy 174.757183 -402.890645) (xy 174.749143 -402.823818)
			(xy 171.471107 -402.823818) (xy 171.471107 -402.823874) (xy 171.463035 -402.89081) (xy 171.447003 -402.956298)
			(xy 171.423242 -403.019393) (xy 171.392094 -403.079187) (xy 171.354007 -403.13482) (xy 171.332144 -403.160484)
			(xy 171.326322 -403.167611) (xy 171.319824 -403.184816) (xy 171.319444 -403.194012) (xy 171.319444 -403.351492)
			(xy 171.318909 -403.361595) (xy 171.311183 -403.380264) (xy 171.296901 -403.394558) (xy 171.278238 -403.402301)
			(xy 171.268136 -403.4028) (xy 170.551856 -403.4028) (xy 170.541744 -403.402351) (xy 170.523065 -403.394599)
			(xy 170.508772 -403.380291) (xy 170.501039 -403.361604) (xy 170.500548 -403.351492) (xy 170.500548 -403.194012)
			(xy 170.500121 -403.184827) (xy 170.493618 -403.167643) (xy 170.487848 -403.160484) (xy 170.465935 -403.134858)
			(xy 170.427845 -403.079219) (xy 170.396693 -403.019418) (xy 170.37293 -402.956316) (xy 170.356896 -402.890822)
			(xy 170.348823 -402.823878) (xy 167.070779 -402.823878) (xy 167.062748 -402.890634) (xy 167.04678 -402.956014)
			(xy 167.023112 -403.019016) (xy 166.992084 -403.078738) (xy 166.954141 -403.134324) (xy 166.932356 -403.159976)
			(xy 166.926539 -403.167107) (xy 166.920038 -403.184308) (xy 166.919656 -403.193504) (xy 166.919656 -403.351492)
			(xy 166.919173 -403.361639) (xy 166.911391 -403.38038) (xy 166.897014 -403.394702) (xy 166.878242 -403.402412)
			(xy 166.868094 -403.4028) (xy 166.151814 -403.4028) (xy 166.141693 -403.402263) (xy 166.12298 -403.394547)
			(xy 166.108624 -403.380277) (xy 166.100798 -403.36161) (xy 166.100252 -403.351492) (xy 166.100252 -403.193504)
			(xy 166.099828 -403.184318) (xy 166.093323 -403.167135) (xy 166.087552 -403.159976) (xy 166.065717 -403.134363)
			(xy 166.027768 -403.078771) (xy 165.996736 -403.019042) (xy 165.973066 -402.956033) (xy 165.957096 -402.890646)
			(xy 165.949055 -402.823818) (xy 162.671019 -402.823818) (xy 162.671019 -402.823874) (xy 162.662948 -402.89081)
			(xy 162.646916 -402.956297) (xy 162.623155 -403.019392) (xy 162.592008 -403.079187) (xy 162.553923 -403.13482)
			(xy 162.53206 -403.160484) (xy 162.52624 -403.167613) (xy 162.51974 -403.184816) (xy 162.51936 -403.194012)
			(xy 162.51936 -403.351492) (xy 162.518976 -403.361619) (xy 162.511224 -403.38033) (xy 162.496896 -403.394646)
			(xy 162.478179 -403.402384) (xy 162.468052 -403.4028) (xy 161.751772 -403.4028) (xy 161.741661 -403.402338)
			(xy 161.722983 -403.394591) (xy 161.708689 -403.380287) (xy 161.700955 -403.361603) (xy 161.700464 -403.351492)
			(xy 161.700464 -403.194012) (xy 161.700034 -403.184827) (xy 161.693532 -403.167643) (xy 161.687764 -403.160484)
			(xy 161.665854 -403.134857) (xy 161.627769 -403.079216) (xy 161.596623 -403.019414) (xy 161.572863 -402.956313)
			(xy 161.556832 -402.890819) (xy 161.54876 -402.823877) (xy 154.57678 -402.823877) (xy 154.57678 -405.623648)
			(xy 159.349158 -405.623648) (xy 159.349158 -405.556343) (xy 159.357202 -405.48952) (xy 159.373175 -405.424138)
			(xy 159.396848 -405.361133) (xy 159.427881 -405.301409) (xy 159.465829 -405.245822) (xy 159.487616 -405.22017)
			(xy 159.49341 -405.213023) (xy 159.499926 -405.195834) (xy 159.500316 -405.186642) (xy 159.500316 -404.693374)
			(xy 159.499915 -404.684186) (xy 159.493395 -404.667002) (xy 159.487616 -404.659846) (xy 159.465851 -404.634176)
			(xy 159.427903 -404.578591) (xy 159.39687 -404.51887) (xy 159.373197 -404.455868) (xy 159.357223 -404.390488)
			(xy 159.349177 -404.323668) (xy 159.349175 -404.256365) (xy 159.357217 -404.189544) (xy 159.373187 -404.124164)
			(xy 159.396856 -404.06116) (xy 159.427886 -404.001437) (xy 159.46583 -403.94585) (xy 159.487616 -403.920198)
			(xy 159.493398 -403.913042) (xy 159.499921 -403.89586) (xy 159.500316 -403.88667) (xy 159.500316 -403.728682)
			(xy 159.500818 -403.718526) (xy 159.508594 -403.69976) (xy 159.522957 -403.685396) (xy 159.541722 -403.677619)
			(xy 159.551878 -403.67712) (xy 160.268158 -403.67712) (xy 160.278325 -403.677598) (xy 160.297115 -403.685366)
			(xy 160.311501 -403.699735) (xy 160.31929 -403.718516) (xy 160.31972 -403.728682) (xy 160.31972 -403.88667)
			(xy 160.32014 -403.895856) (xy 160.326646 -403.913041) (xy 160.33242 -403.920198) (xy 160.354231 -403.945832)
			(xy 160.392181 -404.00142) (xy 160.423216 -404.061146) (xy 160.446889 -404.124153) (xy 160.462862 -404.189538)
			(xy 160.470905 -404.256363) (xy 160.470903 -404.32367) (xy 160.462856 -404.390495) (xy 160.446879 -404.455879)
			(xy 160.423202 -404.518885) (xy 160.392164 -404.578608) (xy 160.35421 -404.634194) (xy 160.33242 -404.659846)
			(xy 160.326624 -404.666992) (xy 160.320108 -404.684182) (xy 160.31972 -404.693374) (xy 160.31972 -405.186642)
			(xy 160.320105 -405.195832) (xy 160.326636 -405.213016) (xy 160.33242 -405.22017) (xy 160.354203 -405.245826)
			(xy 160.392155 -405.301411) (xy 160.42319 -405.361134) (xy 160.446865 -405.424138) (xy 160.46284 -405.48952)
			(xy 160.470885 -405.556343) (xy 160.470886 -405.623648) (xy 160.462842 -405.690471) (xy 160.446868 -405.755853)
			(xy 160.423194 -405.818858) (xy 160.392159 -405.878581) (xy 160.354209 -405.934166) (xy 160.33242 -405.959818)
			(xy 160.326636 -405.966972) (xy 160.320113 -405.984156) (xy 160.31972 -405.993346) (xy 160.31972 -406.151334)
			(xy 160.319363 -406.161513) (xy 160.311559 -406.180317) (xy 160.297153 -406.194702) (xy 160.278338 -406.202478)
			(xy 160.268158 -406.202896) (xy 159.551878 -406.202896) (xy 159.541723 -406.202386) (xy 159.52296 -406.19461)
			(xy 159.508596 -406.18025) (xy 159.500817 -406.161489) (xy 159.500316 -406.151334) (xy 159.500316 -405.993346)
			(xy 159.49988 -405.984162) (xy 159.493384 -405.966977) (xy 159.487616 -405.959818) (xy 159.465823 -405.93417)
			(xy 159.427876 -405.878583) (xy 159.396844 -405.818858) (xy 159.373173 -405.755853) (xy 159.357201 -405.690471)
			(xy 159.349158 -405.623648) (xy 154.57678 -405.623648) (xy 154.57678 -406.723789) (xy 161.548771 -406.723789)
			(xy 161.548774 -406.656363) (xy 161.556853 -406.589423) (xy 161.572891 -406.523933) (xy 161.596657 -406.460835)
			(xy 161.627809 -406.401038) (xy 161.665899 -406.345402) (xy 161.687764 -406.319736) (xy 161.693578 -406.312604)
			(xy 161.70008 -406.295403) (xy 161.700464 -406.286208) (xy 161.700464 -405.793956) (xy 161.700061 -405.784768)
			(xy 161.693541 -405.767585) (xy 161.687764 -405.760428) (xy 161.665897 -405.734765) (xy 161.627811 -405.67913)
			(xy 161.596663 -405.619333) (xy 161.5729 -405.556236) (xy 161.556866 -405.490747) (xy 161.548791 -405.423809)
			(xy 161.548792 -405.356385) (xy 161.556867 -405.289447) (xy 161.572902 -405.223959) (xy 161.596665 -405.160862)
			(xy 161.627814 -405.101065) (xy 161.665901 -405.04543) (xy 161.687764 -405.019764) (xy 161.693566 -405.012623)
			(xy 161.700076 -404.995429) (xy 161.700464 -404.986236) (xy 161.700464 -404.828756) (xy 161.700948 -404.818649)
			(xy 161.708694 -404.799977) (xy 161.72299 -404.785685) (xy 161.741665 -404.777945) (xy 161.751772 -404.777448)
			(xy 162.468052 -404.777448) (xy 162.478165 -404.777954) (xy 162.496858 -404.785677) (xy 162.511172 -404.799965)
			(xy 162.518928 -404.818644) (xy 162.51936 -404.828756) (xy 162.51936 -404.986236) (xy 162.519762 -404.995424)
			(xy 162.526282 -405.012608) (xy 162.53206 -405.019764) (xy 162.553921 -405.045432) (xy 162.592013 -405.101065)
			(xy 162.623166 -405.16086) (xy 162.646932 -405.223957) (xy 162.662969 -405.289446) (xy 162.671046 -405.356385)
			(xy 162.671046 -405.423809) (xy 162.66297 -405.490748) (xy 162.646934 -405.556237) (xy 162.623168 -405.619334)
			(xy 162.620889 -405.623708) (xy 163.748926 -405.623708) (xy 163.748926 -405.556283) (xy 163.757003 -405.489344)
			(xy 163.77304 -405.423855) (xy 163.796805 -405.360758) (xy 163.827957 -405.300961) (xy 163.866047 -405.245327)
			(xy 163.887912 -405.219662) (xy 163.893709 -405.212517) (xy 163.900223 -405.195326) (xy 163.900612 -405.186134)
			(xy 163.900612 -404.693882) (xy 163.900208 -404.684694) (xy 163.89369 -404.66751) (xy 163.887912 -404.660354)
			(xy 163.866069 -404.634671) (xy 163.827979 -404.579039) (xy 163.796827 -404.519246) (xy 163.773061 -404.456151)
			(xy 163.757023 -404.390664) (xy 163.748946 -404.323728) (xy 163.748944 -404.256305) (xy 163.757018 -404.189368)
			(xy 163.773051 -404.12388) (xy 163.796813 -404.060784) (xy 163.827962 -404.000989) (xy 163.866049 -403.945355)
			(xy 163.887912 -403.91969) (xy 163.893697 -403.912536) (xy 163.900218 -403.895352) (xy 163.900612 -403.886162)
			(xy 163.900612 -403.728682) (xy 163.901111 -403.718558) (xy 163.908839 -403.699841) (xy 163.923121 -403.685486)
			(xy 163.941798 -403.677663) (xy 163.95192 -403.67712) (xy 164.6682 -403.67712) (xy 164.678357 -403.677522)
			(xy 164.697113 -403.685321) (xy 164.711437 -403.699724) (xy 164.719133 -403.718523) (xy 164.719508 -403.728682)
			(xy 164.719508 -403.886162) (xy 164.719935 -403.895347) (xy 164.726437 -403.912532) (xy 164.732208 -403.91969)
			(xy 164.754093 -403.945338) (xy 164.792181 -404.000975) (xy 164.82333 -404.060774) (xy 164.847093 -404.123873)
			(xy 164.863126 -404.189364) (xy 164.8712 -404.256304) (xy 164.871198 -404.323729) (xy 164.86312 -404.390669)
			(xy 164.847083 -404.456159) (xy 164.823317 -404.519257) (xy 164.792164 -404.579054) (xy 164.754073 -404.634689)
			(xy 164.732208 -404.660354) (xy 164.726407 -404.667496) (xy 164.719895 -404.684689) (xy 164.719508 -404.693882)
			(xy 164.719508 -405.186134) (xy 164.7199 -405.195323) (xy 164.726426 -405.212508) (xy 164.732208 -405.219662)
			(xy 164.754066 -405.245332) (xy 164.792154 -405.300966) (xy 164.823305 -405.360762) (xy 164.847069 -405.423858)
			(xy 164.863104 -405.489346) (xy 164.871181 -405.556284) (xy 164.871181 -405.623707) (xy 164.863106 -405.690645)
			(xy 164.847072 -405.756133) (xy 164.823308 -405.81923) (xy 164.792159 -405.879026) (xy 164.754071 -405.934661)
			(xy 164.732208 -405.960326) (xy 164.726419 -405.967477) (xy 164.719899 -405.984663) (xy 164.719508 -405.993854)
			(xy 164.719508 -406.151334) (xy 164.719003 -406.161457) (xy 164.711273 -406.18017) (xy 164.696993 -406.194523)
			(xy 164.67832 -406.20235) (xy 164.6682 -406.202896) (xy 163.95192 -406.202896) (xy 163.941767 -406.202462)
			(xy 163.923014 -406.194672) (xy 163.90869 -406.180279) (xy 163.90099 -406.161489) (xy 163.900612 -406.151334)
			(xy 163.900612 -405.993854) (xy 163.900173 -405.98467) (xy 163.893679 -405.967485) (xy 163.887912 -405.960326)
			(xy 163.866042 -405.934666) (xy 163.827952 -405.879031) (xy 163.796801 -405.819234) (xy 163.773037 -405.756137)
			(xy 163.757001 -405.690647) (xy 163.748926 -405.623708) (xy 162.620889 -405.623708) (xy 162.592016 -405.67913)
			(xy 162.553925 -405.734763) (xy 162.53206 -405.760428) (xy 162.526264 -405.767573) (xy 162.51975 -405.784764)
			(xy 162.51936 -405.793956) (xy 162.51936 -406.286208) (xy 162.519775 -406.295394) (xy 162.526286 -406.312578)
			(xy 162.53206 -406.319736) (xy 162.553894 -406.345426) (xy 162.591986 -406.401056) (xy 162.623141 -406.460849)
			(xy 162.646908 -406.523942) (xy 162.662947 -406.589429) (xy 162.671026 -406.656365) (xy 162.671029 -406.72373)
			(xy 165.949066 -406.72373) (xy 165.949069 -406.656422) (xy 165.957117 -406.589597) (xy 165.973094 -406.524213)
			(xy 165.996771 -406.461207) (xy 166.027808 -406.401483) (xy 166.065762 -406.345896) (xy 166.087552 -406.320244)
			(xy 166.093361 -406.313108) (xy 166.099867 -406.29591) (xy 166.100252 -406.286716) (xy 166.100252 -405.793448)
			(xy 166.099807 -405.784265) (xy 166.093316 -405.767081) (xy 166.087552 -405.75992) (xy 166.06576 -405.734271)
			(xy 166.027811 -405.678685) (xy 165.996777 -405.618961) (xy 165.973104 -405.555956) (xy 165.957131 -405.490573)
			(xy 165.949087 -405.42375) (xy 165.949087 -405.356444) (xy 165.957132 -405.289621) (xy 165.973105 -405.224239)
			(xy 165.996779 -405.161234) (xy 166.027814 -405.10151) (xy 166.065764 -405.045924) (xy 166.087552 -405.020272)
			(xy 166.093349 -405.013128) (xy 166.099862 -404.995936) (xy 166.100252 -404.986744) (xy 166.100252 -404.828756)
			(xy 166.100685 -404.818605) (xy 166.108486 -404.799861) (xy 166.122878 -404.785541) (xy 166.141661 -404.777834)
			(xy 166.151814 -404.777448) (xy 166.868094 -404.777448) (xy 166.878221 -404.777932) (xy 166.896944 -404.785659)
			(xy 166.911301 -404.799946) (xy 166.919119 -404.818631) (xy 166.919656 -404.828756) (xy 166.919656 -404.986744)
			(xy 166.920055 -404.995932) (xy 166.926578 -405.013116) (xy 166.932356 -405.020272) (xy 166.95414 -405.045927)
			(xy 166.992089 -405.101513) (xy 167.023123 -405.161236) (xy 167.046796 -405.22424) (xy 167.062769 -405.289622)
			(xy 167.070814 -405.356445) (xy 167.070814 -405.423749) (xy 167.06277 -405.490572) (xy 167.046798 -405.555954)
			(xy 167.023125 -405.618958) (xy 167.020688 -405.623648) (xy 168.149245 -405.623648) (xy 168.149246 -405.556343)
			(xy 168.15729 -405.489521) (xy 168.173263 -405.424139) (xy 168.196934 -405.361134) (xy 168.227966 -405.30141)
			(xy 168.265913 -405.245823) (xy 168.2877 -405.22017) (xy 168.293492 -405.213021) (xy 168.300009 -405.195834)
			(xy 168.3004 -405.186642) (xy 168.3004 -404.693374) (xy 168.300003 -404.684185) (xy 168.29348 -404.667001)
			(xy 168.2877 -404.659846) (xy 168.265935 -404.634176) (xy 168.227988 -404.578591) (xy 168.196956 -404.518869)
			(xy 168.173284 -404.455867) (xy 168.15731 -404.390488) (xy 168.149265 -404.323668) (xy 168.149263 -404.256365)
			(xy 168.157305 -404.189545) (xy 168.173274 -404.124164) (xy 168.196943 -404.061161) (xy 168.227971 -404.001438)
			(xy 168.265915 -403.945851) (xy 168.2877 -403.920198) (xy 168.29348 -403.913041) (xy 168.300005 -403.89586)
			(xy 168.3004 -403.88667) (xy 168.3004 -403.728682) (xy 168.300917 -403.718528) (xy 168.308691 -403.699765)
			(xy 168.323049 -403.685402) (xy 168.341808 -403.677621) (xy 168.351962 -403.67712) (xy 169.068242 -403.67712)
			(xy 169.0784 -403.677599) (xy 169.097167 -403.685383) (xy 169.11153 -403.699753) (xy 169.119306 -403.718524)
			(xy 169.119804 -403.728682) (xy 169.119804 -403.88667) (xy 169.120228 -403.895856) (xy 169.126732 -403.91304)
			(xy 169.132504 -403.920198) (xy 169.154312 -403.945833) (xy 169.192257 -404.001423) (xy 169.223287 -404.061149)
			(xy 169.246957 -404.124156) (xy 169.262927 -404.18954) (xy 169.270969 -404.256364) (xy 169.270967 -404.32367)
			(xy 169.262921 -404.390493) (xy 169.246947 -404.455876) (xy 169.223274 -404.518881) (xy 169.19224 -404.578606)
			(xy 169.154292 -404.634193) (xy 169.132504 -404.659846) (xy 169.126706 -404.66699) (xy 169.120192 -404.684181)
			(xy 169.119804 -404.693374) (xy 169.119804 -405.186642) (xy 169.120193 -405.195832) (xy 169.126721 -405.213016)
			(xy 169.132504 -405.22017) (xy 169.154284 -405.245828) (xy 169.192231 -405.301414) (xy 169.223262 -405.361137)
			(xy 169.246933 -405.424141) (xy 169.262905 -405.489522) (xy 169.270949 -405.556344) (xy 169.27095 -405.623647)
			(xy 169.262907 -405.690469) (xy 169.246936 -405.75585) (xy 169.223266 -405.818854) (xy 169.192235 -405.878578)
			(xy 169.15429 -405.934165) (xy 169.132504 -405.959818) (xy 169.126718 -405.966971) (xy 169.120197 -405.984155)
			(xy 169.119804 -405.993346) (xy 169.119804 -406.151334) (xy 169.119296 -406.161489) (xy 169.111518 -406.180251)
			(xy 169.097157 -406.194613) (xy 169.078397 -406.202394) (xy 169.068242 -406.202896) (xy 168.351962 -406.202896)
			(xy 168.341806 -406.202399) (xy 168.323042 -406.194618) (xy 168.30868 -406.180254) (xy 168.300901 -406.16149)
			(xy 168.3004 -406.151334) (xy 168.3004 -405.993346) (xy 168.299968 -405.984161) (xy 168.293469 -405.966977)
			(xy 168.2877 -405.959818) (xy 168.265908 -405.93417) (xy 168.227961 -405.878582) (xy 168.196931 -405.818858)
			(xy 168.17326 -405.755853) (xy 168.157289 -405.69047) (xy 168.149245 -405.623648) (xy 167.020688 -405.623648)
			(xy 166.992092 -405.678681) (xy 166.954143 -405.734268) (xy 166.932356 -405.75992) (xy 166.926563 -405.767067)
			(xy 166.920047 -405.784256) (xy 166.919656 -405.793448) (xy 166.919656 -406.286716) (xy 166.920068 -406.295903)
			(xy 166.926582 -406.313087) (xy 166.932356 -406.320244) (xy 166.954112 -406.345922) (xy 166.992062 -406.401505)
			(xy 167.023097 -406.461225) (xy 167.046772 -406.524226) (xy 167.062747 -406.589605) (xy 167.070794 -406.656425)
			(xy 167.070797 -406.723727) (xy 167.070789 -406.72379) (xy 170.348835 -406.72379) (xy 170.348838 -406.656362)
			(xy 170.356917 -406.589421) (xy 170.372958 -406.52393) (xy 170.396728 -406.460831) (xy 170.427885 -406.401034)
			(xy 170.46598 -406.3454) (xy 170.487848 -406.319736) (xy 170.49366 -406.312602) (xy 170.500164 -406.295403)
			(xy 170.500548 -406.286208) (xy 170.500548 -405.793956) (xy 170.500148 -405.784768) (xy 170.493626 -405.767584)
			(xy 170.487848 -405.760428) (xy 170.465978 -405.734767) (xy 170.427887 -405.679133) (xy 170.396733 -405.619337)
			(xy 170.372967 -405.556239) (xy 170.356931 -405.490749) (xy 170.348854 -405.423809) (xy 170.348855 -405.356385)
			(xy 170.356932 -405.289445) (xy 170.372969 -405.223955) (xy 170.396736 -405.160858) (xy 170.42789 -405.101062)
			(xy 170.465982 -405.045428) (xy 170.487848 -405.019764) (xy 170.493648 -405.012622) (xy 170.500159 -404.995429)
			(xy 170.500548 -404.986236) (xy 170.500548 -404.828756) (xy 170.501048 -404.818651) (xy 170.50879 -404.799982)
			(xy 170.523082 -404.78569) (xy 170.541751 -404.777948) (xy 170.551856 -404.777448) (xy 171.268136 -404.777448)
			(xy 171.278241 -404.777954) (xy 171.29691 -404.785694) (xy 171.311201 -404.799984) (xy 171.318944 -404.818651)
			(xy 171.319444 -404.828756) (xy 171.319444 -404.986236) (xy 171.31985 -404.995423) (xy 171.326368 -405.012607)
			(xy 171.332144 -405.019764) (xy 171.354006 -405.045432) (xy 171.392099 -405.101064) (xy 171.423253 -405.16086)
			(xy 171.447019 -405.223956) (xy 171.463057 -405.289446) (xy 171.471134 -405.356385) (xy 171.471134 -405.423809)
			(xy 171.463058 -405.490748) (xy 171.447021 -405.556238) (xy 171.423255 -405.619335) (xy 171.421007 -405.623649)
			(xy 172.549012 -405.623649) (xy 172.549013 -405.556342) (xy 172.557058 -405.489518) (xy 172.573033 -405.424135)
			(xy 172.596709 -405.36113) (xy 172.627746 -405.301407) (xy 172.665698 -405.245822) (xy 172.687488 -405.22017)
			(xy 172.693278 -405.21302) (xy 172.699797 -405.195833) (xy 172.700188 -405.186642) (xy 172.700188 -404.693374)
			(xy 172.699793 -404.684185) (xy 172.693269 -404.667001) (xy 172.687488 -404.659846) (xy 172.66572 -404.634177)
			(xy 172.627768 -404.578594) (xy 172.596731 -404.518873) (xy 172.573055 -404.455871) (xy 172.557079 -404.39049)
			(xy 172.549032 -404.323669) (xy 172.54903 -404.256364) (xy 172.557073 -404.189542) (xy 172.573045 -404.124161)
			(xy 172.596717 -404.061157) (xy 172.627751 -404.001435) (xy 172.6657 -403.945849) (xy 172.687488 -403.920198)
			(xy 172.693267 -403.91304) (xy 172.699792 -403.895859) (xy 172.700188 -403.88667) (xy 172.700188 -403.728682)
			(xy 172.70055 -403.718503) (xy 172.708351 -403.699698) (xy 172.722756 -403.685313) (xy 172.74157 -403.677537)
			(xy 172.75175 -403.67712) (xy 173.46803 -403.67712) (xy 173.478187 -403.677608) (xy 173.496954 -403.685389)
			(xy 173.511317 -403.699756) (xy 173.519094 -403.718524) (xy 173.519592 -403.728682) (xy 173.519592 -403.88667)
			(xy 173.520018 -403.895855) (xy 173.526521 -403.91304) (xy 173.532292 -403.920198) (xy 173.5541 -403.945833)
			(xy 173.592047 -404.001422) (xy 173.623077 -404.061149) (xy 173.646747 -404.124155) (xy 173.662718 -404.189539)
			(xy 173.67076 -404.256363) (xy 173.670758 -404.32367) (xy 173.662712 -404.390493) (xy 173.646738 -404.455876)
			(xy 173.623064 -404.518882) (xy 173.59203 -404.578606) (xy 173.55408 -404.634193) (xy 173.532292 -404.659846)
			(xy 173.526492 -404.666989) (xy 173.51998 -404.684181) (xy 173.519592 -404.693374) (xy 173.519592 -405.186642)
			(xy 173.519984 -405.195831) (xy 173.52651 -405.213015) (xy 173.532292 -405.22017) (xy 173.554073 -405.245827)
			(xy 173.59202 -405.301414) (xy 173.623052 -405.361137) (xy 173.646723 -405.424141) (xy 173.662696 -405.489522)
			(xy 173.67074 -405.556343) (xy 173.670741 -405.623647) (xy 173.662698 -405.690469) (xy 173.646726 -405.755851)
			(xy 173.623055 -405.818855) (xy 173.592025 -405.878578) (xy 173.554078 -405.934165) (xy 173.532292 -405.959818)
			(xy 173.526504 -405.96697) (xy 173.519985 -405.984155) (xy 173.519592 -405.993346) (xy 173.519592 -406.151334)
			(xy 173.519095 -406.16149) (xy 173.511315 -406.180254) (xy 173.496951 -406.194617) (xy 173.478186 -406.202396)
			(xy 173.46803 -406.202896) (xy 172.75175 -406.202896) (xy 172.741586 -406.202396) (xy 172.722799 -406.194634)
			(xy 172.708413 -406.180272) (xy 172.70062 -406.161497) (xy 172.700188 -406.151334) (xy 172.700188 -405.993346)
			(xy 172.699759 -405.984161) (xy 172.693259 -405.966976) (xy 172.687488 -405.959818) (xy 172.665693 -405.934171)
			(xy 172.627741 -405.878585) (xy 172.596705 -405.818861) (xy 172.573031 -405.755856) (xy 172.557057 -405.690473)
			(xy 172.549012 -405.623649) (xy 171.421007 -405.623649) (xy 171.392102 -405.67913) (xy 171.35401 -405.734764)
			(xy 171.332144 -405.760428) (xy 171.326346 -405.767572) (xy 171.319834 -405.784764) (xy 171.319444 -405.793956)
			(xy 171.319444 -406.286208) (xy 171.319863 -406.295394) (xy 171.326372 -406.312578) (xy 171.332144 -406.319736)
			(xy 171.353978 -406.345426) (xy 171.392072 -406.401056) (xy 171.423227 -406.460848) (xy 171.446996 -406.523942)
			(xy 171.463035 -406.589428) (xy 171.471114 -406.656365) (xy 171.471117 -406.72373) (xy 174.749154 -406.72373)
			(xy 174.749157 -406.656422) (xy 174.757205 -406.589597) (xy 174.773181 -406.524213) (xy 174.796857 -406.461208)
			(xy 174.827894 -406.401483) (xy 174.865846 -406.345896) (xy 174.887636 -406.320244) (xy 174.893443 -406.313107)
			(xy 174.899951 -406.29591) (xy 174.900336 -406.286716) (xy 174.900336 -405.793448) (xy 174.899895 -405.784264)
			(xy 174.893402 -405.76708) (xy 174.887636 -405.75992) (xy 174.865844 -405.734271) (xy 174.827896 -405.678684)
			(xy 174.796863 -405.61896) (xy 174.77319 -405.555955) (xy 174.757218 -405.490573) (xy 174.749174 -405.42375)
			(xy 174.749174 -405.356444) (xy 174.757219 -405.289621) (xy 174.773192 -405.224239) (xy 174.796865 -405.161234)
			(xy 174.827899 -405.101511) (xy 174.865848 -405.045924) (xy 174.887636 -405.020272) (xy 174.893432 -405.013126)
			(xy 174.899946 -404.995936) (xy 174.900336 -404.986744) (xy 174.900336 -404.828756) (xy 174.900686 -404.818594)
			(xy 174.908503 -404.799834) (xy 174.922922 -404.785511) (xy 174.941734 -404.77782) (xy 174.951898 -404.777448)
			(xy 175.668178 -404.777448) (xy 175.678304 -404.777945) (xy 175.697027 -404.785667) (xy 175.711384 -404.79995)
			(xy 175.719202 -404.818632) (xy 175.71974 -404.828756) (xy 175.71974 -404.986744) (xy 175.720142 -404.995932)
			(xy 175.726663 -405.013115) (xy 175.73244 -405.020272) (xy 175.754224 -405.045927) (xy 175.792175 -405.101513)
			(xy 175.823209 -405.161236) (xy 175.846883 -405.22424) (xy 175.862857 -405.289622) (xy 175.870902 -405.356444)
			(xy 175.870902 -405.42375) (xy 175.862858 -405.490572) (xy 175.846885 -405.555954) (xy 175.823212 -405.618959)
			(xy 175.792178 -405.678682) (xy 175.754228 -405.734268) (xy 175.73244 -405.75992) (xy 175.726645 -405.767066)
			(xy 175.720131 -405.784256) (xy 175.71974 -405.793448) (xy 175.71974 -406.286716) (xy 175.720156 -406.295902)
			(xy 175.726667 -406.313086) (xy 175.73244 -406.320244) (xy 175.754197 -406.345922) (xy 175.792148 -406.401504)
			(xy 175.823184 -406.461224) (xy 175.846859 -406.524225) (xy 175.862835 -406.589604) (xy 175.870882 -406.656424)
			(xy 175.870885 -406.723727) (xy 175.862844 -406.790548) (xy 175.846873 -406.855929) (xy 175.823203 -406.918932)
			(xy 175.792173 -406.978655) (xy 175.754226 -407.03424) (xy 175.73244 -407.059892) (xy 175.726657 -407.067046)
			(xy 175.720136 -407.08423) (xy 175.71974 -407.09342) (xy 175.71974 -407.251408) (xy 175.719286 -407.261558)
			(xy 175.711495 -407.280302) (xy 175.697109 -407.294624) (xy 175.678329 -407.302331) (xy 175.668178 -407.302716)
			(xy 174.951898 -407.302716) (xy 174.941766 -407.302274) (xy 174.923036 -407.294537) (xy 174.908679 -407.280237)
			(xy 174.900867 -407.261538) (xy 174.900336 -407.251408) (xy 174.900336 -407.09342) (xy 174.899908 -407.084235)
			(xy 174.893406 -407.067051) (xy 174.887636 -407.059892) (xy 174.865817 -407.034266) (xy 174.827869 -406.978676)
			(xy 174.796837 -406.918948) (xy 174.773167 -406.85594) (xy 174.757196 -406.790555) (xy 174.749154 -406.72373)
			(xy 171.471117 -406.72373) (xy 171.471117 -406.723787) (xy 171.463044 -406.790724) (xy 171.44701 -406.856212)
			(xy 171.423247 -406.919308) (xy 171.392097 -406.979103) (xy 171.354008 -407.034736) (xy 171.332144 -407.0604)
			(xy 171.326358 -407.067552) (xy 171.319839 -407.084738) (xy 171.319444 -407.093928) (xy 171.319444 -407.251408)
			(xy 171.318922 -407.261512) (xy 171.31119 -407.280182) (xy 171.296905 -407.294475) (xy 171.278239 -407.302217)
			(xy 171.268136 -407.302716) (xy 170.551856 -407.302716) (xy 170.541746 -407.302251) (xy 170.52307 -407.294502)
			(xy 170.508778 -407.280199) (xy 170.501042 -407.261518) (xy 170.500548 -407.251408) (xy 170.500548 -407.093928)
			(xy 170.500114 -407.084744) (xy 170.493616 -407.067559) (xy 170.487848 -407.0604) (xy 170.465951 -407.034762)
			(xy 170.42786 -406.979124) (xy 170.396708 -406.919325) (xy 170.372944 -406.856224) (xy 170.356909 -406.790732)
			(xy 170.348835 -406.72379) (xy 167.070789 -406.72379) (xy 167.062756 -406.790548) (xy 167.046786 -406.855928)
			(xy 167.023117 -406.918931) (xy 166.992087 -406.978654) (xy 166.954142 -407.03424) (xy 166.932356 -407.059892)
			(xy 166.926575 -407.067048) (xy 166.920052 -407.08423) (xy 166.919656 -407.09342) (xy 166.919656 -407.251408)
			(xy 166.919186 -407.261556) (xy 166.911398 -407.280297) (xy 166.897017 -407.294618) (xy 166.878243 -407.302328)
			(xy 166.868094 -407.302716) (xy 166.151814 -407.302716) (xy 166.141683 -407.302261) (xy 166.122954 -407.294529)
			(xy 166.108595 -407.280233) (xy 166.100783 -407.261537) (xy 166.100252 -407.251408) (xy 166.100252 -407.09342)
			(xy 166.099821 -407.084235) (xy 166.093321 -407.067051) (xy 166.087552 -407.059892) (xy 166.065732 -407.034266)
			(xy 166.027784 -406.978676) (xy 165.996751 -406.918949) (xy 165.973079 -406.855941) (xy 165.957108 -406.790556)
			(xy 165.949066 -406.72373) (xy 162.671029 -406.72373) (xy 162.671029 -406.723787) (xy 162.662956 -406.790724)
			(xy 162.646923 -406.856212) (xy 162.62316 -406.919307) (xy 162.592011 -406.979102) (xy 162.553923 -407.034735)
			(xy 162.53206 -407.0604) (xy 162.526276 -407.067554) (xy 162.519755 -407.084738) (xy 162.51936 -407.093928)
			(xy 162.51936 -407.251408) (xy 162.518989 -407.261536) (xy 162.511231 -407.280247) (xy 162.4969 -407.294563)
			(xy 162.47818 -407.3023) (xy 162.468052 -407.302716) (xy 161.751772 -407.302716) (xy 161.741663 -407.302238)
			(xy 161.722988 -407.294494) (xy 161.708694 -407.280196) (xy 161.700958 -407.261517) (xy 161.700464 -407.251408)
			(xy 161.700464 -407.093928) (xy 161.700026 -407.084744) (xy 161.69353 -407.06756) (xy 161.687764 -407.0604)
			(xy 161.66587 -407.03476) (xy 161.627784 -406.979121) (xy 161.596637 -406.919321) (xy 161.572876 -406.856221)
			(xy 161.556844 -406.790729) (xy 161.548771 -406.723789) (xy 154.57678 -406.723789) (xy 154.57678 -409.523827)
			(xy 159.349136 -409.523827) (xy 159.34914 -409.456519) (xy 159.357187 -409.389695) (xy 159.373163 -409.324311)
			(xy 159.396839 -409.261305) (xy 159.427875 -409.20158) (xy 159.465827 -409.145992) (xy 159.487616 -409.12034)
			(xy 159.493422 -409.113202) (xy 159.499931 -409.096006) (xy 159.500316 -409.086812) (xy 159.500316 -408.593544)
			(xy 159.499881 -408.58436) (xy 159.493384 -408.567175) (xy 159.487616 -408.560016) (xy 159.465821 -408.53437)
			(xy 159.427874 -408.478782) (xy 159.396842 -408.419058) (xy 159.373171 -408.356052) (xy 159.357199 -408.29067)
			(xy 159.349156 -408.223847) (xy 159.349157 -408.156541) (xy 159.357201 -408.089719) (xy 159.373175 -408.024336)
			(xy 159.396847 -407.961331) (xy 159.42788 -407.901607) (xy 159.465828 -407.84602) (xy 159.487616 -407.820368)
			(xy 159.49341 -407.813221) (xy 159.499926 -407.796032) (xy 159.500316 -407.78684) (xy 159.500316 -407.628852)
			(xy 159.500683 -407.618693) (xy 159.508497 -407.599936) (xy 159.522911 -407.585614) (xy 159.541716 -407.577919)
			(xy 159.551878 -407.577544) (xy 160.268158 -407.577544) (xy 160.278283 -407.578061) (xy 160.297003 -407.585776)
			(xy 160.311361 -407.600053) (xy 160.319181 -407.61873) (xy 160.31972 -407.628852) (xy 160.31972 -407.78684)
			(xy 160.320107 -407.79603) (xy 160.326636 -407.813214) (xy 160.33242 -407.820368) (xy 160.354201 -407.846026)
			(xy 160.392153 -407.901611) (xy 160.423189 -407.961333) (xy 160.446864 -408.024337) (xy 160.462838 -408.089719)
			(xy 160.470884 -408.156541) (xy 160.470885 -408.223847) (xy 160.462841 -408.290669) (xy 160.446867 -408.356052)
			(xy 160.423194 -408.419056) (xy 160.392159 -408.478779) (xy 160.354208 -408.534364) (xy 160.33242 -408.560016)
			(xy 160.326636 -408.567171) (xy 160.320113 -408.584354) (xy 160.31972 -408.593544) (xy 160.31972 -409.086812)
			(xy 160.32012 -409.096) (xy 160.32664 -409.113185) (xy 160.33242 -409.12034) (xy 160.354174 -409.146021)
			(xy 160.392126 -409.201602) (xy 160.423163 -409.261321) (xy 160.44684 -409.324322) (xy 160.462817 -409.389701)
			(xy 160.470864 -409.456521) (xy 160.470867 -409.523824) (xy 160.462826 -409.590645) (xy 160.446856 -409.656026)
			(xy 160.423185 -409.719029) (xy 160.392154 -409.778751) (xy 160.354207 -409.834336) (xy 160.33242 -409.859988)
			(xy 160.326606 -409.867121) (xy 160.320101 -409.884321) (xy 160.31972 -409.893516) (xy 160.31972 -410.051504)
			(xy 160.319282 -410.061656) (xy 160.311489 -410.080404) (xy 160.297098 -410.094727) (xy 160.278312 -410.10243)
			(xy 160.268158 -410.102812) (xy 159.551878 -410.102812) (xy 159.541756 -410.102293) (xy 159.523044 -410.094568)
			(xy 159.508691 -410.080292) (xy 159.500863 -410.061623) (xy 159.500316 -410.051504) (xy 159.500316 -409.893516)
			(xy 159.499894 -409.88433) (xy 159.493388 -409.867146) (xy 159.487616 -409.859988) (xy 159.465794 -409.834365)
			(xy 159.427847 -409.778774) (xy 159.396817 -409.719046) (xy 159.373147 -409.656038) (xy 159.357177 -409.590652)
			(xy 159.349136 -409.523827) (xy 154.57678 -409.523827) (xy 154.57678 -410.6237) (xy 161.548783 -410.6237)
			(xy 161.548784 -410.556276) (xy 161.556861 -410.489337) (xy 161.572897 -410.423848) (xy 161.596662 -410.36075)
			(xy 161.627812 -410.300953) (xy 161.6659 -410.245318) (xy 161.687764 -410.219652) (xy 161.693571 -410.212515)
			(xy 161.700078 -410.195318) (xy 161.700464 -410.186124) (xy 161.700464 -409.693872) (xy 161.700053 -409.684685)
			(xy 161.693538 -409.667502) (xy 161.687764 -409.660344) (xy 161.665913 -409.634668) (xy 161.627826 -409.579035)
			(xy 161.596677 -409.519239) (xy 161.572914 -409.456144) (xy 161.556879 -409.390657) (xy 161.548802 -409.32372)
			(xy 161.548801 -409.256298) (xy 161.556875 -409.189361) (xy 161.572909 -409.123873) (xy 161.59667 -409.060777)
			(xy 161.627817 -409.000981) (xy 161.665902 -408.945346) (xy 161.687764 -408.91968) (xy 161.693559 -408.912534)
			(xy 161.700073 -408.895344) (xy 161.700464 -408.886152) (xy 161.700464 -408.728672) (xy 161.700961 -408.718566)
			(xy 161.708701 -408.699894) (xy 161.722994 -408.685601) (xy 161.741666 -408.677861) (xy 161.751772 -408.677364)
			(xy 162.468052 -408.677364) (xy 162.478167 -408.677854) (xy 162.496863 -408.68558) (xy 162.511177 -408.699874)
			(xy 162.518931 -408.718558) (xy 162.51936 -408.728672) (xy 162.51936 -408.886152) (xy 162.519802 -408.895336)
			(xy 162.526295 -408.91252) (xy 162.53206 -408.91968) (xy 162.553937 -408.945335) (xy 162.592028 -409.00097)
			(xy 162.623181 -409.060767) (xy 162.646946 -409.123866) (xy 162.662982 -409.189356) (xy 162.671057 -409.256296)
			(xy 162.671056 -409.323722) (xy 162.662978 -409.390662) (xy 162.64694 -409.456152) (xy 162.623173 -409.519249)
			(xy 162.620757 -409.523886) (xy 163.748905 -409.523886) (xy 163.748908 -409.45646) (xy 163.756988 -409.389519)
			(xy 163.773027 -409.324027) (xy 163.796796 -409.260929) (xy 163.827952 -409.201132) (xy 163.866045 -409.145497)
			(xy 163.887912 -409.119832) (xy 163.893721 -409.112696) (xy 163.900228 -409.095498) (xy 163.900612 -409.086304)
			(xy 163.900612 -408.594052) (xy 163.900174 -408.584868) (xy 163.893679 -408.567683) (xy 163.887912 -408.560524)
			(xy 163.86604 -408.534865) (xy 163.82795 -408.47923) (xy 163.796799 -408.419433) (xy 163.773035 -408.356335)
			(xy 163.757 -408.290845) (xy 163.748925 -408.223906) (xy 163.748925 -408.156482) (xy 163.757002 -408.089543)
			(xy 163.773039 -408.024053) (xy 163.796804 -407.960956) (xy 163.827957 -407.901159) (xy 163.866047 -407.845525)
			(xy 163.887912 -407.81986) (xy 163.893709 -407.812715) (xy 163.900223 -407.795524) (xy 163.900612 -407.786332)
			(xy 163.900612 -407.628852) (xy 163.901046 -407.618739) (xy 163.908802 -407.600057) (xy 163.923114 -407.585764)
			(xy 163.941806 -407.578033) (xy 163.95192 -407.577544) (xy 164.6682 -407.577544) (xy 164.678302 -407.578084)
			(xy 164.696969 -407.585811) (xy 164.711262 -407.60009) (xy 164.719007 -407.618751) (xy 164.719508 -407.628852)
			(xy 164.719508 -407.786332) (xy 164.719901 -407.795521) (xy 164.726426 -407.812705) (xy 164.732208 -407.81986)
			(xy 164.754064 -407.845532) (xy 164.792152 -407.901166) (xy 164.823303 -407.960961) (xy 164.847067 -408.024057)
			(xy 164.863103 -408.089545) (xy 164.871179 -408.156483) (xy 164.87118 -408.223905) (xy 164.863105 -408.290843)
			(xy 164.847071 -408.356332) (xy 164.823308 -408.419428) (xy 164.792158 -408.479224) (xy 164.754071 -408.534859)
			(xy 164.732208 -408.560524) (xy 164.72642 -408.567675) (xy 164.7199 -408.584861) (xy 164.719508 -408.594052)
			(xy 164.719508 -409.086304) (xy 164.719915 -409.095492) (xy 164.726431 -409.112676) (xy 164.732208 -409.119832)
			(xy 164.754036 -409.145527) (xy 164.792126 -409.201157) (xy 164.823277 -409.260949) (xy 164.847043 -409.324042)
			(xy 164.863081 -409.389528) (xy 164.87116 -409.456463) (xy 164.871163 -409.523883) (xy 164.863091 -409.590819)
			(xy 164.847059 -409.656306) (xy 164.8233 -409.719401) (xy 164.792153 -409.779196) (xy 164.75407 -409.834831)
			(xy 164.732208 -409.860496) (xy 164.726432 -409.867656) (xy 164.719905 -409.884835) (xy 164.719508 -409.894024)
			(xy 164.719508 -410.051504) (xy 164.719018 -410.061612) (xy 164.711281 -410.080289) (xy 164.696985 -410.094583)
			(xy 164.678308 -410.102319) (xy 164.6682 -410.102812) (xy 163.95192 -410.102812) (xy 163.9418 -410.102368)
			(xy 163.923099 -410.094629) (xy 163.908785 -410.080321) (xy 163.901037 -410.061624) (xy 163.900612 -410.051504)
			(xy 163.900612 -409.894024) (xy 163.900188 -409.884838) (xy 163.893683 -409.867654) (xy 163.887912 -409.860496)
			(xy 163.866012 -409.83486) (xy 163.827924 -409.779222) (xy 163.796774 -409.719422) (xy 163.773011 -409.656321)
			(xy 163.756978 -409.590828) (xy 163.748905 -409.523886) (xy 162.620757 -409.523886) (xy 162.592019 -409.579046)
			(xy 162.553926 -409.634679) (xy 162.53206 -409.660344) (xy 162.526257 -409.667485) (xy 162.519747 -409.684679)
			(xy 162.51936 -409.693872) (xy 162.51936 -410.186124) (xy 162.519768 -410.195311) (xy 162.526284 -410.212495)
			(xy 162.53206 -410.219652) (xy 162.55391 -410.24533) (xy 162.592001 -410.300961) (xy 162.623155 -410.360755)
			(xy 162.646922 -410.423851) (xy 162.66296 -410.489339) (xy 162.671038 -410.556276) (xy 162.671039 -410.623641)
			(xy 165.949078 -410.623641) (xy 165.949079 -410.556335) (xy 165.957125 -410.489511) (xy 165.9731 -410.424127)
			(xy 165.996775 -410.361122) (xy 166.027811 -410.301398) (xy 166.065763 -410.245812) (xy 166.087552 -410.22016)
			(xy 166.093354 -410.213019) (xy 166.099864 -410.195825) (xy 166.100252 -410.186632) (xy 166.100252 -409.693364)
			(xy 166.099847 -409.684176) (xy 166.093328 -409.666993) (xy 166.087552 -409.659836) (xy 166.065776 -409.634174)
			(xy 166.027826 -409.578589) (xy 165.996791 -409.518867) (xy 165.973117 -409.455864) (xy 165.957143 -409.390483)
			(xy 165.949098 -409.323661) (xy 165.949097 -409.256357) (xy 165.95714 -409.189535) (xy 165.973112 -409.124153)
			(xy 165.996784 -409.061149) (xy 166.027817 -409.001426) (xy 166.065765 -408.94584) (xy 166.087552 -408.920188)
			(xy 166.093343 -408.913039) (xy 166.099859 -408.895851) (xy 166.100252 -408.88666) (xy 166.100252 -408.728672)
			(xy 166.100698 -408.718522) (xy 166.108493 -408.699778) (xy 166.122882 -408.685458) (xy 166.141662 -408.67775)
			(xy 166.151814 -408.677364) (xy 166.868094 -408.677364) (xy 166.878223 -408.677832) (xy 166.896949 -408.685562)
			(xy 166.911306 -408.699855) (xy 166.919121 -408.718545) (xy 166.919656 -408.728672) (xy 166.919656 -408.88666)
			(xy 166.920095 -408.895844) (xy 166.92659 -408.913028) (xy 166.932356 -408.920188) (xy 166.954156 -408.94583)
			(xy 166.992105 -409.001418) (xy 167.023138 -409.061143) (xy 167.04681 -409.124149) (xy 167.062782 -409.189532)
			(xy 167.070826 -409.256356) (xy 167.070824 -409.323662) (xy 167.062779 -409.390486) (xy 167.046805 -409.455869)
			(xy 167.02313 -409.518874) (xy 167.020557 -409.523826) (xy 168.149224 -409.523826) (xy 168.149228 -409.456519)
			(xy 168.157275 -409.389695) (xy 168.17325 -409.324311) (xy 168.196925 -409.261305) (xy 168.227961 -409.201581)
			(xy 168.265911 -409.145993) (xy 168.2877 -409.12034) (xy 168.293505 -409.1132) (xy 168.300014 -409.096006)
			(xy 168.3004 -409.086812) (xy 168.3004 -408.593544) (xy 168.299969 -408.584359) (xy 168.29347 -408.567174)
			(xy 168.2877 -408.560016) (xy 168.265906 -408.53437) (xy 168.22796 -408.478782) (xy 168.196929 -408.419057)
			(xy 168.173258 -408.356052) (xy 168.157287 -408.290669) (xy 168.149244 -408.223846) (xy 168.149245 -408.156542)
			(xy 168.157289 -408.089719) (xy 168.173262 -408.024337) (xy 168.196934 -407.961332) (xy 168.227966 -407.901608)
			(xy 168.265913 -407.846021) (xy 168.2877 -407.820368) (xy 168.293493 -407.81322) (xy 168.30001 -407.796032)
			(xy 168.3004 -407.78684) (xy 168.3004 -407.628852) (xy 168.300782 -407.618695) (xy 168.308594 -407.599941)
			(xy 168.323002 -407.58562) (xy 168.341802 -407.577922) (xy 168.351962 -407.577544) (xy 169.068242 -407.577544)
			(xy 169.078372 -407.577992) (xy 169.097095 -407.585735) (xy 169.11145 -407.600032) (xy 169.119267 -407.618724)
			(xy 169.119804 -407.628852) (xy 169.119804 -407.78684) (xy 169.120194 -407.796029) (xy 169.126721 -407.813214)
			(xy 169.132504 -407.820368) (xy 169.154283 -407.846027) (xy 169.192229 -407.901614) (xy 169.22326 -407.961337)
			(xy 169.246931 -408.02434) (xy 169.262904 -408.089721) (xy 169.270948 -408.156542) (xy 169.270948 -408.223846)
			(xy 169.262906 -408.290667) (xy 169.246935 -408.356048) (xy 169.223265 -408.419052) (xy 169.192235 -408.478776)
			(xy 169.15429 -408.534363) (xy 169.132504 -408.560016) (xy 169.126719 -408.567169) (xy 169.120197 -408.584354)
			(xy 169.119804 -408.593544) (xy 169.119804 -409.086812) (xy 169.120208 -409.096) (xy 169.126726 -409.113184)
			(xy 169.132504 -409.12034) (xy 169.154255 -409.146022) (xy 169.192202 -409.201605) (xy 169.223235 -409.261325)
			(xy 169.246908 -409.324325) (xy 169.262882 -409.389704) (xy 169.270928 -409.456522) (xy 169.270931 -409.523824)
			(xy 169.262891 -409.590643) (xy 169.246924 -409.656023) (xy 169.223257 -409.719026) (xy 169.19223 -409.778748)
			(xy 169.154288 -409.834335) (xy 169.132504 -409.859988) (xy 169.126688 -409.86712) (xy 169.120185 -409.88432)
			(xy 169.119804 -409.893516) (xy 169.119804 -410.051504) (xy 169.119382 -410.061658) (xy 169.111586 -410.08041)
			(xy 169.097189 -410.094733) (xy 169.078398 -410.102433) (xy 169.068242 -410.102812) (xy 168.351962 -410.102812)
			(xy 168.341839 -410.102306) (xy 168.323127 -410.094575) (xy 168.308774 -410.080296) (xy 168.300947 -410.061624)
			(xy 168.3004 -410.051504) (xy 168.3004 -409.893516) (xy 168.299982 -409.88433) (xy 168.293474 -409.867145)
			(xy 168.2877 -409.859988) (xy 168.265878 -409.834364) (xy 168.227933 -409.778773) (xy 168.196903 -409.719045)
			(xy 168.173234 -409.656037) (xy 168.157265 -409.590652) (xy 168.149224 -409.523826) (xy 167.020557 -409.523826)
			(xy 166.992095 -409.578598) (xy 166.954145 -409.634184) (xy 166.932356 -409.659836) (xy 166.926556 -409.666979)
			(xy 166.920045 -409.684171) (xy 166.919656 -409.693364) (xy 166.919656 -410.186632) (xy 166.920061 -410.19582)
			(xy 166.926579 -410.213003) (xy 166.932356 -410.22016) (xy 166.954128 -410.245825) (xy 166.992078 -410.30141)
			(xy 167.023112 -410.361131) (xy 167.046786 -410.424134) (xy 167.06276 -410.489515) (xy 167.070805 -410.556336)
			(xy 167.070807 -410.62364) (xy 167.0708 -410.623701) (xy 170.348846 -410.623701) (xy 170.348847 -410.556275)
			(xy 170.356926 -410.489335) (xy 170.372964 -410.423844) (xy 170.396732 -410.360747) (xy 170.427888 -410.30095)
			(xy 170.465981 -410.245316) (xy 170.487848 -410.219652) (xy 170.493653 -410.212513) (xy 170.500162 -410.195318)
			(xy 170.500548 -410.186124) (xy 170.500548 -409.693872) (xy 170.50014 -409.684685) (xy 170.493624 -409.667501)
			(xy 170.487848 -409.660344) (xy 170.465994 -409.63467) (xy 170.427902 -409.579038) (xy 170.396748 -409.519243)
			(xy 170.372981 -409.456147) (xy 170.356943 -409.390659) (xy 170.348866 -409.323721) (xy 170.348865 -409.256297)
			(xy 170.35694 -409.189359) (xy 170.372976 -409.12387) (xy 170.396741 -409.060773) (xy 170.427893 -409.000978)
			(xy 170.465983 -408.945344) (xy 170.487848 -408.91968) (xy 170.493642 -408.912533) (xy 170.500157 -408.895344)
			(xy 170.500548 -408.886152) (xy 170.500548 -408.728672) (xy 170.501061 -408.718568) (xy 170.508798 -408.699899)
			(xy 170.523086 -408.685607) (xy 170.541752 -408.677864) (xy 170.551856 -408.677364) (xy 171.268136 -408.677364)
			(xy 171.278243 -408.677855) (xy 171.296915 -408.685598) (xy 171.311207 -408.699892) (xy 171.318947 -408.718565)
			(xy 171.319444 -408.728672) (xy 171.319444 -408.886152) (xy 171.31989 -408.895335) (xy 171.32638 -408.912519)
			(xy 171.332144 -408.91968) (xy 171.354022 -408.945335) (xy 171.392114 -409.000969) (xy 171.423267 -409.060766)
			(xy 171.447033 -409.123865) (xy 171.463069 -409.189356) (xy 171.471145 -409.256296) (xy 171.471144 -409.323722)
			(xy 171.463066 -409.390662) (xy 171.447028 -409.456152) (xy 171.42326 -409.51925) (xy 171.420875 -409.523827)
			(xy 172.548991 -409.523827) (xy 172.548995 -409.456519) (xy 172.557043 -409.389693) (xy 172.573021 -409.324308)
			(xy 172.5967 -409.261302) (xy 172.62774 -409.201577) (xy 172.665697 -409.145992) (xy 172.687488 -409.12034)
			(xy 172.693291 -409.113199) (xy 172.699802 -409.096005) (xy 172.700188 -409.086812) (xy 172.700188 -408.593544)
			(xy 172.699759 -408.584359) (xy 172.693259 -408.567174) (xy 172.687488 -408.560016) (xy 172.665691 -408.534371)
			(xy 172.627739 -408.478785) (xy 172.596704 -408.419061) (xy 172.573029 -408.356055) (xy 172.557055 -408.290671)
			(xy 172.549011 -408.223847) (xy 172.549012 -408.156541) (xy 172.557057 -408.089717) (xy 172.573033 -408.024333)
			(xy 172.596708 -407.961328) (xy 172.627745 -407.901605) (xy 172.665698 -407.84602) (xy 172.687488 -407.820368)
			(xy 172.693279 -407.813219) (xy 172.699797 -407.796031) (xy 172.700188 -407.78684) (xy 172.700188 -407.628852)
			(xy 172.700582 -407.618696) (xy 172.708391 -407.599945) (xy 172.722796 -407.585624) (xy 172.741592 -407.577924)
			(xy 172.75175 -407.577544) (xy 173.46803 -407.577544) (xy 173.478159 -407.578002) (xy 173.496882 -407.58574)
			(xy 173.511237 -407.600035) (xy 173.519055 -407.618725) (xy 173.519592 -407.628852) (xy 173.519592 -407.78684)
			(xy 173.519985 -407.796029) (xy 173.526511 -407.813213) (xy 173.532292 -407.820368) (xy 173.554071 -407.846027)
			(xy 173.592018 -407.901613) (xy 173.62305 -407.961336) (xy 173.646722 -408.02434) (xy 173.662694 -408.089721)
			(xy 173.670739 -408.156542) (xy 173.670739 -408.223846) (xy 173.662697 -408.290667) (xy 173.646725 -408.356049)
			(xy 173.623055 -408.419053) (xy 173.592024 -408.478776) (xy 173.554078 -408.534363) (xy 173.532292 -408.560016)
			(xy 173.526505 -408.567168) (xy 173.519985 -408.584353) (xy 173.519592 -408.593544) (xy 173.519592 -409.086812)
			(xy 173.519998 -409.096) (xy 173.526515 -409.113184) (xy 173.532292 -409.12034) (xy 173.554043 -409.146022)
			(xy 173.591991 -409.201605) (xy 173.623024 -409.261324) (xy 173.646698 -409.324325) (xy 173.662672 -409.389703)
			(xy 173.670719 -409.456522) (xy 173.670722 -409.523824) (xy 173.662682 -409.590643) (xy 173.646714 -409.656023)
			(xy 173.623047 -409.719026) (xy 173.592019 -409.778749) (xy 173.554077 -409.834336) (xy 173.532292 -409.859988)
			(xy 173.526475 -409.867118) (xy 173.519973 -409.88432) (xy 173.519592 -409.893516) (xy 173.519592 -410.051504)
			(xy 173.519181 -410.061659) (xy 173.511383 -410.080413) (xy 173.496983 -410.094737) (xy 173.478187 -410.102435)
			(xy 173.46803 -410.102812) (xy 172.75175 -410.102812) (xy 172.741633 -410.102234) (xy 172.722923 -410.094532)
			(xy 172.708567 -410.080274) (xy 172.700736 -410.061618) (xy 172.700188 -410.051504) (xy 172.700188 -409.893516)
			(xy 172.699773 -409.884329) (xy 172.693263 -409.867145) (xy 172.687488 -409.859988) (xy 172.665663 -409.834366)
			(xy 172.627713 -409.778776) (xy 172.596678 -409.719049) (xy 172.573005 -409.65604) (xy 172.557033 -409.590654)
			(xy 172.548991 -409.523827) (xy 171.420875 -409.523827) (xy 171.392104 -409.579046) (xy 171.354011 -409.63468)
			(xy 171.332144 -409.660344) (xy 171.326339 -409.667483) (xy 171.319831 -409.684679) (xy 171.319444 -409.693872)
			(xy 171.319444 -410.186124) (xy 171.319855 -410.195311) (xy 171.32637 -410.212494) (xy 171.332144 -410.219652)
			(xy 171.353994 -410.245329) (xy 171.392087 -410.300961) (xy 171.423242 -410.360755) (xy 171.447009 -410.42385)
			(xy 171.463047 -410.489338) (xy 171.471125 -410.556276) (xy 171.471127 -410.623641) (xy 174.749166 -410.623641)
			(xy 174.749167 -410.556335) (xy 174.757213 -410.489511) (xy 174.773187 -410.424128) (xy 174.796862 -410.361123)
			(xy 174.827897 -410.301399) (xy 174.865847 -410.245812) (xy 174.887636 -410.22016) (xy 174.893437 -410.213018)
			(xy 174.899948 -410.195825) (xy 174.900336 -410.186632) (xy 174.900336 -409.693364) (xy 174.899935 -409.684176)
			(xy 174.893414 -409.666992) (xy 174.887636 -409.659836) (xy 174.86586 -409.634174) (xy 174.827911 -409.578589)
			(xy 174.796878 -409.518867) (xy 174.773205 -409.455863) (xy 174.757231 -409.390482) (xy 174.749186 -409.323661)
			(xy 174.749185 -409.256357) (xy 174.757228 -409.189535) (xy 174.773199 -409.124154) (xy 174.79687 -409.06115)
			(xy 174.827902 -409.001427) (xy 174.865849 -408.94584) (xy 174.887636 -408.920188) (xy 174.893425 -408.913037)
			(xy 174.899943 -408.895851) (xy 174.900336 -408.88666) (xy 174.900336 -408.728672) (xy 174.900699 -408.718512)
			(xy 174.908511 -408.699752) (xy 174.922926 -408.685428) (xy 174.941735 -408.677736) (xy 174.951898 -408.677364)
			(xy 175.668178 -408.677364) (xy 175.678306 -408.677845) (xy 175.697032 -408.68557) (xy 175.711389 -408.699859)
			(xy 175.719205 -408.718546) (xy 175.71974 -408.728672) (xy 175.71974 -408.88666) (xy 175.720183 -408.895843)
			(xy 175.726675 -408.913028) (xy 175.73244 -408.920188) (xy 175.75424 -408.94583) (xy 175.79219 -409.001418)
			(xy 175.823224 -409.061142) (xy 175.846897 -409.124148) (xy 175.862869 -409.189532) (xy 175.870913 -409.256356)
			(xy 175.870912 -409.323662) (xy 175.862866 -409.390486) (xy 175.846891 -409.455869) (xy 175.823216 -409.518874)
			(xy 175.792181 -409.578598) (xy 175.754229 -409.634184) (xy 175.73244 -409.659836) (xy 175.726638 -409.666977)
			(xy 175.720128 -409.684171) (xy 175.71974 -409.693364) (xy 175.71974 -410.186632) (xy 175.720148 -410.195819)
			(xy 175.726665 -410.213003) (xy 175.73244 -410.22016) (xy 175.754213 -410.245825) (xy 175.792163 -410.301409)
			(xy 175.823198 -410.361131) (xy 175.846873 -410.424134) (xy 175.862848 -410.489514) (xy 175.870893 -410.556336)
			(xy 175.870895 -410.62364) (xy 175.862852 -410.690462) (xy 175.84688 -410.755843) (xy 175.823208 -410.818847)
			(xy 175.792176 -410.87857) (xy 175.754227 -410.934156) (xy 175.73244 -410.959808) (xy 175.72665 -410.966958)
			(xy 175.720133 -410.984145) (xy 175.71974 -410.993336) (xy 175.71974 -411.151324) (xy 175.719299 -411.161475)
			(xy 175.711503 -411.18022) (xy 175.697113 -411.194541) (xy 175.678331 -411.202247) (xy 175.668178 -411.202632)
			(xy 174.951898 -411.202632) (xy 174.941768 -411.202174) (xy 174.923041 -411.194441) (xy 174.908684 -411.180145)
			(xy 174.90087 -411.161452) (xy 174.900336 -411.151324) (xy 174.900336 -410.993336) (xy 174.8999 -410.984152)
			(xy 174.893403 -410.966968) (xy 174.887636 -410.959808) (xy 174.865833 -410.934169) (xy 174.827884 -410.87858)
			(xy 174.796852 -410.818855) (xy 174.77318 -410.755849) (xy 174.757208 -410.690465) (xy 174.749166 -410.623641)
			(xy 171.471127 -410.623641) (xy 171.471127 -410.6237) (xy 171.463052 -410.690638) (xy 171.447016 -410.756127)
			(xy 171.423251 -410.819223) (xy 171.392099 -410.879019) (xy 171.354009 -410.934652) (xy 171.332144 -410.960316)
			(xy 171.326351 -410.967464) (xy 171.319836 -410.984653) (xy 171.319444 -410.993844) (xy 171.319444 -411.151324)
			(xy 171.318936 -411.161429) (xy 171.311198 -411.180099) (xy 171.296909 -411.194392) (xy 171.278241 -411.202133)
			(xy 171.268136 -411.202632) (xy 170.551856 -411.202632) (xy 170.541748 -411.202152) (xy 170.523075 -411.194405)
			(xy 170.508783 -411.180108) (xy 170.501044 -411.161432) (xy 170.500548 -411.151324) (xy 170.500548 -410.993844)
			(xy 170.500106 -410.98466) (xy 170.493613 -410.967476) (xy 170.487848 -410.960316) (xy 170.465967 -410.934665)
			(xy 170.427875 -410.879029) (xy 170.396723 -410.819232) (xy 170.372957 -410.756133) (xy 170.356921 -410.690641)
			(xy 170.348846 -410.623701) (xy 167.0708 -410.623701) (xy 167.062764 -410.690461) (xy 167.046793 -410.755843)
			(xy 167.023122 -410.818847) (xy 166.99209 -410.87857) (xy 166.954143 -410.934156) (xy 166.932356 -410.959808)
			(xy 166.926568 -410.966959) (xy 166.920049 -410.984145) (xy 166.919656 -410.993336) (xy 166.919656 -411.151324)
			(xy 166.919199 -411.161473) (xy 166.911406 -411.180215) (xy 166.897021 -411.194535) (xy 166.878245 -411.202244)
			(xy 166.868094 -411.202632) (xy 166.151814 -411.202632) (xy 166.141685 -411.202161) (xy 166.122959 -411.194433)
			(xy 166.108601 -411.180141) (xy 166.100786 -411.161451) (xy 166.100252 -411.151324) (xy 166.100252 -410.993336)
			(xy 166.099813 -410.984152) (xy 166.093318 -410.966968) (xy 166.087552 -410.959808) (xy 166.065748 -410.934169)
			(xy 166.027799 -410.878581) (xy 165.996765 -410.818856) (xy 165.973093 -410.75585) (xy 165.957121 -410.690466)
			(xy 165.949078 -410.623641) (xy 162.671039 -410.623641) (xy 162.671039 -410.6237) (xy 162.662964 -410.690637)
			(xy 162.646929 -410.756126) (xy 162.623165 -410.819223) (xy 162.592014 -410.879018) (xy 162.553924 -410.934651)
			(xy 162.53206 -410.960316) (xy 162.526269 -410.967465) (xy 162.519752 -410.984653) (xy 162.51936 -410.993844)
			(xy 162.51936 -411.151324) (xy 162.519003 -411.161453) (xy 162.511239 -411.180165) (xy 162.496904 -411.19448)
			(xy 162.478182 -411.202217) (xy 162.468052 -411.202632) (xy 161.751772 -411.202632) (xy 161.741665 -411.202139)
			(xy 161.722993 -411.194398) (xy 161.7087 -411.180104) (xy 161.700961 -411.161431) (xy 161.700464 -411.151324)
			(xy 161.700464 -410.993844) (xy 161.700019 -410.984661) (xy 161.693528 -410.967477) (xy 161.687764 -410.960316)
			(xy 161.665886 -410.934663) (xy 161.6278 -410.879026) (xy 161.596652 -410.819228) (xy 161.57289 -410.756129)
			(xy 161.556857 -410.690639) (xy 161.548783 -410.6237) (xy 154.57678 -410.6237) (xy 154.57678 -417.021264)
			(xy 154.57824 -417.030391) (xy 154.586758 -417.046776) (xy 154.600563 -417.059042) (xy 154.617837 -417.065574)
			(xy 154.627072 -417.065968) (xy 200.481184 -417.065968) (xy 200.514313 -417.065397) (xy 200.579932 -417.056209)
			(xy 200.643641 -417.038009) (xy 200.704211 -417.011147) (xy 200.760469 -416.976145) (xy 200.811329 -416.933677)
			(xy 200.83399 -416.909504) (xy 200.889199 -416.849276) (xy 201.004414 -416.733405) (xy 201.124876 -416.622999)
			(xy 201.250326 -416.518295) (xy 201.380495 -416.419518) (xy 201.515101 -416.32688) (xy 201.653857 -416.240581)
			(xy 201.796463 -416.160806) (xy 201.942614 -416.087726) (xy 202.091994 -416.021499) (xy 202.244284 -415.962267)
			(xy 202.399156 -415.910157) (xy 202.556276 -415.865281) (xy 202.715308 -415.827736) (xy 202.875909 -415.797602)
			(xy 203.037734 -415.774945) (xy 203.200435 -415.759812) (xy 203.363662 -415.752236) (xy 203.445364 -415.751772)
			(xy 271.794478 -415.751772) (xy 271.87618 -415.752242) (xy 272.039408 -415.759815) (xy 272.202109 -415.774945)
			(xy 272.363935 -415.797601) (xy 272.524536 -415.827733) (xy 272.683568 -415.865277) (xy 272.840689 -415.910151)
			(xy 272.995561 -415.96226) (xy 273.147852 -416.021492) (xy 273.297233 -416.087719) (xy 273.443384 -416.160798)
			(xy 273.585991 -416.240574) (xy 273.724746 -416.326873) (xy 273.859353 -416.419511) (xy 273.989521 -416.518289)
			(xy 274.11497 -416.622994) (xy 274.235432 -416.733401) (xy 274.350646 -416.849273) (xy 274.405852 -416.909504)
			(xy 274.428514 -416.933679) (xy 274.479371 -416.976152) (xy 274.535629 -417.011162) (xy 274.596198 -417.03803)
			(xy 274.659908 -417.056238) (xy 274.725528 -417.065434) (xy 274.758658 -417.065968) (xy 313.023504 -417.065968)
			(xy 313.032722 -417.06555) (xy 313.049945 -417.058972) (xy 313.063715 -417.046711) (xy 313.072237 -417.030362)
			(xy 313.073796 -417.021264) (xy 313.073796 -394.27912) (xy 326.479662 -394.27912) (xy 326.525636 -394.325094)
			(xy 326.525636 -397.823826) (xy 330.929171 -397.823826) (xy 330.929175 -397.756517) (xy 330.937223 -397.689692)
			(xy 330.953201 -397.624307) (xy 330.976879 -397.561301) (xy 331.007918 -397.501576) (xy 331.045873 -397.44599)
			(xy 331.067664 -397.420338) (xy 331.073477 -397.413205) (xy 331.07998 -397.396005) (xy 331.080364 -397.38681)
			(xy 331.080364 -396.893542) (xy 331.079919 -396.884359) (xy 331.073428 -396.867175) (xy 331.067664 -396.860014)
			(xy 331.045866 -396.83437) (xy 331.007916 -396.778783) (xy 330.976881 -396.719059) (xy 330.953208 -396.656053)
			(xy 330.937235 -396.59067) (xy 330.929191 -396.523846) (xy 330.929192 -396.456539) (xy 330.937238 -396.389716)
			(xy 330.953213 -396.324333) (xy 330.976888 -396.261328) (xy 331.007923 -396.201604) (xy 331.045875 -396.146018)
			(xy 331.067664 -396.120366) (xy 331.073465 -396.113225) (xy 331.079975 -396.096031) (xy 331.080364 -396.086838)
			(xy 331.080364 -395.92885) (xy 331.080805 -395.918678) (xy 331.088579 -395.89988) (xy 331.10296 -395.885492)
			(xy 331.121755 -395.87771) (xy 331.131926 -395.877288) (xy 331.848206 -395.877288) (xy 331.858384 -395.87766)
			(xy 331.877189 -395.885456) (xy 331.891575 -395.899859) (xy 331.899351 -395.918671) (xy 331.899768 -395.92885)
			(xy 331.899768 -396.086838) (xy 331.900167 -396.096026) (xy 331.906689 -396.11321) (xy 331.912468 -396.120366)
			(xy 331.934246 -396.146026) (xy 331.972195 -396.201612) (xy 332.003228 -396.261334) (xy 332.026901 -396.324338)
			(xy 332.042874 -396.389719) (xy 332.050919 -396.45654) (xy 332.05092 -396.523845) (xy 332.042877 -396.590666)
			(xy 332.026905 -396.656048) (xy 332.003234 -396.719052) (xy 331.972202 -396.778775) (xy 331.934255 -396.834362)
			(xy 331.912468 -396.860014) (xy 331.906679 -396.867164) (xy 331.90016 -396.884351) (xy 331.899768 -396.893542)
			(xy 331.899768 -397.38681) (xy 331.90018 -397.395997) (xy 331.906693 -397.413181) (xy 331.912468 -397.420338)
			(xy 331.934218 -397.446021) (xy 331.972167 -397.501603) (xy 332.00059 -397.556296) (xy 333.128836 -397.556296)
			(xy 333.136911 -397.489358) (xy 333.152946 -397.423869) (xy 333.17671 -397.360773) (xy 333.20786 -397.300977)
			(xy 333.245948 -397.245343) (xy 333.267812 -397.219678) (xy 333.273602 -397.212528) (xy 333.28012 -397.195341)
			(xy 333.280512 -397.18615) (xy 333.280512 -397.028924) (xy 333.280936 -397.018802) (xy 333.288678 -397.000096)
			(xy 333.302993 -396.985781) (xy 333.321698 -396.978037) (xy 333.33182 -396.977616) (xy 334.0481 -396.977616)
			(xy 334.058224 -396.978016) (xy 334.076931 -396.985768) (xy 334.091246 -397.000089) (xy 334.098988 -397.018799)
			(xy 334.099408 -397.028924) (xy 334.099408 -397.18615) (xy 334.09984 -397.195335) (xy 334.106338 -397.21252)
			(xy 334.112108 -397.219678) (xy 334.133982 -397.245335) (xy 334.172069 -397.300971) (xy 334.203219 -397.360769)
			(xy 334.226982 -397.423866) (xy 334.243017 -397.489356) (xy 334.251092 -397.556295) (xy 334.251091 -397.62372)
			(xy 334.243014 -397.690658) (xy 334.226978 -397.756148) (xy 334.203213 -397.819245) (xy 334.200796 -397.823884)
			(xy 335.328964 -397.823884) (xy 335.328968 -397.756459) (xy 335.337047 -397.689518) (xy 335.353085 -397.624028)
			(xy 335.376852 -397.560929) (xy 335.408005 -397.501132) (xy 335.446095 -397.445496) (xy 335.46796 -397.41983)
			(xy 335.473776 -397.412699) (xy 335.480277 -397.395497) (xy 335.48066 -397.386302) (xy 335.48066 -396.89405)
			(xy 335.480213 -396.884867) (xy 335.473723 -396.867683) (xy 335.46796 -396.860522) (xy 335.446088 -396.834864)
			(xy 335.408002 -396.779228) (xy 335.376854 -396.71943) (xy 335.353092 -396.656332) (xy 335.337058 -396.590843)
			(xy 335.328984 -396.523904) (xy 335.328985 -396.456481) (xy 335.337061 -396.389542) (xy 335.353096 -396.324053)
			(xy 335.37686 -396.260956) (xy 335.40801 -396.201159) (xy 335.446097 -396.145524) (xy 335.46796 -396.119858)
			(xy 335.473764 -396.112719) (xy 335.480273 -396.095523) (xy 335.48066 -396.08633) (xy 335.48066 -395.92885)
			(xy 335.481168 -395.918724) (xy 335.488883 -395.9) (xy 335.503164 -395.885642) (xy 335.521845 -395.877824)
			(xy 335.531968 -395.877288) (xy 336.248248 -395.877288) (xy 336.258404 -395.877682) (xy 336.277155 -395.885491)
			(xy 336.291476 -395.899896) (xy 336.299176 -395.918692) (xy 336.299556 -395.92885) (xy 336.299556 -396.08633)
			(xy 336.299962 -396.095517) (xy 336.30648 -396.112701) (xy 336.312256 -396.119858) (xy 336.334112 -396.145531)
			(xy 336.372204 -396.201163) (xy 336.403357 -396.260958) (xy 336.427124 -396.324054) (xy 336.443161 -396.389542)
			(xy 336.451239 -396.456481) (xy 336.45124 -396.523904) (xy 336.443164 -396.590843) (xy 336.427128 -396.656332)
			(xy 336.403363 -396.719428) (xy 336.372211 -396.779224) (xy 336.334121 -396.834858) (xy 336.312256 -396.860522)
			(xy 336.306462 -396.867669) (xy 336.299947 -396.884858) (xy 336.299556 -396.89405) (xy 336.299556 -397.386302)
			(xy 336.299975 -397.395488) (xy 336.306484 -397.412672) (xy 336.312256 -397.41983) (xy 336.334084 -397.445525)
			(xy 336.372177 -397.501154) (xy 336.40094 -397.556356) (xy 337.529156 -397.556356) (xy 337.537198 -397.489535)
			(xy 337.553169 -397.424153) (xy 337.576839 -397.361149) (xy 337.607869 -397.301426) (xy 337.645814 -397.245839)
			(xy 337.6676 -397.220186) (xy 337.673385 -397.213033) (xy 337.679907 -397.195848) (xy 337.6803 -397.186658)
			(xy 337.6803 -397.028924) (xy 337.680741 -397.018771) (xy 337.688529 -397.000019) (xy 337.70292 -396.985695)
			(xy 337.721708 -396.977995) (xy 337.731862 -396.977616) (xy 338.448142 -396.977616) (xy 338.458268 -396.978091)
			(xy 338.476986 -396.985829) (xy 338.49134 -397.000118) (xy 338.499162 -397.0188) (xy 338.499704 -397.028924)
			(xy 338.499704 -397.186658) (xy 338.500133 -397.195843) (xy 338.506634 -397.213028) (xy 338.512404 -397.220186)
			(xy 338.5342 -397.245831) (xy 338.572146 -397.301419) (xy 338.603176 -397.361144) (xy 338.626847 -397.42415)
			(xy 338.642818 -397.489532) (xy 338.65086 -397.556355) (xy 338.650859 -397.62366) (xy 338.642815 -397.690483)
			(xy 338.626842 -397.755865) (xy 338.60317 -397.81887) (xy 338.600595 -397.823826) (xy 339.729259 -397.823826)
			(xy 339.729263 -397.756517) (xy 339.737311 -397.689692) (xy 339.753288 -397.624308) (xy 339.776965 -397.561301)
			(xy 339.808004 -397.501577) (xy 339.845958 -397.44599) (xy 339.867748 -397.420338) (xy 339.873559 -397.413204)
			(xy 339.880064 -397.396005) (xy 339.880448 -397.38681) (xy 339.880448 -396.893542) (xy 339.880007 -396.884358)
			(xy 339.873513 -396.867174) (xy 339.867748 -396.860014) (xy 339.84595 -396.83437) (xy 339.808001 -396.778783)
			(xy 339.776968 -396.719058) (xy 339.753295 -396.656052) (xy 339.737322 -396.590669) (xy 339.729279 -396.523845)
			(xy 339.72928 -396.456539) (xy 339.737325 -396.389716) (xy 339.753299 -396.324333) (xy 339.776974 -396.261328)
			(xy 339.808009 -396.201604) (xy 339.845959 -396.146018) (xy 339.867748 -396.120366) (xy 339.873547 -396.113223)
			(xy 339.880059 -396.096031) (xy 339.880448 -396.086838) (xy 339.880448 -395.92885) (xy 339.880905 -395.91868)
			(xy 339.888675 -395.899885) (xy 339.903051 -395.885498) (xy 339.921841 -395.877713) (xy 339.93201 -395.877288)
			(xy 340.64829 -395.877288) (xy 340.658467 -395.877673) (xy 340.677271 -395.885464) (xy 340.691658 -395.899862)
			(xy 340.699435 -395.918672) (xy 340.699852 -395.92885) (xy 340.699852 -396.086838) (xy 340.700255 -396.096026)
			(xy 340.706775 -396.113209) (xy 340.712552 -396.120366) (xy 340.73433 -396.146026) (xy 340.77228 -396.201611)
			(xy 340.803314 -396.261334) (xy 340.826988 -396.324337) (xy 340.842962 -396.389718) (xy 340.851007 -396.45654)
			(xy 340.851007 -396.523845) (xy 340.842964 -396.590667) (xy 340.826992 -396.656048) (xy 340.80332 -396.719053)
			(xy 340.772287 -396.778776) (xy 340.734339 -396.834362) (xy 340.712552 -396.860014) (xy 340.706761 -396.867163)
			(xy 340.700244 -396.884351) (xy 340.699852 -396.893542) (xy 340.699852 -397.38681) (xy 340.700268 -397.395996)
			(xy 340.706779 -397.41318) (xy 340.712552 -397.420338) (xy 340.734302 -397.446021) (xy 340.772253 -397.501603)
			(xy 340.800676 -397.556296) (xy 341.928924 -397.556296) (xy 341.936999 -397.489359) (xy 341.953033 -397.42387)
			(xy 341.976796 -397.360774) (xy 342.007946 -397.300978) (xy 342.046033 -397.245343) (xy 342.067896 -397.219678)
			(xy 342.073684 -397.212527) (xy 342.080204 -397.195341) (xy 342.080596 -397.18615) (xy 342.080596 -397.028924)
			(xy 342.081035 -397.018804) (xy 342.088775 -397.000101) (xy 342.103084 -396.985786) (xy 342.121784 -396.978039)
			(xy 342.131904 -396.977616) (xy 342.848184 -396.977616) (xy 342.858307 -396.978029) (xy 342.877014 -396.985775)
			(xy 342.891329 -397.000093) (xy 342.899072 -397.0188) (xy 342.899492 -397.028924) (xy 342.899492 -397.18615)
			(xy 342.899928 -397.195334) (xy 342.906424 -397.212519) (xy 342.912192 -397.219678) (xy 342.934066 -397.245335)
			(xy 342.972155 -397.300971) (xy 343.003306 -397.360768) (xy 343.02707 -397.423866) (xy 343.043105 -397.489356)
			(xy 343.05118 -397.556295) (xy 343.051179 -397.62372) (xy 343.043102 -397.690659) (xy 343.027065 -397.756149)
			(xy 343.0033 -397.819246) (xy 343.000914 -397.823825) (xy 344.12905 -397.823825) (xy 344.129054 -397.756517)
			(xy 344.137101 -397.689692) (xy 344.153078 -397.624308) (xy 344.176755 -397.561302) (xy 344.207793 -397.501577)
			(xy 344.245746 -397.44599) (xy 344.267536 -397.420338) (xy 344.273346 -397.413202) (xy 344.279852 -397.396004)
			(xy 344.280236 -397.38681) (xy 344.280236 -396.893542) (xy 344.279797 -396.884358) (xy 344.273303 -396.867174)
			(xy 344.267536 -396.860014) (xy 344.245738 -396.83437) (xy 344.20779 -396.778782) (xy 344.176757 -396.719058)
			(xy 344.153085 -396.656052) (xy 344.137113 -396.590669) (xy 344.12907 -396.523845) (xy 344.129071 -396.45654)
			(xy 344.137116 -396.389716) (xy 344.15309 -396.324334) (xy 344.176764 -396.261329) (xy 344.207798 -396.201605)
			(xy 344.245748 -396.146018) (xy 344.267536 -396.120366) (xy 344.273334 -396.113222) (xy 344.279847 -396.09603)
			(xy 344.280236 -396.086838) (xy 344.280236 -395.92885) (xy 344.280705 -395.918682) (xy 344.288473 -395.899889)
			(xy 344.302845 -395.885502) (xy 344.32163 -395.877715) (xy 344.331798 -395.877288) (xy 345.048078 -395.877288)
			(xy 345.058254 -395.877683) (xy 345.077058 -395.88547) (xy 345.091445 -395.899866) (xy 345.099222 -395.918673)
			(xy 345.09964 -395.92885) (xy 345.09964 -396.086838) (xy 345.100045 -396.096025) (xy 345.106564 -396.113209)
			(xy 345.11234 -396.120366) (xy 345.134118 -396.146026) (xy 345.172069 -396.201611) (xy 345.203104 -396.261333)
			(xy 345.226778 -396.324337) (xy 345.242752 -396.389718) (xy 345.250798 -396.45654) (xy 345.250798 -396.523845)
			(xy 345.242755 -396.590667) (xy 345.226782 -396.656049) (xy 345.20311 -396.719053) (xy 345.172077 -396.778776)
			(xy 345.134128 -396.834362) (xy 345.11234 -396.860014) (xy 345.106548 -396.867162) (xy 345.100032 -396.884351)
			(xy 345.09964 -396.893542) (xy 345.09964 -397.38681) (xy 345.100059 -397.395996) (xy 345.106568 -397.41318)
			(xy 345.11234 -397.420338) (xy 345.134091 -397.446021) (xy 345.172042 -397.501602) (xy 345.200497 -397.556355)
			(xy 346.32922 -397.556355) (xy 346.337264 -397.489532) (xy 346.353237 -397.42415) (xy 346.37691 -397.361146)
			(xy 346.407945 -397.301423) (xy 346.445896 -397.245838) (xy 346.467684 -397.220186) (xy 346.473467 -397.213031)
			(xy 346.47999 -397.195848) (xy 346.480384 -397.186658) (xy 346.480384 -397.028924) (xy 346.480841 -397.018773)
			(xy 346.488625 -397.000025) (xy 346.503011 -396.985701) (xy 346.521794 -396.977997) (xy 346.531946 -396.977616)
			(xy 347.248226 -396.977616) (xy 347.258351 -396.978104) (xy 347.277069 -396.985836) (xy 347.291423 -397.000121)
			(xy 347.299246 -397.018801) (xy 347.299788 -397.028924) (xy 347.299788 -397.186658) (xy 347.300221 -397.195843)
			(xy 347.306719 -397.213027) (xy 347.312488 -397.220186) (xy 347.334285 -397.24583) (xy 347.372232 -397.301419)
			(xy 347.403263 -397.361143) (xy 347.426934 -397.424149) (xy 347.442905 -397.489532) (xy 347.450948 -397.556355)
			(xy 347.450947 -397.62366) (xy 347.442903 -397.690483) (xy 347.426929 -397.755865) (xy 347.403257 -397.81887)
			(xy 347.400682 -397.823826) (xy 374.92908 -397.823826) (xy 374.929084 -397.756517) (xy 374.937132 -397.689691)
			(xy 374.95311 -397.624306) (xy 374.976789 -397.5613) (xy 375.007829 -397.501576) (xy 375.045785 -397.445989)
			(xy 375.067576 -397.420338) (xy 375.073379 -397.413197) (xy 375.07989 -397.396003) (xy 375.080276 -397.38681)
			(xy 375.080276 -396.893542) (xy 375.079851 -396.884356) (xy 375.073348 -396.867171) (xy 375.067576 -396.860014)
			(xy 375.045777 -396.83437) (xy 375.007826 -396.778784) (xy 374.976792 -396.719059) (xy 374.953118 -396.656053)
			(xy 374.937144 -396.59067) (xy 374.9291 -396.523846) (xy 374.929101 -396.456539) (xy 374.937147 -396.389715)
			(xy 374.953122 -396.324332) (xy 374.976798 -396.261327) (xy 375.007834 -396.201604) (xy 375.045787 -396.146018)
			(xy 375.067576 -396.120366) (xy 375.073367 -396.113216) (xy 375.079886 -396.096029) (xy 375.080276 -396.086838)
			(xy 375.080276 -395.92885) (xy 375.080706 -395.918677) (xy 375.088481 -395.899876) (xy 375.102866 -395.885488)
			(xy 375.121665 -395.877708) (xy 375.131838 -395.877288) (xy 375.848118 -395.877288) (xy 375.858297 -395.87765)
			(xy 375.877102 -395.885451) (xy 375.891487 -395.899856) (xy 375.899263 -395.91867) (xy 375.89968 -395.92885)
			(xy 375.89968 -396.086838) (xy 375.900076 -396.096027) (xy 375.9066 -396.113211) (xy 375.91238 -396.120366)
			(xy 375.934157 -396.146026) (xy 375.972105 -396.201612) (xy 376.003138 -396.261335) (xy 376.02681 -396.324338)
			(xy 376.042784 -396.389719) (xy 376.050828 -396.456541) (xy 376.050829 -396.523844) (xy 376.042786 -396.590666)
			(xy 376.026815 -396.656047) (xy 376.003144 -396.719051) (xy 375.972113 -396.778775) (xy 375.934167 -396.834362)
			(xy 375.91238 -396.860014) (xy 375.906593 -396.867166) (xy 375.900073 -396.884351) (xy 375.89968 -396.893542)
			(xy 375.89968 -397.38681) (xy 375.90009 -397.395997) (xy 375.906604 -397.413181) (xy 375.91238 -397.420338)
			(xy 375.93413 -397.446021) (xy 375.972078 -397.501604) (xy 376.0005 -397.556296) (xy 377.128745 -397.556296)
			(xy 377.136821 -397.489358) (xy 377.152856 -397.423869) (xy 377.17662 -397.360772) (xy 377.207771 -397.300977)
			(xy 377.24586 -397.245343) (xy 377.267724 -397.219678) (xy 377.273515 -397.212529) (xy 377.280032 -397.195341)
			(xy 377.280424 -397.18615) (xy 377.280424 -397.028924) (xy 377.280836 -397.0188) (xy 377.288581 -397.000092)
			(xy 377.302899 -396.985776) (xy 377.321608 -396.978034) (xy 377.331732 -396.977616) (xy 378.048012 -396.977616)
			(xy 378.058137 -396.978006) (xy 378.076844 -396.985761) (xy 378.091159 -397.000086) (xy 378.098901 -397.018798)
			(xy 378.09932 -397.028924) (xy 378.09932 -397.18615) (xy 378.09975 -397.195335) (xy 378.10625 -397.21252)
			(xy 378.11202 -397.219678) (xy 378.133893 -397.245335) (xy 378.17198 -397.300972) (xy 378.203129 -397.360769)
			(xy 378.226892 -397.423867) (xy 378.242926 -397.489357) (xy 378.251001 -397.556295) (xy 378.251 -397.62372)
			(xy 378.242924 -397.690658) (xy 378.226888 -397.756147) (xy 378.203123 -397.819245) (xy 378.200706 -397.823885)
			(xy 379.328873 -397.823885) (xy 379.328877 -397.756458) (xy 379.336956 -397.689518) (xy 379.352995 -397.624027)
			(xy 379.376762 -397.560929) (xy 379.407915 -397.501131) (xy 379.446007 -397.445496) (xy 379.467872 -397.41983)
			(xy 379.47369 -397.4127) (xy 379.48019 -397.395498) (xy 379.480572 -397.386302) (xy 379.480572 -396.89405)
			(xy 379.480144 -396.884865) (xy 379.473643 -396.86768) (xy 379.467872 -396.860522) (xy 379.445999 -396.834864)
			(xy 379.407913 -396.779228) (xy 379.376764 -396.719431) (xy 379.353002 -396.656333) (xy 379.336968 -396.590843)
			(xy 379.328893 -396.523904) (xy 379.328894 -396.456481) (xy 379.33697 -396.389542) (xy 379.353006 -396.324053)
			(xy 379.37677 -396.260956) (xy 379.40792 -396.201159) (xy 379.446008 -396.145524) (xy 379.467872 -396.119858)
			(xy 379.473678 -396.11272) (xy 379.480185 -396.095524) (xy 379.480572 -396.08633) (xy 379.480572 -395.92885)
			(xy 379.481069 -395.918723) (xy 379.488786 -395.899996) (xy 379.50307 -395.885637) (xy 379.521755 -395.877822)
			(xy 379.53188 -395.877288) (xy 380.24816 -395.877288) (xy 380.25831 -395.877754) (xy 380.277059 -395.885534)
			(xy 380.291384 -395.899917) (xy 380.299087 -395.918698) (xy 380.299468 -395.92885) (xy 380.299468 -396.08633)
			(xy 380.299871 -396.095518) (xy 380.30639 -396.112702) (xy 380.312168 -396.119858) (xy 380.334023 -396.145531)
			(xy 380.372114 -396.201163) (xy 380.403267 -396.260958) (xy 380.427033 -396.324054) (xy 380.443071 -396.389543)
			(xy 380.451148 -396.456481) (xy 380.451149 -396.523904) (xy 380.443073 -396.590842) (xy 380.427038 -396.656331)
			(xy 380.403273 -396.719428) (xy 380.372122 -396.779224) (xy 380.334032 -396.834857) (xy 380.312168 -396.860522)
			(xy 380.306375 -396.86767) (xy 380.299859 -396.884858) (xy 380.299468 -396.89405) (xy 380.299468 -397.386302)
			(xy 380.299884 -397.395488) (xy 380.306394 -397.412672) (xy 380.312168 -397.41983) (xy 380.333996 -397.445525)
			(xy 380.372088 -397.501155) (xy 380.40085 -397.556356) (xy 381.529065 -397.556356) (xy 381.537108 -397.489534)
			(xy 381.553079 -397.424153) (xy 381.576749 -397.361149) (xy 381.60778 -397.301425) (xy 381.645726 -397.245838)
			(xy 381.667512 -397.220186) (xy 381.673298 -397.213034) (xy 381.679819 -397.195849) (xy 381.680212 -397.186658)
			(xy 381.680212 -397.028924) (xy 381.680641 -397.01877) (xy 381.688431 -397.000016) (xy 381.702826 -396.985691)
			(xy 381.721618 -396.977993) (xy 381.731774 -396.977616) (xy 382.448054 -396.977616) (xy 382.458175 -396.978164)
			(xy 382.47689 -396.985872) (xy 382.491247 -397.000139) (xy 382.499072 -397.018806) (xy 382.499616 -397.028924)
			(xy 382.499616 -397.186658) (xy 382.500043 -397.195844) (xy 382.506544 -397.213028) (xy 382.512316 -397.220186)
			(xy 382.534115 -397.245829) (xy 382.572066 -397.301416) (xy 382.603102 -397.36114) (xy 382.626776 -397.424146)
			(xy 382.642749 -397.48953) (xy 382.650793 -397.556354) (xy 382.650793 -397.623661) (xy 382.642747 -397.690485)
			(xy 382.626771 -397.755868) (xy 382.603096 -397.818873) (xy 382.600522 -397.823826) (xy 383.729168 -397.823826)
			(xy 383.729172 -397.756517) (xy 383.73722 -397.689692) (xy 383.753198 -397.624307) (xy 383.776876 -397.561301)
			(xy 383.807914 -397.501576) (xy 383.845869 -397.44599) (xy 383.86766 -397.420338) (xy 383.873473 -397.413205)
			(xy 383.879976 -397.396005) (xy 383.88036 -397.38681) (xy 383.88036 -396.893542) (xy 383.879916 -396.884359)
			(xy 383.873425 -396.867175) (xy 383.86766 -396.860014) (xy 383.845862 -396.83437) (xy 383.807912 -396.778783)
			(xy 383.776878 -396.719058) (xy 383.753205 -396.656053) (xy 383.737232 -396.590669) (xy 383.729188 -396.523846)
			(xy 383.729189 -396.456539) (xy 383.737235 -396.389716) (xy 383.753209 -396.324333) (xy 383.776884 -396.261328)
			(xy 383.80792 -396.201604) (xy 383.845871 -396.146018) (xy 383.86766 -396.120366) (xy 383.873461 -396.113224)
			(xy 383.879971 -396.096031) (xy 383.88036 -396.086838) (xy 383.88036 -395.92885) (xy 383.880805 -395.918679)
			(xy 383.888578 -395.899881) (xy 383.902958 -395.885494) (xy 383.921751 -395.877711) (xy 383.931922 -395.877288)
			(xy 384.648202 -395.877288) (xy 384.65838 -395.877663) (xy 384.677184 -395.885458) (xy 384.691571 -395.899859)
			(xy 384.699347 -395.918672) (xy 384.699764 -395.92885) (xy 384.699764 -396.086838) (xy 384.700164 -396.096026)
			(xy 384.706686 -396.11321) (xy 384.712464 -396.120366) (xy 384.734242 -396.146026) (xy 384.772191 -396.201612)
			(xy 384.803224 -396.261334) (xy 384.826898 -396.324337) (xy 384.842871 -396.389719) (xy 384.850916 -396.45654)
			(xy 384.850917 -396.523845) (xy 384.842874 -396.590666) (xy 384.826902 -396.656048) (xy 384.803231 -396.719052)
			(xy 384.772199 -396.778776) (xy 384.734251 -396.834362) (xy 384.712464 -396.860014) (xy 384.706674 -396.867164)
			(xy 384.700156 -396.884351) (xy 384.699764 -396.893542) (xy 384.699764 -397.38681) (xy 384.700177 -397.395997)
			(xy 384.70669 -397.413181) (xy 384.712464 -397.420338) (xy 384.734214 -397.446021) (xy 384.772164 -397.501603)
			(xy 384.800587 -397.556296) (xy 385.928833 -397.556296) (xy 385.936908 -397.489358) (xy 385.952943 -397.42387)
			(xy 385.976706 -397.360773) (xy 386.007856 -397.300977) (xy 386.045944 -397.245343) (xy 386.067808 -397.219678)
			(xy 386.073597 -397.212528) (xy 386.080116 -397.195341) (xy 386.080508 -397.18615) (xy 386.080508 -397.028924)
			(xy 386.080936 -397.018802) (xy 386.088677 -397.000097) (xy 386.102991 -396.985782) (xy 386.121694 -396.978037)
			(xy 386.131816 -396.977616) (xy 386.848096 -396.977616) (xy 386.85822 -396.97802) (xy 386.876927 -396.985769)
			(xy 386.891242 -397.00009) (xy 386.898984 -397.0188) (xy 386.899404 -397.028924) (xy 386.899404 -397.18615)
			(xy 386.899837 -397.195335) (xy 386.906335 -397.212519) (xy 386.912104 -397.219678) (xy 386.933978 -397.245335)
			(xy 386.972066 -397.300971) (xy 387.003216 -397.360768) (xy 387.026979 -397.423866) (xy 387.043014 -397.489356)
			(xy 387.051089 -397.556295) (xy 387.051088 -397.62372) (xy 387.043011 -397.690659) (xy 387.026975 -397.756148)
			(xy 387.00321 -397.819245) (xy 387.000823 -397.823826) (xy 388.128959 -397.823826) (xy 388.128963 -397.756517)
			(xy 388.137011 -397.689692) (xy 388.152988 -397.624308) (xy 388.176665 -397.561301) (xy 388.207704 -397.501577)
			(xy 388.245658 -397.44599) (xy 388.267448 -397.420338) (xy 388.273259 -397.413204) (xy 388.279764 -397.396005)
			(xy 388.280148 -397.38681) (xy 388.280148 -396.893542) (xy 388.279707 -396.884358) (xy 388.273213 -396.867174)
			(xy 388.267448 -396.860014) (xy 388.24565 -396.83437) (xy 388.207701 -396.778783) (xy 388.176668 -396.719058)
			(xy 388.152995 -396.656052) (xy 388.137022 -396.590669) (xy 388.128979 -396.523845) (xy 388.12898 -396.456539)
			(xy 388.137025 -396.389716) (xy 388.152999 -396.324333) (xy 388.176674 -396.261328) (xy 388.207709 -396.201604)
			(xy 388.245659 -396.146018) (xy 388.267448 -396.120366) (xy 388.273247 -396.113223) (xy 388.279759 -396.096031)
			(xy 388.280148 -396.086838) (xy 388.280148 -395.92885) (xy 388.280605 -395.91868) (xy 388.288375 -395.899885)
			(xy 388.302751 -395.885498) (xy 388.321541 -395.877713) (xy 388.33171 -395.877288) (xy 389.04799 -395.877288)
			(xy 389.058167 -395.877673) (xy 389.076971 -395.885464) (xy 389.091358 -395.899862) (xy 389.099135 -395.918672)
			(xy 389.099552 -395.92885) (xy 389.099552 -396.086838) (xy 389.099955 -396.096026) (xy 389.106475 -396.113209)
			(xy 389.112252 -396.120366) (xy 389.13403 -396.146026) (xy 389.17198 -396.201611) (xy 389.203014 -396.261334)
			(xy 389.226688 -396.324337) (xy 389.242662 -396.389718) (xy 389.250707 -396.45654) (xy 389.250707 -396.523845)
			(xy 389.242664 -396.590667) (xy 389.226692 -396.656048) (xy 389.20302 -396.719053) (xy 389.171987 -396.778776)
			(xy 389.134039 -396.834362) (xy 389.112252 -396.860014) (xy 389.106461 -396.867163) (xy 389.099944 -396.884351)
			(xy 389.099552 -396.893542) (xy 389.099552 -397.38681) (xy 389.099968 -397.395996) (xy 389.106479 -397.41318)
			(xy 389.112252 -397.420338) (xy 389.134002 -397.446021) (xy 389.171953 -397.501603) (xy 389.200407 -397.556356)
			(xy 390.329153 -397.556356) (xy 390.337195 -397.489535) (xy 390.353166 -397.424153) (xy 390.376836 -397.36115)
			(xy 390.407865 -397.301426) (xy 390.44581 -397.245839) (xy 390.467596 -397.220186) (xy 390.473381 -397.213032)
			(xy 390.479903 -397.195848) (xy 390.480296 -397.186658) (xy 390.480296 -397.028924) (xy 390.480741 -397.018772)
			(xy 390.488528 -397.000021) (xy 390.502918 -396.985697) (xy 390.521704 -396.977995) (xy 390.531858 -396.977616)
			(xy 391.248138 -396.977616) (xy 391.258264 -396.978095) (xy 391.276982 -396.985831) (xy 391.291336 -397.000119)
			(xy 391.299158 -397.0188) (xy 391.2997 -397.028924) (xy 391.2997 -397.186658) (xy 391.30013 -397.195843)
			(xy 391.30663 -397.213028) (xy 391.3124 -397.220186) (xy 391.334196 -397.245831) (xy 391.372142 -397.301419)
			(xy 391.403173 -397.361144) (xy 391.426844 -397.424149) (xy 391.442815 -397.489532) (xy 391.450857 -397.556355)
			(xy 391.450856 -397.62366) (xy 391.442812 -397.690483) (xy 391.426839 -397.755865) (xy 391.403167 -397.81887)
			(xy 391.372135 -397.878594) (xy 391.334187 -397.934181) (xy 391.3124 -397.959834) (xy 391.306606 -397.966981)
			(xy 391.30009 -397.98417) (xy 391.2997 -397.993362) (xy 391.2997 -398.486884) (xy 391.300118 -398.49607)
			(xy 391.306626 -398.513255) (xy 391.3124 -398.520412) (xy 391.334222 -398.546036) (xy 391.372167 -398.601627)
			(xy 391.403197 -398.661355) (xy 391.426866 -398.724363) (xy 391.442835 -398.789748) (xy 391.450876 -398.856574)
			(xy 391.450872 -398.923881) (xy 391.442825 -398.990705) (xy 391.42685 -399.056089) (xy 391.403175 -399.119095)
			(xy 391.372139 -399.178819) (xy 391.334189 -399.234407) (xy 391.3124 -399.26006) (xy 391.306595 -399.2672)
			(xy 391.300086 -399.284394) (xy 391.2997 -399.293588) (xy 391.2997 -399.451576) (xy 391.299259 -399.461729)
			(xy 391.291471 -399.480481) (xy 391.27708 -399.494805) (xy 391.258292 -399.502505) (xy 391.248138 -399.502884)
			(xy 390.531858 -399.502884) (xy 390.521732 -399.502409) (xy 390.503014 -399.494671) (xy 390.48866 -399.480382)
			(xy 390.480838 -399.4617) (xy 390.480296 -399.451576) (xy 390.480296 -399.293588) (xy 390.479892 -399.2844)
			(xy 390.473374 -399.267216) (xy 390.467596 -399.26006) (xy 390.445845 -399.234378) (xy 390.407898 -399.178795)
			(xy 390.376865 -399.119075) (xy 390.353192 -399.056075) (xy 390.337218 -398.990696) (xy 390.329172 -398.923878)
			(xy 390.329169 -398.856576) (xy 390.337209 -398.789757) (xy 390.353176 -398.724377) (xy 390.376843 -398.661374)
			(xy 390.40787 -398.601652) (xy 390.445812 -398.546065) (xy 390.467596 -398.520412) (xy 390.473412 -398.51328)
			(xy 390.479915 -398.49608) (xy 390.480296 -398.486884) (xy 390.480296 -397.993362) (xy 390.479905 -397.984173)
			(xy 390.473378 -397.966988) (xy 390.467596 -397.959834) (xy 390.445819 -397.934173) (xy 390.407873 -397.878587)
			(xy 390.376842 -397.818864) (xy 390.35317 -397.755861) (xy 390.337198 -397.69048) (xy 390.329154 -397.623659)
			(xy 390.329153 -397.556356) (xy 389.200407 -397.556356) (xy 389.202988 -397.561322) (xy 389.226664 -397.624322)
			(xy 389.24264 -397.689701) (xy 389.250687 -397.75652) (xy 389.25069 -397.823823) (xy 389.24265 -397.890643)
			(xy 389.226681 -397.956023) (xy 389.203012 -398.019026) (xy 389.171982 -398.078748) (xy 389.134038 -398.134334)
			(xy 389.112252 -398.159986) (xy 389.10643 -398.167113) (xy 389.099932 -398.184318) (xy 389.099552 -398.193514)
			(xy 389.099552 -398.351502) (xy 389.099138 -398.361675) (xy 389.09135 -398.380472) (xy 389.076962 -398.394857)
			(xy 389.058163 -398.40264) (xy 389.04799 -398.403064) (xy 388.33171 -398.403064) (xy 388.321539 -398.402628)
			(xy 388.302745 -398.394847) (xy 388.28836 -398.380465) (xy 388.280574 -398.361673) (xy 388.280148 -398.351502)
			(xy 388.280148 -398.193514) (xy 388.27972 -398.184329) (xy 388.273218 -398.167145) (xy 388.267448 -398.159986)
			(xy 388.245622 -398.134365) (xy 388.207674 -398.078774) (xy 388.176642 -398.019046) (xy 388.152971 -397.956038)
			(xy 388.137 -397.890652) (xy 388.128959 -397.823826) (xy 387.000823 -397.823826) (xy 386.972058 -397.879042)
			(xy 386.933968 -397.934677) (xy 386.912104 -397.960342) (xy 386.906308 -397.967487) (xy 386.899793 -397.984678)
			(xy 386.899404 -397.99387) (xy 386.899404 -398.486376) (xy 386.899825 -398.495562) (xy 386.906331 -398.512747)
			(xy 386.912104 -398.519904) (xy 386.934003 -398.54554) (xy 386.972091 -398.601179) (xy 387.003239 -398.660979)
			(xy 387.027001 -398.72408) (xy 387.043034 -398.789572) (xy 387.051107 -398.856514) (xy 387.051104 -398.92394)
			(xy 387.043025 -398.990881) (xy 387.026985 -399.056372) (xy 387.003217 -399.11947) (xy 386.972063 -399.179268)
			(xy 386.93397 -399.234903) (xy 386.912104 -399.260568) (xy 386.906297 -399.267706) (xy 386.899788 -399.284902)
			(xy 386.899404 -399.294096) (xy 386.899404 -399.451576) (xy 386.898965 -399.461696) (xy 386.891225 -399.480399)
			(xy 386.876916 -399.494714) (xy 386.858216 -399.502461) (xy 386.848096 -399.502884) (xy 386.131816 -399.502884)
			(xy 386.121693 -399.502471) (xy 386.102986 -399.494725) (xy 386.088671 -399.480407) (xy 386.080928 -399.4617)
			(xy 386.080508 -399.451576) (xy 386.080508 -399.294096) (xy 386.080098 -399.284909) (xy 386.073584 -399.267725)
			(xy 386.067808 -399.260568) (xy 386.045979 -399.234874) (xy 386.007889 -399.179244) (xy 385.976736 -399.119451)
			(xy 385.95297 -399.056358) (xy 385.936931 -398.990873) (xy 385.928852 -398.923938) (xy 385.928849 -398.856517)
			(xy 385.936922 -398.789581) (xy 385.952954 -398.724093) (xy 385.976714 -398.660998) (xy 386.007861 -398.601203)
			(xy 386.045946 -398.545569) (xy 386.067808 -398.519904) (xy 386.073586 -398.512746) (xy 386.080112 -398.495565)
			(xy 386.080508 -398.486376) (xy 386.080508 -397.99387) (xy 386.080111 -397.984681) (xy 386.073588 -397.967497)
			(xy 386.067808 -397.960342) (xy 386.045954 -397.934669) (xy 386.007864 -397.879036) (xy 385.976712 -397.819241)
			(xy 385.952947 -397.756145) (xy 385.936911 -397.690657) (xy 385.928834 -397.623719) (xy 385.928833 -397.556296)
			(xy 384.800587 -397.556296) (xy 384.803199 -397.561322) (xy 384.826873 -397.624323) (xy 384.842849 -397.689701)
			(xy 384.850896 -397.75652) (xy 384.850899 -397.823822) (xy 384.842859 -397.890642) (xy 384.82689 -397.956022)
			(xy 384.803222 -398.019025) (xy 384.772193 -398.078748) (xy 384.734249 -398.134334) (xy 384.712464 -398.159986)
			(xy 384.706644 -398.167114) (xy 384.700144 -398.184318) (xy 384.699764 -398.193514) (xy 384.699764 -398.351502)
			(xy 384.699268 -398.36166) (xy 384.691494 -398.380428) (xy 384.677128 -398.394794) (xy 384.65836 -398.402568)
			(xy 384.648202 -398.403064) (xy 383.931922 -398.403064) (xy 383.921752 -398.402618) (xy 383.902958 -398.394841)
			(xy 383.888573 -398.380462) (xy 383.880787 -398.361672) (xy 383.88036 -398.351502) (xy 383.88036 -398.193514)
			(xy 383.87993 -398.184329) (xy 383.873429 -398.167145) (xy 383.86766 -398.159986) (xy 383.845834 -398.134365)
			(xy 383.807885 -398.078775) (xy 383.776852 -398.019047) (xy 383.753181 -397.956038) (xy 383.73721 -397.890652)
			(xy 383.729168 -397.823826) (xy 382.600522 -397.823826) (xy 382.572059 -397.878597) (xy 382.534106 -397.934182)
			(xy 382.512316 -397.959834) (xy 382.506524 -397.966983) (xy 382.500006 -397.98417) (xy 382.499616 -397.993362)
			(xy 382.499616 -398.486884) (xy 382.50003 -398.496071) (xy 382.506541 -398.513255) (xy 382.512316 -398.520412)
			(xy 382.53414 -398.546034) (xy 382.572091 -398.601624) (xy 382.603125 -398.661351) (xy 382.626798 -398.72436)
			(xy 382.64277 -398.789746) (xy 382.650812 -398.856573) (xy 382.650808 -398.923881) (xy 382.64276 -398.990707)
			(xy 382.626782 -399.056092) (xy 382.603103 -399.119098) (xy 382.572063 -399.178822) (xy 382.534107 -399.234408)
			(xy 382.512316 -399.26006) (xy 382.506513 -399.267201) (xy 382.500002 -399.284395) (xy 382.499616 -399.293588)
			(xy 382.499616 -399.451576) (xy 382.499159 -399.461727) (xy 382.491375 -399.480475) (xy 382.476989 -399.494799)
			(xy 382.458206 -399.502503) (xy 382.448054 -399.502884) (xy 381.731774 -399.502884) (xy 381.721649 -399.502396)
			(xy 381.702931 -399.494664) (xy 381.688577 -399.480379) (xy 381.680754 -399.461699) (xy 381.680212 -399.451576)
			(xy 381.680212 -399.293588) (xy 381.679805 -399.284401) (xy 381.673289 -399.267216) (xy 381.667512 -399.26006)
			(xy 381.64576 -399.234378) (xy 381.607812 -399.178796) (xy 381.576779 -399.119076) (xy 381.553105 -399.056075)
			(xy 381.537131 -398.990697) (xy 381.529084 -398.923878) (xy 381.529081 -398.856576) (xy 381.537121 -398.789757)
			(xy 381.553089 -398.724377) (xy 381.576757 -398.661374) (xy 381.607784 -398.601651) (xy 381.645727 -398.546064)
			(xy 381.667512 -398.520412) (xy 381.67333 -398.513282) (xy 381.679831 -398.49608) (xy 381.680212 -398.486884)
			(xy 381.680212 -397.993362) (xy 381.679818 -397.984173) (xy 381.673293 -397.966989) (xy 381.667512 -397.959834)
			(xy 381.645735 -397.934173) (xy 381.607788 -397.878588) (xy 381.576755 -397.818865) (xy 381.553083 -397.755862)
			(xy 381.53711 -397.690481) (xy 381.529066 -397.623659) (xy 381.529065 -397.556356) (xy 380.40085 -397.556356)
			(xy 380.403242 -397.560947) (xy 380.42701 -397.62404) (xy 380.443049 -397.689525) (xy 380.451128 -397.756461)
			(xy 380.451131 -397.823882) (xy 380.443059 -397.890818) (xy 380.427026 -397.956306) (xy 380.403265 -398.019401)
			(xy 380.372117 -398.079196) (xy 380.334031 -398.134829) (xy 380.312168 -398.160494) (xy 380.306387 -398.16765)
			(xy 380.299864 -398.184832) (xy 380.299468 -398.194022) (xy 380.299468 -398.351502) (xy 380.298975 -398.361628)
			(xy 380.291248 -398.380347) (xy 380.276964 -398.394703) (xy 380.258283 -398.402524) (xy 380.24816 -398.403064)
			(xy 379.53188 -398.403064) (xy 379.52172 -398.402694) (xy 379.50296 -398.394885) (xy 379.488636 -398.380472)
			(xy 379.480944 -398.361664) (xy 379.480572 -398.351502) (xy 379.480572 -398.194022) (xy 379.480158 -398.184835)
			(xy 379.473648 -398.16765) (xy 379.467872 -398.160494) (xy 379.445972 -398.134859) (xy 379.407886 -398.07922)
			(xy 379.376738 -398.019419) (xy 379.352978 -397.956318) (xy 379.336946 -397.890826) (xy 379.328873 -397.823885)
			(xy 378.200706 -397.823885) (xy 378.171972 -397.879041) (xy 378.133884 -397.934676) (xy 378.11202 -397.960342)
			(xy 378.106225 -397.967489) (xy 378.099709 -397.984678) (xy 378.09932 -397.99387) (xy 378.09932 -398.486376)
			(xy 378.099737 -398.495563) (xy 378.106245 -398.512747) (xy 378.11202 -398.519904) (xy 378.133919 -398.54554)
			(xy 378.172005 -398.60118) (xy 378.203153 -398.66098) (xy 378.226914 -398.724081) (xy 378.242947 -398.789573)
			(xy 378.251019 -398.856514) (xy 378.251016 -398.92394) (xy 378.242937 -398.99088) (xy 378.226898 -399.056371)
			(xy 378.203131 -399.11947) (xy 378.171977 -399.179267) (xy 378.133885 -399.234902) (xy 378.11202 -399.260568)
			(xy 378.106214 -399.267707) (xy 378.099704 -399.284902) (xy 378.09932 -399.294096) (xy 378.09932 -399.451576)
			(xy 378.098865 -399.461694) (xy 378.091128 -399.480394) (xy 378.076824 -399.494708) (xy 378.05813 -399.502458)
			(xy 378.048012 -399.502884) (xy 377.331732 -399.502884) (xy 377.32161 -399.502458) (xy 377.302903 -399.494717)
			(xy 377.288587 -399.480403) (xy 377.280844 -399.461698) (xy 377.280424 -399.451576) (xy 377.280424 -399.294096)
			(xy 377.280011 -399.284909) (xy 377.273499 -399.267725) (xy 377.267724 -399.260568) (xy 377.245895 -399.234874)
			(xy 377.207803 -399.179244) (xy 377.17665 -399.119452) (xy 377.152882 -399.056359) (xy 377.136844 -398.990873)
			(xy 377.128765 -398.923938) (xy 377.128761 -398.856516) (xy 377.136834 -398.78958) (xy 377.152866 -398.724093)
			(xy 377.176627 -398.660997) (xy 377.207775 -398.601202) (xy 377.245861 -398.545569) (xy 377.267724 -398.519904)
			(xy 377.273504 -398.512747) (xy 377.280028 -398.495565) (xy 377.280424 -398.486376) (xy 377.280424 -397.99387)
			(xy 377.280023 -397.984682) (xy 377.273502 -397.967498) (xy 377.267724 -397.960342) (xy 377.245869 -397.934669)
			(xy 377.207778 -397.879036) (xy 377.176626 -397.819241) (xy 377.15286 -397.756145) (xy 377.136823 -397.690657)
			(xy 377.128746 -397.623719) (xy 377.128745 -397.556296) (xy 376.0005 -397.556296) (xy 376.003112 -397.561323)
			(xy 376.026786 -397.624324) (xy 376.042761 -397.689702) (xy 376.050808 -397.756521) (xy 376.050811 -397.823822)
			(xy 376.042771 -397.890642) (xy 376.026803 -397.956022) (xy 376.003135 -398.019025) (xy 375.972108 -398.078747)
			(xy 375.934165 -398.134333) (xy 375.91238 -398.159986) (xy 375.906562 -398.167116) (xy 375.900061 -398.184318)
			(xy 375.89968 -398.193514) (xy 375.89968 -398.351502) (xy 375.899169 -398.361658) (xy 375.891397 -398.380423)
			(xy 375.877037 -398.394788) (xy 375.858274 -398.402565) (xy 375.848118 -398.403064) (xy 375.131838 -398.403064)
			(xy 375.121669 -398.402605) (xy 375.102876 -398.394833) (xy 375.08849 -398.380458) (xy 375.080703 -398.361671)
			(xy 375.080276 -398.351502) (xy 375.080276 -398.193514) (xy 375.079865 -398.184327) (xy 375.073352 -398.167142)
			(xy 375.067576 -398.159986) (xy 375.04575 -398.134365) (xy 375.007799 -398.078775) (xy 374.976766 -398.019048)
			(xy 374.953093 -397.956039) (xy 374.937122 -397.890652) (xy 374.92908 -397.823826) (xy 347.400682 -397.823826)
			(xy 347.372224 -397.878594) (xy 347.334276 -397.934182) (xy 347.312488 -397.959834) (xy 347.306693 -397.96698)
			(xy 347.300178 -397.98417) (xy 347.299788 -397.993362) (xy 347.299788 -398.486884) (xy 347.300209 -398.49607)
			(xy 347.306715 -398.513254) (xy 347.312488 -398.520412) (xy 347.33431 -398.546035) (xy 347.372256 -398.601627)
			(xy 347.403286 -398.661354) (xy 347.426956 -398.724363) (xy 347.442926 -398.789748) (xy 347.450967 -398.856573)
			(xy 347.450963 -398.923881) (xy 347.442916 -398.990705) (xy 347.42694 -399.056089) (xy 347.403264 -399.119095)
			(xy 347.372228 -399.17882) (xy 347.334277 -399.234407) (xy 347.312488 -399.26006) (xy 347.306682 -399.267199)
			(xy 347.300173 -399.284394) (xy 347.299788 -399.293588) (xy 347.299788 -399.451576) (xy 347.299359 -399.46173)
			(xy 347.291569 -399.480484) (xy 347.277174 -399.494809) (xy 347.258382 -399.502507) (xy 347.248226 -399.502884)
			(xy 346.531946 -399.502884) (xy 346.521825 -399.502336) (xy 346.50311 -399.494628) (xy 346.488753 -399.480361)
			(xy 346.480928 -399.461694) (xy 346.480384 -399.451576) (xy 346.480384 -399.293588) (xy 346.479983 -399.2844)
			(xy 346.473463 -399.267215) (xy 346.467684 -399.26006) (xy 346.44593 -399.234379) (xy 346.407977 -399.178798)
			(xy 346.37694 -399.119079) (xy 346.353263 -399.056078) (xy 346.337287 -398.990699) (xy 346.329239 -398.923879)
			(xy 346.329236 -398.856576) (xy 346.337277 -398.789755) (xy 346.353247 -398.724374) (xy 346.376918 -398.661371)
			(xy 346.40795 -398.601648) (xy 346.445897 -398.546064) (xy 346.467684 -398.520412) (xy 346.473499 -398.513279)
			(xy 346.480003 -398.496079) (xy 346.480384 -398.486884) (xy 346.480384 -397.993362) (xy 346.479996 -397.984172)
			(xy 346.473467 -397.966988) (xy 346.467684 -397.959834) (xy 346.445905 -397.934174) (xy 346.407953 -397.87859)
			(xy 346.376917 -397.818868) (xy 346.353241 -397.755864) (xy 346.337266 -397.690483) (xy 346.329221 -397.62366)
			(xy 346.32922 -397.556355) (xy 345.200497 -397.556355) (xy 345.203078 -397.561321) (xy 345.226754 -397.624322)
			(xy 345.24273 -397.689701) (xy 345.250778 -397.75652) (xy 345.250781 -397.823823) (xy 345.242741 -397.890643)
			(xy 345.226771 -397.956023) (xy 345.203102 -398.019026) (xy 345.172072 -398.078749) (xy 345.134126 -398.134334)
			(xy 345.11234 -398.159986) (xy 345.106517 -398.167112) (xy 345.10002 -398.184318) (xy 345.09964 -398.193514)
			(xy 345.09964 -398.351502) (xy 345.099237 -398.361676) (xy 345.091447 -398.380475) (xy 345.077055 -398.394861)
			(xy 345.058253 -398.402642) (xy 345.048078 -398.403064) (xy 344.331798 -398.403064) (xy 344.32164 -398.402568)
			(xy 344.302872 -398.394794) (xy 344.288506 -398.380428) (xy 344.280732 -398.36166) (xy 344.280236 -398.351502)
			(xy 344.280236 -398.193514) (xy 344.279811 -398.184329) (xy 344.273307 -398.167144) (xy 344.267536 -398.159986)
			(xy 344.245711 -398.134365) (xy 344.207763 -398.078774) (xy 344.176732 -398.019046) (xy 344.153061 -397.956037)
			(xy 344.137091 -397.890651) (xy 344.12905 -397.823825) (xy 343.000914 -397.823825) (xy 342.972147 -397.879042)
			(xy 342.934057 -397.934677) (xy 342.912192 -397.960342) (xy 342.906394 -397.967486) (xy 342.899881 -397.984678)
			(xy 342.899492 -397.99387) (xy 342.899492 -398.486376) (xy 342.899916 -398.495562) (xy 342.90642 -398.512746)
			(xy 342.912192 -398.519904) (xy 342.934092 -398.54554) (xy 342.97218 -398.601178) (xy 343.003329 -398.660979)
			(xy 343.027092 -398.724079) (xy 343.043125 -398.789572) (xy 343.051198 -398.856514) (xy 343.051195 -398.92394)
			(xy 343.043115 -398.990881) (xy 343.027076 -399.056372) (xy 343.003307 -399.119471) (xy 342.972152 -399.179268)
			(xy 342.934058 -399.234903) (xy 342.912192 -399.260568) (xy 342.906383 -399.267704) (xy 342.899876 -399.284902)
			(xy 342.899492 -399.294096) (xy 342.899492 -399.451576) (xy 342.899064 -399.461698) (xy 342.891323 -399.480403)
			(xy 342.877009 -399.494718) (xy 342.858306 -399.502463) (xy 342.848184 -399.502884) (xy 342.131904 -399.502884)
			(xy 342.12178 -399.50248) (xy 342.103073 -399.494731) (xy 342.088758 -399.48041) (xy 342.081016 -399.4617)
			(xy 342.080596 -399.451576) (xy 342.080596 -399.294096) (xy 342.080189 -399.284909) (xy 342.073673 -399.267724)
			(xy 342.067896 -399.260568) (xy 342.046068 -399.234874) (xy 342.007978 -399.179243) (xy 341.976826 -399.119451)
			(xy 341.95306 -399.056358) (xy 341.937022 -398.990872) (xy 341.928943 -398.923937) (xy 341.92894 -398.856517)
			(xy 341.937012 -398.789581) (xy 341.953044 -398.724094) (xy 341.976804 -398.660999) (xy 342.00795 -398.601203)
			(xy 342.046034 -398.545569) (xy 342.067896 -398.519904) (xy 342.073673 -398.512745) (xy 342.080199 -398.495565)
			(xy 342.080596 -398.486376) (xy 342.080596 -397.99387) (xy 342.080201 -397.984681) (xy 342.073677 -397.967497)
			(xy 342.067896 -397.960342) (xy 342.046042 -397.934669) (xy 342.007953 -397.879035) (xy 341.976802 -397.81924)
			(xy 341.953038 -397.756144) (xy 341.937002 -397.690656) (xy 341.928925 -397.623719) (xy 341.928924 -397.556296)
			(xy 340.800676 -397.556296) (xy 340.803288 -397.561322) (xy 340.826964 -397.624322) (xy 340.84294 -397.689701)
			(xy 340.850987 -397.75652) (xy 340.85099 -397.823823) (xy 340.84295 -397.890643) (xy 340.826981 -397.956023)
			(xy 340.803312 -398.019026) (xy 340.772282 -398.078748) (xy 340.734338 -398.134334) (xy 340.712552 -398.159986)
			(xy 340.70673 -398.167113) (xy 340.700232 -398.184318) (xy 340.699852 -398.193514) (xy 340.699852 -398.351502)
			(xy 340.699438 -398.361675) (xy 340.69165 -398.380472) (xy 340.677262 -398.394857) (xy 340.658463 -398.40264)
			(xy 340.64829 -398.403064) (xy 339.93201 -398.403064) (xy 339.921839 -398.402628) (xy 339.903045 -398.394847)
			(xy 339.88866 -398.380465) (xy 339.880874 -398.361673) (xy 339.880448 -398.351502) (xy 339.880448 -398.193514)
			(xy 339.88002 -398.184329) (xy 339.873518 -398.167145) (xy 339.867748 -398.159986) (xy 339.845922 -398.134365)
			(xy 339.807974 -398.078774) (xy 339.776942 -398.019046) (xy 339.753271 -397.956038) (xy 339.7373 -397.890652)
			(xy 339.729259 -397.823826) (xy 338.600595 -397.823826) (xy 338.572138 -397.878594) (xy 338.534191 -397.934181)
			(xy 338.512404 -397.959834) (xy 338.506611 -397.966982) (xy 338.500094 -397.98417) (xy 338.499704 -397.993362)
			(xy 338.499704 -398.486884) (xy 338.500121 -398.49607) (xy 338.50663 -398.513255) (xy 338.512404 -398.520412)
			(xy 338.534226 -398.546036) (xy 338.572171 -398.601627) (xy 338.6032 -398.661355) (xy 338.626869 -398.724363)
			(xy 338.642838 -398.789748) (xy 338.650879 -398.856574) (xy 338.650875 -398.923881) (xy 338.642828 -398.990705)
			(xy 338.626853 -399.056089) (xy 338.603178 -399.119094) (xy 338.572143 -399.178819) (xy 338.534193 -399.234407)
			(xy 338.512404 -399.26006) (xy 338.5066 -399.2672) (xy 338.50009 -399.284394) (xy 338.499704 -399.293588)
			(xy 338.499704 -399.451576) (xy 338.499259 -399.461728) (xy 338.491472 -399.480479) (xy 338.477082 -399.494803)
			(xy 338.458296 -399.502505) (xy 338.448142 -399.502884) (xy 337.731862 -399.502884) (xy 337.721736 -399.502405)
			(xy 337.703018 -399.494669) (xy 337.688664 -399.480381) (xy 337.680842 -399.4617) (xy 337.6803 -399.451576)
			(xy 337.6803 -399.293588) (xy 337.679895 -399.2844) (xy 337.673378 -399.267216) (xy 337.6676 -399.26006)
			(xy 337.645849 -399.234378) (xy 337.607901 -399.178795) (xy 337.576869 -399.119075) (xy 337.553196 -399.056075)
			(xy 337.537221 -398.990697) (xy 337.529175 -398.923878) (xy 337.529172 -398.856576) (xy 337.537212 -398.789757)
			(xy 337.55318 -398.724377) (xy 337.576847 -398.661374) (xy 337.607874 -398.601651) (xy 337.645816 -398.546065)
			(xy 337.6676 -398.520412) (xy 337.673416 -398.513281) (xy 337.679919 -398.49608) (xy 337.6803 -398.486884)
			(xy 337.6803 -397.993362) (xy 337.679908 -397.984173) (xy 337.673382 -397.966989) (xy 337.6676 -397.959834)
			(xy 337.645823 -397.934173) (xy 337.607877 -397.878587) (xy 337.576845 -397.818864) (xy 337.553174 -397.755861)
			(xy 337.537201 -397.69048) (xy 337.529157 -397.623659) (xy 337.529156 -397.556356) (xy 336.40094 -397.556356)
			(xy 336.403332 -397.560946) (xy 336.4271 -397.624039) (xy 336.443139 -397.689525) (xy 336.451219 -397.756461)
			(xy 336.451222 -397.823882) (xy 336.44315 -397.890819) (xy 336.427117 -397.956306) (xy 336.403355 -398.019402)
			(xy 336.372206 -398.079196) (xy 336.334119 -398.13483) (xy 336.312256 -398.160494) (xy 336.306474 -398.167649)
			(xy 336.299952 -398.184832) (xy 336.299556 -398.194022) (xy 336.299556 -398.351502) (xy 336.299075 -398.361629)
			(xy 336.291346 -398.380351) (xy 336.277058 -398.394708) (xy 336.258373 -398.402526) (xy 336.248248 -398.403064)
			(xy 335.531968 -398.403064) (xy 335.521807 -398.402704) (xy 335.503047 -398.394891) (xy 335.488724 -398.380475)
			(xy 335.481032 -398.361665) (xy 335.48066 -398.351502) (xy 335.48066 -398.194022) (xy 335.480226 -398.184838)
			(xy 335.473727 -398.167654) (xy 335.46796 -398.160494) (xy 335.44606 -398.134859) (xy 335.407975 -398.079219)
			(xy 335.376828 -398.019418) (xy 335.353068 -397.956318) (xy 335.337036 -397.890825) (xy 335.328964 -397.823884)
			(xy 334.200796 -397.823884) (xy 334.172062 -397.879042) (xy 334.133972 -397.934677) (xy 334.112108 -397.960342)
			(xy 334.106312 -397.967488) (xy 334.099797 -397.984678) (xy 334.099408 -397.99387) (xy 334.099408 -398.486376)
			(xy 334.099828 -398.495562) (xy 334.106335 -398.512747) (xy 334.112108 -398.519904) (xy 334.134007 -398.54554)
			(xy 334.172094 -398.601179) (xy 334.203243 -398.660979) (xy 334.227005 -398.72408) (xy 334.243037 -398.789573)
			(xy 334.25111 -398.856514) (xy 334.251107 -398.92394) (xy 334.243028 -398.990881) (xy 334.226989 -399.056372)
			(xy 334.203221 -399.11947) (xy 334.172066 -399.179267) (xy 334.133974 -399.234903) (xy 334.112108 -399.260568)
			(xy 334.106301 -399.267706) (xy 334.099792 -399.284902) (xy 334.099408 -399.294096) (xy 334.099408 -399.451576)
			(xy 334.098965 -399.461696) (xy 334.091226 -399.480398) (xy 334.076918 -399.494712) (xy 334.05822 -399.50246)
			(xy 334.0481 -399.502884) (xy 333.33182 -399.502884) (xy 333.321697 -399.502467) (xy 333.302991 -399.494723)
			(xy 333.288675 -399.480406) (xy 333.280932 -399.461699) (xy 333.280512 -399.451576) (xy 333.280512 -399.294096)
			(xy 333.280101 -399.284909) (xy 333.273587 -399.267725) (xy 333.267812 -399.260568) (xy 333.245983 -399.234874)
			(xy 333.207892 -399.179244) (xy 333.176739 -399.119452) (xy 333.152973 -399.056358) (xy 333.136934 -398.990873)
			(xy 333.128855 -398.923938) (xy 333.128852 -398.856516) (xy 333.136925 -398.78958) (xy 333.152957 -398.724093)
			(xy 333.176717 -398.660998) (xy 333.207865 -398.601203) (xy 333.24595 -398.545569) (xy 333.267812 -398.519904)
			(xy 333.273591 -398.512746) (xy 333.280116 -398.495565) (xy 333.280512 -398.486376) (xy 333.280512 -397.99387)
			(xy 333.280114 -397.984682) (xy 333.273592 -397.967497) (xy 333.267812 -397.960342) (xy 333.245957 -397.934669)
			(xy 333.207868 -397.879036) (xy 333.176716 -397.819241) (xy 333.152951 -397.756145) (xy 333.136914 -397.690657)
			(xy 333.128837 -397.623719) (xy 333.128836 -397.556296) (xy 332.00059 -397.556296) (xy 332.003202 -397.561323)
			(xy 332.026877 -397.624323) (xy 332.042852 -397.689701) (xy 332.050899 -397.75652) (xy 332.050902 -397.823822)
			(xy 332.042862 -397.890642) (xy 332.026893 -397.956022) (xy 332.003225 -398.019025) (xy 331.972197 -398.078748)
			(xy 331.934253 -398.134334) (xy 331.912468 -398.159986) (xy 331.906648 -398.167115) (xy 331.900148 -398.184318)
			(xy 331.899768 -398.193514) (xy 331.899768 -398.351502) (xy 331.899268 -398.361659) (xy 331.891494 -398.380427)
			(xy 331.877131 -398.394792) (xy 331.858363 -398.402568) (xy 331.848206 -398.403064) (xy 331.131926 -398.403064)
			(xy 331.121756 -398.402615) (xy 331.102963 -398.394839) (xy 331.088577 -398.380461) (xy 331.080791 -398.361671)
			(xy 331.080364 -398.351502) (xy 331.080364 -398.193514) (xy 331.079933 -398.184329) (xy 331.073432 -398.167146)
			(xy 331.067664 -398.159986) (xy 331.045838 -398.134365) (xy 331.007889 -398.078775) (xy 330.976856 -398.019047)
			(xy 330.953184 -397.956038) (xy 330.937213 -397.890652) (xy 330.929171 -397.823826) (xy 326.525636 -397.823826)
			(xy 326.525636 -401.723737) (xy 330.929183 -401.723737) (xy 330.929184 -401.65643) (xy 330.937231 -401.589605)
			(xy 330.953207 -401.524221) (xy 330.976884 -401.461216) (xy 331.007921 -401.401492) (xy 331.045874 -401.345906)
			(xy 331.067664 -401.320254) (xy 331.07347 -401.313116) (xy 331.079977 -401.29592) (xy 331.080364 -401.286726)
			(xy 331.080364 -400.793458) (xy 331.07996 -400.78427) (xy 331.073441 -400.767087) (xy 331.067664 -400.75993)
			(xy 331.045882 -400.734273) (xy 331.007931 -400.678688) (xy 330.976896 -400.618965) (xy 330.953222 -400.555961)
			(xy 330.937248 -400.490579) (xy 330.929203 -400.423757) (xy 330.929202 -400.356452) (xy 330.937246 -400.289629)
			(xy 330.953219 -400.224247) (xy 330.976892 -400.161243) (xy 331.007926 -400.10152) (xy 331.045876 -400.045934)
			(xy 331.067664 -400.020282) (xy 331.073459 -400.013136) (xy 331.079973 -399.995946) (xy 331.080364 -399.986754)
			(xy 331.080364 -399.828766) (xy 331.080806 -399.818603) (xy 331.088597 -399.799828) (xy 331.102978 -399.785463)
			(xy 331.121762 -399.777694) (xy 331.131926 -399.777204) (xy 331.848206 -399.777204) (xy 331.85836 -399.777728)
			(xy 331.877123 -399.785498) (xy 331.891486 -399.799854) (xy 331.899267 -399.818612) (xy 331.899768 -399.828766)
			(xy 331.899768 -399.986754) (xy 331.900208 -399.995938) (xy 331.906702 -400.013122) (xy 331.912468 -400.020282)
			(xy 331.934262 -400.045929) (xy 331.97221 -400.101517) (xy 332.003242 -400.161241) (xy 332.026915 -400.224246)
			(xy 332.042887 -400.289629) (xy 332.05093 -400.356452) (xy 332.05093 -400.423757) (xy 332.042885 -400.49058)
			(xy 332.026912 -400.555963) (xy 332.003239 -400.618967) (xy 331.972205 -400.678691) (xy 331.934256 -400.734278)
			(xy 331.912468 -400.75993) (xy 331.906672 -400.767076) (xy 331.900158 -400.784266) (xy 331.899768 -400.793458)
			(xy 331.899768 -401.286726) (xy 331.900173 -401.295914) (xy 331.906691 -401.313098) (xy 331.912468 -401.320254)
			(xy 331.934234 -401.345924) (xy 331.972183 -401.401508) (xy 332.003216 -401.461229) (xy 332.02689 -401.524231)
			(xy 332.042864 -401.589611) (xy 332.05091 -401.656432) (xy 332.050912 -401.723735) (xy 332.04287 -401.790556)
			(xy 332.0269 -401.855937) (xy 332.00323 -401.91894) (xy 331.9722 -401.978663) (xy 331.934254 -402.03425)
			(xy 331.912468 -402.059902) (xy 331.906684 -402.067056) (xy 331.900163 -402.08424) (xy 331.899768 -402.09343)
			(xy 331.899768 -402.251418) (xy 331.899282 -402.261576) (xy 331.891502 -402.280345) (xy 331.877135 -402.294709)
			(xy 331.858364 -402.302484) (xy 331.848206 -402.30298) (xy 331.131926 -402.30298) (xy 331.121758 -402.302515)
			(xy 331.102968 -402.294742) (xy 331.088583 -402.280369) (xy 331.080794 -402.261585) (xy 331.080364 -402.251418)
			(xy 331.080364 -402.09343) (xy 331.079925 -402.084246) (xy 331.07343 -402.067062) (xy 331.067664 -402.059902)
			(xy 331.045854 -402.034268) (xy 331.007904 -401.97868) (xy 330.97687 -401.918954) (xy 330.953197 -401.855947)
			(xy 330.937225 -401.790562) (xy 330.929183 -401.723737) (xy 326.525636 -401.723737) (xy 326.525636 -402.823878)
			(xy 333.128796 -402.823878) (xy 333.128801 -402.75645) (xy 333.136882 -402.689508) (xy 333.152922 -402.624016)
			(xy 333.176693 -402.560918) (xy 333.20785 -402.50112) (xy 333.245945 -402.445485) (xy 333.267812 -402.41982)
			(xy 333.273626 -402.412687) (xy 333.28013 -402.395487) (xy 333.280512 -402.386292) (xy 333.280512 -401.89404)
			(xy 333.28008 -401.884855) (xy 333.273581 -401.867671) (xy 333.267812 -401.860512) (xy 333.245928 -401.834863)
			(xy 333.207839 -401.779227) (xy 333.176689 -401.719428) (xy 333.152925 -401.656329) (xy 333.136891 -401.590838)
			(xy 333.128816 -401.523898) (xy 333.128818 -401.456472) (xy 333.136896 -401.389532) (xy 333.152934 -401.324042)
			(xy 333.176701 -401.260944) (xy 333.207855 -401.201148) (xy 333.245946 -401.145513) (xy 333.267812 -401.119848)
			(xy 333.273615 -401.112707) (xy 333.280125 -401.095513) (xy 333.280512 -401.08632) (xy 333.280512 -400.92884)
			(xy 333.280949 -400.918719) (xy 333.288686 -400.900014) (xy 333.302997 -400.885698) (xy 333.321699 -400.877953)
			(xy 333.33182 -400.877532) (xy 334.0481 -400.877532) (xy 334.058226 -400.877917) (xy 334.076936 -400.885671)
			(xy 334.091252 -400.899997) (xy 334.098991 -400.918713) (xy 334.099408 -400.92884) (xy 334.099408 -401.08632)
			(xy 334.099807 -401.095508) (xy 334.106328 -401.112693) (xy 334.112108 -401.119848) (xy 334.133952 -401.14553)
			(xy 334.172041 -401.201162) (xy 334.203192 -401.260956) (xy 334.226957 -401.324051) (xy 334.242994 -401.389538)
			(xy 334.251071 -401.456474) (xy 334.251073 -401.523896) (xy 334.242999 -401.590833) (xy 334.226966 -401.656321)
			(xy 334.203204 -401.719417) (xy 334.200923 -401.723796) (xy 335.328975 -401.723796) (xy 335.328977 -401.656371)
			(xy 335.337055 -401.589432) (xy 335.353091 -401.523942) (xy 335.376856 -401.460845) (xy 335.408007 -401.401048)
			(xy 335.446096 -401.345412) (xy 335.46796 -401.319746) (xy 335.473769 -401.31261) (xy 335.480275 -401.295412)
			(xy 335.48066 -401.286218) (xy 335.48066 -400.793966) (xy 335.480253 -400.784779) (xy 335.473735 -400.767595)
			(xy 335.46796 -400.760438) (xy 335.446103 -400.734767) (xy 335.408017 -400.679133) (xy 335.376868 -400.619337)
			(xy 335.353106 -400.556241) (xy 335.337071 -400.490753) (xy 335.328995 -400.423816) (xy 335.328995 -400.356393)
			(xy 335.337069 -400.289456) (xy 335.353103 -400.223968) (xy 335.376865 -400.160872) (xy 335.408012 -400.101075)
			(xy 335.446098 -400.04544) (xy 335.46796 -400.019774) (xy 335.473757 -400.01263) (xy 335.48027 -399.995438)
			(xy 335.48066 -399.986246) (xy 335.48066 -399.828766) (xy 335.481099 -399.818635) (xy 335.488842 -399.799909)
			(xy 335.503143 -399.785553) (xy 335.521839 -399.777739) (xy 335.531968 -399.777204) (xy 336.248248 -399.777204)
			(xy 336.258406 -399.777583) (xy 336.27716 -399.785395) (xy 336.291482 -399.799804) (xy 336.299179 -399.818606)
			(xy 336.299556 -399.828766) (xy 336.299556 -399.986246) (xy 336.300002 -399.995429) (xy 336.306492 -400.012613)
			(xy 336.312256 -400.019774) (xy 336.334127 -400.045434) (xy 336.372219 -400.101068) (xy 336.403372 -400.160864)
			(xy 336.427138 -400.223962) (xy 336.443174 -400.289452) (xy 336.45125 -400.356392) (xy 336.451249 -400.423817)
			(xy 336.443172 -400.490756) (xy 336.427135 -400.556246) (xy 336.403368 -400.619344) (xy 336.372214 -400.67914)
			(xy 336.334122 -400.734774) (xy 336.312256 -400.760438) (xy 336.306455 -400.76758) (xy 336.299944 -400.784773)
			(xy 336.299556 -400.793966) (xy 336.299556 -401.286218) (xy 336.299967 -401.295405) (xy 336.306481 -401.312589)
			(xy 336.312256 -401.319746) (xy 336.3341 -401.345428) (xy 336.372192 -401.401059) (xy 336.403346 -401.460853)
			(xy 336.427114 -401.523948) (xy 336.443152 -401.589435) (xy 336.45123 -401.656372) (xy 336.451232 -401.723795)
			(xy 336.443158 -401.790732) (xy 336.427123 -401.856221) (xy 336.40336 -401.919317) (xy 336.372209 -401.979112)
			(xy 336.33412 -402.034746) (xy 336.312256 -402.06041) (xy 336.306467 -402.06756) (xy 336.299949 -402.084747)
			(xy 336.299556 -402.093938) (xy 336.299556 -402.251418) (xy 336.299088 -402.261546) (xy 336.291354 -402.280269)
			(xy 336.277062 -402.294625) (xy 336.258374 -402.302443) (xy 336.248248 -402.30298) (xy 335.531968 -402.30298)
			(xy 335.521809 -402.302604) (xy 335.503052 -402.294794) (xy 335.488729 -402.280384) (xy 335.481034 -402.261579)
			(xy 335.48066 -402.251418) (xy 335.48066 -402.093938) (xy 335.480218 -402.084754) (xy 335.473725 -402.06757)
			(xy 335.46796 -402.06041) (xy 335.446076 -402.034762) (xy 335.40799 -401.979124) (xy 335.376843 -401.919325)
			(xy 335.353082 -401.856226) (xy 335.337049 -401.790735) (xy 335.328975 -401.723796) (xy 334.200923 -401.723796)
			(xy 334.172056 -401.779212) (xy 334.13397 -401.834847) (xy 334.112108 -401.860512) (xy 334.106325 -401.867667)
			(xy 334.099802 -401.88485) (xy 334.099408 -401.89404) (xy 334.099408 -402.386292) (xy 334.09982 -402.395479)
			(xy 334.106332 -402.412663) (xy 334.112108 -402.41982) (xy 334.133925 -402.445524) (xy 334.172014 -402.501153)
			(xy 334.203166 -402.560944) (xy 334.226933 -402.624036) (xy 334.242972 -402.68952) (xy 334.251051 -402.756454)
			(xy 334.251055 -402.823818) (xy 337.529116 -402.823818) (xy 337.52912 -402.75651) (xy 337.537169 -402.689685)
			(xy 337.553145 -402.6243) (xy 337.576822 -402.561294) (xy 337.607859 -402.501569) (xy 337.645811 -402.445981)
			(xy 337.6676 -402.420328) (xy 337.67341 -402.413192) (xy 337.679917 -402.395994) (xy 337.6803 -402.3868)
			(xy 337.6803 -401.893532) (xy 337.679874 -401.884346) (xy 337.673371 -401.867162) (xy 337.6676 -401.860004)
			(xy 337.645794 -401.834367) (xy 337.607848 -401.778778) (xy 337.576818 -401.719052) (xy 337.553148 -401.656045)
			(xy 337.537178 -401.590662) (xy 337.529136 -401.523838) (xy 337.529137 -401.456532) (xy 337.537183 -401.389709)
			(xy 337.553157 -401.324326) (xy 337.57683 -401.261321) (xy 337.607864 -401.201596) (xy 337.645812 -401.146009)
			(xy 337.6676 -401.120356) (xy 337.673398 -401.113212) (xy 337.679912 -401.09602) (xy 337.6803 -401.086828)
			(xy 337.6803 -400.92884) (xy 337.680755 -400.918688) (xy 337.688537 -400.899937) (xy 337.702924 -400.885612)
			(xy 337.721709 -400.877911) (xy 337.731862 -400.877532) (xy 338.448142 -400.877532) (xy 338.45827 -400.877992)
			(xy 338.476991 -400.885732) (xy 338.491346 -400.900026) (xy 338.499165 -400.918714) (xy 338.499704 -400.92884)
			(xy 338.499704 -401.086828) (xy 338.5001 -401.096017) (xy 338.506623 -401.113201) (xy 338.512404 -401.120356)
			(xy 338.534171 -401.146025) (xy 338.572117 -401.20161) (xy 338.603149 -401.261332) (xy 338.626821 -401.324334)
			(xy 338.642794 -401.389714) (xy 338.650839 -401.456534) (xy 338.650841 -401.523836) (xy 338.6428 -401.590657)
			(xy 338.62683 -401.656037) (xy 338.603161 -401.719041) (xy 338.600721 -401.723737) (xy 339.72927 -401.723737)
			(xy 339.729272 -401.65643) (xy 339.737319 -401.589606) (xy 339.753294 -401.524222) (xy 339.77697 -401.461217)
			(xy 339.808006 -401.401492) (xy 339.845959 -401.345906) (xy 339.867748 -401.320254) (xy 339.873553 -401.313115)
			(xy 339.880061 -401.295919) (xy 339.880448 -401.286726) (xy 339.880448 -400.793458) (xy 339.880047 -400.78427)
			(xy 339.873526 -400.767086) (xy 339.867748 -400.75993) (xy 339.845966 -400.734273) (xy 339.808017 -400.678687)
			(xy 339.776983 -400.618965) (xy 339.753309 -400.555961) (xy 339.737335 -400.490579) (xy 339.729291 -400.423757)
			(xy 339.72929 -400.356452) (xy 339.737334 -400.28963) (xy 339.753306 -400.224248) (xy 339.776979 -400.161244)
			(xy 339.808012 -400.10152) (xy 339.845961 -400.045934) (xy 339.867748 -400.020282) (xy 339.873541 -400.013134)
			(xy 339.880056 -399.995946) (xy 339.880448 -399.986754) (xy 339.880448 -399.828766) (xy 339.880906 -399.818605)
			(xy 339.888693 -399.799833) (xy 339.90307 -399.785469) (xy 339.921848 -399.777697) (xy 339.93201 -399.777204)
			(xy 340.64829 -399.777204) (xy 340.658443 -399.777741) (xy 340.677205 -399.785506) (xy 340.69157 -399.799858)
			(xy 340.699351 -399.818613) (xy 340.699852 -399.828766) (xy 340.699852 -399.986754) (xy 340.700295 -399.995937)
			(xy 340.706787 -400.013121) (xy 340.712552 -400.020282) (xy 340.734346 -400.045929) (xy 340.772295 -400.101516)
			(xy 340.803329 -400.16124) (xy 340.827002 -400.224245) (xy 340.842975 -400.289628) (xy 340.851018 -400.356452)
			(xy 340.851018 -400.423757) (xy 340.842973 -400.490581) (xy 340.826999 -400.555963) (xy 340.803325 -400.618968)
			(xy 340.772291 -400.678692) (xy 340.734341 -400.734278) (xy 340.712552 -400.75993) (xy 340.706754 -400.767074)
			(xy 340.700242 -400.784266) (xy 340.699852 -400.793458) (xy 340.699852 -401.286726) (xy 340.70026 -401.295913)
			(xy 340.706777 -401.313097) (xy 340.712552 -401.320254) (xy 340.734318 -401.345924) (xy 340.772268 -401.401508)
			(xy 340.803303 -401.461229) (xy 340.826977 -401.524231) (xy 340.842952 -401.589611) (xy 340.850998 -401.656432)
			(xy 340.851 -401.723735) (xy 340.842958 -401.790556) (xy 340.826987 -401.855937) (xy 340.803316 -401.918941)
			(xy 340.772285 -401.978664) (xy 340.734338 -402.03425) (xy 340.712552 -402.059902) (xy 340.706766 -402.067055)
			(xy 340.700246 -402.08424) (xy 340.699852 -402.09343) (xy 340.699852 -402.251418) (xy 340.699381 -402.261578)
			(xy 340.691599 -402.28035) (xy 340.677226 -402.294715) (xy 340.65845 -402.302487) (xy 340.64829 -402.30298)
			(xy 339.93201 -402.30298) (xy 339.921855 -402.302459) (xy 339.90309 -402.294691) (xy 339.888725 -402.280334)
			(xy 339.880947 -402.261573) (xy 339.880448 -402.251418) (xy 339.880448 -402.09343) (xy 339.880013 -402.084246)
			(xy 339.873515 -402.067062) (xy 339.867748 -402.059902) (xy 339.845938 -402.034268) (xy 339.807989 -401.978679)
			(xy 339.776957 -401.918953) (xy 339.753285 -401.855946) (xy 339.737313 -401.790562) (xy 339.72927 -401.723737)
			(xy 338.600721 -401.723737) (xy 338.572133 -401.778764) (xy 338.534189 -401.834351) (xy 338.512404 -401.860004)
			(xy 338.506624 -401.867161) (xy 338.500099 -401.884342) (xy 338.499704 -401.893532) (xy 338.499704 -402.3868)
			(xy 338.500113 -402.395987) (xy 338.506628 -402.413172) (xy 338.512404 -402.420328) (xy 338.534143 -402.44602)
			(xy 338.572091 -402.501601) (xy 338.603124 -402.56132) (xy 338.626797 -402.624319) (xy 338.642772 -402.689696)
			(xy 338.65082 -402.756514) (xy 338.650824 -402.823814) (xy 338.650816 -402.823878) (xy 341.928884 -402.823878)
			(xy 341.928889 -402.75645) (xy 341.936969 -402.689509) (xy 341.95301 -402.624017) (xy 341.976779 -402.560918)
			(xy 342.007935 -402.501121) (xy 342.046029 -402.445485) (xy 342.067896 -402.41982) (xy 342.073709 -402.412686)
			(xy 342.080214 -402.395487) (xy 342.080596 -402.386292) (xy 342.080596 -401.89404) (xy 342.080168 -401.884855)
			(xy 342.073667 -401.86767) (xy 342.067896 -401.860512) (xy 342.046013 -401.834863) (xy 342.007925 -401.779226)
			(xy 341.976775 -401.719428) (xy 341.953012 -401.656329) (xy 341.936978 -401.590838) (xy 341.928904 -401.523898)
			(xy 341.928906 -401.456472) (xy 341.936984 -401.389533) (xy 341.953021 -401.324043) (xy 341.976787 -401.260945)
			(xy 342.00794 -401.201148) (xy 342.046031 -401.145513) (xy 342.067896 -401.119848) (xy 342.073697 -401.112706)
			(xy 342.080209 -401.095513) (xy 342.080596 -401.08632) (xy 342.080596 -400.92884) (xy 342.081049 -400.918721)
			(xy 342.088783 -400.900019) (xy 342.103088 -400.885703) (xy 342.121785 -400.877956) (xy 342.131904 -400.877532)
			(xy 342.848184 -400.877532) (xy 342.858309 -400.87793) (xy 342.877019 -400.885679) (xy 342.891335 -400.900001)
			(xy 342.899075 -400.918714) (xy 342.899492 -400.92884) (xy 342.899492 -401.08632) (xy 342.899894 -401.095508)
			(xy 342.906413 -401.112692) (xy 342.912192 -401.119848) (xy 342.934037 -401.145529) (xy 342.972126 -401.201161)
			(xy 343.003278 -401.260955) (xy 343.027044 -401.32405) (xy 343.043081 -401.389537) (xy 343.051159 -401.456474)
			(xy 343.051161 -401.523896) (xy 343.043087 -401.590833) (xy 343.027053 -401.656321) (xy 343.003291 -401.719417)
			(xy 343.001041 -401.723737) (xy 344.129061 -401.723737) (xy 344.129063 -401.65643) (xy 344.13711 -401.589606)
			(xy 344.153085 -401.524223) (xy 344.17676 -401.461217) (xy 344.207796 -401.401493) (xy 344.245747 -401.345906)
			(xy 344.267536 -401.320254) (xy 344.273339 -401.313114) (xy 344.279849 -401.295919) (xy 344.280236 -401.286726)
			(xy 344.280236 -400.793458) (xy 344.279838 -400.78427) (xy 344.273315 -400.767086) (xy 344.267536 -400.75993)
			(xy 344.245754 -400.734273) (xy 344.207805 -400.678687) (xy 344.176772 -400.618964) (xy 344.153099 -400.55596)
			(xy 344.137126 -400.490579) (xy 344.129081 -400.423757) (xy 344.129081 -400.356452) (xy 344.137124 -400.28963)
			(xy 344.153096 -400.224248) (xy 344.176768 -400.161244) (xy 344.207801 -400.101521) (xy 344.245749 -400.045934)
			(xy 344.267536 -400.020282) (xy 344.273327 -400.013133) (xy 344.279844 -399.995945) (xy 344.280236 -399.986754)
			(xy 344.280236 -399.828766) (xy 344.280705 -399.818606) (xy 344.288491 -399.799837) (xy 344.302864 -399.785473)
			(xy 344.321638 -399.777699) (xy 344.331798 -399.777204) (xy 345.048078 -399.777204) (xy 345.05823 -399.77775)
			(xy 345.076992 -399.785511) (xy 345.091357 -399.799861) (xy 345.099139 -399.818614) (xy 345.09964 -399.828766)
			(xy 345.09964 -399.986754) (xy 345.100086 -399.995937) (xy 345.106576 -400.013121) (xy 345.11234 -400.020282)
			(xy 345.134134 -400.045929) (xy 345.172084 -400.101516) (xy 345.203118 -400.16124) (xy 345.226792 -400.224245)
			(xy 345.242765 -400.289628) (xy 345.250809 -400.356452) (xy 345.250808 -400.423757) (xy 345.242763 -400.490581)
			(xy 345.226789 -400.555964) (xy 345.203115 -400.618968) (xy 345.172079 -400.678692) (xy 345.134129 -400.734278)
			(xy 345.11234 -400.75993) (xy 345.106541 -400.767073) (xy 345.100029 -400.784265) (xy 345.09964 -400.793458)
			(xy 345.09964 -401.286726) (xy 345.100051 -401.295913) (xy 345.106566 -401.313096) (xy 345.11234 -401.320254)
			(xy 345.134107 -401.345924) (xy 345.172057 -401.401507) (xy 345.203093 -401.461228) (xy 345.226768 -401.52423)
			(xy 345.242743 -401.589611) (xy 345.250789 -401.656432) (xy 345.250791 -401.723735) (xy 345.242749 -401.790557)
			(xy 345.226778 -401.855938) (xy 345.203106 -401.918942) (xy 345.172074 -401.978664) (xy 345.134127 -402.03425)
			(xy 345.11234 -402.059902) (xy 345.106553 -402.067053) (xy 345.100034 -402.084239) (xy 345.09964 -402.09343)
			(xy 345.09964 -402.251418) (xy 345.09925 -402.261593) (xy 345.091455 -402.280393) (xy 345.077059 -402.294778)
			(xy 345.058254 -402.302558) (xy 345.048078 -402.30298) (xy 344.331798 -402.30298) (xy 344.321642 -402.302469)
			(xy 344.302877 -402.294697) (xy 344.288512 -402.280337) (xy 344.280735 -402.261574) (xy 344.280236 -402.251418)
			(xy 344.280236 -402.09343) (xy 344.279803 -402.084245) (xy 344.273304 -402.067061) (xy 344.267536 -402.059902)
			(xy 344.245727 -402.034268) (xy 344.207779 -401.978679) (xy 344.176746 -401.918953) (xy 344.153075 -401.855946)
			(xy 344.137104 -401.790561) (xy 344.129061 -401.723737) (xy 343.001041 -401.723737) (xy 342.972142 -401.779213)
			(xy 342.934055 -401.834847) (xy 342.912192 -401.860512) (xy 342.906407 -401.867665) (xy 342.899886 -401.88485)
			(xy 342.899492 -401.89404) (xy 342.899492 -402.386292) (xy 342.899908 -402.395479) (xy 342.906418 -402.412663)
			(xy 342.912192 -402.41982) (xy 342.934009 -402.445524) (xy 342.9721 -402.501153) (xy 343.003253 -402.560944)
			(xy 343.02702 -402.624035) (xy 343.043059 -402.68952) (xy 343.051139 -402.756454) (xy 343.051143 -402.823819)
			(xy 346.329179 -402.823819) (xy 346.329184 -402.756509) (xy 346.337233 -402.689682) (xy 346.353213 -402.624297)
			(xy 346.376893 -402.56129) (xy 346.407934 -402.501566) (xy 346.445892 -402.445979) (xy 346.467684 -402.420328)
			(xy 346.473492 -402.413191) (xy 346.48 -402.395994) (xy 346.480384 -402.3868) (xy 346.480384 -401.893532)
			(xy 346.479962 -401.884346) (xy 346.473457 -401.867161) (xy 346.467684 -401.860004) (xy 346.445875 -401.834369)
			(xy 346.407924 -401.778781) (xy 346.376889 -401.719055) (xy 346.353216 -401.656049) (xy 346.337243 -401.590664)
			(xy 346.3292 -401.523839) (xy 346.329201 -401.456531) (xy 346.337248 -401.389707) (xy 346.353225 -401.324323)
			(xy 346.376902 -401.261317) (xy 346.40794 -401.201593) (xy 346.445894 -401.146008) (xy 346.467684 -401.120356)
			(xy 346.47348 -401.11321) (xy 346.479995 -401.09602) (xy 346.480384 -401.086828) (xy 346.480384 -400.92884)
			(xy 346.480854 -400.91869) (xy 346.488634 -400.899942) (xy 346.503015 -400.885618) (xy 346.521795 -400.877914)
			(xy 346.531946 -400.877532) (xy 347.248226 -400.877532) (xy 347.258353 -400.878005) (xy 347.277074 -400.88574)
			(xy 347.291429 -400.90003) (xy 347.299249 -400.918715) (xy 347.299788 -400.92884) (xy 347.299788 -401.086828)
			(xy 347.300187 -401.096016) (xy 347.306709 -401.1132) (xy 347.312488 -401.120356) (xy 347.334255 -401.146025)
			(xy 347.372203 -401.201609) (xy 347.403236 -401.261331) (xy 347.426908 -401.324333) (xy 347.442882 -401.389713)
			(xy 347.450927 -401.456533) (xy 347.450929 -401.523836) (xy 347.442887 -401.590657) (xy 347.426917 -401.656038)
			(xy 347.403248 -401.719042) (xy 347.400809 -401.723737) (xy 374.929092 -401.723737) (xy 374.929094 -401.65643)
			(xy 374.937141 -401.589605) (xy 374.953117 -401.524221) (xy 374.976794 -401.461216) (xy 375.007832 -401.401492)
			(xy 375.045786 -401.345906) (xy 375.067576 -401.320254) (xy 375.073372 -401.313108) (xy 375.079888 -401.295918)
			(xy 375.080276 -401.286726) (xy 375.080276 -400.793458) (xy 375.079891 -400.784268) (xy 375.07336 -400.767084)
			(xy 375.067576 -400.75993) (xy 375.045793 -400.734273) (xy 375.007842 -400.678688) (xy 374.976806 -400.618966)
			(xy 374.953131 -400.555962) (xy 374.937157 -400.49058) (xy 374.929112 -400.423757) (xy 374.929111 -400.356452)
			(xy 374.937155 -400.289629) (xy 374.953129 -400.224247) (xy 374.976802 -400.161242) (xy 375.007837 -400.101519)
			(xy 375.045788 -400.045934) (xy 375.067576 -400.020282) (xy 375.07336 -400.013128) (xy 375.079883 -399.995944)
			(xy 375.080276 -399.986754) (xy 375.080276 -399.828766) (xy 375.080637 -399.818587) (xy 375.08844 -399.799785)
			(xy 375.102845 -399.7854) (xy 375.121659 -399.777623) (xy 375.131838 -399.777204) (xy 375.848118 -399.777204)
			(xy 375.858273 -399.777718) (xy 375.877036 -399.785492) (xy 375.891399 -399.799851) (xy 375.899179 -399.818611)
			(xy 375.89968 -399.828766) (xy 375.89968 -399.986754) (xy 375.900117 -399.995938) (xy 375.906612 -400.013123)
			(xy 375.91238 -400.020282) (xy 375.934173 -400.045929) (xy 375.972121 -400.101517) (xy 376.003152 -400.161241)
			(xy 376.026824 -400.224247) (xy 376.042796 -400.289629) (xy 376.050839 -400.356452) (xy 376.050839 -400.423757)
			(xy 376.042794 -400.49058) (xy 376.026821 -400.555962) (xy 376.003149 -400.618967) (xy 375.972116 -400.678691)
			(xy 375.934168 -400.734278) (xy 375.91238 -400.75993) (xy 375.906586 -400.767077) (xy 375.90007 -400.784266)
			(xy 375.89968 -400.793458) (xy 375.89968 -401.286726) (xy 375.900082 -401.295914) (xy 375.906602 -401.313098)
			(xy 375.91238 -401.320254) (xy 375.934146 -401.345924) (xy 375.972094 -401.401508) (xy 376.003127 -401.46123)
			(xy 376.0268 -401.524232) (xy 376.042774 -401.589612) (xy 376.05082 -401.656432) (xy 376.050822 -401.723735)
			(xy 376.04278 -401.790556) (xy 376.02681 -401.855937) (xy 376.003141 -401.91894) (xy 375.972111 -401.978663)
			(xy 375.934166 -402.03425) (xy 375.91238 -402.059902) (xy 375.906598 -402.067057) (xy 375.900075 -402.08424)
			(xy 375.89968 -402.09343) (xy 375.89968 -402.251418) (xy 375.899182 -402.261575) (xy 375.891405 -402.280341)
			(xy 375.877041 -402.294705) (xy 375.858275 -402.302482) (xy 375.848118 -402.30298) (xy 375.131838 -402.30298)
			(xy 375.121671 -402.302505) (xy 375.102881 -402.294736) (xy 375.088495 -402.280366) (xy 375.080706 -402.261584)
			(xy 375.080276 -402.251418) (xy 375.080276 -402.09343) (xy 375.079857 -402.084244) (xy 375.07335 -402.067059)
			(xy 375.067576 -402.059902) (xy 375.045766 -402.034268) (xy 375.007815 -401.97868) (xy 374.976781 -401.918954)
			(xy 374.953108 -401.855947) (xy 374.937135 -401.790562) (xy 374.929092 -401.723737) (xy 347.400809 -401.723737)
			(xy 347.372218 -401.778765) (xy 347.334274 -401.834352) (xy 347.312488 -401.860004) (xy 347.306706 -401.867159)
			(xy 347.300183 -401.884342) (xy 347.299788 -401.893532) (xy 347.299788 -402.3868) (xy 347.300201 -402.395987)
			(xy 347.306713 -402.413171) (xy 347.312488 -402.420328) (xy 347.334227 -402.44602) (xy 347.372176 -402.501601)
			(xy 347.40321 -402.561319) (xy 347.426884 -402.624319) (xy 347.442859 -402.689696) (xy 347.450907 -402.756514)
			(xy 347.450911 -402.823814) (xy 347.442872 -402.890633) (xy 347.426905 -402.956012) (xy 347.403239 -403.019015)
			(xy 347.372213 -403.078737) (xy 347.334272 -403.134323) (xy 347.312488 -403.159976) (xy 347.306675 -403.16711)
			(xy 347.300171 -403.184309) (xy 347.299788 -403.193504) (xy 347.299788 -403.351492) (xy 347.299372 -403.361647)
			(xy 347.291576 -403.380402) (xy 347.277178 -403.394726) (xy 347.258383 -403.402424) (xy 347.248226 -403.4028)
			(xy 346.531946 -403.4028) (xy 346.521827 -403.402237) (xy 346.503115 -403.394532) (xy 346.488758 -403.380269)
			(xy 346.48093 -403.361607) (xy 346.480384 -403.351492) (xy 346.480384 -403.193504) (xy 346.479975 -403.184317)
			(xy 346.473461 -403.167132) (xy 346.467684 -403.159976) (xy 346.445847 -403.134364) (xy 346.407897 -403.078772)
			(xy 346.376863 -403.019044) (xy 346.353191 -402.956034) (xy 346.33722 -402.890646) (xy 346.329179 -402.823819)
			(xy 343.051143 -402.823819) (xy 343.051143 -402.823874) (xy 343.043072 -402.890809) (xy 343.027042 -402.956296)
			(xy 343.003282 -403.019391) (xy 342.972137 -403.079185) (xy 342.934053 -403.134819) (xy 342.912192 -403.160484)
			(xy 342.906376 -403.167616) (xy 342.899873 -403.184817) (xy 342.899492 -403.194012) (xy 342.899492 -403.351492)
			(xy 342.899077 -403.361615) (xy 342.89133 -403.38032) (xy 342.877013 -403.394635) (xy 342.858307 -403.402379)
			(xy 342.848184 -403.4028) (xy 342.131904 -403.4028) (xy 342.121782 -403.402381) (xy 342.103078 -403.394634)
			(xy 342.088764 -403.380318) (xy 342.081019 -403.361614) (xy 342.080596 -403.351492) (xy 342.080596 -403.194012)
			(xy 342.080181 -403.184825) (xy 342.073671 -403.167641) (xy 342.067896 -403.160484) (xy 342.045985 -403.134858)
			(xy 342.007898 -403.079217) (xy 341.97675 -403.019416) (xy 341.952988 -402.956314) (xy 341.936956 -402.89082)
			(xy 341.928884 -402.823878) (xy 338.650816 -402.823878) (xy 338.642785 -402.890633) (xy 338.626819 -402.956012)
			(xy 338.603153 -403.019014) (xy 338.572128 -403.078737) (xy 338.534188 -403.134323) (xy 338.512404 -403.159976)
			(xy 338.506593 -403.167111) (xy 338.500087 -403.184309) (xy 338.499704 -403.193504) (xy 338.499704 -403.351492)
			(xy 338.499272 -403.361645) (xy 338.49148 -403.380397) (xy 338.477086 -403.39472) (xy 338.458297 -403.402421)
			(xy 338.448142 -403.4028) (xy 337.731862 -403.4028) (xy 337.721738 -403.402306) (xy 337.703023 -403.394573)
			(xy 337.68867 -403.38029) (xy 337.680845 -403.361614) (xy 337.6803 -403.351492) (xy 337.6803 -403.193504)
			(xy 337.679888 -403.184317) (xy 337.673375 -403.167133) (xy 337.6676 -403.159976) (xy 337.645766 -403.134362)
			(xy 337.607822 -403.078769) (xy 337.576793 -403.01904) (xy 337.553124 -402.956031) (xy 337.537156 -402.890644)
			(xy 337.529116 -402.823818) (xy 334.251055 -402.823818) (xy 334.251055 -402.823874) (xy 334.242984 -402.890809)
			(xy 334.226954 -402.956295) (xy 334.203196 -403.01939) (xy 334.172051 -403.079185) (xy 334.133969 -403.134819)
			(xy 334.112108 -403.160484) (xy 334.106294 -403.167617) (xy 334.09979 -403.184817) (xy 334.099408 -403.194012)
			(xy 334.099408 -403.351492) (xy 334.098978 -403.361613) (xy 334.091234 -403.380315) (xy 334.076922 -403.394629)
			(xy 334.058221 -403.402376) (xy 334.0481 -403.4028) (xy 333.33182 -403.4028) (xy 333.321699 -403.402368)
			(xy 333.302996 -403.394626) (xy 333.288681 -403.380315) (xy 333.280935 -403.361613) (xy 333.280512 -403.351492)
			(xy 333.280512 -403.194012) (xy 333.280093 -403.184826) (xy 333.273585 -403.167642) (xy 333.267812 -403.160484)
			(xy 333.2459 -403.134858) (xy 333.207812 -403.079218) (xy 333.176663 -403.019417) (xy 333.152901 -402.956315)
			(xy 333.136869 -402.890821) (xy 333.128796 -402.823878) (xy 326.525636 -402.823878) (xy 326.525636 -405.623648)
			(xy 330.929194 -405.623648) (xy 330.929195 -405.556343) (xy 330.93724 -405.489519) (xy 330.953214 -405.424136)
			(xy 330.976889 -405.361131) (xy 331.007924 -405.301408) (xy 331.045875 -405.245822) (xy 331.067664 -405.22017)
			(xy 331.073464 -405.213027) (xy 331.079975 -405.195835) (xy 331.080364 -405.186642) (xy 331.080364 -404.693374)
			(xy 331.079952 -404.684187) (xy 331.073438 -404.667004) (xy 331.067664 -404.659846) (xy 331.045897 -404.634176)
			(xy 331.007946 -404.578593) (xy 330.976911 -404.518872) (xy 330.953235 -404.45587) (xy 330.93726 -404.390489)
			(xy 330.929214 -404.323668) (xy 330.929212 -404.256365) (xy 330.937254 -404.189543) (xy 330.953226 -404.124162)
			(xy 330.976897 -404.061158) (xy 331.007929 -404.001435) (xy 331.045877 -403.94585) (xy 331.067664 -403.920198)
			(xy 331.073452 -403.913047) (xy 331.07997 -403.895861) (xy 331.080364 -403.88667) (xy 331.080364 -403.728682)
			(xy 331.08075 -403.718506) (xy 331.088546 -403.699706) (xy 331.102943 -403.685321) (xy 331.12175 -403.677541)
			(xy 331.131926 -403.67712) (xy 331.848206 -403.67712) (xy 331.858362 -403.677628) (xy 331.877128 -403.685401)
			(xy 331.891492 -403.699762) (xy 331.899269 -403.718526) (xy 331.899768 -403.728682) (xy 331.899768 -403.88667)
			(xy 331.9002 -403.895855) (xy 331.906699 -403.913039) (xy 331.912468 -403.920198) (xy 331.934277 -403.945832)
			(xy 331.972225 -404.001422) (xy 332.003257 -404.061148) (xy 332.026928 -404.124154) (xy 332.042899 -404.189539)
			(xy 332.050942 -404.256363) (xy 332.05094 -404.32367) (xy 332.042893 -404.390494) (xy 332.026918 -404.455877)
			(xy 332.003243 -404.518883) (xy 331.972208 -404.578607) (xy 331.934257 -404.634194) (xy 331.912468 -404.659846)
			(xy 331.906665 -404.666987) (xy 331.900155 -404.684181) (xy 331.899768 -404.693374) (xy 331.899768 -405.186642)
			(xy 331.900165 -405.19583) (xy 331.906689 -405.213014) (xy 331.912468 -405.22017) (xy 331.93425 -405.245827)
			(xy 331.972198 -405.301413) (xy 332.003231 -405.361136) (xy 332.026904 -405.42414) (xy 332.042877 -405.489521)
			(xy 332.050922 -405.556343) (xy 332.050923 -405.623648) (xy 332.042879 -405.69047) (xy 332.026907 -405.755852)
			(xy 332.003235 -405.818856) (xy 331.972203 -405.878579) (xy 331.934255 -405.934166) (xy 331.912468 -405.959818)
			(xy 331.906677 -405.966967) (xy 331.90016 -405.984155) (xy 331.899768 -405.993346) (xy 331.899768 -406.151334)
			(xy 331.899295 -406.161493) (xy 331.89151 -406.180262) (xy 331.877138 -406.194626) (xy 331.858365 -406.2024)
			(xy 331.848206 -406.202896) (xy 331.131926 -406.202896) (xy 331.121774 -406.202346) (xy 331.103012 -406.194587)
			(xy 331.088647 -406.180238) (xy 331.080865 -406.161485) (xy 331.080364 -406.151334) (xy 331.080364 -405.993346)
			(xy 331.079918 -405.984163) (xy 331.073428 -405.966979) (xy 331.067664 -405.959818) (xy 331.04587 -405.934171)
			(xy 331.007919 -405.878584) (xy 330.976885 -405.81886) (xy 330.953212 -405.755855) (xy 330.937238 -405.690472)
			(xy 330.929194 -405.623648) (xy 326.525636 -405.623648) (xy 326.525636 -406.723789) (xy 333.128808 -406.723789)
			(xy 333.128811 -406.656363) (xy 333.13689 -406.589422) (xy 333.152929 -406.523931) (xy 333.176697 -406.460833)
			(xy 333.207852 -406.401036) (xy 333.245946 -406.345401) (xy 333.267812 -406.319736) (xy 333.27362 -406.312599)
			(xy 333.280127 -406.295402) (xy 333.280512 -406.286208) (xy 333.280512 -405.793956) (xy 333.28012 -405.784767)
			(xy 333.273594 -405.767583) (xy 333.267812 -405.760428) (xy 333.245944 -405.734766) (xy 333.207854 -405.679131)
			(xy 333.176703 -405.619335) (xy 333.152939 -405.556238) (xy 333.136903 -405.490748) (xy 333.128827 -405.423809)
			(xy 333.128828 -405.356385) (xy 333.136904 -405.289446) (xy 333.15294 -405.223957) (xy 333.176706 -405.16086)
			(xy 333.207857 -405.101063) (xy 333.245947 -405.045429) (xy 333.267812 -405.019764) (xy 333.273608 -405.012618)
			(xy 333.280123 -404.995428) (xy 333.280512 -404.986236) (xy 333.280512 -404.828756) (xy 333.280949 -404.818643)
			(xy 333.288704 -404.799961) (xy 333.303015 -404.785668) (xy 333.321706 -404.777937) (xy 333.33182 -404.777448)
			(xy 334.0481 -404.777448) (xy 334.058202 -404.777984) (xy 334.076871 -404.785712) (xy 334.091163 -404.799993)
			(xy 334.098907 -404.818654) (xy 334.099408 -404.828756) (xy 334.099408 -404.986236) (xy 334.099799 -404.995425)
			(xy 334.106326 -405.01261) (xy 334.112108 -405.019764) (xy 334.133968 -405.045433) (xy 334.172056 -405.101067)
			(xy 334.203206 -405.160863) (xy 334.226971 -405.223959) (xy 334.243006 -405.289448) (xy 334.251082 -405.356385)
			(xy 334.251082 -405.423809) (xy 334.243007 -405.490746) (xy 334.226972 -405.556235) (xy 334.203209 -405.619332)
			(xy 334.20093 -405.623707) (xy 335.328987 -405.623707) (xy 335.328987 -405.556284) (xy 335.337063 -405.489346)
			(xy 335.353098 -405.423857) (xy 335.376861 -405.36076) (xy 335.40801 -405.300963) (xy 335.446097 -405.245328)
			(xy 335.46796 -405.219662) (xy 335.473763 -405.212521) (xy 335.480272 -405.195327) (xy 335.48066 -405.186134)
			(xy 335.48066 -404.693882) (xy 335.480245 -404.684696) (xy 335.473733 -404.667512) (xy 335.46796 -404.660354)
			(xy 335.446119 -404.63467) (xy 335.408032 -404.579037) (xy 335.376883 -404.519243) (xy 335.353119 -404.456149)
			(xy 335.337083 -404.390663) (xy 335.329006 -404.323727) (xy 335.329004 -404.256306) (xy 335.337078 -404.18937)
			(xy 335.353109 -404.123883) (xy 335.376869 -404.060787) (xy 335.408015 -404.000991) (xy 335.446099 -403.945356)
			(xy 335.46796 -403.91969) (xy 335.473751 -403.912541) (xy 335.480267 -403.895353) (xy 335.48066 -403.886162)
			(xy 335.48066 -403.728682) (xy 335.481112 -403.718552) (xy 335.48885 -403.699826) (xy 335.503147 -403.68547)
			(xy 335.52184 -403.677655) (xy 335.531968 -403.67712) (xy 336.248248 -403.67712) (xy 336.258408 -403.677483)
			(xy 336.277165 -403.685298) (xy 336.291487 -403.699713) (xy 336.299182 -403.71852) (xy 336.299556 -403.728682)
			(xy 336.299556 -403.886162) (xy 336.299995 -403.895346) (xy 336.30649 -403.91253) (xy 336.312256 -403.91969)
			(xy 336.334143 -403.945337) (xy 336.372234 -404.000973) (xy 336.403386 -404.060771) (xy 336.427151 -404.123871)
			(xy 336.443186 -404.189362) (xy 336.451261 -404.256303) (xy 336.451259 -404.32373) (xy 336.443181 -404.39067)
			(xy 336.427141 -404.456161) (xy 336.403373 -404.519259) (xy 336.372217 -404.579056) (xy 336.334123 -404.634689)
			(xy 336.312256 -404.660354) (xy 336.306449 -404.667491) (xy 336.299941 -404.684688) (xy 336.299556 -404.693882)
			(xy 336.299556 -405.186134) (xy 336.29996 -405.195322) (xy 336.306479 -405.212505) (xy 336.312256 -405.219662)
			(xy 336.334116 -405.245331) (xy 336.372207 -405.300964) (xy 336.403361 -405.360759) (xy 336.427127 -405.423856)
			(xy 336.443164 -405.489345) (xy 336.451242 -405.556283) (xy 336.451242 -405.623708) (xy 336.443166 -405.690646)
			(xy 336.42713 -405.756135) (xy 336.403365 -405.819232) (xy 336.372212 -405.879028) (xy 336.334121 -405.934662)
			(xy 336.312256 -405.960326) (xy 336.30646 -405.967472) (xy 336.299946 -405.984662) (xy 336.299556 -405.993854)
			(xy 336.299556 -406.151334) (xy 336.299101 -406.161463) (xy 336.291362 -406.180186) (xy 336.277066 -406.194541)
			(xy 336.258375 -406.202359) (xy 336.248248 -406.202896) (xy 335.531968 -406.202896) (xy 335.521811 -406.202505)
			(xy 335.503057 -406.194698) (xy 335.488735 -406.180292) (xy 335.481037 -406.161493) (xy 335.48066 -406.151334)
			(xy 335.48066 -405.993854) (xy 335.48021 -405.984671) (xy 335.473722 -405.967487) (xy 335.46796 -405.960326)
			(xy 335.446092 -405.934665) (xy 335.408006 -405.879029) (xy 335.376857 -405.819232) (xy 335.353095 -405.756134)
			(xy 335.337062 -405.690645) (xy 335.328987 -405.623707) (xy 334.20093 -405.623707) (xy 334.172059 -405.679128)
			(xy 334.133971 -405.734763) (xy 334.112108 -405.760428) (xy 334.106318 -405.767578) (xy 334.099799 -405.784765)
			(xy 334.099408 -405.793956) (xy 334.099408 -406.286208) (xy 334.099813 -406.295396) (xy 334.10633 -406.31258)
			(xy 334.112108 -406.319736) (xy 334.13394 -406.345427) (xy 334.172029 -406.401058) (xy 334.203181 -406.460851)
			(xy 334.226947 -406.523944) (xy 334.242984 -406.58943) (xy 334.251062 -406.656365) (xy 334.251065 -406.723729)
			(xy 337.529127 -406.723729) (xy 337.52913 -406.656423) (xy 337.537177 -406.589598) (xy 337.553152 -406.524215)
			(xy 337.576827 -406.461209) (xy 337.607861 -406.401484) (xy 337.645812 -406.345897) (xy 337.6676 -406.320244)
			(xy 337.673403 -406.313103) (xy 337.679914 -406.295909) (xy 337.6803 -406.286716) (xy 337.6803 -405.793448)
			(xy 337.679867 -405.784263) (xy 337.673369 -405.767079) (xy 337.6676 -405.75992) (xy 337.64581 -405.734271)
			(xy 337.607863 -405.678683) (xy 337.576832 -405.618958) (xy 337.553162 -405.555954) (xy 337.53719 -405.490572)
			(xy 337.529147 -405.423749) (xy 337.529147 -405.356445) (xy 337.537191 -405.289622) (xy 337.553163 -405.224241)
			(xy 337.576835 -405.161236) (xy 337.607866 -405.101512) (xy 337.645813 -405.045925) (xy 337.6676 -405.020272)
			(xy 337.673391 -405.013123) (xy 337.679909 -404.995935) (xy 337.6803 -404.986744) (xy 337.6803 -404.828756)
			(xy 337.680686 -404.818599) (xy 337.688496 -404.799846) (xy 337.702903 -404.785524) (xy 337.721703 -404.777826)
			(xy 337.731862 -404.777448) (xy 338.448142 -404.777448) (xy 338.458272 -404.777892) (xy 338.476996 -404.785635)
			(xy 338.491351 -404.799934) (xy 338.499167 -404.818628) (xy 338.499704 -404.828756) (xy 338.499704 -404.986744)
			(xy 338.500092 -404.995934) (xy 338.506621 -405.013118) (xy 338.512404 -405.020272) (xy 338.534186 -405.045928)
			(xy 338.572133 -405.101515) (xy 338.603164 -405.161238) (xy 338.626835 -405.224242) (xy 338.642807 -405.289624)
			(xy 338.650851 -405.356445) (xy 338.650851 -405.423749) (xy 338.642808 -405.490571) (xy 338.626837 -405.555952)
			(xy 338.603166 -405.618956) (xy 338.600728 -405.623648) (xy 339.729282 -405.623648) (xy 339.729282 -405.556343)
			(xy 339.737327 -405.489519) (xy 339.753301 -405.424137) (xy 339.776975 -405.361132) (xy 339.808009 -405.301408)
			(xy 339.845959 -405.245822) (xy 339.867748 -405.22017) (xy 339.873546 -405.213026) (xy 339.880058 -405.195834)
			(xy 339.880448 -405.186642) (xy 339.880448 -404.693374) (xy 339.88004 -404.684187) (xy 339.873523 -404.667003)
			(xy 339.867748 -404.659846) (xy 339.845982 -404.634176) (xy 339.808032 -404.578592) (xy 339.776997 -404.518871)
			(xy 339.753323 -404.455869) (xy 339.737348 -404.390489) (xy 339.729302 -404.323668) (xy 339.7293 -404.256365)
			(xy 339.737342 -404.189544) (xy 339.753313 -404.124163) (xy 339.776984 -404.061159) (xy 339.808015 -404.001436)
			(xy 339.845962 -403.94585) (xy 339.867748 -403.920198) (xy 339.873534 -403.913045) (xy 339.880054 -403.89586)
			(xy 339.880448 -403.88667) (xy 339.880448 -403.728682) (xy 339.880919 -403.718522) (xy 339.888701 -403.69975)
			(xy 339.903074 -403.685385) (xy 339.92185 -403.677613) (xy 339.93201 -403.67712) (xy 340.64829 -403.67712)
			(xy 340.658445 -403.677641) (xy 340.67721 -403.685409) (xy 340.691575 -403.699766) (xy 340.699353 -403.718527)
			(xy 340.699852 -403.728682) (xy 340.699852 -403.88667) (xy 340.700287 -403.895854) (xy 340.706785 -403.913038)
			(xy 340.712552 -403.920198) (xy 340.734362 -403.945832) (xy 340.772311 -404.001421) (xy 340.803343 -404.061147)
			(xy 340.827015 -404.124154) (xy 340.842987 -404.189538) (xy 340.85103 -404.256363) (xy 340.851028 -404.32367)
			(xy 340.842981 -404.390494) (xy 340.827006 -404.455878) (xy 340.80333 -404.518883) (xy 340.772294 -404.578608)
			(xy 340.734341 -404.634194) (xy 340.712552 -404.659846) (xy 340.706747 -404.666985) (xy 340.700239 -404.684181)
			(xy 340.699852 -404.693374) (xy 340.699852 -405.186642) (xy 340.700253 -405.19583) (xy 340.706774 -405.213014)
			(xy 340.712552 -405.22017) (xy 340.734334 -405.245827) (xy 340.772283 -405.301413) (xy 340.803317 -405.361135)
			(xy 340.826991 -405.424139) (xy 340.842965 -405.489521) (xy 340.851009 -405.556343) (xy 340.85101 -405.623648)
			(xy 340.842966 -405.69047) (xy 340.826994 -405.755852) (xy 340.803321 -405.818856) (xy 340.772288 -405.87858)
			(xy 340.734339 -405.934166) (xy 340.712552 -405.959818) (xy 340.706759 -405.966966) (xy 340.700244 -405.984154)
			(xy 340.699852 -405.993346) (xy 340.699852 -406.151334) (xy 340.699394 -406.161495) (xy 340.691607 -406.180267)
			(xy 340.67723 -406.194631) (xy 340.658452 -406.202403) (xy 340.64829 -406.202896) (xy 339.93201 -406.202896)
			(xy 339.921857 -406.202359) (xy 339.903095 -406.194594) (xy 339.88873 -406.180242) (xy 339.880949 -406.161487)
			(xy 339.880448 -406.151334) (xy 339.880448 -405.993346) (xy 339.880005 -405.984163) (xy 339.873513 -405.966979)
			(xy 339.867748 -405.959818) (xy 339.845954 -405.934171) (xy 339.808005 -405.878584) (xy 339.776971 -405.81886)
			(xy 339.753298 -405.755855) (xy 339.737325 -405.690472) (xy 339.729282 -405.623648) (xy 338.600728 -405.623648)
			(xy 338.572136 -405.67868) (xy 338.53419 -405.734267) (xy 338.512404 -405.75992) (xy 338.506617 -405.767072)
			(xy 338.500096 -405.784257) (xy 338.499704 -405.793448) (xy 338.499704 -406.286716) (xy 338.500106 -406.295904)
			(xy 338.506625 -406.313088) (xy 338.512404 -406.320244) (xy 338.534159 -406.345923) (xy 338.572106 -406.401506)
			(xy 338.603138 -406.461227) (xy 338.626811 -406.524228) (xy 338.642785 -406.589606) (xy 338.650831 -406.656425)
			(xy 338.650834 -406.723727) (xy 338.650827 -406.723789) (xy 341.928896 -406.723789) (xy 341.928898 -406.656363)
			(xy 341.936977 -406.589423) (xy 341.953016 -406.523932) (xy 341.976784 -406.460834) (xy 342.007938 -406.401036)
			(xy 342.04603 -406.345401) (xy 342.067896 -406.319736) (xy 342.073702 -406.312597) (xy 342.080211 -406.295402)
			(xy 342.080596 -406.286208) (xy 342.080596 -405.793956) (xy 342.080208 -405.784766) (xy 342.073679 -405.767582)
			(xy 342.067896 -405.760428) (xy 342.046028 -405.734766) (xy 342.00794 -405.679131) (xy 341.97679 -405.619334)
			(xy 341.953026 -405.556237) (xy 341.936991 -405.490748) (xy 341.928915 -405.423809) (xy 341.928916 -405.356385)
			(xy 341.936992 -405.289447) (xy 341.953028 -405.223957) (xy 341.976792 -405.16086) (xy 342.007943 -405.101064)
			(xy 342.046032 -405.045429) (xy 342.067896 -405.019764) (xy 342.07369 -405.012617) (xy 342.080206 -404.995428)
			(xy 342.080596 -404.986236) (xy 342.080596 -404.828756) (xy 342.081049 -404.818645) (xy 342.0888 -404.799967)
			(xy 342.103107 -404.785673) (xy 342.121793 -404.77794) (xy 342.131904 -404.777448) (xy 342.848184 -404.777448)
			(xy 342.858285 -404.777997) (xy 342.876953 -404.78572) (xy 342.891247 -404.799996) (xy 342.898991 -404.818655)
			(xy 342.899492 -404.828756) (xy 342.899492 -404.986236) (xy 342.899886 -404.995425) (xy 342.906411 -405.012609)
			(xy 342.912192 -405.019764) (xy 342.934052 -405.045432) (xy 342.972142 -405.101066) (xy 343.003293 -405.160862)
			(xy 343.027058 -405.223958) (xy 343.043094 -405.289447) (xy 343.05117 -405.356385) (xy 343.05117 -405.423809)
			(xy 343.043095 -405.490747) (xy 343.02706 -405.556236) (xy 343.003295 -405.619333) (xy 343.001047 -405.623648)
			(xy 344.129073 -405.623648) (xy 344.129073 -405.556343) (xy 344.137118 -405.48952) (xy 344.153091 -405.424137)
			(xy 344.176765 -405.361132) (xy 344.207799 -405.301409) (xy 344.245748 -405.245822) (xy 344.267536 -405.22017)
			(xy 344.273332 -405.213025) (xy 344.279846 -405.195834) (xy 344.280236 -405.186642) (xy 344.280236 -404.693374)
			(xy 344.27983 -404.684187) (xy 344.273313 -404.667003) (xy 344.267536 -404.659846) (xy 344.24577 -404.634176)
			(xy 344.207821 -404.578592) (xy 344.176787 -404.518871) (xy 344.153113 -404.455869) (xy 344.137139 -404.390489)
			(xy 344.129093 -404.323668) (xy 344.129091 -404.256365) (xy 344.137133 -404.189544) (xy 344.153103 -404.124163)
			(xy 344.176773 -404.061159) (xy 344.207804 -404.001437) (xy 344.24575 -403.94585) (xy 344.267536 -403.920198)
			(xy 344.273321 -403.913044) (xy 344.279842 -403.89586) (xy 344.280236 -403.88667) (xy 344.280236 -403.728682)
			(xy 344.280718 -403.718523) (xy 344.288498 -403.699754) (xy 344.302867 -403.685389) (xy 344.321639 -403.677615)
			(xy 344.331798 -403.67712) (xy 345.048078 -403.67712) (xy 345.058246 -403.677582) (xy 345.077037 -403.685356)
			(xy 345.091422 -403.69973) (xy 345.09921 -403.718514) (xy 345.09964 -403.728682) (xy 345.09964 -403.88667)
			(xy 345.100078 -403.895854) (xy 345.106574 -403.913038) (xy 345.11234 -403.920198) (xy 345.13415 -403.945832)
			(xy 345.1721 -404.00142) (xy 345.203133 -404.061146) (xy 345.226806 -404.124153) (xy 345.242778 -404.189538)
			(xy 345.250821 -404.256363) (xy 345.250819 -404.32367) (xy 345.242772 -404.390495) (xy 345.226796 -404.455878)
			(xy 345.20312 -404.518884) (xy 345.172083 -404.578608) (xy 345.13413 -404.634194) (xy 345.11234 -404.659846)
			(xy 345.106534 -404.666984) (xy 345.100027 -404.68418) (xy 345.09964 -404.693374) (xy 345.09964 -405.186642)
			(xy 345.100043 -405.19583) (xy 345.106563 -405.213013) (xy 345.11234 -405.22017) (xy 345.134122 -405.245827)
			(xy 345.172073 -405.301412) (xy 345.203107 -405.361135) (xy 345.226781 -405.424139) (xy 345.242755 -405.489521)
			(xy 345.2508 -405.556343) (xy 345.250801 -405.623648) (xy 345.242757 -405.69047) (xy 345.226784 -405.755853)
			(xy 345.203111 -405.818857) (xy 345.172077 -405.87858) (xy 345.134128 -405.934166) (xy 345.11234 -405.959818)
			(xy 345.106546 -405.966965) (xy 345.100031 -405.984154) (xy 345.09964 -405.993346) (xy 345.09964 -406.151334)
			(xy 345.099194 -406.161497) (xy 345.091404 -406.180271) (xy 345.077024 -406.194636) (xy 345.058241 -406.202405)
			(xy 345.048078 -406.202896) (xy 344.331798 -406.202896) (xy 344.321644 -406.202369) (xy 344.302882 -406.1946)
			(xy 344.288518 -406.180245) (xy 344.280737 -406.161487) (xy 344.280236 -406.151334) (xy 344.280236 -405.993346)
			(xy 344.279795 -405.984162) (xy 344.273302 -405.966978) (xy 344.267536 -405.959818) (xy 344.245742 -405.934171)
			(xy 344.207794 -405.878584) (xy 344.176761 -405.818859) (xy 344.153089 -405.755854) (xy 344.137116 -405.690471)
			(xy 344.129073 -405.623648) (xy 343.001047 -405.623648) (xy 342.972145 -405.679129) (xy 342.934056 -405.734763)
			(xy 342.912192 -405.760428) (xy 342.9064 -405.767576) (xy 342.899883 -405.784765) (xy 342.899492 -405.793956)
			(xy 342.899492 -406.286208) (xy 342.8999 -406.295395) (xy 342.906416 -406.312579) (xy 342.912192 -406.319736)
			(xy 342.934025 -406.345427) (xy 342.972115 -406.401058) (xy 343.003268 -406.46085) (xy 343.027034 -406.523944)
			(xy 343.043072 -406.58943) (xy 343.05115 -406.656365) (xy 343.051153 -406.72373) (xy 346.329191 -406.72373)
			(xy 346.329194 -406.656422) (xy 346.337242 -406.589596) (xy 346.35322 -406.524212) (xy 346.376898 -406.461206)
			(xy 346.407937 -406.401482) (xy 346.445893 -406.345896) (xy 346.467684 -406.320244) (xy 346.473485 -406.313102)
			(xy 346.479998 -406.295909) (xy 346.480384 -406.286716) (xy 346.480384 -405.793448) (xy 346.479955 -405.784263)
			(xy 346.473455 -405.767078) (xy 346.467684 -405.75992) (xy 346.445891 -405.734272) (xy 346.407939 -405.678686)
			(xy 346.376904 -405.618962) (xy 346.353229 -405.555957) (xy 346.337255 -405.490574) (xy 346.329211 -405.42375)
			(xy 346.329211 -405.356444) (xy 346.337256 -405.28962) (xy 346.353231 -405.224237) (xy 346.376906 -405.161232)
			(xy 346.407942 -405.101509) (xy 346.445895 -405.045924) (xy 346.467684 -405.020272) (xy 346.473473 -405.013121)
			(xy 346.479993 -404.995935) (xy 346.480384 -404.986744) (xy 346.480384 -404.828756) (xy 346.480785 -404.818601)
			(xy 346.488592 -404.799851) (xy 346.502995 -404.78553) (xy 346.521789 -404.777829) (xy 346.531946 -404.777448)
			(xy 347.248226 -404.777448) (xy 347.258355 -404.777905) (xy 347.277079 -404.785643) (xy 347.291434 -404.799938)
			(xy 347.299251 -404.818629) (xy 347.299788 -404.828756) (xy 347.299788 -404.986744) (xy 347.30018 -404.995933)
			(xy 347.306706 -405.013117) (xy 347.312488 -405.020272) (xy 347.334271 -405.045928) (xy 347.372218 -405.101514)
			(xy 347.40325 -405.161238) (xy 347.426922 -405.224242) (xy 347.442894 -405.289623) (xy 347.450938 -405.356445)
			(xy 347.450939 -405.423749) (xy 347.442895 -405.490571) (xy 347.426924 -405.555953) (xy 347.403253 -405.618957)
			(xy 347.372221 -405.678681) (xy 347.334275 -405.734268) (xy 347.312488 -405.75992) (xy 347.306699 -405.767071)
			(xy 347.30018 -405.784257) (xy 347.299788 -405.793448) (xy 347.299788 -406.286716) (xy 347.300193 -406.295904)
			(xy 347.30671 -406.313088) (xy 347.312488 -406.320244) (xy 347.334244 -406.345922) (xy 347.372192 -406.401506)
			(xy 347.403225 -406.461226) (xy 347.426898 -406.524227) (xy 347.442873 -406.589606) (xy 347.450919 -406.656425)
			(xy 347.450922 -406.723727) (xy 347.442881 -406.790547) (xy 347.426912 -406.855927) (xy 347.403244 -406.91893)
			(xy 347.372216 -406.978653) (xy 347.334273 -407.03424) (xy 347.312488 -407.059892) (xy 347.306711 -407.067051)
			(xy 347.300185 -407.084231) (xy 347.299788 -407.09342) (xy 347.299788 -407.251408) (xy 347.299385 -407.261564)
			(xy 347.291584 -407.280319) (xy 347.277182 -407.294642) (xy 347.258384 -407.30234) (xy 347.248226 -407.302716)
			(xy 346.531946 -407.302716) (xy 346.521817 -407.302234) (xy 346.503088 -407.294514) (xy 346.488729 -407.280225)
			(xy 346.480916 -407.261535) (xy 346.480384 -407.251408) (xy 346.480384 -407.09342) (xy 346.479968 -407.084233)
			(xy 346.473459 -407.067049) (xy 346.467684 -407.059892) (xy 346.445864 -407.034266) (xy 346.407913 -406.978677)
			(xy 346.376878 -406.91895) (xy 346.353205 -406.855942) (xy 346.337233 -406.790556) (xy 346.329191 -406.72373)
			(xy 343.051153 -406.72373) (xy 343.051153 -406.723787) (xy 343.04308 -406.790723) (xy 343.027048 -406.85621)
			(xy 343.003287 -406.919306) (xy 342.97214 -406.979101) (xy 342.934054 -407.034735) (xy 342.912192 -407.0604)
			(xy 342.906412 -407.067557) (xy 342.899888 -407.084738) (xy 342.899492 -407.093928) (xy 342.899492 -407.251408)
			(xy 342.89909 -407.261532) (xy 342.891338 -407.280237) (xy 342.877017 -407.294551) (xy 342.858308 -407.302295)
			(xy 342.848184 -407.302716) (xy 342.131904 -407.302716) (xy 342.121798 -407.302212) (xy 342.103122 -407.294479)
			(xy 342.088828 -407.280188) (xy 342.08109 -407.261514) (xy 342.080596 -407.251408) (xy 342.080596 -407.093928)
			(xy 342.080173 -407.084742) (xy 342.073668 -407.067558) (xy 342.067896 -407.0604) (xy 342.046001 -407.034761)
			(xy 342.007913 -406.979122) (xy 341.976764 -406.919322) (xy 341.953002 -406.856222) (xy 341.936969 -406.79073)
			(xy 341.928896 -406.723789) (xy 338.650827 -406.723789) (xy 338.642793 -406.790546) (xy 338.626825 -406.855926)
			(xy 338.603158 -406.918929) (xy 338.572131 -406.978652) (xy 338.534188 -407.034239) (xy 338.512404 -407.059892)
			(xy 338.506629 -407.067052) (xy 338.500101 -407.084231) (xy 338.499704 -407.09342) (xy 338.499704 -407.251408)
			(xy 338.499285 -407.261562) (xy 338.491487 -407.280314) (xy 338.47709 -407.294637) (xy 338.458298 -407.302337)
			(xy 338.448142 -407.302716) (xy 337.731862 -407.302716) (xy 337.721727 -407.302303) (xy 337.702997 -407.294555)
			(xy 337.688641 -407.280246) (xy 337.68083 -407.261541) (xy 337.6803 -407.251408) (xy 337.6803 -407.09342)
			(xy 337.67988 -407.084234) (xy 337.673373 -407.067049) (xy 337.6676 -407.059892) (xy 337.645782 -407.034265)
			(xy 337.607837 -406.978674) (xy 337.576807 -406.918947) (xy 337.553138 -406.855939) (xy 337.537168 -406.790554)
			(xy 337.529127 -406.723729) (xy 334.251065 -406.723729) (xy 334.251065 -406.723786) (xy 334.242993 -406.790722)
			(xy 334.226961 -406.85621) (xy 334.203201 -406.919305) (xy 334.172054 -406.9791) (xy 334.13397 -407.034735)
			(xy 334.112108 -407.0604) (xy 334.10633 -407.067558) (xy 334.099804 -407.084739) (xy 334.099408 -407.093928)
			(xy 334.099408 -407.251408) (xy 334.098921 -407.261516) (xy 334.091183 -407.280193) (xy 334.076886 -407.294487)
			(xy 334.058208 -407.302223) (xy 334.0481 -407.302716) (xy 333.33182 -407.302716) (xy 333.321701 -407.302268)
			(xy 333.303001 -407.29453) (xy 333.288686 -407.280223) (xy 333.280937 -407.261527) (xy 333.280512 -407.251408)
			(xy 333.280512 -407.093928) (xy 333.280086 -407.084743) (xy 333.273583 -407.067558) (xy 333.267812 -407.0604)
			(xy 333.245916 -407.034761) (xy 333.207828 -406.979123) (xy 333.176678 -406.919323) (xy 333.152915 -406.856223)
			(xy 333.136881 -406.790731) (xy 333.128808 -406.723789) (xy 326.525636 -406.723789) (xy 326.525636 -409.523827)
			(xy 330.929173 -409.523827) (xy 330.929176 -409.456519) (xy 330.937224 -409.389693) (xy 330.953202 -409.324309)
			(xy 330.976879 -409.261303) (xy 331.007918 -409.201578) (xy 331.045873 -409.145992) (xy 331.067664 -409.12034)
			(xy 331.073476 -409.113206) (xy 331.07998 -409.096007) (xy 331.080364 -409.086812) (xy 331.080364 -408.593544)
			(xy 331.079919 -408.584361) (xy 331.073428 -408.567177) (xy 331.067664 -408.560016) (xy 331.045868 -408.534371)
			(xy 331.007918 -408.478784) (xy 330.976883 -408.419059) (xy 330.95321 -408.356054) (xy 330.937237 -408.290671)
			(xy 330.929193 -408.223847) (xy 330.929194 -408.156541) (xy 330.937239 -408.089717) (xy 330.953213 -408.024334)
			(xy 330.976888 -407.96133) (xy 331.007924 -407.901606) (xy 331.045875 -407.84602) (xy 331.067664 -407.820368)
			(xy 331.073464 -407.813226) (xy 331.079975 -407.796033) (xy 331.080364 -407.78684) (xy 331.080364 -407.628852)
			(xy 331.080782 -407.618699) (xy 331.088586 -407.599953) (xy 331.102983 -407.585633) (xy 331.121771 -407.577928)
			(xy 331.131926 -407.577544) (xy 331.848206 -407.577544) (xy 331.858334 -407.578022) (xy 331.877056 -407.585752)
			(xy 331.891412 -407.600041) (xy 331.89923 -407.618727) (xy 331.899768 -407.628852) (xy 331.899768 -407.78684)
			(xy 331.900166 -407.796028) (xy 331.906689 -407.813212) (xy 331.912468 -407.820368) (xy 331.934248 -407.846027)
			(xy 331.972196 -407.901612) (xy 332.00323 -407.961335) (xy 332.026903 -408.024339) (xy 332.042876 -408.08972)
			(xy 332.050921 -408.156542) (xy 332.050921 -408.223846) (xy 332.042878 -408.290668) (xy 332.026906 -408.35605)
			(xy 332.003235 -408.419054) (xy 331.972203 -408.478777) (xy 331.934255 -408.534364) (xy 331.912468 -408.560016)
			(xy 331.906678 -408.567166) (xy 331.90016 -408.584353) (xy 331.899768 -408.593544) (xy 331.899768 -409.086812)
			(xy 331.900179 -409.095999) (xy 331.906693 -409.113183) (xy 331.912468 -409.12034) (xy 331.93422 -409.146022)
			(xy 331.972169 -409.201604) (xy 332.003204 -409.261323) (xy 332.026878 -409.324324) (xy 332.042853 -409.389703)
			(xy 332.0509 -409.456522) (xy 332.050904 -409.523824) (xy 332.042863 -409.590644) (xy 332.026894 -409.656024)
			(xy 332.003226 -409.719027) (xy 331.972197 -409.77875) (xy 331.934253 -409.834336) (xy 331.912468 -409.859988)
			(xy 331.906647 -409.867116) (xy 331.900148 -409.88432) (xy 331.899768 -409.893516) (xy 331.899768 -410.051504)
			(xy 331.899381 -410.061662) (xy 331.891578 -410.080421) (xy 331.87717 -410.094745) (xy 331.858367 -410.102439)
			(xy 331.848206 -410.102812) (xy 331.131926 -410.102812) (xy 331.121807 -410.102254) (xy 331.103097 -410.094544)
			(xy 331.088741 -410.08028) (xy 331.080912 -410.061619) (xy 331.080364 -410.051504) (xy 331.080364 -409.893516)
			(xy 331.079932 -409.884331) (xy 331.073432 -409.867148) (xy 331.067664 -409.859988) (xy 331.04584 -409.834365)
			(xy 331.007891 -409.778775) (xy 330.976857 -409.719048) (xy 330.953186 -409.656039) (xy 330.937214 -409.590653)
			(xy 330.929173 -409.523827) (xy 326.525636 -409.523827) (xy 326.525636 -410.623701) (xy 333.128819 -410.623701)
			(xy 333.12882 -410.556275) (xy 333.136898 -410.489336) (xy 333.152936 -410.423846) (xy 333.176702 -410.360748)
			(xy 333.207855 -410.300952) (xy 333.245947 -410.245317) (xy 333.267812 -410.219652) (xy 333.273613 -410.21251)
			(xy 333.280125 -410.195317) (xy 333.280512 -410.186124) (xy 333.280512 -409.693872) (xy 333.280113 -409.684684)
			(xy 333.273591 -409.6675) (xy 333.267812 -409.660344) (xy 333.245959 -409.634669) (xy 333.20787 -409.579036)
			(xy 333.176718 -409.519242) (xy 333.152952 -409.456146) (xy 333.136916 -409.390658) (xy 333.128839 -409.32372)
			(xy 333.128837 -409.256298) (xy 333.136912 -409.18936) (xy 333.152947 -409.123871) (xy 333.17671 -409.060775)
			(xy 333.20786 -409.000979) (xy 333.245948 -408.945345) (xy 333.267812 -408.91968) (xy 333.273601 -408.912529)
			(xy 333.28012 -408.895343) (xy 333.280512 -408.886152) (xy 333.280512 -408.728672) (xy 333.280962 -408.71856)
			(xy 333.288711 -408.699879) (xy 333.303019 -408.685585) (xy 333.321708 -408.677853) (xy 333.33182 -408.677364)
			(xy 334.0481 -408.677364) (xy 334.058204 -408.677884) (xy 334.076876 -408.685615) (xy 334.091169 -408.699901)
			(xy 334.09891 -408.718568) (xy 334.099408 -408.728672) (xy 334.099408 -408.886152) (xy 334.099839 -408.895337)
			(xy 334.106338 -408.912522) (xy 334.112108 -408.91968) (xy 334.133983 -408.945336) (xy 334.172071 -409.000972)
			(xy 334.203221 -409.060769) (xy 334.226984 -409.123867) (xy 334.243019 -409.189358) (xy 334.251093 -409.256297)
			(xy 334.251092 -409.323721) (xy 334.243015 -409.39066) (xy 334.226979 -409.45615) (xy 334.203214 -409.519247)
			(xy 334.200797 -409.523886) (xy 335.328966 -409.523886) (xy 335.328969 -409.45646) (xy 335.337048 -409.38952)
			(xy 335.353086 -409.32403) (xy 335.376852 -409.260931) (xy 335.408005 -409.201134) (xy 335.446095 -409.145498)
			(xy 335.46796 -409.119832) (xy 335.473775 -409.1127) (xy 335.480277 -409.095499) (xy 335.48066 -409.086304)
			(xy 335.48066 -408.594052) (xy 335.480211 -408.584869) (xy 335.473723 -408.567685) (xy 335.46796 -408.560524)
			(xy 335.44609 -408.534865) (xy 335.408004 -408.479228) (xy 335.376856 -408.419431) (xy 335.353094 -408.356333)
			(xy 335.33706 -408.290844) (xy 335.328985 -408.223906) (xy 335.328986 -408.156482) (xy 335.337062 -408.089544)
			(xy 335.353097 -408.024055) (xy 335.376861 -407.960958) (xy 335.40801 -407.901161) (xy 335.446097 -407.845526)
			(xy 335.46796 -407.81986) (xy 335.473763 -407.81272) (xy 335.480272 -407.795525) (xy 335.48066 -407.786332)
			(xy 335.48066 -407.628852) (xy 335.481145 -407.618745) (xy 335.488891 -407.600074) (xy 335.503187 -407.585782)
			(xy 335.521861 -407.578042) (xy 335.531968 -407.577544) (xy 336.248248 -407.577544) (xy 336.258353 -407.578045)
			(xy 336.277021 -407.585788) (xy 336.291312 -407.600079) (xy 336.299055 -407.618747) (xy 336.299556 -407.628852)
			(xy 336.299556 -407.786332) (xy 336.299961 -407.79552) (xy 336.306479 -407.812703) (xy 336.312256 -407.81986)
			(xy 336.334114 -407.845531) (xy 336.372205 -407.901164) (xy 336.403359 -407.960959) (xy 336.427126 -408.024055)
			(xy 336.443163 -408.089544) (xy 336.45124 -408.156482) (xy 336.451241 -408.223906) (xy 336.443165 -408.290844)
			(xy 336.427129 -408.356334) (xy 336.403364 -408.41943) (xy 336.372212 -408.479226) (xy 336.334121 -408.53486)
			(xy 336.312256 -408.560524) (xy 336.306461 -408.56767) (xy 336.299947 -408.58486) (xy 336.299556 -408.594052)
			(xy 336.299556 -409.086304) (xy 336.299974 -409.09549) (xy 336.306483 -409.112674) (xy 336.312256 -409.119832)
			(xy 336.334086 -409.145526) (xy 336.372179 -409.201155) (xy 336.403334 -409.260947) (xy 336.427102 -409.32404)
			(xy 336.443141 -409.389526) (xy 336.45122 -409.456462) (xy 336.451224 -409.523884) (xy 336.443151 -409.59082)
			(xy 336.427118 -409.656308) (xy 336.403356 -409.719404) (xy 336.372207 -409.779198) (xy 336.334119 -409.834832)
			(xy 336.312256 -409.860496) (xy 336.306473 -409.867651) (xy 336.299951 -409.884834) (xy 336.299556 -409.894024)
			(xy 336.299556 -410.051504) (xy 336.299019 -410.061606) (xy 336.291291 -410.080274) (xy 336.277011 -410.094566)
			(xy 336.25835 -410.102311) (xy 336.248248 -410.102812) (xy 335.531968 -410.102812) (xy 335.521859 -410.102341)
			(xy 335.503182 -410.094595) (xy 335.488889 -410.080294) (xy 335.481153 -410.061614) (xy 335.48066 -410.051504)
			(xy 335.48066 -409.894024) (xy 335.480225 -409.88484) (xy 335.473727 -409.867656) (xy 335.46796 -409.860496)
			(xy 335.446062 -409.834859) (xy 335.407977 -409.77922) (xy 335.37683 -409.719419) (xy 335.35307 -409.656319)
			(xy 335.337038 -409.590827) (xy 335.328966 -409.523886) (xy 334.200797 -409.523886) (xy 334.172062 -409.579044)
			(xy 334.133972 -409.634679) (xy 334.112108 -409.660344) (xy 334.106311 -409.667489) (xy 334.099796 -409.68468)
			(xy 334.099408 -409.693872) (xy 334.099408 -410.186124) (xy 334.099805 -410.195313) (xy 334.106328 -410.212497)
			(xy 334.112108 -410.219652) (xy 334.133956 -410.24533) (xy 334.172045 -410.300963) (xy 334.203196 -410.360758)
			(xy 334.22696 -410.423853) (xy 334.242997 -410.48934) (xy 334.251074 -410.556277) (xy 334.251075 -410.623641)
			(xy 337.529138 -410.623641) (xy 337.52914 -410.556335) (xy 337.537185 -410.489512) (xy 337.553158 -410.42413)
			(xy 337.576831 -410.361125) (xy 337.607864 -410.3014) (xy 337.645813 -410.245813) (xy 337.6676 -410.22016)
			(xy 337.673396 -410.213014) (xy 337.679911 -410.195824) (xy 337.6803 -410.186632) (xy 337.6803 -409.693364)
			(xy 337.679907 -409.684175) (xy 337.673382 -409.666991) (xy 337.6676 -409.659836) (xy 337.645825 -409.634174)
			(xy 337.607879 -409.578588) (xy 337.576847 -409.518865) (xy 337.553175 -409.455862) (xy 337.537203 -409.390482)
			(xy 337.529158 -409.323661) (xy 337.529157 -409.256357) (xy 337.537199 -409.189536) (xy 337.55317 -409.124155)
			(xy 337.57684 -409.061151) (xy 337.607869 -409.001428) (xy 337.645814 -408.945841) (xy 337.6676 -408.920188)
			(xy 337.673384 -408.913034) (xy 337.679906 -408.89585) (xy 337.6803 -408.88666) (xy 337.6803 -408.728672)
			(xy 337.680699 -408.718516) (xy 337.688503 -408.699763) (xy 337.702907 -408.685441) (xy 337.721704 -408.677742)
			(xy 337.731862 -408.677364) (xy 338.448142 -408.677364) (xy 338.458274 -408.677793) (xy 338.477001 -408.685539)
			(xy 338.491357 -408.699843) (xy 338.49917 -408.718542) (xy 338.499704 -408.728672) (xy 338.499704 -408.88666)
			(xy 338.500132 -408.895845) (xy 338.506633 -408.91303) (xy 338.512404 -408.920188) (xy 338.534202 -408.945831)
			(xy 338.572148 -409.00142) (xy 338.603178 -409.061145) (xy 338.626848 -409.124151) (xy 338.642819 -409.189534)
			(xy 338.650862 -409.256356) (xy 338.650861 -409.323662) (xy 338.642816 -409.390484) (xy 338.626843 -409.455867)
			(xy 338.603171 -409.518871) (xy 338.600596 -409.523827) (xy 339.729261 -409.523827) (xy 339.729264 -409.456519)
			(xy 339.737312 -409.389694) (xy 339.753289 -409.324309) (xy 339.776966 -409.261303) (xy 339.808004 -409.201579)
			(xy 339.845958 -409.145992) (xy 339.867748 -409.12034) (xy 339.873559 -409.113205) (xy 339.880064 -409.096006)
			(xy 339.880448 -409.086812) (xy 339.880448 -408.593544) (xy 339.880006 -408.58436) (xy 339.873513 -408.567176)
			(xy 339.867748 -408.560016) (xy 339.845952 -408.534371) (xy 339.808003 -408.478783) (xy 339.776969 -408.419059)
			(xy 339.753297 -408.356054) (xy 339.737324 -408.29067) (xy 339.72928 -408.223847) (xy 339.729281 -408.156541)
			(xy 339.737326 -408.089718) (xy 339.7533 -408.024335) (xy 339.776974 -407.96133) (xy 339.808009 -407.901606)
			(xy 339.845959 -407.84602) (xy 339.867748 -407.820368) (xy 339.873547 -407.813224) (xy 339.880059 -407.796032)
			(xy 339.880448 -407.78684) (xy 339.880448 -407.628852) (xy 339.880881 -407.618701) (xy 339.888683 -407.599958)
			(xy 339.903075 -407.585638) (xy 339.921857 -407.577931) (xy 339.93201 -407.577544) (xy 340.64829 -407.577544)
			(xy 340.658417 -407.578035) (xy 340.677138 -407.58576) (xy 340.691495 -407.600045) (xy 340.699314 -407.618728)
			(xy 340.699852 -407.628852) (xy 340.699852 -407.78684) (xy 340.700254 -407.796028) (xy 340.706775 -407.813211)
			(xy 340.712552 -407.820368) (xy 340.734332 -407.846027) (xy 340.772282 -407.901612) (xy 340.803316 -407.961335)
			(xy 340.826989 -408.024338) (xy 340.842963 -408.08972) (xy 340.851008 -408.156542) (xy 340.851009 -408.223846)
			(xy 340.842965 -408.290668) (xy 340.826993 -408.35605) (xy 340.803321 -408.419054) (xy 340.772288 -408.478778)
			(xy 340.734339 -408.534364) (xy 340.712552 -408.560016) (xy 340.70676 -408.567164) (xy 340.700244 -408.584353)
			(xy 340.699852 -408.593544) (xy 340.699852 -409.086812) (xy 340.700267 -409.095998) (xy 340.706779 -409.113182)
			(xy 340.712552 -409.12034) (xy 340.734304 -409.146021) (xy 340.772255 -409.201603) (xy 340.80329 -409.261323)
			(xy 340.826965 -409.324323) (xy 340.842941 -409.389702) (xy 340.850988 -409.456522) (xy 340.850992 -409.523824)
			(xy 340.842951 -409.590644) (xy 340.826981 -409.656025) (xy 340.803312 -409.719028) (xy 340.772283 -409.77875)
			(xy 340.734338 -409.834336) (xy 340.712552 -409.859988) (xy 340.70673 -409.867115) (xy 340.700232 -409.88432)
			(xy 340.699852 -409.893516) (xy 340.699852 -410.051504) (xy 340.699383 -410.061652) (xy 340.691595 -410.080394)
			(xy 340.677214 -410.094716) (xy 340.65844 -410.102424) (xy 340.64829 -410.102812) (xy 339.93201 -410.102812)
			(xy 339.92189 -410.102267) (xy 339.903179 -410.094552) (xy 339.888824 -410.080284) (xy 339.880996 -410.061621)
			(xy 339.880448 -410.051504) (xy 339.880448 -409.893516) (xy 339.88002 -409.884331) (xy 339.873517 -409.867147)
			(xy 339.867748 -409.859988) (xy 339.845924 -409.834365) (xy 339.807976 -409.778775) (xy 339.776944 -409.719047)
			(xy 339.753273 -409.656039) (xy 339.737302 -409.590653) (xy 339.729261 -409.523827) (xy 338.600596 -409.523827)
			(xy 338.572139 -409.578596) (xy 338.534191 -409.634183) (xy 338.512404 -409.659836) (xy 338.50661 -409.666983)
			(xy 338.500094 -409.684172) (xy 338.499704 -409.693364) (xy 338.499704 -410.186632) (xy 338.500098 -410.195821)
			(xy 338.506623 -410.213005) (xy 338.512404 -410.22016) (xy 338.534175 -410.245826) (xy 338.572121 -410.301411)
			(xy 338.603153 -410.361133) (xy 338.626825 -410.424136) (xy 338.642797 -410.489516) (xy 338.650842 -410.556336)
			(xy 338.650844 -410.623639) (xy 338.650837 -410.6237) (xy 341.928907 -410.6237) (xy 341.928908 -410.556276)
			(xy 341.936986 -410.489336) (xy 341.953023 -410.423846) (xy 341.976789 -410.360749) (xy 342.007941 -410.300952)
			(xy 342.046031 -410.245317) (xy 342.067896 -410.219652) (xy 342.073695 -410.212508) (xy 342.080208 -410.195317)
			(xy 342.080596 -410.186124) (xy 342.080596 -409.693872) (xy 342.0802 -409.684683) (xy 342.073677 -409.667499)
			(xy 342.067896 -409.660344) (xy 342.046044 -409.634669) (xy 342.007955 -409.579036) (xy 341.976804 -409.519241)
			(xy 341.953039 -409.456145) (xy 341.937003 -409.390657) (xy 341.928927 -409.32372) (xy 341.928925 -409.256298)
			(xy 341.937 -409.18936) (xy 341.953034 -409.123872) (xy 341.976797 -409.060776) (xy 342.007946 -409.00098)
			(xy 342.046033 -408.945345) (xy 342.067896 -408.91968) (xy 342.073683 -408.912528) (xy 342.080204 -408.895343)
			(xy 342.080596 -408.886152) (xy 342.080596 -408.728672) (xy 342.081062 -408.718562) (xy 342.088808 -408.699884)
			(xy 342.103111 -408.68559) (xy 342.121794 -408.677856) (xy 342.131904 -408.677364) (xy 342.848184 -408.677364)
			(xy 342.858287 -408.677897) (xy 342.876958 -408.685623) (xy 342.891252 -408.699905) (xy 342.898994 -408.718569)
			(xy 342.899492 -408.728672) (xy 342.899492 -408.886152) (xy 342.899927 -408.895337) (xy 342.906424 -408.912521)
			(xy 342.912192 -408.91968) (xy 342.934068 -408.945335) (xy 342.972157 -409.000971) (xy 343.003308 -409.060769)
			(xy 343.027071 -409.123867) (xy 343.043106 -409.189357) (xy 343.051181 -409.256297) (xy 343.05118 -409.323721)
			(xy 343.043103 -409.390661) (xy 343.027066 -409.45615) (xy 343.0033 -409.519248) (xy 343.000914 -409.523827)
			(xy 344.129052 -409.523827) (xy 344.129055 -409.456519) (xy 344.137102 -409.389694) (xy 344.153079 -409.32431)
			(xy 344.176756 -409.261304) (xy 344.207793 -409.201579) (xy 344.245746 -409.145992) (xy 344.267536 -409.12034)
			(xy 344.273345 -409.113204) (xy 344.279851 -409.096006) (xy 344.280236 -409.086812) (xy 344.280236 -408.593544)
			(xy 344.279796 -408.58436) (xy 344.273302 -408.567176) (xy 344.267536 -408.560016) (xy 344.24574 -408.53437)
			(xy 344.207792 -408.478783) (xy 344.176759 -408.419058) (xy 344.153087 -408.356053) (xy 344.137115 -408.29067)
			(xy 344.129071 -408.223847) (xy 344.129072 -408.156541) (xy 344.137117 -408.089718) (xy 344.153091 -408.024335)
			(xy 344.176764 -407.961331) (xy 344.207798 -407.901607) (xy 344.245748 -407.84602) (xy 344.267536 -407.820368)
			(xy 344.273333 -407.813223) (xy 344.279847 -407.796032) (xy 344.280236 -407.78684) (xy 344.280236 -407.628852)
			(xy 344.280583 -407.61869) (xy 344.288401 -407.59993) (xy 344.302821 -407.585607) (xy 344.321634 -407.577916)
			(xy 344.331798 -407.577544) (xy 345.048078 -407.577544) (xy 345.058204 -407.578045) (xy 345.076925 -407.585766)
			(xy 345.09113 -407.599896) (xy 358.331016 -407.599896) (xy 358.33502 -407.394708) (xy 358.347027 -407.189832)
			(xy 358.367018 -406.985581) (xy 358.394963 -406.782266) (xy 358.430819 -406.580195) (xy 358.474533 -406.379677)
			(xy 358.526036 -406.181018) (xy 358.585251 -405.984519) (xy 358.652087 -405.79048) (xy 358.726443 -405.599197)
			(xy 358.808206 -405.41096) (xy 358.897251 -405.226057) (xy 358.993442 -405.044769) (xy 359.096633 -404.867372)
			(xy 359.206667 -404.694135) (xy 359.323376 -404.525324) (xy 359.446582 -404.361195) (xy 359.576099 -404.201998)
			(xy 359.711728 -404.047976) (xy 359.853263 -403.899362) (xy 360.000488 -403.756384) (xy 360.15318 -403.619259)
			(xy 360.311106 -403.488195) (xy 360.474025 -403.363393) (xy 360.64169 -403.245043) (xy 360.813844 -403.133324)
			(xy 360.990226 -403.028407) (xy 361.170567 -402.930452) (xy 361.354593 -402.839608) (xy 361.542023 -402.756012)
			(xy 361.732572 -402.679793) (xy 361.925949 -402.611067) (xy 362.121861 -402.549938) (xy 362.320008 -402.496499)
			(xy 362.52009 -402.450832) (xy 362.721801 -402.413005) (xy 362.924834 -402.383078) (xy 363.128881 -402.361095)
			(xy 363.33363 -402.34709) (xy 363.538769 -402.341084) (xy 363.743986 -402.343086) (xy 363.948969 -402.353094)
			(xy 364.153406 -402.371091) (xy 364.356984 -402.397051) (xy 364.559395 -402.430934) (xy 364.760329 -402.472689)
			(xy 364.959482 -402.522252) (xy 365.156549 -402.579547) (xy 365.351231 -402.644487) (xy 365.543231 -402.716973)
			(xy 365.732256 -402.796896) (xy 365.789712 -402.823878) (xy 377.128705 -402.823878) (xy 377.12871 -402.75645)
			(xy 377.136791 -402.689508) (xy 377.152832 -402.624016) (xy 377.176603 -402.560917) (xy 377.20776 -402.50112)
			(xy 377.245856 -402.445485) (xy 377.267724 -402.41982) (xy 377.27354 -402.412689) (xy 377.280042 -402.395487)
			(xy 377.280424 -402.386292) (xy 377.280424 -401.89404) (xy 377.279989 -401.884856) (xy 377.273492 -401.867671)
			(xy 377.267724 -401.860512) (xy 377.24584 -401.834863) (xy 377.20775 -401.779227) (xy 377.176599 -401.719429)
			(xy 377.152835 -401.65633) (xy 377.1368 -401.590838) (xy 377.128725 -401.523898) (xy 377.128727 -401.456472)
			(xy 377.136805 -401.389532) (xy 377.152843 -401.324042) (xy 377.176611 -401.260944) (xy 377.207765 -401.201147)
			(xy 377.245858 -401.145513) (xy 377.267724 -401.119848) (xy 377.273528 -401.112708) (xy 377.280037 -401.095513)
			(xy 377.280424 -401.08632) (xy 377.280424 -400.92884) (xy 377.280849 -400.918717) (xy 377.288589 -400.90001)
			(xy 377.302903 -400.885693) (xy 377.321609 -400.877951) (xy 377.331732 -400.877532) (xy 378.048012 -400.877532)
			(xy 378.058139 -400.877907) (xy 378.076849 -400.885665) (xy 378.091164 -400.899994) (xy 378.098904 -400.918712)
			(xy 378.09932 -400.92884) (xy 378.09932 -401.08632) (xy 378.099716 -401.095509) (xy 378.106239 -401.112693)
			(xy 378.11202 -401.119848) (xy 378.133864 -401.14553) (xy 378.171952 -401.201162) (xy 378.203102 -401.260957)
			(xy 378.226866 -401.324051) (xy 378.242903 -401.389538) (xy 378.25098 -401.456474) (xy 378.250982 -401.523896)
			(xy 378.242908 -401.590832) (xy 378.226875 -401.65632) (xy 378.203114 -401.719416) (xy 378.200833 -401.723796)
			(xy 379.328885 -401.723796) (xy 379.328887 -401.656371) (xy 379.336964 -401.589432) (xy 379.353001 -401.523942)
			(xy 379.376766 -401.460844) (xy 379.407918 -401.401047) (xy 379.446008 -401.345412) (xy 379.467872 -401.319746)
			(xy 379.473683 -401.312611) (xy 379.480187 -401.295412) (xy 379.480572 -401.286218) (xy 379.480572 -400.793966)
			(xy 379.480184 -400.784776) (xy 379.473656 -400.767592) (xy 379.467872 -400.760438) (xy 379.446015 -400.734767)
			(xy 379.407928 -400.679133) (xy 379.376778 -400.619337) (xy 379.353015 -400.556241) (xy 379.33698 -400.490753)
			(xy 379.328904 -400.423816) (xy 379.328904 -400.356393) (xy 379.336979 -400.289456) (xy 379.353013 -400.223967)
			(xy 379.376775 -400.160871) (xy 379.407923 -400.101075) (xy 379.446009 -400.04544) (xy 379.467872 -400.019774)
			(xy 379.473671 -400.012631) (xy 379.480182 -399.995438) (xy 379.480572 -399.986246) (xy 379.480572 -399.828766)
			(xy 379.481 -399.818633) (xy 379.488744 -399.799905) (xy 379.503049 -399.785549) (xy 379.521749 -399.777737)
			(xy 379.53188 -399.777204) (xy 380.24816 -399.777204) (xy 380.258312 -399.777655) (xy 380.277064 -399.785438)
			(xy 380.291389 -399.799826) (xy 380.29909 -399.818612) (xy 380.299468 -399.828766) (xy 380.299468 -399.986246)
			(xy 380.299911 -399.99543) (xy 380.306403 -400.012614) (xy 380.312168 -400.019774) (xy 380.334039 -400.045434)
			(xy 380.37213 -400.101068) (xy 380.403282 -400.160865) (xy 380.427047 -400.223963) (xy 380.443083 -400.289453)
			(xy 380.451159 -400.356392) (xy 380.451158 -400.423817) (xy 380.443082 -400.490756) (xy 380.427044 -400.556246)
			(xy 380.403278 -400.619343) (xy 380.372125 -400.679139) (xy 380.334033 -400.734773) (xy 380.312168 -400.760438)
			(xy 380.306369 -400.767581) (xy 380.299856 -400.784773) (xy 380.299468 -400.793966) (xy 380.299468 -401.286218)
			(xy 380.299877 -401.295405) (xy 380.306392 -401.312589) (xy 380.312168 -401.319746) (xy 380.334011 -401.345429)
			(xy 380.372103 -401.40106) (xy 380.403256 -401.460853) (xy 380.427023 -401.523948) (xy 380.443061 -401.589435)
			(xy 380.451139 -401.656372) (xy 380.451141 -401.723795) (xy 380.443067 -401.790732) (xy 380.427033 -401.85622)
			(xy 380.40327 -401.919316) (xy 380.37212 -401.979112) (xy 380.334032 -402.034745) (xy 380.312168 -402.06041)
			(xy 380.306381 -402.067562) (xy 380.299861 -402.084747) (xy 380.299468 -402.093938) (xy 380.299468 -402.251418)
			(xy 380.298989 -402.261545) (xy 380.291256 -402.280265) (xy 380.276968 -402.29462) (xy 380.258284 -402.30244)
			(xy 380.24816 -402.30298) (xy 379.53188 -402.30298) (xy 379.521722 -402.302595) (xy 379.502965 -402.294789)
			(xy 379.488642 -402.280381) (xy 379.480946 -402.261578) (xy 379.480572 -402.251418) (xy 379.480572 -402.093938)
			(xy 379.48015 -402.084752) (xy 379.473645 -402.067567) (xy 379.467872 -402.06041) (xy 379.445987 -402.034762)
			(xy 379.407901 -401.979124) (xy 379.376753 -401.919326) (xy 379.352991 -401.856227) (xy 379.336958 -401.790736)
			(xy 379.328885 -401.723796) (xy 378.200833 -401.723796) (xy 378.171967 -401.779212) (xy 378.133882 -401.834846)
			(xy 378.11202 -401.860512) (xy 378.106238 -401.867668) (xy 378.099714 -401.88485) (xy 378.09932 -401.89404)
			(xy 378.09932 -402.386292) (xy 378.099729 -402.395479) (xy 378.106243 -402.412664) (xy 378.11202 -402.41982)
			(xy 378.133836 -402.445524) (xy 378.171925 -402.501154) (xy 378.203077 -402.560945) (xy 378.226843 -402.624037)
			(xy 378.242881 -402.689521) (xy 378.25096 -402.756454) (xy 378.250965 -402.823818) (xy 381.529025 -402.823818)
			(xy 381.529029 -402.75651) (xy 381.537078 -402.689684) (xy 381.553055 -402.6243) (xy 381.576732 -402.561293)
			(xy 381.607769 -402.501568) (xy 381.645722 -402.445981) (xy 381.667512 -402.420328) (xy 381.673323 -402.413193)
			(xy 381.679829 -402.395995) (xy 381.680212 -402.3868) (xy 381.680212 -401.893532) (xy 381.679784 -401.884347)
			(xy 381.673282 -401.867162) (xy 381.667512 -401.860004) (xy 381.645705 -401.834368) (xy 381.607759 -401.778778)
			(xy 381.576728 -401.719052) (xy 381.553058 -401.656046) (xy 381.537087 -401.590662) (xy 381.529045 -401.523838)
			(xy 381.529046 -401.456532) (xy 381.537092 -401.389708) (xy 381.553066 -401.324325) (xy 381.57674 -401.26132)
			(xy 381.607774 -401.201596) (xy 381.645724 -401.146009) (xy 381.667512 -401.120356) (xy 381.673311 -401.113213)
			(xy 381.679824 -401.096021) (xy 381.680212 -401.086828) (xy 381.680212 -400.92884) (xy 381.680655 -400.918687)
			(xy 381.688439 -400.899933) (xy 381.70283 -400.885608) (xy 381.721619 -400.877909) (xy 381.731774 -400.877532)
			(xy 382.448054 -400.877532) (xy 382.458177 -400.878064) (xy 382.476895 -400.885775) (xy 382.491253 -400.900048)
			(xy 382.499075 -400.91872) (xy 382.499616 -400.92884) (xy 382.499616 -401.086828) (xy 382.500009 -401.096017)
			(xy 382.506534 -401.113201) (xy 382.512316 -401.120356) (xy 382.534085 -401.146024) (xy 382.572038 -401.201607)
			(xy 382.603074 -401.261328) (xy 382.62675 -401.32433) (xy 382.642726 -401.389711) (xy 382.650772 -401.456533)
			(xy 382.650774 -401.523837) (xy 382.642731 -401.590659) (xy 382.626759 -401.656041) (xy 382.603087 -401.719045)
			(xy 382.600649 -401.723737) (xy 383.729179 -401.723737) (xy 383.729181 -401.65643) (xy 383.737228 -401.589605)
			(xy 383.753204 -401.524222) (xy 383.77688 -401.461216) (xy 383.807917 -401.401492) (xy 383.84587 -401.345906)
			(xy 383.86766 -401.320254) (xy 383.873466 -401.313116) (xy 383.879973 -401.29592) (xy 383.88036 -401.286726)
			(xy 383.88036 -400.793458) (xy 383.879957 -400.78427) (xy 383.873437 -400.767087) (xy 383.86766 -400.75993)
			(xy 383.845878 -400.734273) (xy 383.807927 -400.678688) (xy 383.776893 -400.618965) (xy 383.753219 -400.555961)
			(xy 383.737245 -400.490579) (xy 383.7292 -400.423757) (xy 383.729199 -400.356452) (xy 383.737243 -400.28963)
			(xy 383.753216 -400.224247) (xy 383.776889 -400.161243) (xy 383.807923 -400.10152) (xy 383.845872 -400.045934)
			(xy 383.86766 -400.020282) (xy 383.873454 -400.013135) (xy 383.879969 -399.995946) (xy 383.88036 -399.986754)
			(xy 383.88036 -399.828766) (xy 383.880806 -399.818603) (xy 383.888596 -399.799829) (xy 383.902976 -399.785464)
			(xy 383.921759 -399.777695) (xy 383.931922 -399.777204) (xy 384.648202 -399.777204) (xy 384.658356 -399.777731)
			(xy 384.677118 -399.7855) (xy 384.691482 -399.799855) (xy 384.699263 -399.818613) (xy 384.699764 -399.828766)
			(xy 384.699764 -399.986754) (xy 384.700205 -399.995938) (xy 384.706698 -400.013122) (xy 384.712464 -400.020282)
			(xy 384.734258 -400.045929) (xy 384.772206 -400.101516) (xy 384.803239 -400.161241) (xy 384.826911 -400.224246)
			(xy 384.842884 -400.289629) (xy 384.850927 -400.356452) (xy 384.850927 -400.423757) (xy 384.842882 -400.49058)
			(xy 384.826909 -400.555963) (xy 384.803235 -400.618968) (xy 384.772201 -400.678691) (xy 384.734252 -400.734278)
			(xy 384.712464 -400.75993) (xy 384.706668 -400.767075) (xy 384.700154 -400.784266) (xy 384.699764 -400.793458)
			(xy 384.699764 -401.286726) (xy 384.70017 -401.295913) (xy 384.706687 -401.313097) (xy 384.712464 -401.320254)
			(xy 384.73423 -401.345924) (xy 384.772179 -401.401508) (xy 384.803213 -401.461229) (xy 384.826887 -401.524231)
			(xy 384.842861 -401.589611) (xy 384.850907 -401.656432) (xy 384.850909 -401.723735) (xy 384.842867 -401.790556)
			(xy 384.826897 -401.855937) (xy 384.803227 -401.918941) (xy 384.772196 -401.978663) (xy 384.73425 -402.03425)
			(xy 384.712464 -402.059902) (xy 384.706679 -402.067056) (xy 384.700158 -402.08424) (xy 384.699764 -402.09343)
			(xy 384.699764 -402.251418) (xy 384.699282 -402.261577) (xy 384.691502 -402.280346) (xy 384.677133 -402.294711)
			(xy 384.658361 -402.302485) (xy 384.648202 -402.30298) (xy 383.931922 -402.30298) (xy 383.921754 -402.302518)
			(xy 383.902963 -402.294744) (xy 383.888578 -402.28037) (xy 383.88079 -402.261586) (xy 383.88036 -402.251418)
			(xy 383.88036 -402.09343) (xy 383.879922 -402.084246) (xy 383.873426 -402.067062) (xy 383.86766 -402.059902)
			(xy 383.84585 -402.034268) (xy 383.8079 -401.97868) (xy 383.776867 -401.918954) (xy 383.753194 -401.855947)
			(xy 383.737222 -401.790562) (xy 383.729179 -401.723737) (xy 382.600649 -401.723737) (xy 382.572053 -401.778767)
			(xy 382.534104 -401.834352) (xy 382.512316 -401.860004) (xy 382.506537 -401.867162) (xy 382.500011 -401.884343)
			(xy 382.499616 -401.893532) (xy 382.499616 -402.3868) (xy 382.500023 -402.395988) (xy 382.506538 -402.413172)
			(xy 382.512316 -402.420328) (xy 382.534058 -402.446018) (xy 382.572011 -402.501598) (xy 382.603049 -402.561316)
			(xy 382.626726 -402.624316) (xy 382.642704 -402.689694) (xy 382.650753 -402.756513) (xy 382.650757 -402.823815)
			(xy 382.650749 -402.823878) (xy 385.928793 -402.823878) (xy 385.928798 -402.75645) (xy 385.936878 -402.689508)
			(xy 385.952919 -402.624017) (xy 385.976689 -402.560918) (xy 386.007846 -402.50112) (xy 386.045941 -402.445485)
			(xy 386.067808 -402.41982) (xy 386.073622 -402.412687) (xy 386.080126 -402.395487) (xy 386.080508 -402.386292)
			(xy 386.080508 -401.89404) (xy 386.080077 -401.884855) (xy 386.073578 -401.867671) (xy 386.067808 -401.860512)
			(xy 386.045924 -401.834863) (xy 386.007835 -401.779226) (xy 385.976685 -401.719428) (xy 385.952922 -401.656329)
			(xy 385.936887 -401.590838) (xy 385.928813 -401.523898) (xy 385.928815 -401.456472) (xy 385.936893 -401.389533)
			(xy 385.952931 -401.324042) (xy 385.976697 -401.260944) (xy 386.007851 -401.201148) (xy 386.045943 -401.145513)
			(xy 386.067808 -401.119848) (xy 386.07361 -401.112707) (xy 386.080121 -401.095513) (xy 386.080508 -401.08632)
			(xy 386.080508 -400.92884) (xy 386.080949 -400.918719) (xy 386.088686 -400.900015) (xy 386.102995 -400.885699)
			(xy 386.121695 -400.877954) (xy 386.131816 -400.877532) (xy 386.848096 -400.877532) (xy 386.858222 -400.87792)
			(xy 386.876932 -400.885673) (xy 386.891247 -400.899998) (xy 386.898987 -400.918714) (xy 386.899404 -400.92884)
			(xy 386.899404 -401.08632) (xy 386.899804 -401.095508) (xy 386.906325 -401.112692) (xy 386.912104 -401.119848)
			(xy 386.933948 -401.14553) (xy 386.972037 -401.201162) (xy 387.003189 -401.260956) (xy 387.026954 -401.324051)
			(xy 387.04299 -401.389538) (xy 387.051068 -401.456474) (xy 387.05107 -401.523896) (xy 387.042996 -401.590833)
			(xy 387.026963 -401.656321) (xy 387.003201 -401.719417) (xy 387.000951 -401.723737) (xy 388.12897 -401.723737)
			(xy 388.128972 -401.65643) (xy 388.137019 -401.589606) (xy 388.152994 -401.524222) (xy 388.17667 -401.461217)
			(xy 388.207706 -401.401492) (xy 388.245659 -401.345906) (xy 388.267448 -401.320254) (xy 388.273253 -401.313115)
			(xy 388.279761 -401.295919) (xy 388.280148 -401.286726) (xy 388.280148 -400.793458) (xy 388.279747 -400.78427)
			(xy 388.273226 -400.767086) (xy 388.267448 -400.75993) (xy 388.245666 -400.734273) (xy 388.207717 -400.678687)
			(xy 388.176683 -400.618965) (xy 388.153009 -400.555961) (xy 388.137035 -400.490579) (xy 388.128991 -400.423757)
			(xy 388.12899 -400.356452) (xy 388.137034 -400.28963) (xy 388.153006 -400.224248) (xy 388.176679 -400.161244)
			(xy 388.207712 -400.10152) (xy 388.245661 -400.045934) (xy 388.267448 -400.020282) (xy 388.273241 -400.013134)
			(xy 388.279756 -399.995946) (xy 388.280148 -399.986754) (xy 388.280148 -399.828766) (xy 388.280606 -399.818605)
			(xy 388.288393 -399.799833) (xy 388.30277 -399.785469) (xy 388.321548 -399.777697) (xy 388.33171 -399.777204)
			(xy 389.04799 -399.777204) (xy 389.058143 -399.777741) (xy 389.076905 -399.785506) (xy 389.09127 -399.799858)
			(xy 389.099051 -399.818613) (xy 389.099552 -399.828766) (xy 389.099552 -399.986754) (xy 389.099995 -399.995937)
			(xy 389.106487 -400.013121) (xy 389.112252 -400.020282) (xy 389.134046 -400.045929) (xy 389.171995 -400.101516)
			(xy 389.203029 -400.16124) (xy 389.226702 -400.224245) (xy 389.242675 -400.289628) (xy 389.250718 -400.356452)
			(xy 389.250718 -400.423757) (xy 389.242673 -400.490581) (xy 389.226699 -400.555963) (xy 389.203025 -400.618968)
			(xy 389.171991 -400.678692) (xy 389.134041 -400.734278) (xy 389.112252 -400.75993) (xy 389.106454 -400.767074)
			(xy 389.099942 -400.784266) (xy 389.099552 -400.793458) (xy 389.099552 -401.286726) (xy 389.09996 -401.295913)
			(xy 389.106477 -401.313097) (xy 389.112252 -401.320254) (xy 389.134018 -401.345924) (xy 389.171968 -401.401508)
			(xy 389.203003 -401.461229) (xy 389.226677 -401.524231) (xy 389.242652 -401.589611) (xy 389.250698 -401.656432)
			(xy 389.2507 -401.723735) (xy 389.242658 -401.790556) (xy 389.226687 -401.855937) (xy 389.203016 -401.918941)
			(xy 389.171985 -401.978664) (xy 389.134038 -402.03425) (xy 389.112252 -402.059902) (xy 389.106466 -402.067055)
			(xy 389.099946 -402.08424) (xy 389.099552 -402.09343) (xy 389.099552 -402.251418) (xy 389.099081 -402.261578)
			(xy 389.091299 -402.28035) (xy 389.076926 -402.294715) (xy 389.05815 -402.302487) (xy 389.04799 -402.30298)
			(xy 388.33171 -402.30298) (xy 388.321555 -402.302459) (xy 388.30279 -402.294691) (xy 388.288425 -402.280334)
			(xy 388.280647 -402.261573) (xy 388.280148 -402.251418) (xy 388.280148 -402.09343) (xy 388.279713 -402.084246)
			(xy 388.273215 -402.067062) (xy 388.267448 -402.059902) (xy 388.245638 -402.034268) (xy 388.207689 -401.978679)
			(xy 388.176657 -401.918953) (xy 388.152985 -401.855946) (xy 388.137013 -401.790562) (xy 388.12897 -401.723737)
			(xy 387.000951 -401.723737) (xy 386.972053 -401.779212) (xy 386.933967 -401.834847) (xy 386.912104 -401.860512)
			(xy 386.90632 -401.867666) (xy 386.899798 -401.88485) (xy 386.899404 -401.89404) (xy 386.899404 -402.386292)
			(xy 386.899817 -402.395479) (xy 386.906329 -402.412663) (xy 386.912104 -402.41982) (xy 386.933921 -402.445524)
			(xy 386.972011 -402.501153) (xy 387.003163 -402.560944) (xy 387.02693 -402.624036) (xy 387.042968 -402.68952)
			(xy 387.051048 -402.756454) (xy 387.051052 -402.823818) (xy 390.329113 -402.823818) (xy 390.329117 -402.75651)
			(xy 390.337166 -402.689685) (xy 390.353142 -402.6243) (xy 390.376819 -402.561294) (xy 390.407855 -402.501569)
			(xy 390.445807 -402.445981) (xy 390.467596 -402.420328) (xy 390.473405 -402.413192) (xy 390.479912 -402.395994)
			(xy 390.480296 -402.3868) (xy 390.480296 -401.893532) (xy 390.479871 -401.884346) (xy 390.473368 -401.867162)
			(xy 390.467596 -401.860004) (xy 390.44579 -401.834367) (xy 390.407845 -401.778778) (xy 390.376815 -401.719052)
			(xy 390.353145 -401.656045) (xy 390.337174 -401.590661) (xy 390.329133 -401.523838) (xy 390.329134 -401.456532)
			(xy 390.33718 -401.389709) (xy 390.353154 -401.324326) (xy 390.376827 -401.261321) (xy 390.40786 -401.201596)
			(xy 390.445808 -401.146009) (xy 390.467596 -401.120356) (xy 390.473393 -401.113211) (xy 390.479908 -401.09602)
			(xy 390.480296 -401.086828) (xy 390.480296 -400.92884) (xy 390.480754 -400.918689) (xy 390.488536 -400.899938)
			(xy 390.502922 -400.885614) (xy 390.521705 -400.877912) (xy 390.531858 -400.877532) (xy 391.248138 -400.877532)
			(xy 391.258266 -400.877995) (xy 391.276987 -400.885734) (xy 391.291341 -400.900027) (xy 391.299161 -400.918714)
			(xy 391.2997 -400.92884) (xy 391.2997 -401.086828) (xy 391.300096 -401.096017) (xy 391.30662 -401.113201)
			(xy 391.3124 -401.120356) (xy 391.334167 -401.146025) (xy 391.372114 -401.20161) (xy 391.403146 -401.261331)
			(xy 391.426818 -401.324334) (xy 391.442791 -401.389713) (xy 391.450836 -401.456534) (xy 391.450838 -401.523836)
			(xy 391.442797 -401.590657) (xy 391.426827 -401.656038) (xy 391.403158 -401.719041) (xy 391.372129 -401.778764)
			(xy 391.334185 -401.834351) (xy 391.3124 -401.860004) (xy 391.306619 -401.86716) (xy 391.300095 -401.884342)
			(xy 391.2997 -401.893532) (xy 391.2997 -402.3868) (xy 391.30011 -402.395987) (xy 391.306624 -402.413171)
			(xy 391.3124 -402.420328) (xy 391.334139 -402.446019) (xy 391.372087 -402.501601) (xy 391.40312 -402.56132)
			(xy 391.426794 -402.624319) (xy 391.442769 -402.689696) (xy 391.450817 -402.756514) (xy 391.450821 -402.823814)
			(xy 391.442782 -402.890633) (xy 391.426815 -402.956012) (xy 391.40315 -403.019014) (xy 391.372124 -403.078737)
			(xy 391.334184 -403.134323) (xy 391.3124 -403.159976) (xy 391.306589 -403.167111) (xy 391.300083 -403.184309)
			(xy 391.2997 -403.193504) (xy 391.2997 -403.351492) (xy 391.299272 -403.361646) (xy 391.291479 -403.380398)
			(xy 391.277084 -403.394721) (xy 391.258294 -403.402421) (xy 391.248138 -403.4028) (xy 390.531858 -403.4028)
			(xy 390.521734 -403.402309) (xy 390.503019 -403.394575) (xy 390.488666 -403.380291) (xy 390.480841 -403.361614)
			(xy 390.480296 -403.351492) (xy 390.480296 -403.193504) (xy 390.479885 -403.184317) (xy 390.473372 -403.167133)
			(xy 390.467596 -403.159976) (xy 390.445763 -403.134362) (xy 390.407818 -403.078769) (xy 390.376789 -403.01904)
			(xy 390.353121 -402.95603) (xy 390.337153 -402.890644) (xy 390.329113 -402.823818) (xy 387.051052 -402.823818)
			(xy 387.051052 -402.823874) (xy 387.042981 -402.890809) (xy 387.026951 -402.956295) (xy 387.003193 -403.01939)
			(xy 386.972048 -403.079185) (xy 386.933965 -403.134819) (xy 386.912104 -403.160484) (xy 386.90629 -403.167617)
			(xy 386.899785 -403.184817) (xy 386.899404 -403.194012) (xy 386.899404 -403.351492) (xy 386.898978 -403.361613)
			(xy 386.891233 -403.380316) (xy 386.87692 -403.394631) (xy 386.858217 -403.402377) (xy 386.848096 -403.4028)
			(xy 386.131816 -403.4028) (xy 386.121695 -403.402371) (xy 386.102991 -403.394628) (xy 386.088676 -403.380315)
			(xy 386.080931 -403.361613) (xy 386.080508 -403.351492) (xy 386.080508 -403.194012) (xy 386.08009 -403.184826)
			(xy 386.073582 -403.167641) (xy 386.067808 -403.160484) (xy 386.045897 -403.134858) (xy 386.007809 -403.079218)
			(xy 385.97666 -403.019416) (xy 385.952898 -402.956314) (xy 385.936865 -402.89082) (xy 385.928793 -402.823878)
			(xy 382.650749 -402.823878) (xy 382.642717 -402.890635) (xy 382.626748 -402.956015) (xy 382.603078 -403.019018)
			(xy 382.572048 -403.07874) (xy 382.534102 -403.134324) (xy 382.512316 -403.159976) (xy 382.506507 -403.167112)
			(xy 382.499999 -403.18431) (xy 382.499616 -403.193504) (xy 382.499616 -403.351492) (xy 382.499172 -403.361644)
			(xy 382.491382 -403.380393) (xy 382.476993 -403.394716) (xy 382.458207 -403.402419) (xy 382.448054 -403.4028)
			(xy 381.731774 -403.4028) (xy 381.721651 -403.402296) (xy 381.702936 -403.394567) (xy 381.688582 -403.380287)
			(xy 381.680757 -403.361613) (xy 381.680212 -403.351492) (xy 381.680212 -403.193504) (xy 381.679797 -403.184317)
			(xy 381.673286 -403.167133) (xy 381.667512 -403.159976) (xy 381.645678 -403.134362) (xy 381.607732 -403.07877)
			(xy 381.576703 -403.019041) (xy 381.553034 -402.956031) (xy 381.537065 -402.890644) (xy 381.529025 -402.823818)
			(xy 378.250965 -402.823818) (xy 378.250965 -402.823874) (xy 378.242894 -402.890808) (xy 378.226864 -402.956294)
			(xy 378.203106 -403.019389) (xy 378.171962 -403.079184) (xy 378.13388 -403.134818) (xy 378.11202 -403.160484)
			(xy 378.106208 -403.167618) (xy 378.099702 -403.184817) (xy 378.09932 -403.194012) (xy 378.09932 -403.351492)
			(xy 378.098809 -403.361598) (xy 378.091078 -403.380272) (xy 378.076789 -403.394566) (xy 378.058118 -403.402305)
			(xy 378.048012 -403.4028) (xy 377.331732 -403.4028) (xy 377.321612 -403.402358) (xy 377.302909 -403.39462)
			(xy 377.288593 -403.380312) (xy 377.280847 -403.361612) (xy 377.280424 -403.351492) (xy 377.280424 -403.194012)
			(xy 377.280002 -403.184826) (xy 377.273496 -403.167642) (xy 377.267724 -403.160484) (xy 377.245812 -403.134858)
			(xy 377.207723 -403.079218) (xy 377.176573 -403.019417) (xy 377.152811 -402.956315) (xy 377.136778 -402.890821)
			(xy 377.128705 -402.823878) (xy 365.789712 -402.823878) (xy 365.918019 -402.884132) (xy 366.100237 -402.97855)
			(xy 366.278633 -403.080005) (xy 366.452934 -403.188344) (xy 366.622876 -403.3034) (xy 366.788199 -403.425)
			(xy 366.948652 -403.552957) (xy 367.103991 -403.687076) (xy 367.253978 -403.827155) (xy 367.398386 -403.972979)
			(xy 367.536994 -404.124325) (xy 367.669592 -404.280965) (xy 367.795978 -404.442659) (xy 367.915958 -404.609161)
			(xy 368.029351 -404.780217) (xy 368.135984 -404.955567) (xy 368.235694 -405.134944) (xy 368.32833 -405.318074)
			(xy 368.41375 -405.50468) (xy 368.462689 -405.623649) (xy 374.929103 -405.623649) (xy 374.929104 -405.556342)
			(xy 374.937149 -405.489519) (xy 374.953124 -405.424136) (xy 374.976799 -405.361131) (xy 375.007835 -405.301407)
			(xy 375.045787 -405.245822) (xy 375.067576 -405.22017) (xy 375.073365 -405.213019) (xy 375.079885 -405.195833)
			(xy 375.080276 -405.186642) (xy 375.080276 -404.693374) (xy 375.079884 -404.684185) (xy 375.073358 -404.667)
			(xy 375.067576 -404.659846) (xy 375.045809 -404.634177) (xy 375.007857 -404.578593) (xy 374.976821 -404.518873)
			(xy 374.953145 -404.45587) (xy 374.937169 -404.39049) (xy 374.929123 -404.323669) (xy 374.929121 -404.256365)
			(xy 374.937164 -404.189543) (xy 374.953135 -404.124161) (xy 374.976807 -404.061158) (xy 375.00784 -404.001435)
			(xy 375.045789 -403.94585) (xy 375.067576 -403.920198) (xy 375.073353 -403.913039) (xy 375.07988 -403.895859)
			(xy 375.080276 -403.88667) (xy 375.080276 -403.728682) (xy 375.08065 -403.718505) (xy 375.088448 -403.699702)
			(xy 375.102849 -403.685317) (xy 375.12166 -403.677539) (xy 375.131838 -403.67712) (xy 375.848118 -403.67712)
			(xy 375.858275 -403.677618) (xy 375.877041 -403.685395) (xy 375.891405 -403.699759) (xy 375.899182 -403.718525)
			(xy 375.89968 -403.728682) (xy 375.89968 -403.88667) (xy 375.900109 -403.895855) (xy 375.90661 -403.913039)
			(xy 375.91238 -403.920198) (xy 375.934189 -403.945833) (xy 375.972136 -404.001422) (xy 376.003167 -404.061148)
			(xy 376.026838 -404.124155) (xy 376.042809 -404.189539) (xy 376.050851 -404.256363) (xy 376.050849 -404.32367)
			(xy 376.042803 -404.390494) (xy 376.026828 -404.455877) (xy 376.003154 -404.518882) (xy 375.972119 -404.578606)
			(xy 375.934169 -404.634194) (xy 375.91238 -404.659846) (xy 375.906579 -404.666988) (xy 375.900068 -404.684181)
			(xy 375.89968 -404.693374) (xy 375.89968 -405.186642) (xy 375.900074 -405.195831) (xy 375.9066 -405.213015)
			(xy 375.91238 -405.22017) (xy 375.934161 -405.245827) (xy 375.972109 -405.301413) (xy 376.003142 -405.361136)
			(xy 376.026814 -405.42414) (xy 376.042787 -405.489522) (xy 376.050831 -405.556343) (xy 376.050832 -405.623648)
			(xy 376.042788 -405.690469) (xy 376.026817 -405.755851) (xy 376.003145 -405.818855) (xy 375.972114 -405.878579)
			(xy 375.934167 -405.934166) (xy 375.91238 -405.959818) (xy 375.906591 -405.966968) (xy 375.900072 -405.984155)
			(xy 375.89968 -405.993346) (xy 375.89968 -406.151334) (xy 375.899195 -406.161492) (xy 375.891413 -406.180258)
			(xy 375.877045 -406.194622) (xy 375.858276 -406.202398) (xy 375.848118 -406.202896) (xy 375.131838 -406.202896)
			(xy 375.121673 -406.202406) (xy 375.102886 -406.19464) (xy 375.088501 -406.180275) (xy 375.080708 -406.161498)
			(xy 375.080276 -406.151334) (xy 375.080276 -405.993346) (xy 375.079849 -405.984161) (xy 375.073347 -405.966976)
			(xy 375.067576 -405.959818) (xy 375.045781 -405.934171) (xy 375.00783 -405.878585) (xy 374.976795 -405.818861)
			(xy 374.953121 -405.755856) (xy 374.937148 -405.690472) (xy 374.929103 -405.623649) (xy 368.462689 -405.623649)
			(xy 368.491824 -405.694476) (xy 368.562434 -405.887174) (xy 368.625471 -406.08248) (xy 368.680841 -406.280096)
			(xy 368.728458 -406.479723) (xy 368.76825 -406.681055) (xy 368.774976 -406.723789) (xy 377.128717 -406.723789)
			(xy 377.12872 -406.656363) (xy 377.136799 -406.589422) (xy 377.152839 -406.523931) (xy 377.176607 -406.460832)
			(xy 377.207763 -406.401035) (xy 377.245857 -406.345401) (xy 377.267724 -406.319736) (xy 377.273533 -406.3126)
			(xy 377.280039 -406.295402) (xy 377.280424 -406.286208) (xy 377.280424 -405.793956) (xy 377.28003 -405.784767)
			(xy 377.273504 -405.767583) (xy 377.267724 -405.760428) (xy 377.245855 -405.734766) (xy 377.207765 -405.679132)
			(xy 377.176613 -405.619335) (xy 377.152848 -405.556238) (xy 377.136812 -405.490748) (xy 377.128736 -405.423809)
			(xy 377.128737 -405.356385) (xy 377.136813 -405.289446) (xy 377.15285 -405.223956) (xy 377.176616 -405.160859)
			(xy 377.207768 -405.101063) (xy 377.245859 -405.045429) (xy 377.267724 -405.019764) (xy 377.273521 -405.012619)
			(xy 377.280035 -404.995428) (xy 377.280424 -404.986236) (xy 377.280424 -404.828756) (xy 377.28085 -404.818641)
			(xy 377.288606 -404.799958) (xy 377.302922 -404.785664) (xy 377.321617 -404.777935) (xy 377.331732 -404.777448)
			(xy 378.048012 -404.777448) (xy 378.058115 -404.777974) (xy 378.076783 -404.785706) (xy 378.091076 -404.79999)
			(xy 378.098819 -404.818653) (xy 378.09932 -404.828756) (xy 378.09932 -404.986236) (xy 378.099709 -404.995426)
			(xy 378.106237 -405.01261) (xy 378.11202 -405.019764) (xy 378.133879 -405.045433) (xy 378.171967 -405.101067)
			(xy 378.203117 -405.160863) (xy 378.22688 -405.22396) (xy 378.242915 -405.289448) (xy 378.250991 -405.356386)
			(xy 378.250992 -405.423808) (xy 378.242916 -405.490746) (xy 378.226882 -405.556235) (xy 378.203119 -405.619331)
			(xy 378.200839 -405.623707) (xy 379.328896 -405.623707) (xy 379.328896 -405.556284) (xy 379.336972 -405.489346)
			(xy 379.353008 -405.423856) (xy 379.376771 -405.360759) (xy 379.407921 -405.300963) (xy 379.446009 -405.245328)
			(xy 379.467872 -405.219662) (xy 379.473676 -405.212522) (xy 379.480184 -405.195327) (xy 379.480572 -405.186134)
			(xy 379.480572 -404.693882) (xy 379.480177 -404.684693) (xy 379.473653 -404.667509) (xy 379.467872 -404.660354)
			(xy 379.446031 -404.63467) (xy 379.407943 -404.579038) (xy 379.376793 -404.519244) (xy 379.353029 -404.45615)
			(xy 379.336993 -404.390663) (xy 379.328915 -404.323727) (xy 379.328913 -404.256306) (xy 379.336987 -404.18937)
			(xy 379.353019 -404.123882) (xy 379.376779 -404.060786) (xy 379.407926 -404.00099) (xy 379.44601 -403.945356)
			(xy 379.467872 -403.91969) (xy 379.473664 -403.912542) (xy 379.480179 -403.895353) (xy 379.480572 -403.886162)
			(xy 379.480572 -403.728682) (xy 379.481013 -403.71855) (xy 379.488752 -403.699822) (xy 379.503053 -403.685466)
			(xy 379.52175 -403.677653) (xy 379.53188 -403.67712) (xy 380.24816 -403.67712) (xy 380.258314 -403.677555)
			(xy 380.277069 -403.685341) (xy 380.291395 -403.699734) (xy 380.299092 -403.718526) (xy 380.299468 -403.728682)
			(xy 380.299468 -403.886162) (xy 380.299904 -403.895346) (xy 380.306401 -403.91253) (xy 380.312168 -403.91969)
			(xy 380.334055 -403.945337) (xy 380.372145 -404.000973) (xy 380.403296 -404.060772) (xy 380.427061 -404.123871)
			(xy 380.443096 -404.189363) (xy 380.45117 -404.256303) (xy 380.451168 -404.32373) (xy 380.44309 -404.39067)
			(xy 380.427051 -404.456161) (xy 380.403283 -404.519259) (xy 380.372128 -404.579055) (xy 380.334034 -404.634689)
			(xy 380.312168 -404.660354) (xy 380.306362 -404.667492) (xy 380.299854 -404.684688) (xy 380.299468 -404.693882)
			(xy 380.299468 -405.186134) (xy 380.299869 -405.195322) (xy 380.30639 -405.212506) (xy 380.312168 -405.219662)
			(xy 380.334027 -405.245332) (xy 380.372118 -405.300965) (xy 380.403271 -405.36076) (xy 380.427037 -405.423856)
			(xy 380.443074 -405.489345) (xy 380.451151 -405.556284) (xy 380.451151 -405.623707) (xy 380.443075 -405.690646)
			(xy 380.42704 -405.756135) (xy 380.403275 -405.819232) (xy 380.372123 -405.879028) (xy 380.334033 -405.934661)
			(xy 380.312168 -405.960326) (xy 380.306374 -405.967473) (xy 380.299858 -405.984662) (xy 380.299468 -405.993854)
			(xy 380.299468 -406.151334) (xy 380.299002 -406.161462) (xy 380.291264 -406.180182) (xy 380.276972 -406.194537)
			(xy 380.258286 -406.202357) (xy 380.24816 -406.202896) (xy 379.53188 -406.202896) (xy 379.521724 -406.202495)
			(xy 379.50297 -406.194692) (xy 379.488648 -406.180289) (xy 379.480949 -406.161492) (xy 379.480572 -406.151334)
			(xy 379.480572 -405.993854) (xy 379.480142 -405.984669) (xy 379.473643 -405.967484) (xy 379.467872 -405.960326)
			(xy 379.446003 -405.934665) (xy 379.407916 -405.879029) (xy 379.376768 -405.819232) (xy 379.353005 -405.756135)
			(xy 379.336971 -405.690646) (xy 379.328896 -405.623707) (xy 378.200839 -405.623707) (xy 378.17197 -405.679128)
			(xy 378.133883 -405.734762) (xy 378.11202 -405.760428) (xy 378.106231 -405.767579) (xy 378.099711 -405.784765)
			(xy 378.09932 -405.793956) (xy 378.09932 -406.286208) (xy 378.099722 -406.295396) (xy 378.106241 -406.312581)
			(xy 378.11202 -406.319736) (xy 378.133852 -406.345428) (xy 378.17194 -406.401059) (xy 378.203091 -406.460852)
			(xy 378.226856 -406.523945) (xy 378.242893 -406.589431) (xy 378.250971 -406.656366) (xy 378.250974 -406.723729)
			(xy 381.529036 -406.723729) (xy 381.529039 -406.656422) (xy 381.537086 -406.589598) (xy 381.553062 -406.524214)
			(xy 381.576737 -406.461209) (xy 381.607772 -406.401484) (xy 381.645723 -406.345897) (xy 381.667512 -406.320244)
			(xy 381.673316 -406.313104) (xy 381.679826 -406.29591) (xy 381.680212 -406.286716) (xy 381.680212 -405.793448)
			(xy 381.679776 -405.784264) (xy 381.67328 -405.767079) (xy 381.667512 -405.75992) (xy 381.645721 -405.734271)
			(xy 381.607774 -405.678683) (xy 381.576743 -405.618959) (xy 381.553071 -405.555954) (xy 381.537099 -405.490572)
			(xy 381.529056 -405.423749) (xy 381.529056 -405.356445) (xy 381.5371 -405.289622) (xy 381.553073 -405.22424)
			(xy 381.576745 -405.161235) (xy 381.607777 -405.101512) (xy 381.645725 -405.045924) (xy 381.667512 -405.020272)
			(xy 381.673304 -405.013124) (xy 381.679821 -404.995936) (xy 381.680212 -404.986744) (xy 381.680212 -404.828756)
			(xy 381.680586 -404.818598) (xy 381.688398 -404.799842) (xy 381.702809 -404.78552) (xy 381.721613 -404.777824)
			(xy 381.731774 -404.777448) (xy 382.448054 -404.777448) (xy 382.458179 -404.777965) (xy 382.4769 -404.785679)
			(xy 382.491258 -404.799956) (xy 382.499078 -404.818634) (xy 382.499616 -404.828756) (xy 382.499616 -404.986744)
			(xy 382.500001 -404.995934) (xy 382.506532 -405.013118) (xy 382.512316 -405.020272) (xy 382.534101 -405.045927)
			(xy 382.572053 -405.101512) (xy 382.603089 -405.161235) (xy 382.626764 -405.224239) (xy 382.642738 -405.289621)
			(xy 382.650784 -405.356444) (xy 382.650784 -405.42375) (xy 382.64274 -405.490573) (xy 382.626766 -405.555955)
			(xy 382.603091 -405.61896) (xy 382.600655 -405.623648) (xy 383.729191 -405.623648) (xy 383.729192 -405.556343)
			(xy 383.737237 -405.489519) (xy 383.753211 -405.424136) (xy 383.776885 -405.361132) (xy 383.807921 -405.301408)
			(xy 383.845871 -405.245822) (xy 383.86766 -405.22017) (xy 383.873459 -405.213027) (xy 383.879971 -405.195835)
			(xy 383.88036 -405.186642) (xy 383.88036 -404.693374) (xy 383.879949 -404.684187) (xy 383.873434 -404.667004)
			(xy 383.86766 -404.659846) (xy 383.845893 -404.634176) (xy 383.807943 -404.578593) (xy 383.776907 -404.518872)
			(xy 383.753232 -404.45587) (xy 383.737257 -404.390489) (xy 383.729211 -404.323668) (xy 383.729209 -404.256365)
			(xy 383.737251 -404.189543) (xy 383.753222 -404.124162) (xy 383.776894 -404.061158) (xy 383.807926 -404.001436)
			(xy 383.845873 -403.94585) (xy 383.86766 -403.920198) (xy 383.873447 -403.913047) (xy 383.879966 -403.895861)
			(xy 383.88036 -403.88667) (xy 383.88036 -403.728682) (xy 383.88075 -403.718507) (xy 383.888545 -403.699707)
			(xy 383.902941 -403.685322) (xy 383.921746 -403.677542) (xy 383.931922 -403.67712) (xy 384.648202 -403.67712)
			(xy 384.658358 -403.677631) (xy 384.677123 -403.685403) (xy 384.691488 -403.699763) (xy 384.699265 -403.718526)
			(xy 384.699764 -403.728682) (xy 384.699764 -403.88667) (xy 384.700197 -403.895855) (xy 384.706696 -403.913039)
			(xy 384.712464 -403.920198) (xy 384.734273 -403.945832) (xy 384.772221 -404.001421) (xy 384.803254 -404.061147)
			(xy 384.826925 -404.124154) (xy 384.842896 -404.189539) (xy 384.850939 -404.256363) (xy 384.850937 -404.32367)
			(xy 384.84289 -404.390494) (xy 384.826915 -404.455877) (xy 384.80324 -404.518883) (xy 384.772204 -404.578607)
			(xy 384.734253 -404.634194) (xy 384.712464 -404.659846) (xy 384.706661 -404.666986) (xy 384.700151 -404.684181)
			(xy 384.699764 -404.693374) (xy 384.699764 -405.186642) (xy 384.700162 -405.19583) (xy 384.706685 -405.213014)
			(xy 384.712464 -405.22017) (xy 384.734246 -405.245827) (xy 384.772195 -405.301413) (xy 384.803228 -405.361136)
			(xy 384.826901 -405.42414) (xy 384.842874 -405.489521) (xy 384.850919 -405.556343) (xy 384.850919 -405.623648)
			(xy 384.842876 -405.69047) (xy 384.826904 -405.755852) (xy 384.803232 -405.818856) (xy 384.772199 -405.878579)
			(xy 384.734251 -405.934166) (xy 384.712464 -405.959818) (xy 384.706673 -405.966967) (xy 384.700156 -405.984155)
			(xy 384.699764 -405.993346) (xy 384.699764 -406.151334) (xy 384.699295 -406.161494) (xy 384.691509 -406.180263)
			(xy 384.677136 -406.194627) (xy 384.658362 -406.202401) (xy 384.648202 -406.202896) (xy 383.931922 -406.202896)
			(xy 383.92177 -406.20235) (xy 383.903008 -406.194589) (xy 383.888643 -406.180239) (xy 383.880861 -406.161486)
			(xy 383.88036 -406.151334) (xy 383.88036 -405.993346) (xy 383.879914 -405.984163) (xy 383.873424 -405.966979)
			(xy 383.86766 -405.959818) (xy 383.845866 -405.934171) (xy 383.807916 -405.878584) (xy 383.776882 -405.81886)
			(xy 383.753208 -405.755855) (xy 383.737235 -405.690472) (xy 383.729191 -405.623648) (xy 382.600655 -405.623648)
			(xy 382.572056 -405.678683) (xy 382.534105 -405.734268) (xy 382.512316 -405.75992) (xy 382.50653 -405.767073)
			(xy 382.500009 -405.784257) (xy 382.499616 -405.793448) (xy 382.499616 -406.286716) (xy 382.500015 -406.295904)
			(xy 382.506536 -406.313089) (xy 382.512316 -406.320244) (xy 382.534074 -406.345921) (xy 382.572026 -406.401503)
			(xy 382.603063 -406.461223) (xy 382.62674 -406.524224) (xy 382.642717 -406.589604) (xy 382.650764 -406.656424)
			(xy 382.650767 -406.723728) (xy 382.65076 -406.723789) (xy 385.928805 -406.723789) (xy 385.928807 -406.656363)
			(xy 385.936887 -406.589422) (xy 385.952926 -406.523931) (xy 385.976694 -406.460833) (xy 386.007849 -406.401036)
			(xy 386.045942 -406.345401) (xy 386.067808 -406.319736) (xy 386.073615 -406.312598) (xy 386.080123 -406.295402)
			(xy 386.080508 -406.286208) (xy 386.080508 -405.793956) (xy 386.080117 -405.784767) (xy 386.07359 -405.767583)
			(xy 386.067808 -405.760428) (xy 386.04594 -405.734766) (xy 386.007851 -405.679131) (xy 385.9767 -405.619335)
			(xy 385.952935 -405.556237) (xy 385.9369 -405.490748) (xy 385.928824 -405.423809) (xy 385.928825 -405.356385)
			(xy 385.936901 -405.289446) (xy 385.952937 -405.223957) (xy 385.976702 -405.16086) (xy 386.007854 -405.101064)
			(xy 386.045944 -405.045429) (xy 386.067808 -405.019764) (xy 386.073603 -405.012618) (xy 386.080118 -404.995428)
			(xy 386.080508 -404.986236) (xy 386.080508 -404.828756) (xy 386.080949 -404.818643) (xy 386.088703 -404.799963)
			(xy 386.103013 -404.785669) (xy 386.121703 -404.777938) (xy 386.131816 -404.777448) (xy 386.848096 -404.777448)
			(xy 386.858198 -404.777987) (xy 386.876866 -404.785714) (xy 386.891159 -404.799993) (xy 386.898903 -404.818654)
			(xy 386.899404 -404.828756) (xy 386.899404 -404.986236) (xy 386.899796 -404.995425) (xy 386.906322 -405.012609)
			(xy 386.912104 -405.019764) (xy 386.933964 -405.045433) (xy 386.972052 -405.101067) (xy 387.003203 -405.160862)
			(xy 387.026967 -405.223959) (xy 387.043003 -405.289448) (xy 387.051079 -405.356385) (xy 387.051079 -405.423809)
			(xy 387.043004 -405.490747) (xy 387.026969 -405.556235) (xy 387.003206 -405.619332) (xy 387.000958 -405.623648)
			(xy 388.128982 -405.623648) (xy 388.128982 -405.556343) (xy 388.137027 -405.489519) (xy 388.153001 -405.424137)
			(xy 388.176675 -405.361132) (xy 388.207709 -405.301408) (xy 388.245659 -405.245822) (xy 388.267448 -405.22017)
			(xy 388.273246 -405.213026) (xy 388.279758 -405.195834) (xy 388.280148 -405.186642) (xy 388.280148 -404.693374)
			(xy 388.27974 -404.684187) (xy 388.273223 -404.667003) (xy 388.267448 -404.659846) (xy 388.245682 -404.634176)
			(xy 388.207732 -404.578592) (xy 388.176697 -404.518871) (xy 388.153023 -404.455869) (xy 388.137048 -404.390489)
			(xy 388.129002 -404.323668) (xy 388.129 -404.256365) (xy 388.137042 -404.189544) (xy 388.153013 -404.124163)
			(xy 388.176684 -404.061159) (xy 388.207715 -404.001436) (xy 388.245662 -403.94585) (xy 388.267448 -403.920198)
			(xy 388.273234 -403.913045) (xy 388.279754 -403.89586) (xy 388.280148 -403.88667) (xy 388.280148 -403.728682)
			(xy 388.280619 -403.718522) (xy 388.288401 -403.69975) (xy 388.302774 -403.685385) (xy 388.32155 -403.677613)
			(xy 388.33171 -403.67712) (xy 389.04799 -403.67712) (xy 389.058145 -403.677641) (xy 389.07691 -403.685409)
			(xy 389.091275 -403.699766) (xy 389.099053 -403.718527) (xy 389.099552 -403.728682) (xy 389.099552 -403.88667)
			(xy 389.099987 -403.895854) (xy 389.106485 -403.913038) (xy 389.112252 -403.920198) (xy 389.134062 -403.945832)
			(xy 389.172011 -404.001421) (xy 389.203043 -404.061147) (xy 389.226715 -404.124154) (xy 389.242687 -404.189538)
			(xy 389.25073 -404.256363) (xy 389.250728 -404.32367) (xy 389.242681 -404.390494) (xy 389.226706 -404.455878)
			(xy 389.20303 -404.518883) (xy 389.171994 -404.578608) (xy 389.134041 -404.634194) (xy 389.112252 -404.659846)
			(xy 389.106447 -404.666985) (xy 389.099939 -404.684181) (xy 389.099552 -404.693374) (xy 389.099552 -405.186642)
			(xy 389.099953 -405.19583) (xy 389.106474 -405.213014) (xy 389.112252 -405.22017) (xy 389.134034 -405.245827)
			(xy 389.171983 -405.301413) (xy 389.203017 -405.361135) (xy 389.226691 -405.424139) (xy 389.242665 -405.489521)
			(xy 389.250709 -405.556343) (xy 389.25071 -405.623648) (xy 389.242666 -405.69047) (xy 389.226694 -405.755852)
			(xy 389.203021 -405.818856) (xy 389.171988 -405.87858) (xy 389.134039 -405.934166) (xy 389.112252 -405.959818)
			(xy 389.106459 -405.966966) (xy 389.099944 -405.984154) (xy 389.099552 -405.993346) (xy 389.099552 -406.151334)
			(xy 389.099094 -406.161495) (xy 389.091307 -406.180267) (xy 389.07693 -406.194631) (xy 389.058152 -406.202403)
			(xy 389.04799 -406.202896) (xy 388.33171 -406.202896) (xy 388.321557 -406.202359) (xy 388.302795 -406.194594)
			(xy 388.28843 -406.180242) (xy 388.280649 -406.161487) (xy 388.280148 -406.151334) (xy 388.280148 -405.993346)
			(xy 388.279705 -405.984163) (xy 388.273213 -405.966979) (xy 388.267448 -405.959818) (xy 388.245654 -405.934171)
			(xy 388.207705 -405.878584) (xy 388.176671 -405.81886) (xy 388.152998 -405.755855) (xy 388.137025 -405.690472)
			(xy 388.128982 -405.623648) (xy 387.000958 -405.623648) (xy 386.972056 -405.679128) (xy 386.933968 -405.734763)
			(xy 386.912104 -405.760428) (xy 386.906314 -405.767578) (xy 386.899795 -405.784765) (xy 386.899404 -405.793956)
			(xy 386.899404 -406.286208) (xy 386.89981 -406.295396) (xy 386.906326 -406.31258) (xy 386.912104 -406.319736)
			(xy 386.933936 -406.345427) (xy 386.972026 -406.401058) (xy 387.003178 -406.460851) (xy 387.026943 -406.523944)
			(xy 387.042981 -406.58943) (xy 387.051059 -406.656365) (xy 387.051062 -406.723729) (xy 390.329124 -406.723729)
			(xy 390.329127 -406.656423) (xy 390.337174 -406.589599) (xy 390.353149 -406.524215) (xy 390.376823 -406.461209)
			(xy 390.407858 -406.401485) (xy 390.445808 -406.345897) (xy 390.467596 -406.320244) (xy 390.473398 -406.313103)
			(xy 390.47991 -406.295909) (xy 390.480296 -406.286716) (xy 390.480296 -405.793448) (xy 390.479864 -405.784263)
			(xy 390.473366 -405.767078) (xy 390.467596 -405.75992) (xy 390.445806 -405.73427) (xy 390.40786 -405.678683)
			(xy 390.376829 -405.618958) (xy 390.353158 -405.555954) (xy 390.337187 -405.490571) (xy 390.329144 -405.423749)
			(xy 390.329144 -405.356445) (xy 390.337188 -405.289623) (xy 390.35316 -405.224241) (xy 390.376832 -405.161236)
			(xy 390.407863 -405.101512) (xy 390.445809 -405.045925) (xy 390.467596 -405.020272) (xy 390.473386 -405.013122)
			(xy 390.479905 -404.995935) (xy 390.480296 -404.986744) (xy 390.480296 -404.828756) (xy 390.480686 -404.8186)
			(xy 390.488495 -404.799847) (xy 390.502901 -404.785525) (xy 390.521699 -404.777826) (xy 390.531858 -404.777448)
			(xy 391.248138 -404.777448) (xy 391.258268 -404.777896) (xy 391.276992 -404.785637) (xy 391.291347 -404.799935)
			(xy 391.299163 -404.818628) (xy 391.2997 -404.828756) (xy 391.2997 -404.986744) (xy 391.300089 -404.995933)
			(xy 391.306617 -405.013118) (xy 391.3124 -405.020272) (xy 391.334183 -405.045928) (xy 391.372129 -405.101515)
			(xy 391.40316 -405.161238) (xy 391.426832 -405.224242) (xy 391.442804 -405.289623) (xy 391.450848 -405.356445)
			(xy 391.450848 -405.423749) (xy 391.442805 -405.490571) (xy 391.426833 -405.555952) (xy 391.403163 -405.618956)
			(xy 391.372132 -405.67868) (xy 391.334186 -405.734267) (xy 391.3124 -405.75992) (xy 391.306612 -405.767072)
			(xy 391.300092 -405.784257) (xy 391.2997 -405.793448) (xy 391.2997 -406.286716) (xy 391.300103 -406.295904)
			(xy 391.306622 -406.313088) (xy 391.3124 -406.320244) (xy 391.334155 -406.345923) (xy 391.372102 -406.401506)
			(xy 391.403135 -406.461226) (xy 391.426808 -406.524227) (xy 391.442782 -406.589606) (xy 391.450828 -406.656425)
			(xy 391.450831 -406.723727) (xy 391.44279 -406.790547) (xy 391.426822 -406.855927) (xy 391.403154 -406.91893)
			(xy 391.372127 -406.978653) (xy 391.334185 -407.034239) (xy 391.3124 -407.059892) (xy 391.306624 -407.067052)
			(xy 391.300097 -407.084231) (xy 391.2997 -407.09342) (xy 391.2997 -407.251408) (xy 391.299285 -407.261563)
			(xy 391.291487 -407.280315) (xy 391.277088 -407.294638) (xy 391.258295 -407.302338) (xy 391.248138 -407.302716)
			(xy 390.531858 -407.302716) (xy 390.521723 -407.302307) (xy 390.502993 -407.294557) (xy 390.488636 -407.280247)
			(xy 390.480826 -407.261541) (xy 390.480296 -407.251408) (xy 390.480296 -407.09342) (xy 390.479877 -407.084234)
			(xy 390.47337 -407.067049) (xy 390.467596 -407.059892) (xy 390.445778 -407.034265) (xy 390.407833 -406.978674)
			(xy 390.376804 -406.918947) (xy 390.353135 -406.855939) (xy 390.337165 -406.790554) (xy 390.329124 -406.723729)
			(xy 387.051062 -406.723729) (xy 387.051062 -406.723787) (xy 387.04299 -406.790723) (xy 387.026958 -406.85621)
			(xy 387.003197 -406.919305) (xy 386.972051 -406.979101) (xy 386.933966 -407.034735) (xy 386.912104 -407.0604)
			(xy 386.906325 -407.067558) (xy 386.8998 -407.084739) (xy 386.899404 -407.093928) (xy 386.899404 -407.251408)
			(xy 386.898921 -407.261517) (xy 386.891182 -407.280194) (xy 386.876884 -407.294489) (xy 386.858205 -407.302224)
			(xy 386.848096 -407.302716) (xy 386.131816 -407.302716) (xy 386.121697 -407.302271) (xy 386.102996 -407.294531)
			(xy 386.088682 -407.280224) (xy 386.080933 -407.261527) (xy 386.080508 -407.251408) (xy 386.080508 -407.093928)
			(xy 386.080083 -407.084742) (xy 386.073579 -407.067558) (xy 386.067808 -407.0604) (xy 386.045912 -407.034761)
			(xy 386.007824 -406.979123) (xy 385.976674 -406.919323) (xy 385.952912 -406.856223) (xy 385.936878 -406.79073)
			(xy 385.928805 -406.723789) (xy 382.65076 -406.723789) (xy 382.642725 -406.790549) (xy 382.626754 -406.85593)
			(xy 382.603083 -406.918933) (xy 382.572051 -406.978655) (xy 382.534103 -407.03424) (xy 382.512316 -407.059892)
			(xy 382.506542 -407.067053) (xy 382.500013 -407.084231) (xy 382.499616 -407.09342) (xy 382.499616 -407.251408)
			(xy 382.499185 -407.261561) (xy 382.49139 -407.28031) (xy 382.476996 -407.294632) (xy 382.458209 -407.302335)
			(xy 382.448054 -407.302716) (xy 381.731774 -407.302716) (xy 381.72164 -407.302294) (xy 381.70291 -407.294549)
			(xy 381.688553 -407.280243) (xy 381.680743 -407.26154) (xy 381.680212 -407.251408) (xy 381.680212 -407.09342)
			(xy 381.679789 -407.084234) (xy 381.673284 -407.06705) (xy 381.667512 -407.059892) (xy 381.645694 -407.034265)
			(xy 381.607748 -406.978675) (xy 381.576717 -406.918947) (xy 381.553047 -406.855939) (xy 381.537077 -406.790554)
			(xy 381.529036 -406.723729) (xy 378.250974 -406.723729) (xy 378.250974 -406.723786) (xy 378.242902 -406.790722)
			(xy 378.226871 -406.856209) (xy 378.203111 -406.919305) (xy 378.171965 -406.9791) (xy 378.133881 -407.034734)
			(xy 378.11202 -407.0604) (xy 378.106243 -407.067559) (xy 378.099716 -407.084739) (xy 378.09932 -407.093928)
			(xy 378.09932 -407.251408) (xy 378.098822 -407.261515) (xy 378.091085 -407.280189) (xy 378.076793 -407.294483)
			(xy 378.058119 -407.302221) (xy 378.048012 -407.302716) (xy 377.331732 -407.302716) (xy 377.321614 -407.302258)
			(xy 377.302914 -407.294524) (xy 377.288599 -407.28022) (xy 377.280849 -407.261526) (xy 377.280424 -407.251408)
			(xy 377.280424 -407.093928) (xy 377.279995 -407.084743) (xy 377.273494 -407.067559) (xy 377.267724 -407.0604)
			(xy 377.245828 -407.034761) (xy 377.207738 -406.979123) (xy 377.176588 -406.919324) (xy 377.152824 -406.856223)
			(xy 377.13679 -406.790731) (xy 377.128717 -406.723789) (xy 368.774976 -406.723789) (xy 368.800157 -406.883787)
			(xy 368.82413 -407.087609) (xy 368.840132 -407.292212) (xy 368.848139 -407.497282) (xy 368.84864 -407.599896)
			(xy 368.848139 -407.70251) (xy 368.840132 -407.90758) (xy 368.82413 -408.112183) (xy 368.800157 -408.316005)
			(xy 368.76825 -408.518737) (xy 368.728458 -408.720069) (xy 368.680841 -408.919696) (xy 368.625471 -409.117312)
			(xy 368.562434 -409.312618) (xy 368.491824 -409.505316) (xy 368.484209 -409.523827) (xy 374.929082 -409.523827)
			(xy 374.929085 -409.456519) (xy 374.937133 -409.389693) (xy 374.953111 -409.324308) (xy 374.97679 -409.261302)
			(xy 375.007829 -409.201578) (xy 375.045785 -409.145991) (xy 375.067576 -409.12034) (xy 375.073378 -409.113198)
			(xy 375.07989 -409.096005) (xy 375.080276 -409.086812) (xy 375.080276 -408.593544) (xy 375.07985 -408.584358)
			(xy 375.073348 -408.567174) (xy 375.067576 -408.560016) (xy 375.045779 -408.534371) (xy 375.007828 -408.478784)
			(xy 374.976793 -408.41906) (xy 374.953119 -408.356055) (xy 374.937146 -408.290671) (xy 374.929102 -408.223847)
			(xy 374.929103 -408.156541) (xy 374.937148 -408.089717) (xy 374.953123 -408.024334) (xy 374.976798 -407.961329)
			(xy 375.007835 -407.901605) (xy 375.045787 -407.84602) (xy 375.067576 -407.820368) (xy 375.073366 -407.813218)
			(xy 375.079885 -407.796031) (xy 375.080276 -407.78684) (xy 375.080276 -407.628852) (xy 375.080682 -407.618698)
			(xy 375.088489 -407.599949) (xy 375.10289 -407.585628) (xy 375.121682 -407.577926) (xy 375.131838 -407.577544)
			(xy 375.848118 -407.577544) (xy 375.858246 -407.578012) (xy 375.876969 -407.585746) (xy 375.891325 -407.600038)
			(xy 375.899143 -407.618726) (xy 375.89968 -407.628852) (xy 375.89968 -407.78684) (xy 375.900075 -407.796029)
			(xy 375.9066 -407.813213) (xy 375.91238 -407.820368) (xy 375.934159 -407.846027) (xy 375.972107 -407.901613)
			(xy 376.00314 -407.961336) (xy 376.026812 -408.024339) (xy 376.042785 -408.08972) (xy 376.05083 -408.156542)
			(xy 376.05083 -408.223846) (xy 376.042787 -408.290668) (xy 376.026816 -408.356049) (xy 376.003145 -408.419053)
			(xy 375.972113 -408.478777) (xy 375.934167 -408.534364) (xy 375.91238 -408.560016) (xy 375.906592 -408.567167)
			(xy 375.900073 -408.584353) (xy 375.89968 -408.593544) (xy 375.89968 -409.086812) (xy 375.900089 -409.095999)
			(xy 375.906604 -409.113183) (xy 375.91238 -409.12034) (xy 375.934131 -409.146022) (xy 375.97208 -409.201604)
			(xy 376.003114 -409.261324) (xy 376.026788 -409.324325) (xy 376.042763 -409.389703) (xy 376.050809 -409.456522)
			(xy 376.050813 -409.523824) (xy 376.042772 -409.590644) (xy 376.026804 -409.656024) (xy 376.003136 -409.719026)
			(xy 375.972108 -409.778749) (xy 375.934165 -409.834335) (xy 375.91238 -409.859988) (xy 375.906561 -409.867117)
			(xy 375.90006 -409.88432) (xy 375.89968 -409.893516) (xy 375.89968 -410.051504) (xy 375.899281 -410.061661)
			(xy 375.891481 -410.080417) (xy 375.877077 -410.094741) (xy 375.858277 -410.102437) (xy 375.848118 -410.102812)
			(xy 375.131838 -410.102812) (xy 375.12172 -410.102244) (xy 375.10301 -410.094538) (xy 375.088654 -410.080277)
			(xy 375.080824 -410.061618) (xy 375.080276 -410.051504) (xy 375.080276 -409.893516) (xy 375.079864 -409.884329)
			(xy 375.073352 -409.867144) (xy 375.067576 -409.859988) (xy 375.045751 -409.834366) (xy 375.007801 -409.778776)
			(xy 374.976768 -409.719048) (xy 374.953095 -409.65604) (xy 374.937124 -409.590654) (xy 374.929082 -409.523827)
			(xy 368.484209 -409.523827) (xy 368.41375 -409.695112) (xy 368.32833 -409.881718) (xy 368.235694 -410.064848)
			(xy 368.135984 -410.244225) (xy 368.029351 -410.419575) (xy 367.915958 -410.590631) (xy 367.892128 -410.623701)
			(xy 377.128728 -410.623701) (xy 377.128729 -410.556275) (xy 377.136807 -410.489335) (xy 377.152845 -410.423845)
			(xy 377.176612 -410.360748) (xy 377.207766 -410.300951) (xy 377.245858 -410.245317) (xy 377.267724 -410.219652)
			(xy 377.273526 -410.212511) (xy 377.280037 -410.195317) (xy 377.280424 -410.186124) (xy 377.280424 -409.693872)
			(xy 377.280022 -409.684684) (xy 377.273502 -409.6675) (xy 377.267724 -409.660344) (xy 377.245871 -409.634669)
			(xy 377.20778 -409.579037) (xy 377.176628 -409.519242) (xy 377.152862 -409.456146) (xy 377.136825 -409.390658)
			(xy 377.128748 -409.323721) (xy 377.128747 -409.256297) (xy 377.136822 -409.18936) (xy 377.152857 -409.123871)
			(xy 377.17662 -409.060774) (xy 377.207771 -409.000979) (xy 377.24586 -408.945345) (xy 377.267724 -408.91968)
			(xy 377.273514 -408.912531) (xy 377.280032 -408.895343) (xy 377.280424 -408.886152) (xy 377.280424 -408.728672)
			(xy 377.280794 -408.718545) (xy 377.288555 -408.699836) (xy 377.302886 -408.685522) (xy 377.321604 -408.677782)
			(xy 377.331732 -408.677364) (xy 378.048012 -408.677364) (xy 378.058117 -408.677875) (xy 378.076789 -408.685609)
			(xy 378.091082 -408.699898) (xy 378.098822 -408.718567) (xy 378.09932 -408.728672) (xy 378.09932 -408.886152)
			(xy 378.099749 -408.895337) (xy 378.106249 -408.912522) (xy 378.11202 -408.91968) (xy 378.133895 -408.945336)
			(xy 378.171982 -409.000972) (xy 378.203131 -409.06077) (xy 378.226894 -409.123868) (xy 378.242928 -409.189358)
			(xy 378.251002 -409.256297) (xy 378.251001 -409.323721) (xy 378.242925 -409.39066) (xy 378.226888 -409.456149)
			(xy 378.203124 -409.519247) (xy 378.200707 -409.523886) (xy 379.328875 -409.523886) (xy 379.328878 -409.45646)
			(xy 379.336957 -409.38952) (xy 379.352995 -409.324029) (xy 379.376762 -409.260931) (xy 379.407916 -409.201133)
			(xy 379.446007 -409.145498) (xy 379.467872 -409.119832) (xy 379.473689 -409.112701) (xy 379.480189 -409.095499)
			(xy 379.480572 -409.086304) (xy 379.480572 -408.594052) (xy 379.480143 -408.584867) (xy 379.473643 -408.567682)
			(xy 379.467872 -408.560524) (xy 379.446001 -408.534865) (xy 379.407915 -408.479229) (xy 379.376766 -408.419431)
			(xy 379.353003 -408.356334) (xy 379.336969 -408.290844) (xy 379.328894 -408.223906) (xy 379.328895 -408.156482)
			(xy 379.336971 -408.089544) (xy 379.353007 -408.024055) (xy 379.376771 -407.960958) (xy 379.407921 -407.901161)
			(xy 379.446009 -407.845526) (xy 379.467872 -407.81986) (xy 379.473677 -407.812721) (xy 379.480185 -407.795525)
			(xy 379.480572 -407.786332) (xy 379.480572 -407.628852) (xy 379.481045 -407.618744) (xy 379.488793 -407.60007)
			(xy 379.503093 -407.585778) (xy 379.521771 -407.57804) (xy 379.53188 -407.577544) (xy 380.24816 -407.577544)
			(xy 380.258259 -407.578117) (xy 380.276926 -407.585831) (xy 380.29122 -407.6001) (xy 380.298966 -407.618754)
			(xy 380.299468 -407.628852) (xy 380.299468 -407.786332) (xy 380.29987 -407.79552) (xy 380.30639 -407.812704)
			(xy 380.312168 -407.81986) (xy 380.334025 -407.845531) (xy 380.372116 -407.901164) (xy 380.403269 -407.960959)
			(xy 380.427035 -408.024055) (xy 380.443072 -408.089544) (xy 380.451149 -408.156482) (xy 380.45115 -408.223906)
			(xy 380.443074 -408.290844) (xy 380.427039 -408.356333) (xy 380.403274 -408.41943) (xy 380.372122 -408.479226)
			(xy 380.334033 -408.534859) (xy 380.312168 -408.560524) (xy 380.306375 -408.567671) (xy 380.299859 -408.58486)
			(xy 380.299468 -408.594052) (xy 380.299468 -409.086304) (xy 380.299883 -409.09549) (xy 380.306394 -409.112675)
			(xy 380.312168 -409.119832) (xy 380.333998 -409.145526) (xy 380.37209 -409.201156) (xy 380.403244 -409.260947)
			(xy 380.427011 -409.324041) (xy 380.44305 -409.389527) (xy 380.451129 -409.456462) (xy 380.451133 -409.523884)
			(xy 380.44306 -409.59082) (xy 380.427027 -409.656308) (xy 380.403266 -409.719403) (xy 380.372117 -409.779198)
			(xy 380.334031 -409.834831) (xy 380.312168 -409.860496) (xy 380.306386 -409.867652) (xy 380.299864 -409.884834)
			(xy 380.299468 -409.894024) (xy 380.299468 -410.051504) (xy 380.299086 -410.061631) (xy 380.291331 -410.08034)
			(xy 380.277003 -410.094656) (xy 380.258287 -410.102395) (xy 380.24816 -410.102812) (xy 379.53188 -410.102812)
			(xy 379.521771 -410.102332) (xy 379.503095 -410.09459) (xy 379.488801 -410.080292) (xy 379.481065 -410.061613)
			(xy 379.480572 -410.051504) (xy 379.480572 -409.894024) (xy 379.480157 -409.884837) (xy 379.473647 -409.867652)
			(xy 379.467872 -409.860496) (xy 379.445974 -409.834859) (xy 379.407888 -409.77922) (xy 379.37674 -409.71942)
			(xy 379.352979 -409.656319) (xy 379.336947 -409.590827) (xy 379.328875 -409.523886) (xy 378.200707 -409.523886)
			(xy 378.171973 -409.579043) (xy 378.133884 -409.634678) (xy 378.11202 -409.660344) (xy 378.106225 -409.66749)
			(xy 378.099709 -409.68468) (xy 378.09932 -409.693872) (xy 378.09932 -410.186124) (xy 378.099714 -410.195313)
			(xy 378.106239 -410.212497) (xy 378.11202 -410.219652) (xy 378.133868 -410.245331) (xy 378.171955 -410.300964)
			(xy 378.203106 -410.360758) (xy 378.22687 -410.423853) (xy 378.242906 -410.48934) (xy 378.250983 -410.556277)
			(xy 378.250984 -410.623641) (xy 381.529047 -410.623641) (xy 381.529049 -410.556335) (xy 381.537094 -410.489512)
			(xy 381.553068 -410.424129) (xy 381.576742 -410.361124) (xy 381.607775 -410.3014) (xy 381.645724 -410.245812)
			(xy 381.667512 -410.22016) (xy 381.673309 -410.213015) (xy 381.679823 -410.195824) (xy 381.680212 -410.186632)
			(xy 381.680212 -409.693364) (xy 381.679817 -409.684175) (xy 381.673292 -409.666991) (xy 381.667512 -409.659836)
			(xy 381.645737 -409.634174) (xy 381.607789 -409.578588) (xy 381.576757 -409.518866) (xy 381.553085 -409.455863)
			(xy 381.537112 -409.390482) (xy 381.529067 -409.323661) (xy 381.529066 -409.256357) (xy 381.537109 -409.189536)
			(xy 381.553079 -409.124155) (xy 381.57675 -409.061151) (xy 381.60778 -409.001427) (xy 381.645726 -408.94584)
			(xy 381.667512 -408.920188) (xy 381.673298 -408.913035) (xy 381.679818 -408.89585) (xy 381.680212 -408.88666)
			(xy 381.680212 -408.728672) (xy 381.680599 -408.718515) (xy 381.688406 -408.699759) (xy 381.702813 -408.685436)
			(xy 381.721614 -408.67774) (xy 381.731774 -408.677364) (xy 382.448054 -408.677364) (xy 382.458181 -408.677865)
			(xy 382.476905 -408.685582) (xy 382.491264 -408.699865) (xy 382.499081 -408.718548) (xy 382.499616 -408.728672)
			(xy 382.499616 -408.88666) (xy 382.500042 -408.895846) (xy 382.506544 -408.91303) (xy 382.512316 -408.920188)
			(xy 382.534117 -408.94583) (xy 382.572068 -409.001417) (xy 382.603103 -409.061141) (xy 382.626778 -409.124147)
			(xy 382.642751 -409.189531) (xy 382.650795 -409.256356) (xy 382.650794 -409.323662) (xy 382.642748 -409.390487)
			(xy 382.626772 -409.45587) (xy 382.603096 -409.518875) (xy 382.600523 -409.523827) (xy 383.72917 -409.523827)
			(xy 383.729173 -409.456519) (xy 383.737221 -409.389693) (xy 383.753198 -409.324309) (xy 383.776876 -409.261303)
			(xy 383.807915 -409.201578) (xy 383.845869 -409.145992) (xy 383.86766 -409.12034) (xy 383.873472 -409.113206)
			(xy 383.879976 -409.096007) (xy 383.88036 -409.086812) (xy 383.88036 -408.593544) (xy 383.879915 -408.584361)
			(xy 383.873424 -408.567177) (xy 383.86766 -408.560016) (xy 383.845864 -408.53437) (xy 383.807914 -408.478784)
			(xy 383.77688 -408.419059) (xy 383.753207 -408.356054) (xy 383.737234 -408.290671) (xy 383.72919 -408.223847)
			(xy 383.729191 -408.156541) (xy 383.737236 -408.089717) (xy 383.75321 -408.024335) (xy 383.776885 -407.96133)
			(xy 383.80792 -407.901606) (xy 383.845871 -407.84602) (xy 383.86766 -407.820368) (xy 383.87346 -407.813226)
			(xy 383.879971 -407.796033) (xy 383.88036 -407.78684) (xy 383.88036 -407.628852) (xy 383.880782 -407.6187)
			(xy 383.888586 -407.599954) (xy 383.902981 -407.585634) (xy 383.921768 -407.577929) (xy 383.931922 -407.577544)
			(xy 384.648202 -407.577544) (xy 384.658329 -407.578025) (xy 384.677051 -407.585754) (xy 384.691408 -407.600042)
			(xy 384.699226 -407.618727) (xy 384.699764 -407.628852) (xy 384.699764 -407.78684) (xy 384.700163 -407.796028)
			(xy 384.706685 -407.813212) (xy 384.712464 -407.820368) (xy 384.734244 -407.846027) (xy 384.772193 -407.901612)
			(xy 384.803226 -407.961335) (xy 384.826899 -408.024339) (xy 384.842873 -408.08972) (xy 384.850918 -408.156542)
			(xy 384.850918 -408.223846) (xy 384.842875 -408.290668) (xy 384.826903 -408.35605) (xy 384.803231 -408.419054)
			(xy 384.772199 -408.478778) (xy 384.734251 -408.534364) (xy 384.712464 -408.560016) (xy 384.706674 -408.567165)
			(xy 384.700156 -408.584353) (xy 384.699764 -408.593544) (xy 384.699764 -409.086812) (xy 384.700176 -409.095999)
			(xy 384.706689 -409.113183) (xy 384.712464 -409.12034) (xy 384.734216 -409.146021) (xy 384.772166 -409.201604)
			(xy 384.8032 -409.261323) (xy 384.826875 -409.324324) (xy 384.84285 -409.389703) (xy 384.850897 -409.456522)
			(xy 384.850901 -409.523824) (xy 384.84286 -409.590644) (xy 384.826891 -409.656024) (xy 384.803222 -409.719027)
			(xy 384.772194 -409.77875) (xy 384.734249 -409.834336) (xy 384.712464 -409.859988) (xy 384.706643 -409.867116)
			(xy 384.700144 -409.88432) (xy 384.699764 -409.893516) (xy 384.699764 -410.051504) (xy 384.699381 -410.061663)
			(xy 384.691577 -410.080422) (xy 384.677168 -410.094747) (xy 384.658363 -410.10244) (xy 384.648202 -410.102812)
			(xy 383.931922 -410.102812) (xy 383.921803 -410.102257) (xy 383.903092 -410.094546) (xy 383.888737 -410.080281)
			(xy 383.880908 -410.06162) (xy 383.88036 -410.051504) (xy 383.88036 -409.893516) (xy 383.879929 -409.884331)
			(xy 383.873428 -409.867147) (xy 383.86766 -409.859988) (xy 383.845836 -409.834365) (xy 383.807887 -409.778775)
			(xy 383.776854 -409.719048) (xy 383.753182 -409.656039) (xy 383.737211 -409.590653) (xy 383.72917 -409.523827)
			(xy 382.600523 -409.523827) (xy 382.572059 -409.578599) (xy 382.534106 -409.634184) (xy 382.512316 -409.659836)
			(xy 382.506523 -409.666984) (xy 382.500006 -409.684172) (xy 382.499616 -409.693364) (xy 382.499616 -410.186632)
			(xy 382.500007 -410.195821) (xy 382.506534 -410.213006) (xy 382.512316 -410.22016) (xy 382.534089 -410.245824)
			(xy 382.572042 -410.301408) (xy 382.603078 -410.36113) (xy 382.626754 -410.424133) (xy 382.642729 -410.489514)
			(xy 382.650775 -410.556336) (xy 382.650777 -410.62364) (xy 382.65077 -410.623701) (xy 385.928816 -410.623701)
			(xy 385.928817 -410.556275) (xy 385.936895 -410.489336) (xy 385.952932 -410.423846) (xy 385.976699 -410.360748)
			(xy 386.007852 -410.300952) (xy 386.045943 -410.245317) (xy 386.067808 -410.219652) (xy 386.073608 -410.21251)
			(xy 386.080121 -410.195317) (xy 386.080508 -410.186124) (xy 386.080508 -409.693872) (xy 386.08011 -409.684684)
			(xy 386.073588 -409.667499) (xy 386.067808 -409.660344) (xy 386.045956 -409.634669) (xy 386.007866 -409.579036)
			(xy 385.976714 -409.519241) (xy 385.952949 -409.456146) (xy 385.936913 -409.390658) (xy 385.928836 -409.32372)
			(xy 385.928834 -409.256298) (xy 385.936909 -409.18936) (xy 385.952944 -409.123871) (xy 385.976707 -409.060775)
			(xy 386.007857 -409.000979) (xy 386.045944 -408.945345) (xy 386.067808 -408.91968) (xy 386.073596 -408.912529)
			(xy 386.080116 -408.895343) (xy 386.080508 -408.886152) (xy 386.080508 -408.728672) (xy 386.080962 -408.71856)
			(xy 386.088711 -408.69988) (xy 386.103017 -408.685586) (xy 386.121704 -408.677854) (xy 386.131816 -408.677364)
			(xy 386.848096 -408.677364) (xy 386.8582 -408.677888) (xy 386.876871 -408.685617) (xy 386.891165 -408.699902)
			(xy 386.898906 -408.718568) (xy 386.899404 -408.728672) (xy 386.899404 -408.886152) (xy 386.899836 -408.895337)
			(xy 386.906334 -408.912522) (xy 386.912104 -408.91968) (xy 386.93398 -408.945336) (xy 386.972068 -409.000972)
			(xy 387.003218 -409.060769) (xy 387.026981 -409.123867) (xy 387.043016 -409.189357) (xy 387.05109 -409.256297)
			(xy 387.051089 -409.323721) (xy 387.043012 -409.39066) (xy 387.026976 -409.45615) (xy 387.00321 -409.519247)
			(xy 387.000824 -409.523827) (xy 388.128961 -409.523827) (xy 388.128964 -409.456519) (xy 388.137012 -409.389694)
			(xy 388.152989 -409.324309) (xy 388.176666 -409.261303) (xy 388.207704 -409.201579) (xy 388.245658 -409.145992)
			(xy 388.267448 -409.12034) (xy 388.273259 -409.113205) (xy 388.279764 -409.096006) (xy 388.280148 -409.086812)
			(xy 388.280148 -408.593544) (xy 388.279706 -408.58436) (xy 388.273213 -408.567176) (xy 388.267448 -408.560016)
			(xy 388.245652 -408.534371) (xy 388.207703 -408.478783) (xy 388.176669 -408.419059) (xy 388.152997 -408.356054)
			(xy 388.137024 -408.29067) (xy 388.12898 -408.223847) (xy 388.128981 -408.156541) (xy 388.137026 -408.089718)
			(xy 388.153 -408.024335) (xy 388.176674 -407.96133) (xy 388.207709 -407.901606) (xy 388.245659 -407.84602)
			(xy 388.267448 -407.820368) (xy 388.273247 -407.813224) (xy 388.279759 -407.796032) (xy 388.280148 -407.78684)
			(xy 388.280148 -407.628852) (xy 388.280581 -407.618701) (xy 388.288383 -407.599958) (xy 388.302775 -407.585638)
			(xy 388.321557 -407.577931) (xy 388.33171 -407.577544) (xy 389.04799 -407.577544) (xy 389.058117 -407.578035)
			(xy 389.076838 -407.58576) (xy 389.091195 -407.600045) (xy 389.099014 -407.618728) (xy 389.099552 -407.628852)
			(xy 389.099552 -407.78684) (xy 389.099954 -407.796028) (xy 389.106475 -407.813211) (xy 389.112252 -407.820368)
			(xy 389.134032 -407.846027) (xy 389.171982 -407.901612) (xy 389.203016 -407.961335) (xy 389.226689 -408.024338)
			(xy 389.242663 -408.08972) (xy 389.250708 -408.156542) (xy 389.250709 -408.223846) (xy 389.242665 -408.290668)
			(xy 389.226693 -408.35605) (xy 389.203021 -408.419054) (xy 389.171988 -408.478778) (xy 389.134039 -408.534364)
			(xy 389.112252 -408.560016) (xy 389.10646 -408.567164) (xy 389.099944 -408.584353) (xy 389.099552 -408.593544)
			(xy 389.099552 -409.086812) (xy 389.099967 -409.095998) (xy 389.106479 -409.113182) (xy 389.112252 -409.12034)
			(xy 389.134004 -409.146021) (xy 389.171955 -409.201603) (xy 389.20299 -409.261323) (xy 389.226665 -409.324323)
			(xy 389.242641 -409.389702) (xy 389.250688 -409.456522) (xy 389.250692 -409.523824) (xy 389.242651 -409.590644)
			(xy 389.226681 -409.656025) (xy 389.203012 -409.719028) (xy 389.171983 -409.77875) (xy 389.134038 -409.834336)
			(xy 389.112252 -409.859988) (xy 389.10643 -409.867115) (xy 389.099932 -409.88432) (xy 389.099552 -409.893516)
			(xy 389.099552 -410.051504) (xy 389.099083 -410.061652) (xy 389.091295 -410.080394) (xy 389.076914 -410.094716)
			(xy 389.05814 -410.102424) (xy 389.04799 -410.102812) (xy 388.33171 -410.102812) (xy 388.32159 -410.102267)
			(xy 388.302879 -410.094552) (xy 388.288524 -410.080284) (xy 388.280696 -410.061621) (xy 388.280148 -410.051504)
			(xy 388.280148 -409.893516) (xy 388.27972 -409.884331) (xy 388.273217 -409.867147) (xy 388.267448 -409.859988)
			(xy 388.245624 -409.834365) (xy 388.207676 -409.778775) (xy 388.176644 -409.719047) (xy 388.152973 -409.656039)
			(xy 388.137002 -409.590653) (xy 388.128961 -409.523827) (xy 387.000824 -409.523827) (xy 386.972058 -409.579044)
			(xy 386.933969 -409.634679) (xy 386.912104 -409.660344) (xy 386.906307 -409.667489) (xy 386.899792 -409.68468)
			(xy 386.899404 -409.693872) (xy 386.899404 -410.186124) (xy 386.899801 -410.195313) (xy 386.906324 -410.212497)
			(xy 386.912104 -410.219652) (xy 386.933952 -410.24533) (xy 386.972041 -410.300963) (xy 387.003192 -410.360757)
			(xy 387.026957 -410.423853) (xy 387.042994 -410.48934) (xy 387.051071 -410.556277) (xy 387.051072 -410.623641)
			(xy 390.329135 -410.623641) (xy 390.329137 -410.556335) (xy 390.337182 -410.489512) (xy 390.353155 -410.42413)
			(xy 390.376828 -410.361125) (xy 390.407861 -410.3014) (xy 390.445809 -410.245813) (xy 390.467596 -410.22016)
			(xy 390.473392 -410.213014) (xy 390.479907 -410.195824) (xy 390.480296 -410.186632) (xy 390.480296 -409.693364)
			(xy 390.479904 -409.684175) (xy 390.473378 -409.666991) (xy 390.467596 -409.659836) (xy 390.445821 -409.634174)
			(xy 390.407875 -409.578588) (xy 390.376844 -409.518865) (xy 390.353172 -409.455862) (xy 390.3372 -409.390481)
			(xy 390.329155 -409.323661) (xy 390.329154 -409.256357) (xy 390.337196 -409.189536) (xy 390.353167 -409.124155)
			(xy 390.376836 -409.061151) (xy 390.407866 -409.001428) (xy 390.44581 -408.945841) (xy 390.467596 -408.920188)
			(xy 390.47338 -408.913034) (xy 390.479902 -408.89585) (xy 390.480296 -408.88666) (xy 390.480296 -408.728672)
			(xy 390.480699 -408.718517) (xy 390.488503 -408.699764) (xy 390.502905 -408.685442) (xy 390.5217 -408.677743)
			(xy 390.531858 -408.677364) (xy 391.248138 -408.677364) (xy 391.25827 -408.677796) (xy 391.276997 -408.685541)
			(xy 391.291352 -408.699844) (xy 391.299166 -408.718542) (xy 391.2997 -408.728672) (xy 391.2997 -408.88666)
			(xy 391.300129 -408.895845) (xy 391.30663 -408.91303) (xy 391.3124 -408.920188) (xy 391.334198 -408.945831)
			(xy 391.372144 -409.00142) (xy 391.403175 -409.061145) (xy 391.426845 -409.12415) (xy 391.442816 -409.189533)
			(xy 391.450859 -409.256356) (xy 391.450858 -409.323662) (xy 391.442813 -409.390484) (xy 391.42684 -409.455867)
			(xy 391.403167 -409.518872) (xy 391.372135 -409.578596) (xy 391.334187 -409.634183) (xy 391.3124 -409.659836)
			(xy 391.306606 -409.666983) (xy 391.30009 -409.684172) (xy 391.2997 -409.693364) (xy 391.2997 -410.186632)
			(xy 391.300095 -410.195821) (xy 391.306619 -410.213005) (xy 391.3124 -410.22016) (xy 391.334171 -410.245826)
			(xy 391.372118 -410.301411) (xy 391.403149 -410.361133) (xy 391.426821 -410.424136) (xy 391.442794 -410.489516)
			(xy 391.450839 -410.556336) (xy 391.450841 -410.623639) (xy 391.442799 -410.69046) (xy 391.426828 -410.755841)
			(xy 391.403159 -410.818845) (xy 391.37213 -410.878568) (xy 391.334186 -410.934155) (xy 391.3124 -410.959808)
			(xy 391.306618 -410.966963) (xy 391.300094 -410.984146) (xy 391.2997 -410.993336) (xy 391.2997 -411.151324)
			(xy 391.299298 -411.16148) (xy 391.291495 -411.180233) (xy 391.277092 -411.194555) (xy 391.258296 -411.202254)
			(xy 391.248138 -411.202632) (xy 390.531858 -411.202632) (xy 390.521725 -411.202207) (xy 390.502998 -411.19446)
			(xy 390.488642 -411.180155) (xy 390.480829 -411.161455) (xy 390.480296 -411.151324) (xy 390.480296 -410.993336)
			(xy 390.479869 -410.984151) (xy 390.473367 -410.966966) (xy 390.467596 -410.959808) (xy 390.445794 -410.934168)
			(xy 390.407848 -410.878579) (xy 390.376818 -410.818853) (xy 390.353148 -410.755847) (xy 390.337178 -410.690464)
			(xy 390.329135 -410.623641) (xy 387.051072 -410.623641) (xy 387.051072 -410.623699) (xy 387.042998 -410.690636)
			(xy 387.026964 -410.756124) (xy 387.003202 -410.819221) (xy 386.972053 -410.879016) (xy 386.933967 -410.934651)
			(xy 386.912104 -410.960316) (xy 386.906319 -410.967469) (xy 386.899797 -410.984654) (xy 386.899404 -410.993844)
			(xy 386.899404 -411.151324) (xy 386.898935 -411.161434) (xy 386.89119 -411.180112) (xy 386.876888 -411.194406)
			(xy 386.858206 -411.20214) (xy 386.848096 -411.202632) (xy 386.131816 -411.202632) (xy 386.121712 -411.202103)
			(xy 386.10304 -411.194376) (xy 386.088746 -411.180093) (xy 386.081005 -411.161427) (xy 386.080508 -411.151324)
			(xy 386.080508 -410.993844) (xy 386.080075 -410.984659) (xy 386.073577 -410.967475) (xy 386.067808 -410.960316)
			(xy 386.045928 -410.934664) (xy 386.007839 -410.879028) (xy 385.976689 -410.81923) (xy 385.952925 -410.756131)
			(xy 385.936891 -410.69064) (xy 385.928816 -410.623701) (xy 382.65077 -410.623701) (xy 382.642733 -410.690463)
			(xy 382.626761 -410.755844) (xy 382.603088 -410.818848) (xy 382.572054 -410.878571) (xy 382.534104 -410.934156)
			(xy 382.512316 -410.959808) (xy 382.506535 -410.966965) (xy 382.500011 -410.984146) (xy 382.499616 -410.993336)
			(xy 382.499616 -411.151324) (xy 382.499198 -411.161478) (xy 382.491398 -411.180228) (xy 382.477 -411.19455)
			(xy 382.45821 -411.202251) (xy 382.448054 -411.202632) (xy 381.731774 -411.202632) (xy 381.721642 -411.202194)
			(xy 381.702915 -411.194453) (xy 381.688559 -411.180151) (xy 381.680745 -411.161454) (xy 381.680212 -411.151324)
			(xy 381.680212 -410.993336) (xy 381.679782 -410.984151) (xy 381.673282 -410.966967) (xy 381.667512 -410.959808)
			(xy 381.645709 -410.934168) (xy 381.607763 -410.87858) (xy 381.576732 -410.818854) (xy 381.553061 -410.755848)
			(xy 381.53709 -410.690464) (xy 381.529047 -410.623641) (xy 378.250984 -410.623641) (xy 378.250984 -410.623699)
			(xy 378.24291 -410.690636) (xy 378.226877 -410.756124) (xy 378.203116 -410.81922) (xy 378.171968 -410.879016)
			(xy 378.133882 -410.93465) (xy 378.11202 -410.960316) (xy 378.106236 -410.967471) (xy 378.099713 -410.984654)
			(xy 378.09932 -410.993844) (xy 378.09932 -411.151324) (xy 378.098835 -411.161432) (xy 378.091093 -411.180107)
			(xy 378.076797 -411.1944) (xy 378.05812 -411.202138) (xy 378.048012 -411.202632) (xy 377.331732 -411.202632)
			(xy 377.321615 -411.202159) (xy 377.302919 -411.194427) (xy 377.288604 -411.180128) (xy 377.280852 -411.16144)
			(xy 377.280424 -411.151324) (xy 377.280424 -410.993844) (xy 377.279987 -410.98466) (xy 377.273491 -410.967475)
			(xy 377.267724 -410.960316) (xy 377.245843 -410.934664) (xy 377.207754 -410.879028) (xy 377.176602 -410.81923)
			(xy 377.152838 -410.756132) (xy 377.136803 -410.690641) (xy 377.128728 -410.623701) (xy 367.892128 -410.623701)
			(xy 367.795978 -410.757133) (xy 367.669592 -410.918827) (xy 367.536994 -411.075467) (xy 367.398386 -411.226813)
			(xy 367.253978 -411.372637) (xy 367.103991 -411.512716) (xy 366.948652 -411.646835) (xy 366.788199 -411.774792)
			(xy 366.622876 -411.896392) (xy 366.452934 -412.011448) (xy 366.278633 -412.119787) (xy 366.100237 -412.221242)
			(xy 365.918019 -412.31566) (xy 365.732256 -412.402896) (xy 365.543231 -412.482819) (xy 365.351231 -412.555305)
			(xy 365.156549 -412.620245) (xy 364.959482 -412.67754) (xy 364.760329 -412.727103) (xy 364.559395 -412.768858)
			(xy 364.356984 -412.802741) (xy 364.153406 -412.828701) (xy 363.948969 -412.846698) (xy 363.743986 -412.856706)
			(xy 363.538769 -412.858708) (xy 363.33363 -412.852702) (xy 363.128881 -412.838697) (xy 362.924834 -412.816714)
			(xy 362.721801 -412.786787) (xy 362.52009 -412.74896) (xy 362.320008 -412.703293) (xy 362.121861 -412.649854)
			(xy 361.925949 -412.588725) (xy 361.732572 -412.519999) (xy 361.542023 -412.44378) (xy 361.354593 -412.360184)
			(xy 361.170567 -412.26934) (xy 360.990226 -412.171385) (xy 360.813844 -412.066468) (xy 360.64169 -411.954749)
			(xy 360.474025 -411.836399) (xy 360.311106 -411.711597) (xy 360.15318 -411.580533) (xy 360.000488 -411.443408)
			(xy 359.853263 -411.30043) (xy 359.711728 -411.151816) (xy 359.576099 -410.997794) (xy 359.446582 -410.838597)
			(xy 359.323376 -410.674468) (xy 359.206667 -410.505657) (xy 359.096633 -410.33242) (xy 358.993442 -410.155023)
			(xy 358.897251 -409.973735) (xy 358.808206 -409.788832) (xy 358.726443 -409.600595) (xy 358.652087 -409.409312)
			(xy 358.585251 -409.215273) (xy 358.526036 -409.018774) (xy 358.474533 -408.820115) (xy 358.430819 -408.619597)
			(xy 358.394963 -408.417526) (xy 358.367018 -408.214211) (xy 358.347027 -408.00996) (xy 358.33502 -407.805084)
			(xy 358.331016 -407.599896) (xy 345.09113 -407.599896) (xy 345.091283 -407.600048) (xy 345.099102 -407.618729)
			(xy 345.09964 -407.628852) (xy 345.09964 -407.78684) (xy 345.100044 -407.796028) (xy 345.106563 -407.813211)
			(xy 345.11234 -407.820368) (xy 345.13412 -407.846026) (xy 345.172071 -407.901611) (xy 345.203106 -407.961334)
			(xy 345.22678 -408.024338) (xy 345.242754 -408.089719) (xy 345.250799 -408.156542) (xy 345.2508 -408.223846)
			(xy 345.242756 -408.290669) (xy 345.226783 -408.356051) (xy 345.20311 -408.419055) (xy 345.172077 -408.478778)
			(xy 345.134128 -408.534364) (xy 345.11234 -408.560016) (xy 345.106547 -408.567163) (xy 345.100032 -408.584352)
			(xy 345.09964 -408.593544) (xy 345.09964 -409.086812) (xy 345.100058 -409.095998) (xy 345.106568 -409.113182)
			(xy 345.11234 -409.12034) (xy 345.134093 -409.146021) (xy 345.172044 -409.201603) (xy 345.20308 -409.261322)
			(xy 345.226756 -409.324323) (xy 345.242732 -409.389702) (xy 345.250779 -409.456522) (xy 345.250783 -409.523824)
			(xy 345.242742 -409.590645) (xy 345.226772 -409.656025) (xy 345.203102 -409.719028) (xy 345.172072 -409.778751)
			(xy 345.134126 -409.834336) (xy 345.11234 -409.859988) (xy 345.106516 -409.867114) (xy 345.100019 -409.884319)
			(xy 345.09964 -409.893516) (xy 345.09964 -410.051504) (xy 345.099182 -410.061653) (xy 345.091393 -410.080398)
			(xy 345.077008 -410.09472) (xy 345.058229 -410.102427) (xy 345.048078 -410.102812) (xy 344.331798 -410.102812)
			(xy 344.321678 -410.102277) (xy 344.302966 -410.094558) (xy 344.288612 -410.080287) (xy 344.280784 -410.061621)
			(xy 344.280236 -410.051504) (xy 344.280236 -409.893516) (xy 344.27981 -409.884331) (xy 344.273307 -409.867146)
			(xy 344.267536 -409.859988) (xy 344.245713 -409.834365) (xy 344.207765 -409.778774) (xy 344.176734 -409.719047)
			(xy 344.153063 -409.656038) (xy 344.137093 -409.590653) (xy 344.129052 -409.523827) (xy 343.000914 -409.523827)
			(xy 342.972148 -409.579044) (xy 342.934057 -409.634679) (xy 342.912192 -409.660344) (xy 342.906393 -409.667488)
			(xy 342.89988 -409.684679) (xy 342.899492 -409.693872) (xy 342.899492 -410.186124) (xy 342.899892 -410.195312)
			(xy 342.906413 -410.212496) (xy 342.912192 -410.219652) (xy 342.934041 -410.24533) (xy 342.97213 -410.300963)
			(xy 343.003282 -410.360757) (xy 343.027048 -410.423852) (xy 343.043084 -410.48934) (xy 343.051162 -410.556277)
			(xy 343.051163 -410.623642) (xy 346.329202 -410.623642) (xy 346.329204 -410.556334) (xy 346.33725 -410.48951)
			(xy 346.353226 -410.424126) (xy 346.376903 -410.361121) (xy 346.40794 -410.301397) (xy 346.445894 -410.245812)
			(xy 346.467684 -410.22016) (xy 346.473478 -410.213013) (xy 346.479995 -410.195824) (xy 346.480384 -410.186632)
			(xy 346.480384 -409.693364) (xy 346.479995 -409.684175) (xy 346.473467 -409.66699) (xy 346.467684 -409.659836)
			(xy 346.445907 -409.634175) (xy 346.407955 -409.578591) (xy 346.376918 -409.518869) (xy 346.353243 -409.455865)
			(xy 346.337268 -409.390484) (xy 346.329222 -409.323661) (xy 346.329221 -409.256357) (xy 346.337265 -409.189534)
			(xy 346.353238 -409.124152) (xy 346.376911 -409.061148) (xy 346.407945 -409.001425) (xy 346.445896 -408.94584)
			(xy 346.467684 -408.920188) (xy 346.473466 -408.913033) (xy 346.47999 -408.89585) (xy 346.480384 -408.88666)
			(xy 346.480384 -408.728672) (xy 346.480798 -408.718518) (xy 346.4886 -408.699768) (xy 346.502999 -408.685446)
			(xy 346.52179 -408.677745) (xy 346.531946 -408.677364) (xy 347.248226 -408.677364) (xy 347.258357 -408.677806)
			(xy 347.277084 -408.685547) (xy 347.29144 -408.699847) (xy 347.299254 -408.718543) (xy 347.299788 -408.728672)
			(xy 347.299788 -408.88666) (xy 347.30022 -408.895845) (xy 347.306719 -408.913029) (xy 347.312488 -408.920188)
			(xy 347.334287 -408.945831) (xy 347.372233 -409.001419) (xy 347.403265 -409.061144) (xy 347.426936 -409.12415)
			(xy 347.442907 -409.189533) (xy 347.45095 -409.256356) (xy 347.450949 -409.323662) (xy 347.442904 -409.390485)
			(xy 347.42693 -409.455867) (xy 347.403257 -409.518872) (xy 347.372224 -409.578596) (xy 347.334276 -409.634184)
			(xy 347.312488 -409.659836) (xy 347.306692 -409.666982) (xy 347.300177 -409.684172) (xy 347.299788 -409.693364)
			(xy 347.299788 -410.186632) (xy 347.300185 -410.195821) (xy 347.306708 -410.213005) (xy 347.312488 -410.22016)
			(xy 347.334259 -410.245825) (xy 347.372207 -410.301411) (xy 347.403239 -410.361133) (xy 347.426912 -410.424135)
			(xy 347.442885 -410.489516) (xy 347.45093 -410.556336) (xy 347.450931 -410.62364) (xy 347.442889 -410.690461)
			(xy 347.426919 -410.755842) (xy 347.403249 -410.818845) (xy 347.372219 -410.878569) (xy 347.334274 -410.934156)
			(xy 347.312488 -410.959808) (xy 347.306704 -410.966962) (xy 347.300182 -410.984146) (xy 347.299788 -410.993336)
			(xy 347.299788 -411.151324) (xy 347.299398 -411.161481) (xy 347.291592 -411.180236) (xy 347.277186 -411.194559)
			(xy 347.258386 -411.202256) (xy 347.248226 -411.202632) (xy 346.531946 -411.202632) (xy 346.521819 -411.202135)
			(xy 346.503093 -411.194417) (xy 346.488735 -411.180133) (xy 346.480919 -411.161449) (xy 346.480384 -411.151324)
			(xy 346.480384 -410.993336) (xy 346.47996 -410.98415) (xy 346.473456 -410.966965) (xy 346.467684 -410.959808)
			(xy 346.445879 -410.934169) (xy 346.407928 -410.878582) (xy 346.376893 -410.818857) (xy 346.353219 -410.755851)
			(xy 346.337246 -410.690466) (xy 346.329202 -410.623642) (xy 343.051163 -410.623642) (xy 343.051163 -410.623699)
			(xy 343.043089 -410.690637) (xy 343.027055 -410.756125) (xy 343.003292 -410.819221) (xy 342.972143 -410.879017)
			(xy 342.934055 -410.934651) (xy 342.912192 -410.960316) (xy 342.906405 -410.967468) (xy 342.899885 -410.984653)
			(xy 342.899492 -410.993844) (xy 342.899492 -411.151324) (xy 342.899034 -411.161435) (xy 342.891287 -411.180116)
			(xy 342.876982 -411.19441) (xy 342.858296 -411.202142) (xy 342.848184 -411.202632) (xy 342.131904 -411.202632)
			(xy 342.121799 -411.202112) (xy 342.103128 -411.194382) (xy 342.088834 -411.180096) (xy 342.081093 -411.161428)
			(xy 342.080596 -411.151324) (xy 342.080596 -410.993844) (xy 342.080166 -410.984659) (xy 342.073666 -410.967474)
			(xy 342.067896 -410.960316) (xy 342.046016 -410.934664) (xy 342.007928 -410.879027) (xy 341.976779 -410.819229)
			(xy 341.953016 -410.756131) (xy 341.936981 -410.69064) (xy 341.928907 -410.6237) (xy 338.650837 -410.6237)
			(xy 338.642802 -410.69046) (xy 338.626832 -410.755841) (xy 338.603163 -410.818845) (xy 338.572134 -410.878568)
			(xy 338.534189 -410.934155) (xy 338.512404 -410.959808) (xy 338.506622 -410.966964) (xy 338.500098 -410.984146)
			(xy 338.499704 -410.993336) (xy 338.499704 -411.151324) (xy 338.499298 -411.161479) (xy 338.491495 -411.180231)
			(xy 338.477094 -411.194554) (xy 338.458299 -411.202253) (xy 338.448142 -411.202632) (xy 337.731862 -411.202632)
			(xy 337.721729 -411.202204) (xy 337.703002 -411.194458) (xy 337.688646 -411.180154) (xy 337.680833 -411.161455)
			(xy 337.6803 -411.151324) (xy 337.6803 -410.993336) (xy 337.679873 -410.984151) (xy 337.673371 -410.966966)
			(xy 337.6676 -410.959808) (xy 337.645798 -410.934168) (xy 337.607852 -410.878579) (xy 337.576822 -410.818853)
			(xy 337.553151 -410.755847) (xy 337.537181 -410.690464) (xy 337.529138 -410.623641) (xy 334.251075 -410.623641)
			(xy 334.251075 -410.623699) (xy 334.243001 -410.690636) (xy 334.226967 -410.756124) (xy 334.203205 -410.81922)
			(xy 334.172057 -410.879016) (xy 334.133971 -410.934651) (xy 334.112108 -410.960316) (xy 334.106323 -410.96747)
			(xy 334.099801 -410.984654) (xy 334.099408 -410.993844) (xy 334.099408 -411.151324) (xy 334.098935 -411.161433)
			(xy 334.091191 -411.180111) (xy 334.07689 -411.194404) (xy 334.05821 -411.20214) (xy 334.0481 -411.202632)
			(xy 333.33182 -411.202632) (xy 333.321716 -411.202099) (xy 333.303045 -411.194374) (xy 333.28875 -411.180092)
			(xy 333.281009 -411.161427) (xy 333.280512 -411.151324) (xy 333.280512 -410.993844) (xy 333.280078 -410.984659)
			(xy 333.273581 -410.967475) (xy 333.267812 -410.960316) (xy 333.245932 -410.934664) (xy 333.207843 -410.879028)
			(xy 333.176692 -410.81923) (xy 333.152928 -410.756131) (xy 333.136894 -410.69064) (xy 333.128819 -410.623701)
			(xy 326.525636 -410.623701) (xy 326.525636 -417.018724) (xy 326.526762 -417.028228) (xy 326.535073 -417.045453)
			(xy 326.549085 -417.05847) (xy 326.566875 -417.065491) (xy 326.576436 -417.065968) (xy 401.023328 -417.065968)
			(xy 401.032909 -417.065579) (xy 401.050747 -417.058582) (xy 401.06478 -417.045534) (xy 401.073054 -417.028252)
			(xy 401.074128 -417.018724) (xy 401.074128 -394.27912) (xy 414.451292 -394.27912) (xy 414.525968 -394.353542)
			(xy 414.525968 -397.823826) (xy 418.92899 -397.823826) (xy 418.928993 -397.756517) (xy 418.937042 -397.689691)
			(xy 418.95302 -397.624306) (xy 418.9767 -397.5613) (xy 419.00774 -397.501575) (xy 419.045697 -397.44599)
			(xy 419.067488 -397.420338) (xy 419.073292 -397.413198) (xy 419.079803 -397.396004) (xy 419.080188 -397.38681)
			(xy 419.080188 -396.893542) (xy 419.07976 -396.884357) (xy 419.073259 -396.867172) (xy 419.067488 -396.860014)
			(xy 419.045689 -396.834371) (xy 419.007737 -396.778784) (xy 418.976702 -396.71906) (xy 418.953027 -396.656054)
			(xy 418.937054 -396.59067) (xy 418.92901 -396.523846) (xy 418.92901 -396.456539) (xy 418.937056 -396.389715)
			(xy 418.953032 -396.324332) (xy 418.976708 -396.261327) (xy 419.007745 -396.201603) (xy 419.045698 -396.146018)
			(xy 419.067488 -396.120366) (xy 419.07328 -396.113218) (xy 419.079798 -396.09603) (xy 419.080188 -396.086838)
			(xy 419.080188 -395.92885) (xy 419.080606 -395.918675) (xy 419.088384 -395.899872) (xy 419.102772 -395.885484)
			(xy 419.121575 -395.877706) (xy 419.13175 -395.877288) (xy 419.84803 -395.877288) (xy 419.85821 -395.87764)
			(xy 419.877015 -395.885445) (xy 419.8914 -395.899852) (xy 419.899175 -395.91867) (xy 419.899592 -395.92885)
			(xy 419.899592 -396.086838) (xy 419.899986 -396.096027) (xy 419.906511 -396.113211) (xy 419.912292 -396.120366)
			(xy 419.934069 -396.146027) (xy 419.972016 -396.201613) (xy 420.003048 -396.261335) (xy 420.02672 -396.324339)
			(xy 420.042693 -396.389719) (xy 420.050737 -396.456541) (xy 420.050738 -396.523844) (xy 420.042695 -396.590666)
			(xy 420.026725 -396.656047) (xy 420.003054 -396.719051) (xy 419.972024 -396.778774) (xy 419.934078 -396.834361)
			(xy 419.912292 -396.860014) (xy 419.906506 -396.867167) (xy 419.899985 -396.884351) (xy 419.899592 -396.893542)
			(xy 419.899592 -397.38681) (xy 419.899999 -397.395998) (xy 419.906515 -397.413182) (xy 419.912292 -397.420338)
			(xy 419.934041 -397.446021) (xy 419.971989 -397.501604) (xy 420.00041 -397.556296) (xy 421.128654 -397.556296)
			(xy 421.13673 -397.489357) (xy 421.152765 -397.423869) (xy 421.17653 -397.360772) (xy 421.207681 -397.300976)
			(xy 421.245771 -397.245343) (xy 421.267636 -397.219678) (xy 421.273429 -397.21253) (xy 421.279945 -397.195342)
			(xy 421.280336 -397.18615) (xy 421.280336 -397.028924) (xy 421.280736 -397.018799) (xy 421.288483 -397.000089)
			(xy 421.302805 -396.985772) (xy 421.321518 -396.978032) (xy 421.331644 -396.977616) (xy 422.047924 -396.977616)
			(xy 422.058036 -396.978066) (xy 422.076718 -396.985814) (xy 422.091013 -397.000122) (xy 422.098744 -397.018811)
			(xy 422.099232 -397.028924) (xy 422.099232 -397.18615) (xy 422.099681 -397.195333) (xy 422.106169 -397.212517)
			(xy 422.111932 -397.219678) (xy 422.133805 -397.245336) (xy 422.171891 -397.300972) (xy 422.203039 -397.36077)
			(xy 422.226802 -397.423867) (xy 422.242835 -397.489357) (xy 422.25091 -397.556296) (xy 422.250909 -397.623719)
			(xy 422.242833 -397.690658) (xy 422.226797 -397.756147) (xy 422.203033 -397.819244) (xy 422.200615 -397.823885)
			(xy 423.328782 -397.823885) (xy 423.328786 -397.756458) (xy 423.336865 -397.689518) (xy 423.352904 -397.624027)
			(xy 423.376672 -397.560928) (xy 423.407826 -397.501131) (xy 423.445918 -397.445496) (xy 423.467784 -397.41983)
			(xy 423.473591 -397.412692) (xy 423.4801 -397.395496) (xy 423.480484 -397.386302) (xy 423.480484 -396.89405)
			(xy 423.480054 -396.884865) (xy 423.473554 -396.86768) (xy 423.467784 -396.860522) (xy 423.445911 -396.834865)
			(xy 423.407823 -396.779229) (xy 423.376674 -396.719431) (xy 423.352911 -396.656333) (xy 423.336877 -396.590843)
			(xy 423.328802 -396.523905) (xy 423.328803 -396.45648) (xy 423.33688 -396.389542) (xy 423.352916 -396.324052)
			(xy 423.37668 -396.260955) (xy 423.407831 -396.201159) (xy 423.44592 -396.145524) (xy 423.467784 -396.119858)
			(xy 423.473579 -396.112712) (xy 423.480095 -396.095522) (xy 423.480484 -396.08633) (xy 423.480484 -395.92885)
			(xy 423.480969 -395.918721) (xy 423.488688 -395.899993) (xy 423.502976 -395.885633) (xy 423.521666 -395.87782)
			(xy 423.531792 -395.877288) (xy 424.248072 -395.877288) (xy 424.258223 -395.877744) (xy 424.276972 -395.885528)
			(xy 424.291296 -395.899914) (xy 424.298999 -395.918697) (xy 424.29938 -395.92885) (xy 424.29938 -396.08633)
			(xy 424.29978 -396.095518) (xy 424.306301 -396.112702) (xy 424.31208 -396.119858) (xy 424.333935 -396.145531)
			(xy 424.372025 -396.201164) (xy 424.403177 -396.260959) (xy 424.426943 -396.324055) (xy 424.44298 -396.389543)
			(xy 424.451057 -396.456481) (xy 424.451058 -396.523904) (xy 424.442983 -396.590842) (xy 424.426948 -396.656331)
			(xy 424.403184 -396.719427) (xy 424.372033 -396.779223) (xy 424.333944 -396.834857) (xy 424.31208 -396.860522)
			(xy 424.306289 -396.867671) (xy 424.299772 -396.884859) (xy 424.29938 -396.89405) (xy 424.29938 -397.386302)
			(xy 424.299793 -397.395489) (xy 424.306305 -397.412673) (xy 424.31208 -397.41983) (xy 424.333907 -397.445526)
			(xy 424.371998 -397.501155) (xy 424.40076 -397.556356) (xy 425.528974 -397.556356) (xy 425.537017 -397.489534)
			(xy 425.552988 -397.424152) (xy 425.576659 -397.361148) (xy 425.607691 -397.301425) (xy 425.645637 -397.245838)
			(xy 425.667424 -397.220186) (xy 425.673212 -397.213035) (xy 425.679731 -397.195849) (xy 425.680124 -397.186658)
			(xy 425.680124 -397.028924) (xy 425.680542 -397.018768) (xy 425.688334 -397.000012) (xy 425.702732 -396.985687)
			(xy 425.721528 -396.97799) (xy 425.731686 -396.977616) (xy 426.447966 -396.977616) (xy 426.458088 -396.978154)
			(xy 426.476803 -396.985866) (xy 426.49116 -397.000137) (xy 426.498984 -397.018806) (xy 426.499528 -397.028924)
			(xy 426.499528 -397.186658) (xy 426.499952 -397.195844) (xy 426.506456 -397.213029) (xy 426.512228 -397.220186)
			(xy 426.534026 -397.24583) (xy 426.571977 -397.301417) (xy 426.603012 -397.361141) (xy 426.626685 -397.424147)
			(xy 426.642659 -397.48953) (xy 426.650703 -397.556354) (xy 426.650702 -397.623661) (xy 426.642656 -397.690485)
			(xy 426.626681 -397.755868) (xy 426.603006 -397.818873) (xy 426.600432 -397.823826) (xy 427.729077 -397.823826)
			(xy 427.729081 -397.756517) (xy 427.737129 -397.689691) (xy 427.753107 -397.624307) (xy 427.776786 -397.5613)
			(xy 427.807825 -397.501576) (xy 427.845781 -397.44599) (xy 427.867572 -397.420338) (xy 427.873386 -397.413206)
			(xy 427.879888 -397.396005) (xy 427.880272 -397.38681) (xy 427.880272 -396.893542) (xy 427.879848 -396.884356)
			(xy 427.873344 -396.867171) (xy 427.867572 -396.860014) (xy 427.845774 -396.83437) (xy 427.807823 -396.778783)
			(xy 427.776788 -396.719059) (xy 427.753115 -396.656053) (xy 427.737141 -396.59067) (xy 427.729097 -396.523846)
			(xy 427.729098 -396.456539) (xy 427.737144 -396.389715) (xy 427.753119 -396.324332) (xy 427.776794 -396.261327)
			(xy 427.807831 -396.201604) (xy 427.845783 -396.146018) (xy 427.867572 -396.120366) (xy 427.873374 -396.113225)
			(xy 427.879883 -396.096031) (xy 427.880272 -396.086838) (xy 427.880272 -395.92885) (xy 427.880706 -395.918677)
			(xy 427.88848 -395.899877) (xy 427.902864 -395.885489) (xy 427.921662 -395.877709) (xy 427.931834 -395.877288)
			(xy 428.648114 -395.877288) (xy 428.658293 -395.877654) (xy 428.677097 -395.885453) (xy 428.691483 -395.899857)
			(xy 428.699259 -395.918671) (xy 428.699676 -395.92885) (xy 428.699676 -396.086838) (xy 428.700073 -396.096026)
			(xy 428.706596 -396.11321) (xy 428.712376 -396.120366) (xy 428.734154 -396.146026) (xy 428.772102 -396.201612)
			(xy 428.803135 -396.261335) (xy 428.826807 -396.324338) (xy 428.84278 -396.389719) (xy 428.850825 -396.45654)
			(xy 428.850826 -396.523844) (xy 428.842783 -396.590666) (xy 428.826812 -396.656048) (xy 428.803141 -396.719052)
			(xy 428.772109 -396.778775) (xy 428.734163 -396.834362) (xy 428.712376 -396.860014) (xy 428.706588 -396.867165)
			(xy 428.700069 -396.884351) (xy 428.699676 -396.893542) (xy 428.699676 -397.38681) (xy 428.700087 -397.395997)
			(xy 428.7066 -397.413181) (xy 428.712376 -397.420338) (xy 428.734126 -397.446021) (xy 428.772075 -397.501604)
			(xy 428.800497 -397.556296) (xy 429.928742 -397.556296) (xy 429.936817 -397.489358) (xy 429.952852 -397.423869)
			(xy 429.976616 -397.360773) (xy 430.007767 -397.300977) (xy 430.045856 -397.245343) (xy 430.06772 -397.219678)
			(xy 430.073511 -397.212529) (xy 430.080028 -397.195341) (xy 430.08042 -397.18615) (xy 430.08042 -397.028924)
			(xy 430.080836 -397.018801) (xy 430.08858 -397.000094) (xy 430.102897 -396.985778) (xy 430.121605 -396.978035)
			(xy 430.131728 -396.977616) (xy 430.848008 -396.977616) (xy 430.858133 -396.97801) (xy 430.87684 -396.985764)
			(xy 430.891154 -397.000087) (xy 430.898896 -397.018799) (xy 430.899316 -397.028924) (xy 430.899316 -397.18615)
			(xy 430.899746 -397.195335) (xy 430.906246 -397.21252) (xy 430.912016 -397.219678) (xy 430.933889 -397.245335)
			(xy 430.971977 -397.300971) (xy 431.003126 -397.360769) (xy 431.026889 -397.423867) (xy 431.042923 -397.489357)
			(xy 431.050998 -397.556295) (xy 431.050997 -397.62372) (xy 431.04292 -397.690658) (xy 431.026884 -397.756148)
			(xy 431.00312 -397.819245) (xy 431.000734 -397.823826) (xy 432.128868 -397.823826) (xy 432.128872 -397.756517)
			(xy 432.13692 -397.689692) (xy 432.152898 -397.624307) (xy 432.176576 -397.561301) (xy 432.207614 -397.501576)
			(xy 432.245569 -397.44599) (xy 432.26736 -397.420338) (xy 432.273173 -397.413205) (xy 432.279676 -397.396005)
			(xy 432.28006 -397.38681) (xy 432.28006 -396.893542) (xy 432.279616 -396.884359) (xy 432.273125 -396.867175)
			(xy 432.26736 -396.860014) (xy 432.245562 -396.83437) (xy 432.207612 -396.778783) (xy 432.176578 -396.719058)
			(xy 432.152905 -396.656053) (xy 432.136932 -396.590669) (xy 432.128888 -396.523846) (xy 432.128889 -396.456539)
			(xy 432.136935 -396.389716) (xy 432.152909 -396.324333) (xy 432.176584 -396.261328) (xy 432.20762 -396.201604)
			(xy 432.245571 -396.146018) (xy 432.26736 -396.120366) (xy 432.273161 -396.113224) (xy 432.279671 -396.096031)
			(xy 432.28006 -396.086838) (xy 432.28006 -395.92885) (xy 432.280505 -395.918679) (xy 432.288278 -395.899881)
			(xy 432.302658 -395.885494) (xy 432.321451 -395.877711) (xy 432.331622 -395.877288) (xy 433.047902 -395.877288)
			(xy 433.05808 -395.877663) (xy 433.076884 -395.885458) (xy 433.091271 -395.899859) (xy 433.099047 -395.918672)
			(xy 433.099464 -395.92885) (xy 433.099464 -396.086838) (xy 433.099864 -396.096026) (xy 433.106386 -396.11321)
			(xy 433.112164 -396.120366) (xy 433.133942 -396.146026) (xy 433.171891 -396.201612) (xy 433.202924 -396.261334)
			(xy 433.226598 -396.324337) (xy 433.242571 -396.389719) (xy 433.250616 -396.45654) (xy 433.250617 -396.523845)
			(xy 433.242574 -396.590666) (xy 433.226602 -396.656048) (xy 433.202931 -396.719052) (xy 433.171899 -396.778776)
			(xy 433.133951 -396.834362) (xy 433.112164 -396.860014) (xy 433.106374 -396.867164) (xy 433.099856 -396.884351)
			(xy 433.099464 -396.893542) (xy 433.099464 -397.38681) (xy 433.099877 -397.395997) (xy 433.10639 -397.413181)
			(xy 433.112164 -397.420338) (xy 433.133914 -397.446021) (xy 433.171864 -397.501603) (xy 433.200318 -397.556356)
			(xy 434.329062 -397.556356) (xy 434.337105 -397.489534) (xy 434.353075 -397.424153) (xy 434.376746 -397.361149)
			(xy 434.407776 -397.301426) (xy 434.445722 -397.245839) (xy 434.467508 -397.220186) (xy 434.473294 -397.213033)
			(xy 434.479815 -397.195849) (xy 434.480208 -397.186658) (xy 434.480208 -397.028924) (xy 434.480641 -397.01877)
			(xy 434.48843 -397.000017) (xy 434.502824 -396.985692) (xy 434.521614 -396.977993) (xy 434.53177 -396.977616)
			(xy 435.24805 -396.977616) (xy 435.258171 -396.978167) (xy 435.276886 -396.985874) (xy 435.291243 -397.00014)
			(xy 435.299068 -397.018807) (xy 435.299612 -397.028924) (xy 435.299612 -397.186658) (xy 435.30004 -397.195843)
			(xy 435.306541 -397.213028) (xy 435.312312 -397.220186) (xy 435.334111 -397.245829) (xy 435.372063 -397.301416)
			(xy 435.403098 -397.36114) (xy 435.426773 -397.424146) (xy 435.442746 -397.48953) (xy 435.45079 -397.556354)
			(xy 435.45079 -397.623661) (xy 435.442744 -397.690485) (xy 435.426768 -397.755868) (xy 435.403092 -397.818873)
			(xy 435.372055 -397.878597) (xy 435.334102 -397.934182) (xy 435.312312 -397.959834) (xy 435.30652 -397.966982)
			(xy 435.300002 -397.98417) (xy 435.299612 -397.993362) (xy 435.299612 -398.100042) (xy 459.541382 -398.100042)
			(xy 459.545364 -397.972056) (xy 459.557296 -397.844565) (xy 459.57713 -397.718062) (xy 459.604791 -397.593037)
			(xy 459.640171 -397.469974) (xy 459.683133 -397.349348) (xy 459.733511 -397.231627) (xy 459.791111 -397.117265)
			(xy 459.855709 -397.006706) (xy 459.927056 -396.900376) (xy 460.004875 -396.798688) (xy 460.088865 -396.702034)
			(xy 460.178702 -396.610789) (xy 460.274038 -396.525306) (xy 460.374503 -396.445915) (xy 460.479711 -396.372923)
			(xy 460.589252 -396.306614) (xy 460.702704 -396.247243) (xy 460.819628 -396.195039) (xy 460.939571 -396.150206)
			(xy 461.062069 -396.112917) (xy 461.186649 -396.083315) (xy 461.312827 -396.061516) (xy 461.440117 -396.047603)
			(xy 461.568026 -396.041631) (xy 461.696059 -396.043622) (xy 461.82372 -396.05357) (xy 461.950516 -396.071434)
			(xy 462.075955 -396.097147) (xy 462.199554 -396.130609) (xy 462.320833 -396.17169) (xy 462.439324 -396.220232)
			(xy 462.554568 -396.276046) (xy 462.666118 -396.338917) (xy 462.773545 -396.408601) (xy 462.876431 -396.484829)
			(xy 462.974379 -396.567306) (xy 463.06701 -396.655713) (xy 463.153966 -396.749708) (xy 463.23491 -396.848927)
			(xy 463.309529 -396.952986) (xy 463.377534 -397.061483) (xy 463.438662 -397.173998) (xy 463.492677 -397.290096)
			(xy 463.53937 -397.409327) (xy 463.57856 -397.531231) (xy 463.610096 -397.655335) (xy 463.633855 -397.781159)
			(xy 463.649745 -397.908218) (xy 463.657706 -398.036018) (xy 463.658204 -398.100042) (xy 463.657706 -398.164066)
			(xy 463.649745 -398.291866) (xy 463.633855 -398.418925) (xy 463.610096 -398.544749) (xy 463.57856 -398.668853)
			(xy 463.53937 -398.790757) (xy 463.492677 -398.909988) (xy 463.438662 -399.026086) (xy 463.377534 -399.138601)
			(xy 463.309529 -399.247098) (xy 463.23491 -399.351157) (xy 463.153966 -399.450376) (xy 463.06701 -399.544371)
			(xy 462.974379 -399.632778) (xy 462.876431 -399.715255) (xy 462.773545 -399.791483) (xy 462.666118 -399.861167)
			(xy 462.554568 -399.924038) (xy 462.439324 -399.979852) (xy 462.320833 -400.028394) (xy 462.199554 -400.069475)
			(xy 462.075955 -400.102937) (xy 461.950516 -400.12865) (xy 461.82372 -400.146514) (xy 461.696059 -400.156462)
			(xy 461.568026 -400.158453) (xy 461.440117 -400.152481) (xy 461.312827 -400.138568) (xy 461.186649 -400.116769)
			(xy 461.062069 -400.087167) (xy 460.939571 -400.049878) (xy 460.819628 -400.005045) (xy 460.702704 -399.952841)
			(xy 460.589252 -399.89347) (xy 460.479711 -399.827161) (xy 460.374503 -399.754169) (xy 460.274038 -399.674778)
			(xy 460.178702 -399.589295) (xy 460.088865 -399.49805) (xy 460.004875 -399.401396) (xy 459.927056 -399.299708)
			(xy 459.855709 -399.193378) (xy 459.791111 -399.082819) (xy 459.733511 -398.968457) (xy 459.683133 -398.850736)
			(xy 459.640171 -398.73011) (xy 459.604791 -398.607047) (xy 459.57713 -398.482022) (xy 459.557296 -398.355519)
			(xy 459.545364 -398.228028) (xy 459.541382 -398.100042) (xy 435.299612 -398.100042) (xy 435.299612 -398.486884)
			(xy 435.300027 -398.496071) (xy 435.306537 -398.513255) (xy 435.312312 -398.520412) (xy 435.334137 -398.546034)
			(xy 435.372087 -398.601624) (xy 435.403122 -398.661351) (xy 435.426795 -398.72436) (xy 435.442767 -398.789746)
			(xy 435.450809 -398.856573) (xy 435.450805 -398.923881) (xy 435.442757 -398.990707) (xy 435.426779 -399.056092)
			(xy 435.4031 -399.119098) (xy 435.37206 -399.178823) (xy 435.334103 -399.234408) (xy 435.312312 -399.26006)
			(xy 435.306509 -399.267201) (xy 435.299998 -399.284395) (xy 435.299612 -399.293588) (xy 435.299612 -399.451576)
			(xy 435.299159 -399.461727) (xy 435.291374 -399.480477) (xy 435.276987 -399.494801) (xy 435.258203 -399.502503)
			(xy 435.24805 -399.502884) (xy 434.53177 -399.502884) (xy 434.521644 -399.502399) (xy 434.502927 -399.494666)
			(xy 434.488573 -399.480379) (xy 434.48075 -399.461699) (xy 434.480208 -399.451576) (xy 434.480208 -399.293588)
			(xy 434.479802 -399.2844) (xy 434.473285 -399.267216) (xy 434.467508 -399.26006) (xy 434.445757 -399.234378)
			(xy 434.407809 -399.178795) (xy 434.376776 -399.119076) (xy 434.353102 -399.056075) (xy 434.337128 -398.990697)
			(xy 434.329081 -398.923878) (xy 434.329078 -398.856576) (xy 434.337118 -398.789757) (xy 434.353086 -398.724377)
			(xy 434.376753 -398.661374) (xy 434.407781 -398.601651) (xy 434.445723 -398.546064) (xy 434.467508 -398.520412)
			(xy 434.473325 -398.513282) (xy 434.479827 -398.49608) (xy 434.480208 -398.486884) (xy 434.480208 -397.993362)
			(xy 434.479814 -397.984173) (xy 434.473289 -397.966989) (xy 434.467508 -397.959834) (xy 434.445731 -397.934173)
			(xy 434.407784 -397.878587) (xy 434.376752 -397.818865) (xy 434.35308 -397.755861) (xy 434.337107 -397.690481)
			(xy 434.329063 -397.623659) (xy 434.329062 -397.556356) (xy 433.200318 -397.556356) (xy 433.202899 -397.561322)
			(xy 433.226573 -397.624323) (xy 433.242549 -397.689701) (xy 433.250596 -397.75652) (xy 433.250599 -397.823822)
			(xy 433.242559 -397.890642) (xy 433.22659 -397.956022) (xy 433.202922 -398.019025) (xy 433.171893 -398.078748)
			(xy 433.133949 -398.134334) (xy 433.112164 -398.159986) (xy 433.106344 -398.167114) (xy 433.099844 -398.184318)
			(xy 433.099464 -398.193514) (xy 433.099464 -398.351502) (xy 433.098968 -398.36166) (xy 433.091194 -398.380428)
			(xy 433.076828 -398.394794) (xy 433.05806 -398.402568) (xy 433.047902 -398.403064) (xy 432.331622 -398.403064)
			(xy 432.321452 -398.402618) (xy 432.302658 -398.394841) (xy 432.288273 -398.380462) (xy 432.280487 -398.361672)
			(xy 432.28006 -398.351502) (xy 432.28006 -398.193514) (xy 432.27963 -398.184329) (xy 432.273129 -398.167145)
			(xy 432.26736 -398.159986) (xy 432.245534 -398.134365) (xy 432.207585 -398.078775) (xy 432.176552 -398.019047)
			(xy 432.152881 -397.956038) (xy 432.13691 -397.890652) (xy 432.128868 -397.823826) (xy 431.000734 -397.823826)
			(xy 430.971969 -397.879041) (xy 430.93388 -397.934676) (xy 430.912016 -397.960342) (xy 430.906221 -397.967488)
			(xy 430.899705 -397.984678) (xy 430.899316 -397.99387) (xy 430.899316 -398.486376) (xy 430.899734 -398.495562)
			(xy 430.906242 -398.512747) (xy 430.912016 -398.519904) (xy 430.933915 -398.54554) (xy 430.972001 -398.601179)
			(xy 431.00315 -398.66098) (xy 431.026911 -398.72408) (xy 431.042944 -398.789573) (xy 431.051016 -398.856514)
			(xy 431.051013 -398.92394) (xy 431.042934 -398.990881) (xy 431.026895 -399.056371) (xy 431.003128 -399.11947)
			(xy 430.971974 -399.179267) (xy 430.933882 -399.234902) (xy 430.912016 -399.260568) (xy 430.90621 -399.267707)
			(xy 430.8997 -399.284902) (xy 430.899316 -399.294096) (xy 430.899316 -399.451576) (xy 430.898865 -399.461695)
			(xy 430.891128 -399.480395) (xy 430.876822 -399.49471) (xy 430.858127 -399.502459) (xy 430.848008 -399.502884)
			(xy 430.131728 -399.502884) (xy 430.121605 -399.502461) (xy 430.102899 -399.494719) (xy 430.088583 -399.480404)
			(xy 430.08084 -399.461699) (xy 430.08042 -399.451576) (xy 430.08042 -399.294096) (xy 430.080008 -399.284909)
			(xy 430.073495 -399.267725) (xy 430.06772 -399.260568) (xy 430.045891 -399.234874) (xy 430.0078 -399.179244)
			(xy 429.976646 -399.119452) (xy 429.952879 -399.056359) (xy 429.936841 -398.990873) (xy 429.928761 -398.923938)
			(xy 429.928758 -398.856516) (xy 429.936831 -398.78958) (xy 429.952863 -398.724093) (xy 429.976624 -398.660997)
			(xy 430.007772 -398.601202) (xy 430.045857 -398.545569) (xy 430.06772 -398.519904) (xy 430.0735 -398.512747)
			(xy 430.080024 -398.495565) (xy 430.08042 -398.486376) (xy 430.08042 -397.99387) (xy 430.08002 -397.984682)
			(xy 430.073499 -397.967498) (xy 430.06772 -397.960342) (xy 430.045865 -397.934669) (xy 430.007775 -397.879036)
			(xy 429.976623 -397.819241) (xy 429.952857 -397.756145) (xy 429.93682 -397.690657) (xy 429.928743 -397.623719)
			(xy 429.928742 -397.556296) (xy 428.800497 -397.556296) (xy 428.803109 -397.561323) (xy 428.826783 -397.624323)
			(xy 428.842758 -397.689702) (xy 428.850805 -397.756521) (xy 428.850808 -397.823822) (xy 428.842768 -397.890642)
			(xy 428.8268 -397.956022) (xy 428.803132 -398.019025) (xy 428.772104 -398.078747) (xy 428.734161 -398.134333)
			(xy 428.712376 -398.159986) (xy 428.706558 -398.167116) (xy 428.700057 -398.184318) (xy 428.699676 -398.193514)
			(xy 428.699676 -398.351502) (xy 428.699169 -398.361658) (xy 428.691396 -398.380425) (xy 428.677035 -398.394789)
			(xy 428.65827 -398.402566) (xy 428.648114 -398.403064) (xy 427.931834 -398.403064) (xy 427.921665 -398.402608)
			(xy 427.902871 -398.394835) (xy 427.888485 -398.380459) (xy 427.880699 -398.361671) (xy 427.880272 -398.351502)
			(xy 427.880272 -398.193514) (xy 427.879861 -398.184327) (xy 427.873349 -398.167142) (xy 427.867572 -398.159986)
			(xy 427.845746 -398.134365) (xy 427.807796 -398.078775) (xy 427.776762 -398.019047) (xy 427.75309 -397.956039)
			(xy 427.737119 -397.890652) (xy 427.729077 -397.823826) (xy 426.600432 -397.823826) (xy 426.571969 -397.878596)
			(xy 426.534017 -397.934182) (xy 426.512228 -397.959834) (xy 426.506426 -397.966975) (xy 426.499917 -397.984169)
			(xy 426.499528 -397.993362) (xy 426.499528 -398.486884) (xy 426.499939 -398.496071) (xy 426.506451 -398.513256)
			(xy 426.512228 -398.520412) (xy 426.534052 -398.546034) (xy 426.572002 -398.601624) (xy 426.603036 -398.661352)
			(xy 426.626708 -398.72436) (xy 426.64268 -398.789746) (xy 426.650721 -398.856573) (xy 426.650718 -398.923881)
			(xy 426.64267 -398.990707) (xy 426.626692 -399.056092) (xy 426.603014 -399.119098) (xy 426.571974 -399.178822)
			(xy 426.534019 -399.234408) (xy 426.512228 -399.26006) (xy 426.506415 -399.267193) (xy 426.499912 -399.284393)
			(xy 426.499528 -399.293588) (xy 426.499528 -399.451576) (xy 426.499059 -399.461725) (xy 426.491277 -399.480472)
			(xy 426.476895 -399.494795) (xy 426.458117 -399.502501) (xy 426.447966 -399.502884) (xy 425.731686 -399.502884)
			(xy 425.721561 -399.502385) (xy 425.702845 -399.494657) (xy 425.68849 -399.480375) (xy 425.680667 -399.461698)
			(xy 425.680124 -399.451576) (xy 425.680124 -399.293588) (xy 425.679714 -399.284401) (xy 425.6732 -399.267217)
			(xy 425.667424 -399.26006) (xy 425.645672 -399.234378) (xy 425.607723 -399.178796) (xy 425.576689 -399.119076)
			(xy 425.553015 -399.056076) (xy 425.53704 -398.990697) (xy 425.528994 -398.923878) (xy 425.52899 -398.856576)
			(xy 425.537031 -398.789756) (xy 425.552999 -398.724376) (xy 425.576667 -398.661373) (xy 425.607696 -398.601651)
			(xy 425.645639 -398.546065) (xy 425.667424 -398.520412) (xy 425.673243 -398.513283) (xy 425.679744 -398.49608)
			(xy 425.680124 -398.486884) (xy 425.680124 -397.993362) (xy 425.679727 -397.984174) (xy 425.673204 -397.96699)
			(xy 425.667424 -397.959834) (xy 425.645646 -397.934174) (xy 425.607698 -397.878588) (xy 425.576665 -397.818865)
			(xy 425.552993 -397.755862) (xy 425.53702 -397.690481) (xy 425.528975 -397.62366) (xy 425.528974 -397.556356)
			(xy 424.40076 -397.556356) (xy 424.403152 -397.560947) (xy 424.426919 -397.62404) (xy 424.442958 -397.689526)
			(xy 424.451037 -397.756461) (xy 424.451041 -397.823882) (xy 424.442968 -397.890818) (xy 424.426936 -397.956305)
			(xy 424.403175 -398.019401) (xy 424.372028 -398.079196) (xy 424.333942 -398.134829) (xy 424.31208 -398.160494)
			(xy 424.306301 -398.167652) (xy 424.299777 -398.184833) (xy 424.29938 -398.194022) (xy 424.29938 -398.351502)
			(xy 424.298876 -398.361626) (xy 424.291151 -398.380344) (xy 424.27687 -398.394699) (xy 424.258194 -398.402522)
			(xy 424.248072 -398.403064) (xy 423.531792 -398.403064) (xy 423.521633 -398.402684) (xy 423.502873 -398.394879)
			(xy 423.488549 -398.380469) (xy 423.480856 -398.361663) (xy 423.480484 -398.351502) (xy 423.480484 -398.194022)
			(xy 423.480067 -398.184835) (xy 423.473558 -398.167651) (xy 423.467784 -398.160494) (xy 423.445883 -398.134859)
			(xy 423.407797 -398.07922) (xy 423.376649 -398.019419) (xy 423.352887 -397.956319) (xy 423.336855 -397.890826)
			(xy 423.328782 -397.823885) (xy 422.200615 -397.823885) (xy 422.171883 -397.879041) (xy 422.133795 -397.934676)
			(xy 422.111932 -397.960342) (xy 422.106127 -397.967481) (xy 422.099619 -397.984676) (xy 422.099232 -397.99387)
			(xy 422.099232 -398.486376) (xy 422.099669 -398.49556) (xy 422.106166 -398.512744) (xy 422.111932 -398.519904)
			(xy 422.13383 -398.545541) (xy 422.171916 -398.60118) (xy 422.203063 -398.66098) (xy 422.226824 -398.724081)
			(xy 422.242856 -398.789573) (xy 422.250928 -398.856514) (xy 422.250925 -398.92394) (xy 422.242846 -398.99088)
			(xy 422.226808 -399.056371) (xy 422.203041 -399.119469) (xy 422.171888 -399.179266) (xy 422.133797 -399.234902)
			(xy 422.111932 -399.260568) (xy 422.106116 -399.267699) (xy 422.099615 -399.284901) (xy 422.099232 -399.294096)
			(xy 422.099232 -399.451576) (xy 422.098696 -399.461679) (xy 422.090972 -399.480351) (xy 422.076691 -399.494645)
			(xy 422.058027 -399.502387) (xy 422.047924 -399.502884) (xy 421.331644 -399.502884) (xy 421.321522 -399.502447)
			(xy 421.302817 -399.494711) (xy 421.2885 -399.4804) (xy 421.280756 -399.461697) (xy 421.280336 -399.451576)
			(xy 421.280336 -399.294096) (xy 421.27992 -399.28491) (xy 421.27341 -399.267726) (xy 421.267636 -399.260568)
			(xy 421.245806 -399.234874) (xy 421.207714 -399.179245) (xy 421.17656 -399.119453) (xy 421.152792 -399.056359)
			(xy 421.136753 -398.990873) (xy 421.128674 -398.923938) (xy 421.12867 -398.856516) (xy 421.136743 -398.78958)
			(xy 421.152776 -398.724092) (xy 421.176538 -398.660997) (xy 421.207686 -398.601202) (xy 421.245773 -398.545569)
			(xy 421.267636 -398.519904) (xy 421.273418 -398.512749) (xy 421.27994 -398.495566) (xy 421.280336 -398.486376)
			(xy 421.280336 -397.99387) (xy 421.279932 -397.984682) (xy 421.273413 -397.967498) (xy 421.267636 -397.960342)
			(xy 421.245781 -397.934669) (xy 421.207689 -397.879037) (xy 421.176536 -397.819242) (xy 421.15277 -397.756146)
			(xy 421.136732 -397.690657) (xy 421.128655 -397.623719) (xy 421.128654 -397.556296) (xy 420.00041 -397.556296)
			(xy 420.003023 -397.561324) (xy 420.026696 -397.624324) (xy 420.042671 -397.689702) (xy 420.050718 -397.756521)
			(xy 420.050721 -397.823822) (xy 420.042681 -397.890642) (xy 420.026713 -397.956021) (xy 420.003046 -398.019024)
			(xy 419.972019 -398.078747) (xy 419.934077 -398.134334) (xy 419.912292 -398.159986) (xy 419.906475 -398.167117)
			(xy 419.899973 -398.184318) (xy 419.899592 -398.193514) (xy 419.899592 -398.351502) (xy 419.899069 -398.361656)
			(xy 419.891299 -398.38042) (xy 419.876943 -398.394784) (xy 419.858184 -398.402563) (xy 419.84803 -398.403064)
			(xy 419.13175 -398.403064) (xy 419.121582 -398.402595) (xy 419.102789 -398.394827) (xy 419.088402 -398.380455)
			(xy 419.080615 -398.36167) (xy 419.080188 -398.351502) (xy 419.080188 -398.193514) (xy 419.079774 -398.184327)
			(xy 419.073263 -398.167143) (xy 419.067488 -398.159986) (xy 419.045661 -398.134365) (xy 419.007711 -398.078775)
			(xy 418.976676 -398.019048) (xy 418.953004 -397.956039) (xy 418.937032 -397.890653) (xy 418.92899 -397.823826)
			(xy 414.525968 -397.823826) (xy 414.525968 -401.723737) (xy 418.929001 -401.723737) (xy 418.929003 -401.65643)
			(xy 418.93705 -401.589605) (xy 418.953027 -401.524221) (xy 418.976704 -401.461215) (xy 419.007743 -401.401491)
			(xy 419.045697 -401.345906) (xy 419.067488 -401.320254) (xy 419.073285 -401.313109) (xy 419.0798 -401.295918)
			(xy 419.080188 -401.286726) (xy 419.080188 -400.793458) (xy 419.079801 -400.784268) (xy 419.073272 -400.767084)
			(xy 419.067488 -400.75993) (xy 419.045705 -400.734274) (xy 419.007752 -400.678689) (xy 418.976716 -400.618966)
			(xy 418.953041 -400.555962) (xy 418.937066 -400.49058) (xy 418.929021 -400.423757) (xy 418.92902 -400.356452)
			(xy 418.937065 -400.289629) (xy 418.953038 -400.224246) (xy 418.976713 -400.161242) (xy 419.007748 -400.101519)
			(xy 419.045699 -400.045933) (xy 419.067488 -400.020282) (xy 419.073273 -400.013129) (xy 419.079795 -399.995944)
			(xy 419.080188 -399.986754) (xy 419.080188 -399.828766) (xy 419.080537 -399.818586) (xy 419.088343 -399.799781)
			(xy 419.102752 -399.785395) (xy 419.121569 -399.777621) (xy 419.13175 -399.777204) (xy 419.84803 -399.777204)
			(xy 419.858186 -399.777708) (xy 419.876949 -399.785486) (xy 419.891312 -399.799848) (xy 419.899091 -399.818611)
			(xy 419.899592 -399.828766) (xy 419.899592 -399.986754) (xy 419.900026 -399.995939) (xy 419.906523 -400.013123)
			(xy 419.912292 -400.020282) (xy 419.934085 -400.04593) (xy 419.972031 -400.101518) (xy 420.003063 -400.161242)
			(xy 420.026734 -400.224247) (xy 420.042705 -400.289629) (xy 420.050749 -400.356452) (xy 420.050748 -400.423757)
			(xy 420.042704 -400.490579) (xy 420.026731 -400.555962) (xy 420.003059 -400.618966) (xy 419.972027 -400.67869)
			(xy 419.934079 -400.734277) (xy 419.912292 -400.75993) (xy 419.906499 -400.767078) (xy 419.899983 -400.784266)
			(xy 419.899592 -400.793458) (xy 419.899592 -401.286726) (xy 419.899991 -401.295914) (xy 419.906513 -401.313099)
			(xy 419.912292 -401.320254) (xy 419.934057 -401.345924) (xy 419.972005 -401.401509) (xy 420.003037 -401.46123)
			(xy 420.02671 -401.524232) (xy 420.042683 -401.589612) (xy 420.050729 -401.656432) (xy 420.050731 -401.723735)
			(xy 420.042689 -401.790555) (xy 420.02672 -401.855936) (xy 420.003051 -401.918939) (xy 419.972022 -401.978663)
			(xy 419.934077 -402.034249) (xy 419.912292 -402.059902) (xy 419.906511 -402.067058) (xy 419.899987 -402.08424)
			(xy 419.899592 -402.09343) (xy 419.899592 -402.251418) (xy 419.899082 -402.261573) (xy 419.891308 -402.280337)
			(xy 419.876947 -402.294701) (xy 419.858185 -402.30248) (xy 419.84803 -402.30298) (xy 419.13175 -402.30298)
			(xy 419.121584 -402.302496) (xy 419.102794 -402.29473) (xy 419.088408 -402.280363) (xy 419.080618 -402.261584)
			(xy 419.080188 -402.251418) (xy 419.080188 -402.09343) (xy 419.079766 -402.084244) (xy 419.073261 -402.067059)
			(xy 419.067488 -402.059902) (xy 419.045677 -402.034268) (xy 419.007726 -401.97868) (xy 418.976691 -401.918955)
			(xy 418.953017 -401.855948) (xy 418.937044 -401.790563) (xy 418.929001 -401.723737) (xy 414.525968 -401.723737)
			(xy 414.525968 -402.823878) (xy 421.128614 -402.823878) (xy 421.128619 -402.75645) (xy 421.1367 -402.689508)
			(xy 421.152742 -402.624016) (xy 421.176513 -402.560916) (xy 421.207671 -402.501119) (xy 421.245768 -402.445485)
			(xy 421.267636 -402.41982) (xy 421.273454 -402.41269) (xy 421.279955 -402.395488) (xy 421.280336 -402.386292)
			(xy 421.280336 -401.89404) (xy 421.279898 -401.884856) (xy 421.273403 -401.867672) (xy 421.267636 -401.860512)
			(xy 421.245751 -401.834864) (xy 421.207661 -401.779227) (xy 421.176509 -401.719429) (xy 421.152744 -401.65633)
			(xy 421.136709 -401.590839) (xy 421.128634 -401.523898) (xy 421.128636 -401.456472) (xy 421.136714 -401.389532)
			(xy 421.152753 -401.324041) (xy 421.176521 -401.260943) (xy 421.207676 -401.201147) (xy 421.24577 -401.145513)
			(xy 421.267636 -401.119848) (xy 421.273442 -401.112709) (xy 421.27995 -401.095514) (xy 421.280336 -401.08632)
			(xy 421.280336 -400.92884) (xy 421.28075 -400.918716) (xy 421.288491 -400.900006) (xy 421.302809 -400.885689)
			(xy 421.32152 -400.877949) (xy 421.331644 -400.877532) (xy 422.047924 -400.877532) (xy 422.058052 -400.877897)
			(xy 422.076762 -400.885659) (xy 422.091077 -400.899991) (xy 422.098816 -400.918711) (xy 422.099232 -400.92884)
			(xy 422.099232 -401.08632) (xy 422.099648 -401.095506) (xy 422.106159 -401.11269) (xy 422.111932 -401.119848)
			(xy 422.133775 -401.14553) (xy 422.171862 -401.201163) (xy 422.203012 -401.260957) (xy 422.226776 -401.324052)
			(xy 422.242812 -401.389538) (xy 422.250889 -401.456474) (xy 422.250891 -401.523896) (xy 422.242817 -401.590832)
			(xy 422.226785 -401.65632) (xy 422.203024 -401.719415) (xy 422.200742 -401.723796) (xy 423.328794 -401.723796)
			(xy 423.328796 -401.656371) (xy 423.336873 -401.589431) (xy 423.352911 -401.523941) (xy 423.376677 -401.460844)
			(xy 423.407829 -401.401047) (xy 423.445919 -401.345412) (xy 423.467784 -401.319746) (xy 423.473584 -401.312603)
			(xy 423.480097 -401.295411) (xy 423.480484 -401.286218) (xy 423.480484 -400.793966) (xy 423.480094 -400.784777)
			(xy 423.473566 -400.767592) (xy 423.467784 -400.760438) (xy 423.445926 -400.734768) (xy 423.407839 -400.679133)
			(xy 423.376689 -400.619338) (xy 423.352925 -400.556242) (xy 423.336889 -400.490753) (xy 423.328813 -400.423816)
			(xy 423.328813 -400.356393) (xy 423.336888 -400.289455) (xy 423.352922 -400.223967) (xy 423.376685 -400.16087)
			(xy 423.407834 -400.101074) (xy 423.445921 -400.045439) (xy 423.467784 -400.019774) (xy 423.473572 -400.012623)
			(xy 423.480092 -399.995437) (xy 423.480484 -399.986246) (xy 423.480484 -399.828766) (xy 423.4809 -399.818632)
			(xy 423.488647 -399.799901) (xy 423.502955 -399.785545) (xy 423.521659 -399.777735) (xy 423.531792 -399.777204)
			(xy 424.248072 -399.777204) (xy 424.258225 -399.777644) (xy 424.276977 -399.785431) (xy 424.291302 -399.799823)
			(xy 424.299002 -399.818611) (xy 424.29938 -399.828766) (xy 424.29938 -399.986246) (xy 424.299821 -399.99543)
			(xy 424.306314 -400.012614) (xy 424.31208 -400.019774) (xy 424.333951 -400.045434) (xy 424.37204 -400.101069)
			(xy 424.403192 -400.160866) (xy 424.426957 -400.223963) (xy 424.442992 -400.289453) (xy 424.451068 -400.356392)
			(xy 424.451068 -400.423817) (xy 424.442991 -400.490756) (xy 424.426954 -400.556245) (xy 424.403188 -400.619343)
			(xy 424.372036 -400.679139) (xy 424.333945 -400.734773) (xy 424.31208 -400.760438) (xy 424.306282 -400.767582)
			(xy 424.299769 -400.784774) (xy 424.29938 -400.793966) (xy 424.29938 -401.286218) (xy 424.299786 -401.295406)
			(xy 424.306303 -401.31259) (xy 424.31208 -401.319746) (xy 424.333923 -401.345429) (xy 424.372014 -401.40106)
			(xy 424.403167 -401.460854) (xy 424.426933 -401.523949) (xy 424.44297 -401.589436) (xy 424.451048 -401.656372)
			(xy 424.45105 -401.723795) (xy 424.442976 -401.790732) (xy 424.426943 -401.85622) (xy 424.40318 -401.919316)
			(xy 424.372031 -401.979111) (xy 424.333943 -402.034745) (xy 424.31208 -402.06041) (xy 424.306294 -402.067563)
			(xy 424.299774 -402.084748) (xy 424.29938 -402.093938) (xy 424.29938 -402.251418) (xy 424.298889 -402.261543)
			(xy 424.291159 -402.280261) (xy 424.276874 -402.294616) (xy 424.258195 -402.302438) (xy 424.248072 -402.30298)
			(xy 423.531792 -402.30298) (xy 423.521635 -402.302584) (xy 423.502879 -402.294782) (xy 423.488555 -402.280378)
			(xy 423.480859 -402.261577) (xy 423.480484 -402.251418) (xy 423.480484 -402.093938) (xy 423.480059 -402.084752)
			(xy 423.473556 -402.067568) (xy 423.467784 -402.06041) (xy 423.445899 -402.034762) (xy 423.407812 -401.979125)
			(xy 423.376663 -401.919326) (xy 423.352901 -401.856227) (xy 423.336867 -401.790736) (xy 423.328794 -401.723796)
			(xy 422.200742 -401.723796) (xy 422.171878 -401.779211) (xy 422.133794 -401.834846) (xy 422.111932 -401.860512)
			(xy 422.10614 -401.86766) (xy 422.099624 -401.884849) (xy 422.099232 -401.89404) (xy 422.099232 -402.386292)
			(xy 422.099661 -402.395477) (xy 422.106163 -402.412661) (xy 422.111932 -402.41982) (xy 422.133748 -402.445525)
			(xy 422.171836 -402.501154) (xy 422.202987 -402.560945) (xy 422.226752 -402.624037) (xy 422.24279 -402.689521)
			(xy 422.250869 -402.756454) (xy 422.250874 -402.823818) (xy 425.528934 -402.823818) (xy 425.528938 -402.75651)
			(xy 425.536987 -402.689684) (xy 425.552965 -402.624299) (xy 425.576642 -402.561293) (xy 425.60768 -402.501568)
			(xy 425.645634 -402.44598) (xy 425.667424 -402.420328) (xy 425.673236 -402.413194) (xy 425.679741 -402.395995)
			(xy 425.680124 -402.3868) (xy 425.680124 -401.893532) (xy 425.679693 -401.884347) (xy 425.673193 -401.867163)
			(xy 425.667424 -401.860004) (xy 425.645617 -401.834368) (xy 425.60767 -401.778779) (xy 425.576638 -401.719053)
			(xy 425.552967 -401.656046) (xy 425.536996 -401.590662) (xy 425.528954 -401.523838) (xy 425.528956 -401.456532)
			(xy 425.537001 -401.389708) (xy 425.552976 -401.324325) (xy 425.57665 -401.26132) (xy 425.607685 -401.201595)
			(xy 425.645635 -401.146008) (xy 425.667424 -401.120356) (xy 425.673225 -401.113214) (xy 425.679736 -401.096021)
			(xy 425.680124 -401.086828) (xy 425.680124 -400.92884) (xy 425.680555 -400.918686) (xy 425.688342 -400.899929)
			(xy 425.702736 -400.885604) (xy 425.72153 -400.877907) (xy 425.731686 -400.877532) (xy 426.447966 -400.877532)
			(xy 426.45809 -400.878054) (xy 426.476808 -400.88577) (xy 426.491165 -400.900045) (xy 426.498987 -400.918719)
			(xy 426.499528 -400.92884) (xy 426.499528 -401.086828) (xy 426.499918 -401.096017) (xy 426.506445 -401.113202)
			(xy 426.512228 -401.120356) (xy 426.533997 -401.146024) (xy 426.571949 -401.201607) (xy 426.602985 -401.261328)
			(xy 426.62666 -401.324331) (xy 426.642635 -401.389712) (xy 426.650681 -401.456533) (xy 426.650683 -401.523837)
			(xy 426.642641 -401.590659) (xy 426.626669 -401.65604) (xy 426.602997 -401.719044) (xy 426.600558 -401.723737)
			(xy 427.729089 -401.723737) (xy 427.729091 -401.65643) (xy 427.737138 -401.589605) (xy 427.753114 -401.524221)
			(xy 427.776791 -401.461216) (xy 427.807828 -401.401492) (xy 427.845782 -401.345906) (xy 427.867572 -401.320254)
			(xy 427.873379 -401.313117) (xy 427.879886 -401.29592) (xy 427.880272 -401.286726) (xy 427.880272 -400.793458)
			(xy 427.879888 -400.784268) (xy 427.873357 -400.767084) (xy 427.867572 -400.75993) (xy 427.845789 -400.734273)
			(xy 427.807838 -400.678688) (xy 427.776803 -400.618966) (xy 427.753128 -400.555962) (xy 427.737154 -400.49058)
			(xy 427.729109 -400.423757) (xy 427.729108 -400.356452) (xy 427.737152 -400.289629) (xy 427.753126 -400.224247)
			(xy 427.776799 -400.161243) (xy 427.807833 -400.101519) (xy 427.845784 -400.045934) (xy 427.867572 -400.020282)
			(xy 427.873367 -400.013136) (xy 427.879881 -399.995946) (xy 427.880272 -399.986754) (xy 427.880272 -399.828766)
			(xy 427.880706 -399.818602) (xy 427.888498 -399.799825) (xy 427.902883 -399.78546) (xy 427.921669 -399.777693)
			(xy 427.931834 -399.777204) (xy 428.648114 -399.777204) (xy 428.658268 -399.777721) (xy 428.677031 -399.785494)
			(xy 428.691395 -399.799852) (xy 428.699175 -399.818612) (xy 428.699676 -399.828766) (xy 428.699676 -399.986754)
			(xy 428.700114 -399.995938) (xy 428.706609 -400.013122) (xy 428.712376 -400.020282) (xy 428.734169 -400.045929)
			(xy 428.772117 -400.101517) (xy 428.803149 -400.161241) (xy 428.826821 -400.224246) (xy 428.842793 -400.289629)
			(xy 428.850836 -400.356452) (xy 428.850836 -400.423757) (xy 428.842791 -400.49058) (xy 428.826818 -400.555962)
			(xy 428.803145 -400.618967) (xy 428.772112 -400.678691) (xy 428.734164 -400.734278) (xy 428.712376 -400.75993)
			(xy 428.706581 -400.767076) (xy 428.700066 -400.784266) (xy 428.699676 -400.793458) (xy 428.699676 -401.286726)
			(xy 428.700079 -401.295914) (xy 428.706598 -401.313098) (xy 428.712376 -401.320254) (xy 428.734142 -401.345924)
			(xy 428.77209 -401.401508) (xy 428.803124 -401.46123) (xy 428.826797 -401.524232) (xy 428.842771 -401.589612)
			(xy 428.850817 -401.656432) (xy 428.850819 -401.723735) (xy 428.842777 -401.790556) (xy 428.826807 -401.855937)
			(xy 428.803137 -401.91894) (xy 428.772107 -401.978663) (xy 428.734162 -402.03425) (xy 428.712376 -402.059902)
			(xy 428.706593 -402.067057) (xy 428.700071 -402.08424) (xy 428.699676 -402.09343) (xy 428.699676 -402.251418)
			(xy 428.699182 -402.261575) (xy 428.691404 -402.280342) (xy 428.677039 -402.294706) (xy 428.658271 -402.302483)
			(xy 428.648114 -402.30298) (xy 427.931834 -402.30298) (xy 427.921667 -402.302509) (xy 427.902876 -402.294738)
			(xy 427.888491 -402.280367) (xy 427.880702 -402.261585) (xy 427.880272 -402.251418) (xy 427.880272 -402.09343)
			(xy 427.879854 -402.084244) (xy 427.873347 -402.067059) (xy 427.867572 -402.059902) (xy 427.845762 -402.034268)
			(xy 427.807811 -401.97868) (xy 427.776777 -401.918954) (xy 427.753104 -401.855947) (xy 427.737132 -401.790562)
			(xy 427.729089 -401.723737) (xy 426.600558 -401.723737) (xy 426.571964 -401.778767) (xy 426.534015 -401.834352)
			(xy 426.512228 -401.860004) (xy 426.506438 -401.867154) (xy 426.499922 -401.884341) (xy 426.499528 -401.893532)
			(xy 426.499528 -402.3868) (xy 426.499932 -402.395988) (xy 426.506449 -402.413173) (xy 426.512228 -402.420328)
			(xy 426.53397 -402.446019) (xy 426.571922 -402.501599) (xy 426.602959 -402.561317) (xy 426.626636 -402.624316)
			(xy 426.642613 -402.689694) (xy 426.650662 -402.756513) (xy 426.650666 -402.823815) (xy 426.650658 -402.823878)
			(xy 429.928702 -402.823878) (xy 429.928707 -402.75645) (xy 429.936788 -402.689508) (xy 429.952829 -402.624016)
			(xy 429.976599 -402.560917) (xy 430.007757 -402.50112) (xy 430.045852 -402.445485) (xy 430.06772 -402.41982)
			(xy 430.073535 -402.412688) (xy 430.080038 -402.395487) (xy 430.08042 -402.386292) (xy 430.08042 -401.89404)
			(xy 430.079986 -401.884855) (xy 430.073488 -401.867671) (xy 430.06772 -401.860512) (xy 430.045836 -401.834863)
			(xy 430.007746 -401.779227) (xy 429.976595 -401.719429) (xy 429.952831 -401.656329) (xy 429.936797 -401.590838)
			(xy 429.928722 -401.523898) (xy 429.928724 -401.456472) (xy 429.936802 -401.389532) (xy 429.95284 -401.324042)
			(xy 429.976608 -401.260944) (xy 430.007762 -401.201147) (xy 430.045854 -401.145513) (xy 430.06772 -401.119848)
			(xy 430.073523 -401.112708) (xy 430.080033 -401.095513) (xy 430.08042 -401.08632) (xy 430.08042 -400.92884)
			(xy 430.080849 -400.918718) (xy 430.088588 -400.900011) (xy 430.102901 -400.885695) (xy 430.121606 -400.877952)
			(xy 430.131728 -400.877532) (xy 430.848008 -400.877532) (xy 430.858135 -400.87791) (xy 430.876845 -400.885667)
			(xy 430.89116 -400.899996) (xy 430.898899 -400.918713) (xy 430.899316 -400.92884) (xy 430.899316 -401.08632)
			(xy 430.899713 -401.095509) (xy 430.906236 -401.112693) (xy 430.912016 -401.119848) (xy 430.93386 -401.14553)
			(xy 430.971948 -401.201162) (xy 431.003099 -401.260956) (xy 431.026863 -401.324051) (xy 431.0429 -401.389538)
			(xy 431.050977 -401.456474) (xy 431.050979 -401.523896) (xy 431.042905 -401.590832) (xy 431.026872 -401.65632)
			(xy 431.003111 -401.719416) (xy 431.00086 -401.723737) (xy 432.128879 -401.723737) (xy 432.128881 -401.65643)
			(xy 432.136928 -401.589605) (xy 432.152904 -401.524222) (xy 432.17658 -401.461216) (xy 432.207617 -401.401492)
			(xy 432.24557 -401.345906) (xy 432.26736 -401.320254) (xy 432.273166 -401.313116) (xy 432.279673 -401.29592)
			(xy 432.28006 -401.286726) (xy 432.28006 -400.793458) (xy 432.279657 -400.78427) (xy 432.273137 -400.767087)
			(xy 432.26736 -400.75993) (xy 432.245578 -400.734273) (xy 432.207627 -400.678688) (xy 432.176593 -400.618965)
			(xy 432.152919 -400.555961) (xy 432.136945 -400.490579) (xy 432.1289 -400.423757) (xy 432.128899 -400.356452)
			(xy 432.136943 -400.28963) (xy 432.152916 -400.224247) (xy 432.176589 -400.161243) (xy 432.207623 -400.10152)
			(xy 432.245572 -400.045934) (xy 432.26736 -400.020282) (xy 432.273154 -400.013135) (xy 432.279669 -399.995946)
			(xy 432.28006 -399.986754) (xy 432.28006 -399.828766) (xy 432.280506 -399.818603) (xy 432.288296 -399.799829)
			(xy 432.302676 -399.785464) (xy 432.321459 -399.777695) (xy 432.331622 -399.777204) (xy 433.047902 -399.777204)
			(xy 433.058056 -399.777731) (xy 433.076818 -399.7855) (xy 433.091182 -399.799855) (xy 433.098963 -399.818613)
			(xy 433.099464 -399.828766) (xy 433.099464 -399.986754) (xy 433.099905 -399.995938) (xy 433.106398 -400.013122)
			(xy 433.112164 -400.020282) (xy 433.133958 -400.045929) (xy 433.171906 -400.101516) (xy 433.202939 -400.161241)
			(xy 433.226611 -400.224246) (xy 433.242584 -400.289629) (xy 433.250627 -400.356452) (xy 433.250627 -400.423757)
			(xy 433.242582 -400.49058) (xy 433.226609 -400.555963) (xy 433.202935 -400.618968) (xy 433.171901 -400.678691)
			(xy 433.133952 -400.734278) (xy 433.112164 -400.75993) (xy 433.106368 -400.767075) (xy 433.099854 -400.784266)
			(xy 433.099464 -400.793458) (xy 433.099464 -401.286726) (xy 433.09987 -401.295913) (xy 433.106387 -401.313097)
			(xy 433.112164 -401.320254) (xy 433.13393 -401.345924) (xy 433.171879 -401.401508) (xy 433.202913 -401.461229)
			(xy 433.226587 -401.524231) (xy 433.242561 -401.589611) (xy 433.250607 -401.656432) (xy 433.250609 -401.723735)
			(xy 433.242567 -401.790556) (xy 433.226597 -401.855937) (xy 433.202927 -401.918941) (xy 433.171896 -401.978663)
			(xy 433.13395 -402.03425) (xy 433.112164 -402.059902) (xy 433.106379 -402.067056) (xy 433.099858 -402.08424)
			(xy 433.099464 -402.09343) (xy 433.099464 -402.251418) (xy 433.098982 -402.261577) (xy 433.091202 -402.280346)
			(xy 433.076833 -402.294711) (xy 433.058061 -402.302485) (xy 433.047902 -402.30298) (xy 432.331622 -402.30298)
			(xy 432.321454 -402.302518) (xy 432.302663 -402.294744) (xy 432.288278 -402.28037) (xy 432.28049 -402.261586)
			(xy 432.28006 -402.251418) (xy 432.28006 -402.09343) (xy 432.279622 -402.084246) (xy 432.273126 -402.067062)
			(xy 432.26736 -402.059902) (xy 432.24555 -402.034268) (xy 432.2076 -401.97868) (xy 432.176567 -401.918954)
			(xy 432.152894 -401.855947) (xy 432.136922 -401.790562) (xy 432.128879 -401.723737) (xy 431.00086 -401.723737)
			(xy 430.971963 -401.779212) (xy 430.933878 -401.834847) (xy 430.912016 -401.860512) (xy 430.906234 -401.867667)
			(xy 430.89971 -401.88485) (xy 430.899316 -401.89404) (xy 430.899316 -402.386292) (xy 430.899726 -402.395479)
			(xy 430.90624 -402.412664) (xy 430.912016 -402.41982) (xy 430.933832 -402.445524) (xy 430.971921 -402.501154)
			(xy 431.003073 -402.560945) (xy 431.026839 -402.624036) (xy 431.042878 -402.68952) (xy 431.050957 -402.756454)
			(xy 431.050962 -402.823818) (xy 434.329022 -402.823818) (xy 434.329026 -402.75651) (xy 434.337075 -402.689684)
			(xy 434.353052 -402.6243) (xy 434.376729 -402.561294) (xy 434.407766 -402.501568) (xy 434.445718 -402.445981)
			(xy 434.467508 -402.420328) (xy 434.473319 -402.413193) (xy 434.479825 -402.395995) (xy 434.480208 -402.3868)
			(xy 434.480208 -401.893532) (xy 434.479781 -401.884347) (xy 434.473279 -401.867162) (xy 434.467508 -401.860004)
			(xy 434.445702 -401.834368) (xy 434.407755 -401.778778) (xy 434.376725 -401.719052) (xy 434.353054 -401.656046)
			(xy 434.337084 -401.590662) (xy 434.329042 -401.523838) (xy 434.329043 -401.456532) (xy 434.337089 -401.389709)
			(xy 434.353063 -401.324326) (xy 434.376737 -401.26132) (xy 434.407771 -401.201596) (xy 434.44572 -401.146009)
			(xy 434.467508 -401.120356) (xy 434.473307 -401.113212) (xy 434.47982 -401.096021) (xy 434.480208 -401.086828)
			(xy 434.480208 -400.92884) (xy 434.480655 -400.918688) (xy 434.488438 -400.899934) (xy 434.502828 -400.885609)
			(xy 434.521616 -400.87791) (xy 434.53177 -400.877532) (xy 435.24805 -400.877532) (xy 435.258173 -400.878067)
			(xy 435.276891 -400.885777) (xy 435.291249 -400.900049) (xy 435.299071 -400.918721) (xy 435.299612 -400.92884)
			(xy 435.299612 -401.086828) (xy 435.300006 -401.096017) (xy 435.306531 -401.113201) (xy 435.312312 -401.120356)
			(xy 435.334082 -401.146024) (xy 435.372034 -401.201607) (xy 435.403071 -401.261328) (xy 435.426747 -401.32433)
			(xy 435.442723 -401.389711) (xy 435.450769 -401.456533) (xy 435.450771 -401.523837) (xy 435.442728 -401.590659)
			(xy 435.426756 -401.656041) (xy 435.403083 -401.719045) (xy 435.37205 -401.778767) (xy 435.3341 -401.834353)
			(xy 435.312312 -401.860004) (xy 435.306533 -401.867161) (xy 435.300007 -401.884343) (xy 435.299612 -401.893532)
			(xy 435.299612 -402.3868) (xy 435.30002 -402.395988) (xy 435.306535 -402.413172) (xy 435.312312 -402.420328)
			(xy 435.334054 -402.446018) (xy 435.372008 -402.501598) (xy 435.403046 -402.561316) (xy 435.426723 -402.624316)
			(xy 435.442701 -402.689694) (xy 435.45075 -402.756513) (xy 435.450754 -402.823815) (xy 435.442714 -402.890635)
			(xy 435.426745 -402.956015) (xy 435.403075 -403.019018) (xy 435.372045 -403.07874) (xy 435.334098 -403.134325)
			(xy 435.312312 -403.159976) (xy 435.306502 -403.167112) (xy 435.299995 -403.184309) (xy 435.299612 -403.193504)
			(xy 435.299612 -403.351492) (xy 435.299172 -403.361644) (xy 435.291381 -403.380394) (xy 435.27699 -403.394717)
			(xy 435.258204 -403.402419) (xy 435.24805 -403.4028) (xy 434.53177 -403.4028) (xy 434.521646 -403.402299)
			(xy 434.502932 -403.394569) (xy 434.488578 -403.380288) (xy 434.480753 -403.361613) (xy 434.480208 -403.351492)
			(xy 434.480208 -403.193504) (xy 434.479794 -403.184317) (xy 434.473283 -403.167133) (xy 434.467508 -403.159976)
			(xy 434.445674 -403.134362) (xy 434.407729 -403.07877) (xy 434.376699 -403.01904) (xy 434.353031 -402.956031)
			(xy 434.337062 -402.890644) (xy 434.329022 -402.823818) (xy 431.050962 -402.823818) (xy 431.050962 -402.823874)
			(xy 431.042891 -402.890808) (xy 431.026861 -402.956295) (xy 431.003103 -403.019389) (xy 430.971958 -403.079184)
			(xy 430.933877 -403.134819) (xy 430.912016 -403.160484) (xy 430.906203 -403.167618) (xy 430.899698 -403.184817)
			(xy 430.899316 -403.194012) (xy 430.899316 -403.351492) (xy 430.898809 -403.361598) (xy 430.891077 -403.380273)
			(xy 430.876787 -403.394568) (xy 430.858114 -403.402306) (xy 430.848008 -403.4028) (xy 430.131728 -403.4028)
			(xy 430.121607 -403.402361) (xy 430.102904 -403.394622) (xy 430.088589 -403.380313) (xy 430.080843 -403.361613)
			(xy 430.08042 -403.351492) (xy 430.08042 -403.194012) (xy 430.079999 -403.184826) (xy 430.073492 -403.167642)
			(xy 430.06772 -403.160484) (xy 430.045808 -403.134858) (xy 430.00772 -403.079218) (xy 429.97657 -403.019417)
			(xy 429.952807 -402.956315) (xy 429.936775 -402.890821) (xy 429.928702 -402.823878) (xy 426.650658 -402.823878)
			(xy 426.642626 -402.890635) (xy 426.626657 -402.956015) (xy 426.602989 -403.019017) (xy 426.571959 -403.078739)
			(xy 426.534014 -403.134324) (xy 426.512228 -403.159976) (xy 426.506408 -403.167104) (xy 426.499909 -403.184308)
			(xy 426.499528 -403.193504) (xy 426.499528 -403.351492) (xy 426.499072 -403.361642) (xy 426.491285 -403.380389)
			(xy 426.476899 -403.394712) (xy 426.458118 -403.402417) (xy 426.447966 -403.4028) (xy 425.731686 -403.4028)
			(xy 425.721563 -403.402286) (xy 425.70285 -403.394561) (xy 425.688495 -403.380284) (xy 425.68067 -403.361612)
			(xy 425.680124 -403.351492) (xy 425.680124 -403.193504) (xy 425.679707 -403.184318) (xy 425.673198 -403.167133)
			(xy 425.667424 -403.159976) (xy 425.64559 -403.134362) (xy 425.607643 -403.07877) (xy 425.576613 -403.019041)
			(xy 425.552943 -402.956032) (xy 425.536974 -402.890645) (xy 425.528934 -402.823818) (xy 422.250874 -402.823818)
			(xy 422.250874 -402.823874) (xy 422.242803 -402.890808) (xy 422.226774 -402.956294) (xy 422.203016 -403.019389)
			(xy 422.171873 -403.079184) (xy 422.133792 -403.134818) (xy 422.111932 -403.160484) (xy 422.106109 -403.16761)
			(xy 422.099612 -403.184816) (xy 422.099232 -403.194012) (xy 422.099232 -403.351492) (xy 422.098709 -403.361596)
			(xy 422.09098 -403.380268) (xy 422.076695 -403.394562) (xy 422.058028 -403.402303) (xy 422.047924 -403.4028)
			(xy 421.331644 -403.4028) (xy 421.321524 -403.402348) (xy 421.302822 -403.394614) (xy 421.288506 -403.380308)
			(xy 421.280759 -403.361611) (xy 421.280336 -403.351492) (xy 421.280336 -403.194012) (xy 421.279912 -403.184826)
			(xy 421.273407 -403.167642) (xy 421.267636 -403.160484) (xy 421.245724 -403.134858) (xy 421.207634 -403.079219)
			(xy 421.176483 -403.019418) (xy 421.15272 -402.956315) (xy 421.136687 -402.890821) (xy 421.128614 -402.823878)
			(xy 414.525968 -402.823878) (xy 414.525968 -405.623649) (xy 418.929012 -405.623649) (xy 418.929013 -405.556342)
			(xy 418.937058 -405.489518) (xy 418.953033 -405.424135) (xy 418.976709 -405.36113) (xy 419.007746 -405.301407)
			(xy 419.045698 -405.245822) (xy 419.067488 -405.22017) (xy 419.073278 -405.21302) (xy 419.079797 -405.195833)
			(xy 419.080188 -405.186642) (xy 419.080188 -404.693374) (xy 419.079793 -404.684185) (xy 419.073269 -404.667001)
			(xy 419.067488 -404.659846) (xy 419.04572 -404.634177) (xy 419.007768 -404.578594) (xy 418.976731 -404.518873)
			(xy 418.953055 -404.455871) (xy 418.937079 -404.39049) (xy 418.929032 -404.323669) (xy 418.92903 -404.256364)
			(xy 418.937073 -404.189542) (xy 418.953045 -404.124161) (xy 418.976717 -404.061157) (xy 419.007751 -404.001435)
			(xy 419.0457 -403.945849) (xy 419.067488 -403.920198) (xy 419.073267 -403.91304) (xy 419.079792 -403.895859)
			(xy 419.080188 -403.88667) (xy 419.080188 -403.728682) (xy 419.08055 -403.718503) (xy 419.088351 -403.699698)
			(xy 419.102756 -403.685313) (xy 419.12157 -403.677537) (xy 419.13175 -403.67712) (xy 419.84803 -403.67712)
			(xy 419.858187 -403.677608) (xy 419.876954 -403.685389) (xy 419.891317 -403.699756) (xy 419.899094 -403.718524)
			(xy 419.899592 -403.728682) (xy 419.899592 -403.88667) (xy 419.900018 -403.895855) (xy 419.906521 -403.91304)
			(xy 419.912292 -403.920198) (xy 419.9341 -403.945833) (xy 419.972047 -404.001422) (xy 420.003077 -404.061149)
			(xy 420.026747 -404.124155) (xy 420.042718 -404.189539) (xy 420.05076 -404.256363) (xy 420.050758 -404.32367)
			(xy 420.042712 -404.390493) (xy 420.026738 -404.455876) (xy 420.003064 -404.518882) (xy 419.97203 -404.578606)
			(xy 419.93408 -404.634193) (xy 419.912292 -404.659846) (xy 419.906492 -404.666989) (xy 419.89998 -404.684181)
			(xy 419.899592 -404.693374) (xy 419.899592 -405.186642) (xy 419.899984 -405.195831) (xy 419.90651 -405.213015)
			(xy 419.912292 -405.22017) (xy 419.934073 -405.245827) (xy 419.97202 -405.301414) (xy 420.003052 -405.361137)
			(xy 420.026723 -405.424141) (xy 420.042696 -405.489522) (xy 420.05074 -405.556343) (xy 420.050741 -405.623647)
			(xy 420.042698 -405.690469) (xy 420.026726 -405.755851) (xy 420.003055 -405.818855) (xy 419.972025 -405.878578)
			(xy 419.934078 -405.934165) (xy 419.912292 -405.959818) (xy 419.906504 -405.96697) (xy 419.899985 -405.984155)
			(xy 419.899592 -405.993346) (xy 419.899592 -406.151334) (xy 419.899095 -406.16149) (xy 419.891315 -406.180254)
			(xy 419.876951 -406.194617) (xy 419.858186 -406.202396) (xy 419.84803 -406.202896) (xy 419.13175 -406.202896)
			(xy 419.121586 -406.202396) (xy 419.102799 -406.194634) (xy 419.088413 -406.180272) (xy 419.08062 -406.161497)
			(xy 419.080188 -406.151334) (xy 419.080188 -405.993346) (xy 419.079759 -405.984161) (xy 419.073259 -405.966976)
			(xy 419.067488 -405.959818) (xy 419.045693 -405.934171) (xy 419.007741 -405.878585) (xy 418.976705 -405.818861)
			(xy 418.953031 -405.755856) (xy 418.937057 -405.690473) (xy 418.929012 -405.623649) (xy 414.525968 -405.623649)
			(xy 414.525968 -406.723789) (xy 421.128626 -406.723789) (xy 421.128629 -406.656363) (xy 421.136708 -406.589421)
			(xy 421.152748 -406.52393) (xy 421.176518 -406.460832) (xy 421.207674 -406.401035) (xy 421.245769 -406.345401)
			(xy 421.267636 -406.319736) (xy 421.273447 -406.312601) (xy 421.279952 -406.295403) (xy 421.280336 -406.286208)
			(xy 421.280336 -405.793956) (xy 421.279939 -405.784768) (xy 421.273415 -405.767584) (xy 421.267636 -405.760428)
			(xy 421.245767 -405.734767) (xy 421.207676 -405.679132) (xy 421.176523 -405.619336) (xy 421.152758 -405.556239)
			(xy 421.136722 -405.490749) (xy 421.128645 -405.423809) (xy 421.128646 -405.356385) (xy 421.136723 -405.289445)
			(xy 421.15276 -405.223956) (xy 421.176526 -405.160859) (xy 421.207679 -405.101062) (xy 421.245771 -405.045429)
			(xy 421.267636 -405.019764) (xy 421.273435 -405.012621) (xy 421.279947 -404.995429) (xy 421.280336 -404.986236)
			(xy 421.280336 -404.828756) (xy 421.28075 -404.81864) (xy 421.288509 -404.799954) (xy 421.302828 -404.785659)
			(xy 421.321527 -404.777933) (xy 421.331644 -404.777448) (xy 422.047924 -404.777448) (xy 422.058028 -404.777964)
			(xy 422.076697 -404.7857) (xy 422.090989 -404.799986) (xy 422.098732 -404.818652) (xy 422.099232 -404.828756)
			(xy 422.099232 -404.986236) (xy 422.09964 -404.995423) (xy 422.106157 -405.012607) (xy 422.111932 -405.019764)
			(xy 422.133791 -405.045433) (xy 422.171878 -405.101068) (xy 422.203027 -405.160864) (xy 422.22679 -405.22396)
			(xy 422.242825 -405.289448) (xy 422.2509 -405.356386) (xy 422.250901 -405.423808) (xy 422.242826 -405.490746)
			(xy 422.226792 -405.556234) (xy 422.203029 -405.619331) (xy 422.20075 -405.623707) (xy 423.328805 -405.623707)
			(xy 423.328805 -405.556284) (xy 423.336882 -405.489345) (xy 423.352917 -405.423856) (xy 423.376681 -405.360759)
			(xy 423.407832 -405.300962) (xy 423.44592 -405.245328) (xy 423.467784 -405.219662) (xy 423.473577 -405.212514)
			(xy 423.480094 -405.195326) (xy 423.480484 -405.186134) (xy 423.480484 -404.693882) (xy 423.480086 -404.684693)
			(xy 423.473564 -404.667509) (xy 423.467784 -404.660354) (xy 423.445942 -404.634671) (xy 423.407854 -404.579038)
			(xy 423.376703 -404.519245) (xy 423.352938 -404.45615) (xy 423.336902 -404.390663) (xy 423.328825 -404.323727)
			(xy 423.328823 -404.256306) (xy 423.336896 -404.189369) (xy 423.352929 -404.123882) (xy 423.37669 -404.060786)
			(xy 423.407837 -404.00099) (xy 423.445922 -403.945355) (xy 423.467784 -403.91969) (xy 423.473565 -403.912534)
			(xy 423.48009 -403.895352) (xy 423.480484 -403.886162) (xy 423.480484 -403.728682) (xy 423.480913 -403.718549)
			(xy 423.488655 -403.699819) (xy 423.502959 -403.685461) (xy 423.521661 -403.677651) (xy 423.531792 -403.67712)
			(xy 424.248072 -403.67712) (xy 424.258227 -403.677545) (xy 424.276983 -403.685335) (xy 424.291308 -403.699731)
			(xy 424.299005 -403.718525) (xy 424.29938 -403.728682) (xy 424.29938 -403.886162) (xy 424.299813 -403.895347)
			(xy 424.306311 -403.912531) (xy 424.31208 -403.91969) (xy 424.333966 -403.945337) (xy 424.372056 -404.000974)
			(xy 424.403207 -404.060772) (xy 424.42697 -404.123872) (xy 424.443005 -404.189363) (xy 424.451079 -404.256304)
			(xy 424.451077 -404.323729) (xy 424.442999 -404.39067) (xy 424.426961 -404.45616) (xy 424.403193 -404.519258)
			(xy 424.372039 -404.579055) (xy 424.333946 -404.634689) (xy 424.31208 -404.660354) (xy 424.306276 -404.667494)
			(xy 424.299766 -404.684688) (xy 424.29938 -404.693882) (xy 424.29938 -405.186134) (xy 424.299778 -405.195322)
			(xy 424.306301 -405.212506) (xy 424.31208 -405.219662) (xy 424.333939 -405.245332) (xy 424.372029 -405.300965)
			(xy 424.403181 -405.360761) (xy 424.426946 -405.423857) (xy 424.442983 -405.489346) (xy 424.45106 -405.556284)
			(xy 424.45106 -405.623707) (xy 424.442985 -405.690646) (xy 424.426949 -405.756134) (xy 424.403185 -405.819231)
			(xy 424.372034 -405.879027) (xy 424.333944 -405.934661) (xy 424.31208 -405.960326) (xy 424.306288 -405.967474)
			(xy 424.299771 -405.984662) (xy 424.29938 -405.993854) (xy 424.29938 -406.151334) (xy 424.298902 -406.16146)
			(xy 424.291167 -406.180179) (xy 424.276878 -406.194533) (xy 424.258196 -406.202355) (xy 424.248072 -406.202896)
			(xy 423.531792 -406.202896) (xy 423.521637 -406.202485) (xy 423.502884 -406.194686) (xy 423.48856 -406.180286)
			(xy 423.480862 -406.161491) (xy 423.480484 -406.151334) (xy 423.480484 -405.993854) (xy 423.480051 -405.984669)
			(xy 423.473553 -405.967484) (xy 423.467784 -405.960326) (xy 423.445915 -405.934665) (xy 423.407827 -405.87903)
			(xy 423.376678 -405.819233) (xy 423.352915 -405.756135) (xy 423.33688 -405.690646) (xy 423.328805 -405.623707)
			(xy 422.20075 -405.623707) (xy 422.171881 -405.679127) (xy 422.133795 -405.734762) (xy 422.111932 -405.760428)
			(xy 422.106133 -405.767571) (xy 422.099622 -405.784763) (xy 422.099232 -405.793956) (xy 422.099232 -406.286208)
			(xy 422.099654 -406.295394) (xy 422.106161 -406.312577) (xy 422.111932 -406.319736) (xy 422.133763 -406.345428)
			(xy 422.171851 -406.401059) (xy 422.203001 -406.460852) (xy 422.226766 -406.523945) (xy 422.242803 -406.589431)
			(xy 422.250881 -406.656366) (xy 422.250883 -406.72373) (xy 425.528945 -406.72373) (xy 425.528948 -406.656422)
			(xy 425.536995 -406.589598) (xy 425.552971 -406.524214) (xy 425.576647 -406.461208) (xy 425.607683 -406.401484)
			(xy 425.645635 -406.345896) (xy 425.667424 -406.320244) (xy 425.67323 -406.313105) (xy 425.679738 -406.29591)
			(xy 425.680124 -406.286716) (xy 425.680124 -405.793448) (xy 425.679685 -405.784264) (xy 425.673191 -405.76708)
			(xy 425.667424 -405.75992) (xy 425.645633 -405.734271) (xy 425.607685 -405.678684) (xy 425.576653 -405.61896)
			(xy 425.552981 -405.555955) (xy 425.537009 -405.490572) (xy 425.528965 -405.42375) (xy 425.528965 -405.356444)
			(xy 425.53701 -405.289622) (xy 425.552983 -405.22424) (xy 425.576655 -405.161235) (xy 425.607688 -405.101511)
			(xy 425.645636 -405.045924) (xy 425.667424 -405.020272) (xy 425.673218 -405.013125) (xy 425.679733 -404.995936)
			(xy 425.680124 -404.986744) (xy 425.680124 -404.828756) (xy 425.680486 -404.818596) (xy 425.688301 -404.799838)
			(xy 425.702716 -404.785515) (xy 425.721523 -404.777822) (xy 425.731686 -404.777448) (xy 426.447966 -404.777448)
			(xy 426.458091 -404.777955) (xy 426.476813 -404.785673) (xy 426.491171 -404.799953) (xy 426.49899 -404.818633)
			(xy 426.499528 -404.828756) (xy 426.499528 -404.986744) (xy 426.499911 -404.995934) (xy 426.506443 -405.013119)
			(xy 426.512228 -405.020272) (xy 426.534013 -405.045927) (xy 426.571964 -405.101512) (xy 426.602999 -405.161235)
			(xy 426.626674 -405.224239) (xy 426.642648 -405.289622) (xy 426.650693 -405.356444) (xy 426.650693 -405.42375)
			(xy 426.642649 -405.490573) (xy 426.626675 -405.555955) (xy 426.603002 -405.618959) (xy 426.600565 -405.623649)
			(xy 427.7291 -405.623649) (xy 427.729101 -405.556342) (xy 427.737146 -405.489519) (xy 427.753121 -405.424136)
			(xy 427.776796 -405.361131) (xy 427.807831 -405.301408) (xy 427.845783 -405.245822) (xy 427.867572 -405.22017)
			(xy 427.873373 -405.213028) (xy 427.879883 -405.195835) (xy 427.880272 -405.186642) (xy 427.880272 -404.693374)
			(xy 427.879881 -404.684185) (xy 427.873355 -404.667) (xy 427.867572 -404.659846) (xy 427.845805 -404.634176)
			(xy 427.807853 -404.578593) (xy 427.776817 -404.518872) (xy 427.753142 -404.45587) (xy 427.737166 -404.39049)
			(xy 427.72912 -404.323668) (xy 427.729118 -404.256365) (xy 427.73716 -404.189543) (xy 427.753132 -404.124162)
			(xy 427.776804 -404.061158) (xy 427.807836 -404.001435) (xy 427.845785 -403.94585) (xy 427.867572 -403.920198)
			(xy 427.873361 -403.913048) (xy 427.879878 -403.895861) (xy 427.880272 -403.88667) (xy 427.880272 -403.728682)
			(xy 427.88065 -403.718505) (xy 427.888447 -403.699703) (xy 427.902847 -403.685318) (xy 427.921657 -403.67754)
			(xy 427.931834 -403.67712) (xy 428.648114 -403.67712) (xy 428.65827 -403.677622) (xy 428.677036 -403.685397)
			(xy 428.6914 -403.69976) (xy 428.699178 -403.718526) (xy 428.699676 -403.728682) (xy 428.699676 -403.88667)
			(xy 428.700106 -403.895855) (xy 428.706607 -403.913039) (xy 428.712376 -403.920198) (xy 428.734185 -403.945833)
			(xy 428.772132 -404.001422) (xy 428.803164 -404.061148) (xy 428.826835 -404.124155) (xy 428.842806 -404.189539)
			(xy 428.850848 -404.256363) (xy 428.850846 -404.32367) (xy 428.8428 -404.390494) (xy 428.826825 -404.455877)
			(xy 428.80315 -404.518882) (xy 428.772115 -404.578607) (xy 428.734165 -404.634194) (xy 428.712376 -404.659846)
			(xy 428.706575 -404.666988) (xy 428.700064 -404.684181) (xy 428.699676 -404.693374) (xy 428.699676 -405.186642)
			(xy 428.700071 -405.195831) (xy 428.706596 -405.213015) (xy 428.712376 -405.22017) (xy 428.734157 -405.245827)
			(xy 428.772106 -405.301413) (xy 428.803138 -405.361136) (xy 428.826811 -405.42414) (xy 428.842784 -405.489522)
			(xy 428.850828 -405.556343) (xy 428.850829 -405.623648) (xy 428.842785 -405.69047) (xy 428.826813 -405.755851)
			(xy 428.803142 -405.818856) (xy 428.77211 -405.878579) (xy 428.734163 -405.934166) (xy 428.712376 -405.959818)
			(xy 428.706587 -405.966968) (xy 428.700068 -405.984155) (xy 428.699676 -405.993346) (xy 428.699676 -406.151334)
			(xy 428.699195 -406.161492) (xy 428.691412 -406.180259) (xy 428.677043 -406.194623) (xy 428.658272 -406.202399)
			(xy 428.648114 -406.202896) (xy 427.931834 -406.202896) (xy 427.921683 -406.202339) (xy 427.902921 -406.194583)
			(xy 427.888556 -406.180236) (xy 427.880774 -406.161485) (xy 427.880272 -406.151334) (xy 427.880272 -405.993346)
			(xy 427.879846 -405.98416) (xy 427.873344 -405.966976) (xy 427.867572 -405.959818) (xy 427.845777 -405.934171)
			(xy 427.807827 -405.878585) (xy 427.776792 -405.818861) (xy 427.753118 -405.755855) (xy 427.737144 -405.690472)
			(xy 427.7291 -405.623649) (xy 426.600565 -405.623649) (xy 426.571967 -405.678683) (xy 426.534016 -405.734268)
			(xy 426.512228 -405.75992) (xy 426.506432 -405.767065) (xy 426.499919 -405.784256) (xy 426.499528 -405.793448)
			(xy 426.499528 -406.286716) (xy 426.499924 -406.295905) (xy 426.506447 -406.313089) (xy 426.512228 -406.320244)
			(xy 426.533985 -406.345922) (xy 426.571937 -406.401504) (xy 426.602974 -406.461223) (xy 426.62665 -406.524225)
			(xy 426.642626 -406.589604) (xy 426.650673 -406.656424) (xy 426.650676 -406.723728) (xy 426.650669 -406.723789)
			(xy 429.928714 -406.723789) (xy 429.928717 -406.656363) (xy 429.936796 -406.589422) (xy 429.952835 -406.523931)
			(xy 429.976604 -406.460832) (xy 430.00776 -406.401036) (xy 430.045853 -406.345401) (xy 430.06772 -406.319736)
			(xy 430.073529 -406.312599) (xy 430.080035 -406.295402) (xy 430.08042 -406.286208) (xy 430.08042 -405.793956)
			(xy 430.080027 -405.784767) (xy 430.073501 -405.767583) (xy 430.06772 -405.760428) (xy 430.045851 -405.734766)
			(xy 430.007761 -405.679132) (xy 429.97661 -405.619335) (xy 429.952845 -405.556238) (xy 429.936809 -405.490748)
			(xy 429.928733 -405.423809) (xy 429.928734 -405.356385) (xy 429.93681 -405.289446) (xy 429.952847 -405.223956)
			(xy 429.976612 -405.160859) (xy 430.007765 -405.101063) (xy 430.045855 -405.045429) (xy 430.06772 -405.019764)
			(xy 430.073517 -405.012619) (xy 430.080031 -404.995428) (xy 430.08042 -404.986236) (xy 430.08042 -404.828756)
			(xy 430.08085 -404.818642) (xy 430.088605 -404.799959) (xy 430.102919 -404.785665) (xy 430.121613 -404.777935)
			(xy 430.131728 -404.777448) (xy 430.848008 -404.777448) (xy 430.858111 -404.777977) (xy 430.876779 -404.785708)
			(xy 430.891072 -404.799991) (xy 430.898815 -404.818654) (xy 430.899316 -404.828756) (xy 430.899316 -404.986236)
			(xy 430.899705 -404.995425) (xy 430.906233 -405.01261) (xy 430.912016 -405.019764) (xy 430.933875 -405.045433)
			(xy 430.971963 -405.101067) (xy 431.003113 -405.160863) (xy 431.026877 -405.223959) (xy 431.042912 -405.289448)
			(xy 431.050988 -405.356385) (xy 431.050989 -405.423809) (xy 431.042913 -405.490746) (xy 431.026879 -405.556235)
			(xy 431.003116 -405.619331) (xy 431.000867 -405.623648) (xy 432.128891 -405.623648) (xy 432.128892 -405.556343)
			(xy 432.136937 -405.489519) (xy 432.152911 -405.424136) (xy 432.176585 -405.361132) (xy 432.207621 -405.301408)
			(xy 432.245571 -405.245822) (xy 432.26736 -405.22017) (xy 432.273159 -405.213027) (xy 432.279671 -405.195835)
			(xy 432.28006 -405.186642) (xy 432.28006 -404.693374) (xy 432.279649 -404.684187) (xy 432.273134 -404.667004)
			(xy 432.26736 -404.659846) (xy 432.245593 -404.634176) (xy 432.207643 -404.578593) (xy 432.176607 -404.518872)
			(xy 432.152932 -404.45587) (xy 432.136957 -404.390489) (xy 432.128911 -404.323668) (xy 432.128909 -404.256365)
			(xy 432.136951 -404.189543) (xy 432.152922 -404.124162) (xy 432.176594 -404.061158) (xy 432.207626 -404.001436)
			(xy 432.245573 -403.94585) (xy 432.26736 -403.920198) (xy 432.273147 -403.913047) (xy 432.279666 -403.895861)
			(xy 432.28006 -403.88667) (xy 432.28006 -403.728682) (xy 432.28045 -403.718507) (xy 432.288245 -403.699707)
			(xy 432.302641 -403.685322) (xy 432.321446 -403.677542) (xy 432.331622 -403.67712) (xy 433.047902 -403.67712)
			(xy 433.058058 -403.677631) (xy 433.076823 -403.685403) (xy 433.091188 -403.699763) (xy 433.098965 -403.718526)
			(xy 433.099464 -403.728682) (xy 433.099464 -403.88667) (xy 433.099897 -403.895855) (xy 433.106396 -403.913039)
			(xy 433.112164 -403.920198) (xy 433.133973 -403.945832) (xy 433.171921 -404.001421) (xy 433.202954 -404.061147)
			(xy 433.226625 -404.124154) (xy 433.242596 -404.189539) (xy 433.250639 -404.256363) (xy 433.250637 -404.32367)
			(xy 433.24259 -404.390494) (xy 433.226615 -404.455877) (xy 433.20294 -404.518883) (xy 433.171904 -404.578607)
			(xy 433.133953 -404.634194) (xy 433.112164 -404.659846) (xy 433.106361 -404.666986) (xy 433.099851 -404.684181)
			(xy 433.099464 -404.693374) (xy 433.099464 -405.186642) (xy 433.099862 -405.19583) (xy 433.106385 -405.213014)
			(xy 433.112164 -405.22017) (xy 433.133946 -405.245827) (xy 433.171895 -405.301413) (xy 433.202928 -405.361136)
			(xy 433.226601 -405.42414) (xy 433.242574 -405.489521) (xy 433.250619 -405.556343) (xy 433.250619 -405.623648)
			(xy 433.242576 -405.69047) (xy 433.226604 -405.755852) (xy 433.202932 -405.818856) (xy 433.171899 -405.878579)
			(xy 433.133951 -405.934166) (xy 433.112164 -405.959818) (xy 433.106373 -405.966967) (xy 433.099856 -405.984155)
			(xy 433.099464 -405.993346) (xy 433.099464 -406.151334) (xy 433.098995 -406.161494) (xy 433.091209 -406.180263)
			(xy 433.076836 -406.194627) (xy 433.058062 -406.202401) (xy 433.047902 -406.202896) (xy 432.331622 -406.202896)
			(xy 432.32147 -406.20235) (xy 432.302708 -406.194589) (xy 432.288343 -406.180239) (xy 432.280561 -406.161486)
			(xy 432.28006 -406.151334) (xy 432.28006 -405.993346) (xy 432.279614 -405.984163) (xy 432.273124 -405.966979)
			(xy 432.26736 -405.959818) (xy 432.245566 -405.934171) (xy 432.207616 -405.878584) (xy 432.176582 -405.81886)
			(xy 432.152908 -405.755855) (xy 432.136935 -405.690472) (xy 432.128891 -405.623648) (xy 431.000867 -405.623648)
			(xy 430.971966 -405.679128) (xy 430.933879 -405.734762) (xy 430.912016 -405.760428) (xy 430.906227 -405.767579)
			(xy 430.899707 -405.784765) (xy 430.899316 -405.793956) (xy 430.899316 -406.286208) (xy 430.899719 -406.295396)
			(xy 430.906237 -406.31258) (xy 430.912016 -406.319736) (xy 430.933848 -406.345427) (xy 430.971937 -406.401059)
			(xy 431.003088 -406.460851) (xy 431.026853 -406.523945) (xy 431.04289 -406.58943) (xy 431.050968 -406.656366)
			(xy 431.050971 -406.723729) (xy 434.329033 -406.723729) (xy 434.329036 -406.656422) (xy 434.337083 -406.589598)
			(xy 434.353058 -406.524215) (xy 434.376733 -406.461209) (xy 434.407769 -406.401484) (xy 434.445719 -406.345897)
			(xy 434.467508 -406.320244) (xy 434.473312 -406.313104) (xy 434.479822 -406.295909) (xy 434.480208 -406.286716)
			(xy 434.480208 -405.793448) (xy 434.479773 -405.784263) (xy 434.473276 -405.767079) (xy 434.467508 -405.75992)
			(xy 434.445717 -405.734271) (xy 434.407771 -405.678683) (xy 434.376739 -405.618959) (xy 434.353068 -405.555954)
			(xy 434.337096 -405.490572) (xy 434.329053 -405.423749) (xy 434.329053 -405.356445) (xy 434.337097 -405.289622)
			(xy 434.35307 -405.22424) (xy 434.376742 -405.161236) (xy 434.407774 -405.101512) (xy 434.445721 -405.045925)
			(xy 434.467508 -405.020272) (xy 434.4733 -405.013124) (xy 434.479817 -404.995935) (xy 434.480208 -404.986744)
			(xy 434.480208 -404.828756) (xy 434.480586 -404.818598) (xy 434.488397 -404.799843) (xy 434.502807 -404.785521)
			(xy 434.52161 -404.777824) (xy 434.53177 -404.777448) (xy 435.24805 -404.777448) (xy 435.258175 -404.777968)
			(xy 435.276896 -404.785681) (xy 435.291254 -404.799957) (xy 435.299074 -404.818634) (xy 435.299612 -404.828756)
			(xy 435.299612 -404.986744) (xy 435.299998 -404.995934) (xy 435.306528 -405.013118) (xy 435.312312 -405.020272)
			(xy 435.334097 -405.045927) (xy 435.372049 -405.101512) (xy 435.403086 -405.161234) (xy 435.426761 -405.224239)
			(xy 435.442735 -405.289621) (xy 435.450781 -405.356444) (xy 435.450781 -405.42375) (xy 435.442736 -405.490573)
			(xy 435.426762 -405.555956) (xy 435.403088 -405.61896) (xy 435.372052 -405.678683) (xy 435.334101 -405.734269)
			(xy 435.312312 -405.75992) (xy 435.306526 -405.767073) (xy 435.300005 -405.784257) (xy 435.299612 -405.793448)
			(xy 435.299612 -406.286716) (xy 435.300012 -406.295904) (xy 435.306532 -406.313089) (xy 435.312312 -406.320244)
			(xy 435.33407 -406.345921) (xy 435.372023 -406.401503) (xy 435.40306 -406.461223) (xy 435.426737 -406.524224)
			(xy 435.442713 -406.589604) (xy 435.450761 -406.656424) (xy 435.450764 -406.723728) (xy 435.442722 -406.790549)
			(xy 435.426751 -406.85593) (xy 435.40308 -406.918933) (xy 435.372048 -406.978656) (xy 435.334099 -407.034241)
			(xy 435.312312 -407.059892) (xy 435.306538 -407.067053) (xy 435.300009 -407.084231) (xy 435.299612 -407.09342)
			(xy 435.299612 -407.251408) (xy 435.299185 -407.261561) (xy 435.291389 -407.280311) (xy 435.276994 -407.294634)
			(xy 435.258205 -407.302335) (xy 435.24805 -407.302716) (xy 434.53177 -407.302716) (xy 434.521636 -407.302297)
			(xy 434.502906 -407.294551) (xy 434.488549 -407.280244) (xy 434.480739 -407.26154) (xy 434.480208 -407.251408)
			(xy 434.480208 -407.09342) (xy 434.479786 -407.084234) (xy 434.47328 -407.06705) (xy 434.467508 -407.059892)
			(xy 434.44569 -407.034265) (xy 434.407744 -406.978674) (xy 434.376714 -406.918947) (xy 434.353044 -406.855939)
			(xy 434.337074 -406.790554) (xy 434.329033 -406.723729) (xy 431.050971 -406.723729) (xy 431.050971 -406.723786)
			(xy 431.042899 -406.790722) (xy 431.026867 -406.856209) (xy 431.003107 -406.919305) (xy 430.971961 -406.9791)
			(xy 430.933877 -407.034735) (xy 430.912016 -407.0604) (xy 430.906239 -407.067559) (xy 430.899712 -407.084739)
			(xy 430.899316 -407.093928) (xy 430.899316 -407.251408) (xy 430.898822 -407.261515) (xy 430.891084 -407.28019)
			(xy 430.87679 -407.294484) (xy 430.858115 -407.302222) (xy 430.848008 -407.302716) (xy 430.131728 -407.302716)
			(xy 430.121609 -407.302262) (xy 430.102909 -407.294526) (xy 430.088595 -407.280221) (xy 430.080845 -407.261526)
			(xy 430.08042 -407.251408) (xy 430.08042 -407.093928) (xy 430.079992 -407.084743) (xy 430.07349 -407.067559)
			(xy 430.06772 -407.0604) (xy 430.045824 -407.034761) (xy 430.007735 -406.979123) (xy 429.976584 -406.919324)
			(xy 429.952821 -406.856223) (xy 429.936787 -406.790731) (xy 429.928714 -406.723789) (xy 426.650669 -406.723789)
			(xy 426.642634 -406.790548) (xy 426.626664 -406.855929) (xy 426.602993 -406.918933) (xy 426.571962 -406.978655)
			(xy 426.534015 -407.03424) (xy 426.512228 -407.059892) (xy 426.506444 -407.067045) (xy 426.499924 -407.08423)
			(xy 426.499528 -407.09342) (xy 426.499528 -407.251408) (xy 426.499085 -407.261559) (xy 426.491292 -407.280306)
			(xy 426.476903 -407.294628) (xy 426.458119 -407.302333) (xy 426.447966 -407.302716) (xy 425.731686 -407.302716)
			(xy 425.721553 -407.302283) (xy 425.702823 -407.294543) (xy 425.688466 -407.28024) (xy 425.680655 -407.261539)
			(xy 425.680124 -407.251408) (xy 425.680124 -407.09342) (xy 425.679699 -407.084235) (xy 425.673195 -407.06705)
			(xy 425.667424 -407.059892) (xy 425.645605 -407.034266) (xy 425.607658 -406.978675) (xy 425.576627 -406.918948)
			(xy 425.552957 -406.85594) (xy 425.536987 -406.790555) (xy 425.528945 -406.72373) (xy 422.250883 -406.72373)
			(xy 422.250883 -406.723786) (xy 422.242811 -406.790722) (xy 422.22678 -406.856209) (xy 422.203021 -406.919304)
			(xy 422.171876 -406.9791) (xy 422.133793 -407.034734) (xy 422.111932 -407.0604) (xy 422.106145 -407.067551)
			(xy 422.099626 -407.084737) (xy 422.099232 -407.093928) (xy 422.099232 -407.251408) (xy 422.098722 -407.261513)
			(xy 422.090988 -407.280185) (xy 422.076699 -407.294479) (xy 422.058029 -407.302219) (xy 422.047924 -407.302716)
			(xy 421.331644 -407.302716) (xy 421.321526 -407.302248) (xy 421.302827 -407.294518) (xy 421.288512 -407.280217)
			(xy 421.280762 -407.261525) (xy 421.280336 -407.251408) (xy 421.280336 -407.093928) (xy 421.279904 -407.084743)
			(xy 421.273405 -407.067559) (xy 421.267636 -407.0604) (xy 421.245739 -407.034761) (xy 421.207649 -406.979124)
			(xy 421.176498 -406.919324) (xy 421.152734 -406.856224) (xy 421.1367 -406.790731) (xy 421.128626 -406.723789)
			(xy 414.525968 -406.723789) (xy 414.525968 -409.523827) (xy 418.928991 -409.523827) (xy 418.928995 -409.456519)
			(xy 418.937043 -409.389693) (xy 418.953021 -409.324308) (xy 418.9767 -409.261302) (xy 419.00774 -409.201577)
			(xy 419.045697 -409.145992) (xy 419.067488 -409.12034) (xy 419.073291 -409.113199) (xy 419.079802 -409.096005)
			(xy 419.080188 -409.086812) (xy 419.080188 -408.593544) (xy 419.079759 -408.584359) (xy 419.073259 -408.567174)
			(xy 419.067488 -408.560016) (xy 419.045691 -408.534371) (xy 419.007739 -408.478785) (xy 418.976704 -408.419061)
			(xy 418.953029 -408.356055) (xy 418.937055 -408.290671) (xy 418.929011 -408.223847) (xy 418.929012 -408.156541)
			(xy 418.937057 -408.089717) (xy 418.953033 -408.024333) (xy 418.976708 -407.961328) (xy 419.007745 -407.901605)
			(xy 419.045698 -407.84602) (xy 419.067488 -407.820368) (xy 419.073279 -407.813219) (xy 419.079797 -407.796031)
			(xy 419.080188 -407.78684) (xy 419.080188 -407.628852) (xy 419.080582 -407.618696) (xy 419.088391 -407.599945)
			(xy 419.102796 -407.585624) (xy 419.121592 -407.577924) (xy 419.13175 -407.577544) (xy 419.84803 -407.577544)
			(xy 419.858159 -407.578002) (xy 419.876882 -407.58574) (xy 419.891237 -407.600035) (xy 419.899055 -407.618725)
			(xy 419.899592 -407.628852) (xy 419.899592 -407.78684) (xy 419.899985 -407.796029) (xy 419.906511 -407.813213)
			(xy 419.912292 -407.820368) (xy 419.934071 -407.846027) (xy 419.972018 -407.901613) (xy 420.00305 -407.961336)
			(xy 420.026722 -408.02434) (xy 420.042694 -408.089721) (xy 420.050739 -408.156542) (xy 420.050739 -408.223846)
			(xy 420.042697 -408.290667) (xy 420.026725 -408.356049) (xy 420.003055 -408.419053) (xy 419.972024 -408.478776)
			(xy 419.934078 -408.534363) (xy 419.912292 -408.560016) (xy 419.906505 -408.567168) (xy 419.899985 -408.584353)
			(xy 419.899592 -408.593544) (xy 419.899592 -409.086812) (xy 419.899998 -409.096) (xy 419.906515 -409.113184)
			(xy 419.912292 -409.12034) (xy 419.934043 -409.146022) (xy 419.971991 -409.201605) (xy 420.003024 -409.261324)
			(xy 420.026698 -409.324325) (xy 420.042672 -409.389703) (xy 420.050719 -409.456522) (xy 420.050722 -409.523824)
			(xy 420.042682 -409.590643) (xy 420.026714 -409.656023) (xy 420.003047 -409.719026) (xy 419.972019 -409.778749)
			(xy 419.934077 -409.834336) (xy 419.912292 -409.859988) (xy 419.906475 -409.867118) (xy 419.899973 -409.88432)
			(xy 419.899592 -409.893516) (xy 419.899592 -410.051504) (xy 419.899181 -410.061659) (xy 419.891383 -410.080413)
			(xy 419.876983 -410.094737) (xy 419.858187 -410.102435) (xy 419.84803 -410.102812) (xy 419.13175 -410.102812)
			(xy 419.121633 -410.102234) (xy 419.102923 -410.094532) (xy 419.088567 -410.080274) (xy 419.080736 -410.061618)
			(xy 419.080188 -410.051504) (xy 419.080188 -409.893516) (xy 419.079773 -409.884329) (xy 419.073263 -409.867145)
			(xy 419.067488 -409.859988) (xy 419.045663 -409.834366) (xy 419.007713 -409.778776) (xy 418.976678 -409.719049)
			(xy 418.953005 -409.65604) (xy 418.937033 -409.590654) (xy 418.928991 -409.523827) (xy 414.525968 -409.523827)
			(xy 414.525968 -410.623701) (xy 421.128637 -410.623701) (xy 421.128638 -410.556275) (xy 421.136716 -410.489335)
			(xy 421.152755 -410.423845) (xy 421.176522 -410.360747) (xy 421.207677 -410.300951) (xy 421.24577 -410.245317)
			(xy 421.267636 -410.219652) (xy 421.27344 -410.212512) (xy 421.279949 -410.195317) (xy 421.280336 -410.186124)
			(xy 421.280336 -409.693872) (xy 421.279931 -409.684684) (xy 421.273413 -409.667501) (xy 421.267636 -409.660344)
			(xy 421.245783 -409.63467) (xy 421.207691 -409.579037) (xy 421.176538 -409.519243) (xy 421.152771 -409.456147)
			(xy 421.136734 -409.390659) (xy 421.128657 -409.323721) (xy 421.128656 -409.256297) (xy 421.136731 -409.189359)
			(xy 421.152766 -409.12387) (xy 421.176531 -409.060774) (xy 421.207682 -409.000978) (xy 421.245771 -408.945345)
			(xy 421.267636 -408.91968) (xy 421.273428 -408.912532) (xy 421.279945 -408.895343) (xy 421.280336 -408.886152)
			(xy 421.280336 -408.728672) (xy 421.280694 -408.718543) (xy 421.288458 -408.699832) (xy 421.302793 -408.685517)
			(xy 421.321515 -408.67778) (xy 421.331644 -408.677364) (xy 422.047924 -408.677364) (xy 422.05803 -408.677864)
			(xy 422.076702 -408.685603) (xy 422.090994 -408.699895) (xy 422.098735 -408.718566) (xy 422.099232 -408.728672)
			(xy 422.099232 -408.886152) (xy 422.09968 -408.895335) (xy 422.106169 -408.912519) (xy 422.111932 -408.91968)
			(xy 422.133807 -408.945336) (xy 422.171893 -409.000973) (xy 422.203041 -409.06077) (xy 422.226803 -409.123868)
			(xy 422.242837 -409.189358) (xy 422.250911 -409.256297) (xy 422.25091 -409.323721) (xy 422.242834 -409.39066)
			(xy 422.226798 -409.456149) (xy 422.203034 -409.519246) (xy 422.200617 -409.523886) (xy 423.328784 -409.523886)
			(xy 423.328787 -409.45646) (xy 423.336866 -409.389519) (xy 423.352905 -409.324029) (xy 423.376672 -409.26093)
			(xy 423.407826 -409.201133) (xy 423.445918 -409.145498) (xy 423.467784 -409.119832) (xy 423.47359 -409.112693)
			(xy 423.4801 -409.095498) (xy 423.480484 -409.086304) (xy 423.480484 -408.594052) (xy 423.480052 -408.584867)
			(xy 423.473554 -408.567682) (xy 423.467784 -408.560524) (xy 423.445913 -408.534865) (xy 423.407825 -408.479229)
			(xy 423.376676 -408.419432) (xy 423.352913 -408.356334) (xy 423.336878 -408.290845) (xy 423.328803 -408.223906)
			(xy 423.328804 -408.156482) (xy 423.336881 -408.089543) (xy 423.352916 -408.024054) (xy 423.376681 -407.960957)
			(xy 423.407832 -407.901161) (xy 423.44592 -407.845526) (xy 423.467784 -407.81986) (xy 423.473578 -407.812713)
			(xy 423.480095 -407.795524) (xy 423.480484 -407.786332) (xy 423.480484 -407.628852) (xy 423.480946 -407.618742)
			(xy 423.488696 -407.600066) (xy 423.503 -407.585774) (xy 423.521682 -407.578038) (xy 423.531792 -407.577544)
			(xy 424.248072 -407.577544) (xy 424.258172 -407.578106) (xy 424.276839 -407.585825) (xy 424.291133 -407.600097)
			(xy 424.298879 -407.618753) (xy 424.29938 -407.628852) (xy 424.29938 -407.786332) (xy 424.299779 -407.79552)
			(xy 424.306301 -407.812704) (xy 424.31208 -407.81986) (xy 424.333937 -407.845531) (xy 424.372027 -407.901165)
			(xy 424.403179 -407.96096) (xy 424.426945 -408.024056) (xy 424.442981 -408.089544) (xy 424.451058 -408.156482)
			(xy 424.451059 -408.223906) (xy 424.442984 -408.290844) (xy 424.426948 -408.356333) (xy 424.403184 -408.419429)
			(xy 424.372033 -408.479225) (xy 424.333944 -408.534859) (xy 424.31208 -408.560524) (xy 424.306288 -408.567673)
			(xy 424.299771 -408.584861) (xy 424.29938 -408.594052) (xy 424.29938 -409.086304) (xy 424.299792 -409.095491)
			(xy 424.306305 -409.112675) (xy 424.31208 -409.119832) (xy 424.333909 -409.145526) (xy 424.372 -409.201156)
			(xy 424.403154 -409.260948) (xy 424.426921 -409.324041) (xy 424.442959 -409.389527) (xy 424.451039 -409.456462)
			(xy 424.451042 -409.523884) (xy 424.442969 -409.59082) (xy 424.426937 -409.656307) (xy 424.403176 -409.719403)
			(xy 424.372028 -409.779198) (xy 424.333943 -409.834831) (xy 424.31208 -409.860496) (xy 424.3063 -409.867653)
			(xy 424.299776 -409.884835) (xy 424.29938 -409.894024) (xy 424.29938 -410.051504) (xy 424.298987 -410.061629)
			(xy 424.291234 -410.080337) (xy 424.27691 -410.094651) (xy 424.258197 -410.102393) (xy 424.248072 -410.102812)
			(xy 423.531792 -410.102812) (xy 423.521684 -410.102322) (xy 423.503008 -410.094584) (xy 423.488714 -410.080288)
			(xy 423.480978 -410.061612) (xy 423.480484 -410.051504) (xy 423.480484 -409.894024) (xy 423.480066 -409.884838)
			(xy 423.473558 -409.867653) (xy 423.467784 -409.860496) (xy 423.445885 -409.83486) (xy 423.407799 -409.779221)
			(xy 423.37665 -409.71942) (xy 423.352889 -409.65632) (xy 423.336856 -409.590827) (xy 423.328784 -409.523886)
			(xy 422.200617 -409.523886) (xy 422.171884 -409.579043) (xy 422.133796 -409.634678) (xy 422.111932 -409.660344)
			(xy 422.106126 -409.667482) (xy 422.099619 -409.684678) (xy 422.099232 -409.693872) (xy 422.099232 -410.186124)
			(xy 422.099646 -410.19531) (xy 422.106159 -410.212494) (xy 422.111932 -410.219652) (xy 422.133779 -410.245331)
			(xy 422.171866 -410.300964) (xy 422.203016 -410.360759) (xy 422.22678 -410.423854) (xy 422.242815 -410.489341)
			(xy 422.250892 -410.556277) (xy 422.250893 -410.623641) (xy 425.528957 -410.623641) (xy 425.528958 -410.556335)
			(xy 425.537003 -410.489512) (xy 425.552978 -410.424129) (xy 425.576652 -410.361123) (xy 425.607686 -410.301399)
			(xy 425.645636 -410.245812) (xy 425.667424 -410.22016) (xy 425.673223 -410.213017) (xy 425.679735 -410.195825)
			(xy 425.680124 -410.186632) (xy 425.680124 -409.693364) (xy 425.679726 -409.684176) (xy 425.673203 -409.666992)
			(xy 425.667424 -409.659836) (xy 425.645648 -409.634174) (xy 425.6077 -409.578589) (xy 425.576667 -409.518866)
			(xy 425.552994 -409.455863) (xy 425.537021 -409.390482) (xy 425.528976 -409.323661) (xy 425.528975 -409.256357)
			(xy 425.537018 -409.189536) (xy 425.552989 -409.124154) (xy 425.57666 -409.06115) (xy 425.607691 -409.001427)
			(xy 425.645637 -408.94584) (xy 425.667424 -408.920188) (xy 425.673211 -408.913036) (xy 425.679731 -408.895851)
			(xy 425.680124 -408.88666) (xy 425.680124 -408.728672) (xy 425.680499 -408.718513) (xy 425.688308 -408.699755)
			(xy 425.70272 -408.685432) (xy 425.721525 -408.677738) (xy 425.731686 -408.677364) (xy 426.447966 -408.677364)
			(xy 426.458093 -408.677855) (xy 426.476818 -408.685576) (xy 426.491177 -408.699862) (xy 426.498993 -408.718547)
			(xy 426.499528 -408.728672) (xy 426.499528 -408.88666) (xy 426.499951 -408.895846) (xy 426.506455 -408.913031)
			(xy 426.512228 -408.920188) (xy 426.534028 -408.94583) (xy 426.571979 -409.001417) (xy 426.603014 -409.061142)
			(xy 426.626687 -409.124148) (xy 426.64266 -409.189532) (xy 426.650704 -409.256356) (xy 426.650703 -409.323662)
			(xy 426.642657 -409.390486) (xy 426.626682 -409.45587) (xy 426.603006 -409.518875) (xy 426.600433 -409.523827)
			(xy 427.729079 -409.523827) (xy 427.729082 -409.456519) (xy 427.73713 -409.389693) (xy 427.753108 -409.324308)
			(xy 427.776786 -409.261302) (xy 427.807826 -409.201578) (xy 427.845781 -409.145992) (xy 427.867572 -409.12034)
			(xy 427.873385 -409.113207) (xy 427.879888 -409.096007) (xy 427.880272 -409.086812) (xy 427.880272 -408.593544)
			(xy 427.879847 -408.584358) (xy 427.873344 -408.567174) (xy 427.867572 -408.560016) (xy 427.845776 -408.534371)
			(xy 427.807825 -408.478784) (xy 427.77679 -408.41906) (xy 427.753116 -408.356054) (xy 427.737143 -408.290671)
			(xy 427.729099 -408.223847) (xy 427.7291 -408.156541) (xy 427.737145 -408.089717) (xy 427.75312 -408.024334)
			(xy 427.776795 -407.961329) (xy 427.807831 -407.901606) (xy 427.845783 -407.84602) (xy 427.867572 -407.820368)
			(xy 427.873373 -407.813227) (xy 427.879883 -407.796033) (xy 427.880272 -407.78684) (xy 427.880272 -407.628852)
			(xy 427.880682 -407.618698) (xy 427.888488 -407.59995) (xy 427.902887 -407.58563) (xy 427.921678 -407.577927)
			(xy 427.931834 -407.577544) (xy 428.648114 -407.577544) (xy 428.658242 -407.578015) (xy 428.676964 -407.585749)
			(xy 428.69132 -407.600039) (xy 428.699138 -407.618726) (xy 428.699676 -407.628852) (xy 428.699676 -407.78684)
			(xy 428.700072 -407.796029) (xy 428.706596 -407.813212) (xy 428.712376 -407.820368) (xy 428.734155 -407.846027)
			(xy 428.772104 -407.901613) (xy 428.803136 -407.961335) (xy 428.826809 -408.024339) (xy 428.842782 -408.08972)
			(xy 428.850827 -408.156542) (xy 428.850827 -408.223846) (xy 428.842784 -408.290668) (xy 428.826813 -408.356049)
			(xy 428.803141 -408.419054) (xy 428.77211 -408.478777) (xy 428.734163 -408.534364) (xy 428.712376 -408.560016)
			(xy 428.706587 -408.567167) (xy 428.700069 -408.584353) (xy 428.699676 -408.593544) (xy 428.699676 -409.086812)
			(xy 428.700086 -409.095999) (xy 428.7066 -409.113183) (xy 428.712376 -409.12034) (xy 428.734128 -409.146022)
			(xy 428.772077 -409.201604) (xy 428.803111 -409.261324) (xy 428.826785 -409.324324) (xy 428.84276 -409.389703)
			(xy 428.850806 -409.456522) (xy 428.85081 -409.523824) (xy 428.842769 -409.590644) (xy 428.826801 -409.656024)
			(xy 428.803133 -409.719027) (xy 428.772104 -409.778749) (xy 428.734161 -409.834335) (xy 428.712376 -409.859988)
			(xy 428.706557 -409.867117) (xy 428.700056 -409.88432) (xy 428.699676 -409.893516) (xy 428.699676 -410.051504)
			(xy 428.699281 -410.061661) (xy 428.69148 -410.080418) (xy 428.677074 -410.094742) (xy 428.658274 -410.102438)
			(xy 428.648114 -410.102812) (xy 427.931834 -410.102812) (xy 427.921716 -410.102247) (xy 427.903005 -410.09454)
			(xy 427.88865 -410.080278) (xy 427.88082 -410.061619) (xy 427.880272 -410.051504) (xy 427.880272 -409.893516)
			(xy 427.879861 -409.884329) (xy 427.873349 -409.867144) (xy 427.867572 -409.859988) (xy 427.845748 -409.834366)
			(xy 427.807798 -409.778776) (xy 427.776764 -409.719048) (xy 427.753092 -409.65604) (xy 427.73712 -409.590654)
			(xy 427.729079 -409.523827) (xy 426.600433 -409.523827) (xy 426.57197 -409.578598) (xy 426.534017 -409.634184)
			(xy 426.512228 -409.659836) (xy 426.506425 -409.666976) (xy 426.499916 -409.684171) (xy 426.499528 -409.693364)
			(xy 426.499528 -410.186632) (xy 426.499917 -410.195822) (xy 426.506445 -410.213006) (xy 426.512228 -410.22016)
			(xy 426.534001 -410.245825) (xy 426.571952 -410.301409) (xy 426.602988 -410.36113) (xy 426.626663 -410.424133)
			(xy 426.642638 -410.489514) (xy 426.650684 -410.556336) (xy 426.650686 -410.62364) (xy 426.650679 -410.623701)
			(xy 429.928725 -410.623701) (xy 429.928726 -410.556275) (xy 429.936804 -410.489336) (xy 429.952842 -410.423845)
			(xy 429.976609 -410.360748) (xy 430.007762 -410.300951) (xy 430.045854 -410.245317) (xy 430.06772 -410.219652)
			(xy 430.073522 -410.212511) (xy 430.080033 -410.195317) (xy 430.08042 -410.186124) (xy 430.08042 -409.693872)
			(xy 430.080019 -409.684684) (xy 430.073498 -409.6675) (xy 430.06772 -409.660344) (xy 430.045867 -409.634669)
			(xy 430.007777 -409.579037) (xy 429.976624 -409.519242) (xy 429.952859 -409.456146) (xy 429.936822 -409.390658)
			(xy 429.928745 -409.323721) (xy 429.928744 -409.256297) (xy 429.936819 -409.18936) (xy 429.952853 -409.123871)
			(xy 429.976617 -409.060775) (xy 430.007767 -409.000979) (xy 430.045856 -408.945345) (xy 430.06772 -408.91968)
			(xy 430.07351 -408.91253) (xy 430.080028 -408.895343) (xy 430.08042 -408.886152) (xy 430.08042 -408.728672)
			(xy 430.080863 -408.718559) (xy 430.088613 -408.699876) (xy 430.102923 -408.685582) (xy 430.121614 -408.677852)
			(xy 430.131728 -408.677364) (xy 430.848008 -408.677364) (xy 430.858113 -408.677878) (xy 430.876784 -408.685611)
			(xy 430.891077 -408.699899) (xy 430.898818 -408.718567) (xy 430.899316 -408.728672) (xy 430.899316 -408.886152)
			(xy 430.899745 -408.895337) (xy 430.906245 -408.912522) (xy 430.912016 -408.91968) (xy 430.933891 -408.945336)
			(xy 430.971979 -409.000972) (xy 431.003128 -409.06077) (xy 431.026891 -409.123868) (xy 431.042925 -409.189358)
			(xy 431.050999 -409.256297) (xy 431.050998 -409.323721) (xy 431.042922 -409.39066) (xy 431.026885 -409.456149)
			(xy 431.00312 -409.519247) (xy 431.000734 -409.523827) (xy 432.12887 -409.523827) (xy 432.128873 -409.456519)
			(xy 432.136921 -409.389693) (xy 432.152898 -409.324309) (xy 432.176576 -409.261303) (xy 432.207615 -409.201578)
			(xy 432.245569 -409.145992) (xy 432.26736 -409.12034) (xy 432.273172 -409.113206) (xy 432.279676 -409.096007)
			(xy 432.28006 -409.086812) (xy 432.28006 -408.593544) (xy 432.279615 -408.584361) (xy 432.273124 -408.567177)
			(xy 432.26736 -408.560016) (xy 432.245564 -408.53437) (xy 432.207614 -408.478784) (xy 432.17658 -408.419059)
			(xy 432.152907 -408.356054) (xy 432.136934 -408.290671) (xy 432.12889 -408.223847) (xy 432.128891 -408.156541)
			(xy 432.136936 -408.089717) (xy 432.15291 -408.024335) (xy 432.176585 -407.96133) (xy 432.20762 -407.901606)
			(xy 432.245571 -407.84602) (xy 432.26736 -407.820368) (xy 432.27316 -407.813226) (xy 432.279671 -407.796033)
			(xy 432.28006 -407.78684) (xy 432.28006 -407.628852) (xy 432.280482 -407.6187) (xy 432.288286 -407.599954)
			(xy 432.302681 -407.585634) (xy 432.321468 -407.577929) (xy 432.331622 -407.577544) (xy 433.047902 -407.577544)
			(xy 433.058029 -407.578025) (xy 433.076751 -407.585754) (xy 433.091108 -407.600042) (xy 433.098926 -407.618727)
			(xy 433.099464 -407.628852) (xy 433.099464 -407.78684) (xy 433.099863 -407.796028) (xy 433.106385 -407.813212)
			(xy 433.112164 -407.820368) (xy 433.133944 -407.846027) (xy 433.171893 -407.901612) (xy 433.202926 -407.961335)
			(xy 433.226599 -408.024339) (xy 433.242573 -408.08972) (xy 433.250618 -408.156542) (xy 433.250618 -408.223846)
			(xy 433.242575 -408.290668) (xy 433.226603 -408.35605) (xy 433.202931 -408.419054) (xy 433.171899 -408.478778)
			(xy 433.133951 -408.534364) (xy 433.112164 -408.560016) (xy 433.106374 -408.567165) (xy 433.099856 -408.584353)
			(xy 433.099464 -408.593544) (xy 433.099464 -409.086812) (xy 433.099876 -409.095999) (xy 433.106389 -409.113183)
			(xy 433.112164 -409.12034) (xy 433.133916 -409.146021) (xy 433.171866 -409.201604) (xy 433.2029 -409.261323)
			(xy 433.226575 -409.324324) (xy 433.24255 -409.389703) (xy 433.250597 -409.456522) (xy 433.250601 -409.523824)
			(xy 433.24256 -409.590644) (xy 433.226591 -409.656024) (xy 433.202922 -409.719027) (xy 433.171894 -409.77875)
			(xy 433.133949 -409.834336) (xy 433.112164 -409.859988) (xy 433.106343 -409.867116) (xy 433.099844 -409.88432)
			(xy 433.099464 -409.893516) (xy 433.099464 -410.051504) (xy 433.099081 -410.061663) (xy 433.091277 -410.080422)
			(xy 433.076868 -410.094747) (xy 433.058063 -410.10244) (xy 433.047902 -410.102812) (xy 432.331622 -410.102812)
			(xy 432.321503 -410.102257) (xy 432.302792 -410.094546) (xy 432.288437 -410.080281) (xy 432.280608 -410.06162)
			(xy 432.28006 -410.051504) (xy 432.28006 -409.893516) (xy 432.279629 -409.884331) (xy 432.273128 -409.867147)
			(xy 432.26736 -409.859988) (xy 432.245536 -409.834365) (xy 432.207587 -409.778775) (xy 432.176554 -409.719048)
			(xy 432.152882 -409.656039) (xy 432.136911 -409.590653) (xy 432.12887 -409.523827) (xy 431.000734 -409.523827)
			(xy 430.971969 -409.579043) (xy 430.93388 -409.634678) (xy 430.912016 -409.660344) (xy 430.90622 -409.66749)
			(xy 430.899705 -409.68468) (xy 430.899316 -409.693872) (xy 430.899316 -410.186124) (xy 430.899711 -410.195313)
			(xy 430.906235 -410.212497) (xy 430.912016 -410.219652) (xy 430.933864 -410.24533) (xy 430.971952 -410.300963)
			(xy 431.003102 -410.360758) (xy 431.026867 -410.423853) (xy 431.042903 -410.48934) (xy 431.05098 -410.556277)
			(xy 431.050981 -410.623641) (xy 434.329044 -410.623641) (xy 434.329046 -410.556335) (xy 434.337091 -410.489512)
			(xy 434.353065 -410.424129) (xy 434.376738 -410.361124) (xy 434.407772 -410.3014) (xy 434.44572 -410.245813)
			(xy 434.467508 -410.22016) (xy 434.473305 -410.213015) (xy 434.479819 -410.195824) (xy 434.480208 -410.186632)
			(xy 434.480208 -409.693364) (xy 434.479814 -409.684175) (xy 434.473289 -409.666991) (xy 434.467508 -409.659836)
			(xy 434.445733 -409.634174) (xy 434.407786 -409.578588) (xy 434.376754 -409.518866) (xy 434.353082 -409.455862)
			(xy 434.337109 -409.390482) (xy 434.329064 -409.323661) (xy 434.329063 -409.256357) (xy 434.337106 -409.189536)
			(xy 434.353076 -409.124155) (xy 434.376746 -409.061151) (xy 434.407777 -409.001427) (xy 434.445722 -408.945841)
			(xy 434.467508 -408.920188) (xy 434.473293 -408.913035) (xy 434.479814 -408.89585) (xy 434.480208 -408.88666)
			(xy 434.480208 -408.728672) (xy 434.480599 -408.718515) (xy 434.488405 -408.69976) (xy 434.502811 -408.685438)
			(xy 434.521611 -408.67774) (xy 434.53177 -408.677364) (xy 435.24805 -408.677364) (xy 435.258176 -408.677868)
			(xy 435.276901 -408.685584) (xy 435.29126 -408.699866) (xy 435.299077 -408.718548) (xy 435.299612 -408.728672)
			(xy 435.299612 -408.88666) (xy 435.300039 -408.895846) (xy 435.30654 -408.91303) (xy 435.312312 -408.920188)
			(xy 435.334113 -408.94583) (xy 435.372065 -409.001417) (xy 435.4031 -409.061141) (xy 435.426774 -409.124147)
			(xy 435.442748 -409.189531) (xy 435.450792 -409.256356) (xy 435.450791 -409.323662) (xy 435.442745 -409.390487)
			(xy 435.426769 -409.45587) (xy 435.403093 -409.518875) (xy 435.372055 -409.578599) (xy 435.334102 -409.634184)
			(xy 435.312312 -409.659836) (xy 435.306519 -409.666984) (xy 435.300002 -409.684172) (xy 435.299612 -409.693364)
			(xy 435.299612 -410.186632) (xy 435.300004 -410.195821) (xy 435.30653 -410.213006) (xy 435.312312 -410.22016)
			(xy 435.334085 -410.245824) (xy 435.372038 -410.301408) (xy 435.403075 -410.361129) (xy 435.42675 -410.424132)
			(xy 435.442726 -410.489514) (xy 435.450772 -410.556336) (xy 435.450774 -410.62364) (xy 435.44273 -410.690463)
			(xy 435.426758 -410.755845) (xy 435.403084 -410.818849) (xy 435.37205 -410.878571) (xy 435.3341 -410.934157)
			(xy 435.312312 -410.959808) (xy 435.306531 -410.966964) (xy 435.300007 -410.984146) (xy 435.299612 -410.993336)
			(xy 435.299612 -411.151324) (xy 435.299198 -411.161478) (xy 435.291397 -411.180229) (xy 435.276998 -411.194551)
			(xy 435.258206 -411.202252) (xy 435.24805 -411.202632) (xy 434.53177 -411.202632) (xy 434.521638 -411.202197)
			(xy 434.502911 -411.194454) (xy 434.488554 -411.180152) (xy 434.480741 -411.161454) (xy 434.480208 -411.151324)
			(xy 434.480208 -410.993336) (xy 434.479779 -410.984151) (xy 434.473278 -410.966966) (xy 434.467508 -410.959808)
			(xy 434.445706 -410.934168) (xy 434.407759 -410.878579) (xy 434.376728 -410.818854) (xy 434.353058 -410.755848)
			(xy 434.337087 -410.690464) (xy 434.329044 -410.623641) (xy 431.050981 -410.623641) (xy 431.050981 -410.623699)
			(xy 431.042907 -410.690636) (xy 431.026874 -410.756124) (xy 431.003112 -410.81922) (xy 430.971964 -410.879016)
			(xy 430.933878 -410.934651) (xy 430.912016 -410.960316) (xy 430.906232 -410.96747) (xy 430.899709 -410.984654)
			(xy 430.899316 -410.993844) (xy 430.899316 -411.151324) (xy 430.898835 -411.161432) (xy 430.891092 -411.180108)
			(xy 430.876795 -411.194401) (xy 430.858116 -411.202138) (xy 430.848008 -411.202632) (xy 430.131728 -411.202632)
			(xy 430.121611 -411.202162) (xy 430.102914 -411.194429) (xy 430.0886 -411.180129) (xy 430.080848 -411.16144)
			(xy 430.08042 -411.151324) (xy 430.08042 -410.993844) (xy 430.079984 -410.98466) (xy 430.073488 -410.967475)
			(xy 430.06772 -410.960316) (xy 430.04584 -410.934664) (xy 430.00775 -410.879028) (xy 429.976599 -410.81923)
			(xy 429.952835 -410.756132) (xy 429.9368 -410.690641) (xy 429.928725 -410.623701) (xy 426.650679 -410.623701)
			(xy 426.642643 -410.690462) (xy 426.62667 -410.755844) (xy 426.602998 -410.818848) (xy 426.571965 -410.878571)
			(xy 426.534016 -410.934156) (xy 426.512228 -410.959808) (xy 426.506437 -410.966957) (xy 426.499921 -410.984145)
			(xy 426.499528 -410.993336) (xy 426.499528 -411.151324) (xy 426.499099 -411.161476) (xy 426.4913 -411.180224)
			(xy 426.476907 -411.194545) (xy 426.45812 -411.202249) (xy 426.447966 -411.202632) (xy 425.731686 -411.202632)
			(xy 425.721555 -411.202184) (xy 425.702828 -411.194446) (xy 425.688472 -411.180148) (xy 425.680658 -411.161453)
			(xy 425.680124 -411.151324) (xy 425.680124 -410.993336) (xy 425.679691 -410.984151) (xy 425.673193 -410.966967)
			(xy 425.667424 -410.959808) (xy 425.645621 -410.934169) (xy 425.607674 -410.87858) (xy 425.576642 -410.818855)
			(xy 425.552971 -410.755848) (xy 425.536999 -410.690465) (xy 425.528957 -410.623641) (xy 422.250893 -410.623641)
			(xy 422.250893 -410.623699) (xy 422.242819 -410.690635) (xy 422.226787 -410.756123) (xy 422.203026 -410.819219)
			(xy 422.171879 -410.879015) (xy 422.133794 -410.93465) (xy 422.111932 -410.960316) (xy 422.106138 -410.967463)
			(xy 422.099624 -410.984652) (xy 422.099232 -410.993844) (xy 422.099232 -411.151324) (xy 422.098735 -411.16143)
			(xy 422.090996 -411.180103) (xy 422.076703 -411.194396) (xy 422.05803 -411.202135) (xy 422.047924 -411.202632)
			(xy 421.331644 -411.202632) (xy 421.321528 -411.202149) (xy 421.302832 -411.194421) (xy 421.288517 -411.180125)
			(xy 421.280765 -411.161439) (xy 421.280336 -411.151324) (xy 421.280336 -410.993844) (xy 421.279896 -410.98466)
			(xy 421.273402 -410.967476) (xy 421.267636 -410.960316) (xy 421.245755 -410.934664) (xy 421.207664 -410.879029)
			(xy 421.176512 -410.819231) (xy 421.152748 -410.756132) (xy 421.136712 -410.690641) (xy 421.128637 -410.623701)
			(xy 414.525968 -410.623701) (xy 414.525968 -417.021264) (xy 414.527428 -417.030391) (xy 414.535946 -417.046779)
			(xy 414.54975 -417.059048) (xy 414.567024 -417.065584) (xy 414.57626 -417.065968) (xy 465.600034 -417.065968)
			(xy 465.631197 -417.065456) (xy 465.692989 -417.057317) (xy 465.75319 -417.041181) (xy 465.81077 -417.017326)
			(xy 465.864744 -416.98616) (xy 465.914188 -416.948215) (xy 465.958256 -416.904141) (xy 465.996194 -416.854692)
			(xy 466.027354 -416.800714) (xy 466.051201 -416.743131) (xy 466.067329 -416.682928) (xy 466.07546 -416.621135)
			(xy 466.07603 -416.589972) (xy 466.07603 -410.697426) (xy 466.075569 -410.686698) (xy 466.066825 -410.667107)
			(xy 466.050819 -410.652822) (xy 466.040724 -410.649166) (xy 465.93252 -410.614622) (xy 465.901278 -410.625036)
			(xy 465.891626 -410.638752) (xy 465.830771 -410.7238) (xy 465.703208 -410.889549) (xy 465.569155 -411.050095)
			(xy 465.428824 -411.205182) (xy 465.282437 -411.354567) (xy 465.130225 -411.498013) (xy 464.97243 -411.635292)
			(xy 464.809301 -411.766189) (xy 464.641095 -411.890494) (xy 464.46808 -412.008013) (xy 464.290528 -412.11856)
			(xy 464.108721 -412.221958) (xy 463.922947 -412.318045) (xy 463.733498 -412.406669) (xy 463.540675 -412.487689)
			(xy 463.344782 -412.560978) (xy 463.146131 -412.626419) (xy 462.945034 -412.683909) (xy 462.74181 -412.733357)
			(xy 462.536781 -412.774685) (xy 462.33027 -412.807827) (xy 462.122605 -412.832731) (xy 461.914114 -412.849358)
			(xy 461.705127 -412.85768) (xy 461.60055 -412.858204) (xy 461.600042 -412.858204) (xy 461.498066 -412.857716)
			(xy 461.294268 -412.84981) (xy 461.09093 -412.834007) (xy 460.888357 -412.810331) (xy 460.686855 -412.778818)
			(xy 460.486726 -412.739515) (xy 460.288272 -412.692482) (xy 460.091791 -412.637789) (xy 459.897578 -412.575519)
			(xy 459.705926 -412.505765) (xy 459.517123 -412.428631) (xy 459.331452 -412.344235) (xy 459.149194 -412.252703)
			(xy 458.970622 -412.154172) (xy 458.796005 -412.048792) (xy 458.625605 -411.936719) (xy 458.45968 -411.818124)
			(xy 458.298477 -411.693184) (xy 458.142241 -411.562087) (xy 457.991205 -411.425031) (xy 457.845598 -411.282221)
			(xy 457.705637 -411.133873) (xy 457.571534 -410.980209) (xy 457.44349 -410.82146) (xy 457.321698 -410.657867)
			(xy 457.206341 -410.489673) (xy 457.097593 -410.317133) (xy 456.995617 -410.140507) (xy 456.900566 -409.960058)
			(xy 456.812584 -409.77606) (xy 456.731803 -409.588789) (xy 456.658343 -409.398526) (xy 456.592317 -409.205558)
			(xy 456.533823 -409.010174) (xy 456.482949 -408.81267) (xy 456.439771 -408.613341) (xy 456.404355 -408.412488)
			(xy 456.376754 -408.210413) (xy 456.357009 -408.00742) (xy 456.34515 -407.803813) (xy 456.341195 -407.5999)
			(xy 456.34515 -407.395987) (xy 456.357009 -407.19238) (xy 456.376754 -406.989387) (xy 456.404355 -406.787312)
			(xy 456.439771 -406.586459) (xy 456.482949 -406.38713) (xy 456.533823 -406.189626) (xy 456.592317 -405.994242)
			(xy 456.658343 -405.801274) (xy 456.731803 -405.611011) (xy 456.812584 -405.42374) (xy 456.900566 -405.239742)
			(xy 456.995617 -405.059293) (xy 457.097593 -404.882667) (xy 457.206341 -404.710127) (xy 457.321698 -404.541933)
			(xy 457.44349 -404.37834) (xy 457.571534 -404.219591) (xy 457.705637 -404.065927) (xy 457.845598 -403.917579)
			(xy 457.991205 -403.774769) (xy 458.142241 -403.637713) (xy 458.298477 -403.506616) (xy 458.45968 -403.381676)
			(xy 458.625605 -403.263081) (xy 458.796005 -403.151008) (xy 458.970622 -403.045628) (xy 459.149194 -402.947097)
			(xy 459.331452 -402.855565) (xy 459.517123 -402.771169) (xy 459.705926 -402.694035) (xy 459.897578 -402.624281)
			(xy 460.091791 -402.562011) (xy 460.288272 -402.507318) (xy 460.486726 -402.460285) (xy 460.686855 -402.420982)
			(xy 460.888357 -402.389469) (xy 461.09093 -402.365793) (xy 461.294268 -402.34999) (xy 461.498066 -402.342084)
			(xy 461.600042 -402.341588) (xy 461.60055 -402.341588) (xy 461.705126 -402.342106) (xy 461.914113 -402.350433)
			(xy 462.122604 -402.367063) (xy 462.330269 -402.39197) (xy 462.536778 -402.425114) (xy 462.741807 -402.466444)
			(xy 462.94503 -402.515894) (xy 463.146126 -402.573385) (xy 463.344777 -402.638827) (xy 463.540669 -402.712117)
			(xy 463.733492 -402.793137) (xy 463.92294 -402.881761) (xy 464.108715 -402.977848) (xy 464.290522 -403.081246)
			(xy 464.468074 -403.191791) (xy 464.64109 -403.309309) (xy 464.809296 -403.433613) (xy 464.972426 -403.564508)
			(xy 465.130223 -403.701785) (xy 465.282436 -403.845229) (xy 465.428825 -403.994611) (xy 465.569159 -404.149696)
			(xy 465.703214 -404.310239) (xy 465.830781 -404.475985) (xy 465.891626 -404.56104) (xy 465.901278 -404.574756)
			(xy 465.93252 -404.58517) (xy 466.040724 -404.550626) (xy 466.050721 -404.546809) (xy 466.066638 -404.532543)
			(xy 466.075404 -404.51305) (xy 466.07603 -404.502366) (xy 466.07603 -367.551462) (xy 466.075536 -367.541457)
			(xy 466.067871 -367.522973) (xy 466.05372 -367.508825) (xy 466.035235 -367.501162) (xy 466.02523 -367.500662)
			(xy 452.507604 -367.500662) (xy 452.496172 -367.501293) (xy 452.475561 -367.511191) (xy 452.461267 -367.529037)
			(xy 452.458074 -367.540032) (xy 452.451516 -367.566194) (xy 452.43203 -367.616485) (xy 452.405654 -367.663531)
			(xy 452.372916 -367.706393) (xy 452.334468 -367.744217) (xy 452.291075 -367.776249) (xy 452.243604 -367.80185)
			(xy 452.193 -367.82051) (xy 452.140272 -367.831857) (xy 452.086472 -367.835665) (xy 452.032672 -367.831857)
			(xy 451.979944 -367.82051) (xy 451.92934 -367.80185) (xy 451.881869 -367.776249) (xy 451.838476 -367.744217)
			(xy 451.800028 -367.706393) (xy 451.76729 -367.663531) (xy 451.740914 -367.616485) (xy 451.721428 -367.566194)
			(xy 451.71487 -367.540032) (xy 451.711689 -367.529027) (xy 451.697401 -367.511162) (xy 451.676778 -367.501263)
			(xy 451.66534 -367.500662) (xy 406.004268 -367.500662) (xy 405.993768 -367.501181) (xy 405.974517 -367.509577)
			(xy 405.960218 -367.524958) (xy 405.956262 -367.534698) (xy 405.946606 -367.560634) (xy 405.920876 -367.609631)
			(xy 405.888338 -367.654397) (xy 405.849674 -367.693993) (xy 405.805696 -367.727588) (xy 405.757326 -367.754478)
			(xy 405.705579 -367.774098) (xy 405.65154 -367.786038) (xy 405.596344 -367.790045) (xy 405.541148 -367.786038)
			(xy 405.487109 -367.774098) (xy 405.435362 -367.754478) (xy 405.386992 -367.727588) (xy 405.343014 -367.693993)
			(xy 405.30435 -367.654397) (xy 405.271812 -367.609631) (xy 405.246082 -367.560634) (xy 405.236426 -367.534698)
			(xy 405.232478 -367.524948) (xy 405.218191 -367.509541) (xy 405.198927 -367.50115) (xy 405.18842 -367.500662)
			(xy 271.887442 -367.500662) (xy 271.881433 -367.50083) (xy 271.86975 -367.503653) (xy 271.864328 -367.50625)
			(xy 271.841012 -367.51782) (xy 271.791961 -367.535237) (xy 271.740998 -367.545818) (xy 271.689068 -367.549366)
			(xy 271.637138 -367.545818) (xy 271.586175 -367.535237) (xy 271.537124 -367.51782) (xy 271.513808 -367.50625)
			(xy 271.50822 -367.503456) (xy 271.49679 -367.500662) (xy 268.042898 -367.500662) (xy 268.032829 -367.501087)
			(xy 268.014231 -367.508809) (xy 268.00683 -367.515648) (xy 267.118338 -368.40414) (xy 267.10034 -368.421425)
			(xy 267.059957 -368.450735) (xy 267.015491 -368.473377) (xy 266.968034 -368.488792) (xy 266.918751 -368.496604)
			(xy 266.893802 -368.497104) (xy 266.868148 -368.497104) (xy 266.857226 -368.508788) (xy 266.516358 -368.849656)
			(xy 266.509514 -368.857055) (xy 266.501791 -368.875654) (xy 266.501372 -368.885724) (xy 266.501372 -370.523704)
			(xy 286.928752 -370.523704) (xy 286.928753 -370.456278) (xy 286.936831 -370.389338) (xy 286.952869 -370.323848)
			(xy 286.976637 -370.26075) (xy 287.007792 -370.200954) (xy 287.045885 -370.14532) (xy 287.067752 -370.119656)
			(xy 287.073556 -370.112516) (xy 287.080065 -370.095321) (xy 287.080452 -370.086128) (xy 287.080452 -369.928902)
			(xy 287.080929 -369.918774) (xy 287.088658 -369.900051) (xy 287.102947 -369.885694) (xy 287.121634 -369.877877)
			(xy 287.13176 -369.87734) (xy 287.84804 -369.87734) (xy 287.858202 -369.87769) (xy 287.876963 -369.885506)
			(xy 287.891286 -369.899925) (xy 287.898977 -369.918738) (xy 287.899348 -369.928902) (xy 287.899348 -370.086128)
			(xy 287.899756 -370.095315) (xy 287.906273 -370.112499) (xy 287.912048 -370.119656) (xy 287.933902 -370.14533)
			(xy 287.971994 -370.200962) (xy 288.003149 -370.260757) (xy 288.026916 -370.323852) (xy 288.042954 -370.389341)
			(xy 288.051031 -370.456279) (xy 288.051032 -370.523644) (xy 291.329071 -370.523644) (xy 291.329073 -370.456338)
			(xy 291.337118 -370.389515) (xy 291.353092 -370.324132) (xy 291.376766 -370.261127) (xy 291.407801 -370.201403)
			(xy 291.445751 -370.145816) (xy 291.46754 -370.120164) (xy 291.473339 -370.113021) (xy 291.479851 -370.095829)
			(xy 291.48024 -370.086636) (xy 291.48024 -369.928902) (xy 291.480665 -369.91873) (xy 291.48845 -369.899935)
			(xy 291.502835 -369.88555) (xy 291.52163 -369.877765) (xy 291.531802 -369.87734) (xy 292.248082 -369.87734)
			(xy 292.258253 -369.877778) (xy 292.277047 -369.885558) (xy 292.291433 -369.899939) (xy 292.299218 -369.918731)
			(xy 292.299644 -369.928902) (xy 292.299644 -370.086636) (xy 292.30005 -370.095823) (xy 292.306568 -370.113007)
			(xy 292.312344 -370.120164) (xy 292.33412 -370.145826) (xy 292.372071 -370.20141) (xy 292.403105 -370.261132)
			(xy 292.426779 -370.324136) (xy 292.442754 -370.389517) (xy 292.450799 -370.456339) (xy 292.4508 -370.523643)
			(xy 292.450793 -370.523704) (xy 295.72884 -370.523704) (xy 295.728841 -370.456278) (xy 295.736918 -370.389339)
			(xy 295.752956 -370.323848) (xy 295.776723 -370.260751) (xy 295.807878 -370.200955) (xy 295.84597 -370.145321)
			(xy 295.867836 -370.119656) (xy 295.873638 -370.112515) (xy 295.880149 -370.095321) (xy 295.880536 -370.086128)
			(xy 295.880536 -369.928902) (xy 295.881028 -369.918776) (xy 295.888755 -369.900056) (xy 295.903039 -369.885699)
			(xy 295.92172 -369.877879) (xy 295.931844 -369.87734) (xy 296.648124 -369.87734) (xy 296.658285 -369.877703)
			(xy 296.677045 -369.885514) (xy 296.691369 -369.899929) (xy 296.699061 -369.918739) (xy 296.699432 -369.928902)
			(xy 296.699432 -370.086128) (xy 296.699844 -370.095315) (xy 296.706358 -370.112498) (xy 296.712132 -370.119656)
			(xy 296.733983 -370.145332) (xy 296.77207 -370.200965) (xy 296.803219 -370.26076) (xy 296.826983 -370.323856)
			(xy 296.843018 -370.389343) (xy 296.851095 -370.45628) (xy 296.851096 -370.523702) (xy 296.851096 -370.523704)
			(xy 300.128631 -370.523704) (xy 300.128632 -370.456278) (xy 300.136709 -370.389339) (xy 300.152747 -370.323849)
			(xy 300.176513 -370.260751) (xy 300.207667 -370.200955) (xy 300.245758 -370.145321) (xy 300.267624 -370.119656)
			(xy 300.273425 -370.112514) (xy 300.279936 -370.095321) (xy 300.280324 -370.086128) (xy 300.280324 -369.928902)
			(xy 300.280828 -369.918777) (xy 300.288552 -369.900059) (xy 300.302833 -369.885704) (xy 300.32151 -369.877882)
			(xy 300.331632 -369.87734) (xy 301.047912 -369.87734) (xy 301.058072 -369.877712) (xy 301.076832 -369.885519)
			(xy 301.091157 -369.899932) (xy 301.098849 -369.91874) (xy 301.09922 -369.928902) (xy 301.09922 -370.086128)
			(xy 301.099612 -370.095317) (xy 301.106138 -370.112502) (xy 301.11192 -370.119656) (xy 301.133771 -370.145331)
			(xy 301.171859 -370.200965) (xy 301.203009 -370.26076) (xy 301.226773 -370.323855) (xy 301.242809 -370.389343)
			(xy 301.250886 -370.45628) (xy 301.250887 -370.523644) (xy 330.92919 -370.523644) (xy 330.929191 -370.456338)
			(xy 330.937237 -370.389514) (xy 330.953212 -370.324131) (xy 330.976887 -370.261126) (xy 331.007923 -370.201402)
			(xy 331.045875 -370.145816) (xy 331.067664 -370.120164) (xy 331.073466 -370.113023) (xy 331.079976 -370.095829)
			(xy 331.080364 -370.086636) (xy 331.080364 -369.928902) (xy 331.080766 -369.918727) (xy 331.088555 -369.899928)
			(xy 331.102948 -369.885542) (xy 331.121751 -369.877761) (xy 331.131926 -369.87734) (xy 331.848206 -369.87734)
			(xy 331.858364 -369.877829) (xy 331.877134 -369.885605) (xy 331.891499 -369.899973) (xy 331.899273 -369.918744)
			(xy 331.899768 -369.928902) (xy 331.899768 -370.086636) (xy 331.900168 -370.095824) (xy 331.90669 -370.113008)
			(xy 331.912468 -370.120164) (xy 331.934244 -370.145826) (xy 331.972193 -370.201411) (xy 332.003226 -370.261133)
			(xy 332.026899 -370.324137) (xy 332.042873 -370.389518) (xy 332.050918 -370.456339) (xy 332.050919 -370.523643)
			(xy 332.050912 -370.523703) (xy 335.328983 -370.523703) (xy 335.328984 -370.456279) (xy 335.33706 -370.389341)
			(xy 335.353096 -370.323852) (xy 335.376859 -370.260754) (xy 335.408009 -370.200957) (xy 335.446097 -370.145322)
			(xy 335.46796 -370.119656) (xy 335.473765 -370.112517) (xy 335.480273 -370.095322) (xy 335.48066 -370.086128)
			(xy 335.48066 -369.928902) (xy 335.481129 -369.918773) (xy 335.48886 -369.900048) (xy 335.503152 -369.885691)
			(xy 335.521841 -369.877875) (xy 335.531968 -369.87734) (xy 336.248248 -369.87734) (xy 336.25841 -369.877683)
			(xy 336.277171 -369.885502) (xy 336.291494 -369.899923) (xy 336.299185 -369.918737) (xy 336.299556 -369.928902)
			(xy 336.299556 -370.086128) (xy 336.299963 -370.095315) (xy 336.30648 -370.112499) (xy 336.312256 -370.119656)
			(xy 336.33411 -370.14533) (xy 336.372202 -370.200962) (xy 336.403355 -370.260757) (xy 336.427122 -370.323853)
			(xy 336.44316 -370.389341) (xy 336.451237 -370.456279) (xy 336.451238 -370.523644) (xy 339.729277 -370.523644)
			(xy 339.729279 -370.456338) (xy 339.737324 -370.389514) (xy 339.753299 -370.324131) (xy 339.776973 -370.261126)
			(xy 339.808008 -370.201402) (xy 339.845959 -370.145816) (xy 339.867748 -370.120164) (xy 339.873548 -370.113022)
			(xy 339.880059 -370.095829) (xy 339.880448 -370.086636) (xy 339.880448 -369.928902) (xy 339.880866 -369.918729)
			(xy 339.888652 -369.899933) (xy 339.903039 -369.885547) (xy 339.921837 -369.877764) (xy 339.93201 -369.87734)
			(xy 340.64829 -369.87734) (xy 340.658461 -369.877772) (xy 340.677256 -369.885554) (xy 340.691641 -369.899937)
			(xy 340.699426 -369.918731) (xy 340.699852 -369.928902) (xy 340.699852 -370.086636) (xy 340.700256 -370.095824)
			(xy 340.706775 -370.113007) (xy 340.712552 -370.120164) (xy 340.734328 -370.145826) (xy 340.772278 -370.201411)
			(xy 340.803312 -370.261133) (xy 340.826986 -370.324136) (xy 340.84296 -370.389517) (xy 340.851005 -370.456339)
			(xy 340.851006 -370.523643) (xy 340.851006 -370.523644) (xy 344.129068 -370.523644) (xy 344.129069 -370.456338)
			(xy 344.137115 -370.389515) (xy 344.153089 -370.324132) (xy 344.176763 -370.261127) (xy 344.207797 -370.201403)
			(xy 344.245748 -370.145816) (xy 344.267536 -370.120164) (xy 344.273335 -370.113021) (xy 344.279847 -370.095829)
			(xy 344.280236 -370.086636) (xy 344.280236 -369.928902) (xy 344.280735 -369.918745) (xy 344.288508 -369.899976)
			(xy 344.302873 -369.885611) (xy 344.321641 -369.877836) (xy 344.331798 -369.87734) (xy 345.048078 -369.87734)
			(xy 345.058248 -369.877782) (xy 345.077043 -369.88556) (xy 345.091429 -369.89994) (xy 345.099214 -369.918732)
			(xy 345.09964 -369.928902) (xy 345.09964 -370.086636) (xy 345.100046 -370.095823) (xy 345.106564 -370.113007)
			(xy 345.11234 -370.120164) (xy 345.134116 -370.145826) (xy 345.172067 -370.20141) (xy 345.203102 -370.261132)
			(xy 345.226776 -370.324136) (xy 345.242751 -370.389517) (xy 345.250796 -370.456339) (xy 345.250797 -370.523643)
			(xy 345.250797 -370.523644) (xy 374.929099 -370.523644) (xy 374.9291 -370.456338) (xy 374.937146 -370.389514)
			(xy 374.953121 -370.32413) (xy 374.976797 -370.261125) (xy 375.007834 -370.201402) (xy 375.045787 -370.145816)
			(xy 375.067576 -370.120164) (xy 375.073368 -370.113015) (xy 375.079886 -370.095828) (xy 375.080276 -370.086636)
			(xy 375.080276 -369.928902) (xy 375.080666 -369.918726) (xy 375.088458 -369.899924) (xy 375.102854 -369.885538)
			(xy 375.121661 -369.877759) (xy 375.131838 -369.87734) (xy 375.848118 -369.87734) (xy 375.858277 -369.877818)
			(xy 375.877047 -369.885599) (xy 375.891412 -369.89997) (xy 375.899185 -369.918743) (xy 375.89968 -369.928902)
			(xy 375.89968 -370.086636) (xy 375.900077 -370.095824) (xy 375.9066 -370.113008) (xy 375.91238 -370.120164)
			(xy 375.934155 -370.145826) (xy 375.972103 -370.201412) (xy 376.003136 -370.261134) (xy 376.026809 -370.324137)
			(xy 376.042782 -370.389518) (xy 376.050827 -370.456339) (xy 376.050828 -370.523643) (xy 376.050821 -370.523703)
			(xy 379.328892 -370.523703) (xy 379.328893 -370.456279) (xy 379.336969 -370.38934) (xy 379.353005 -370.323851)
			(xy 379.376769 -370.260754) (xy 379.40792 -370.200957) (xy 379.446008 -370.145322) (xy 379.467872 -370.119656)
			(xy 379.473678 -370.112518) (xy 379.480185 -370.095322) (xy 379.480572 -370.086128) (xy 379.480572 -369.928902)
			(xy 379.481029 -369.918772) (xy 379.488762 -369.900044) (xy 379.503058 -369.885687) (xy 379.521752 -369.877873)
			(xy 379.53188 -369.87734) (xy 380.24816 -369.87734) (xy 380.258316 -369.877755) (xy 380.277076 -369.885545)
			(xy 380.291402 -369.899945) (xy 380.299096 -369.918743) (xy 380.299468 -369.928902) (xy 380.299468 -370.086128)
			(xy 380.299872 -370.095316) (xy 380.306391 -370.1125) (xy 380.312168 -370.119656) (xy 380.334021 -370.14533)
			(xy 380.372112 -370.200963) (xy 380.403265 -370.260758) (xy 380.427032 -370.323853) (xy 380.443069 -370.389342)
			(xy 380.451146 -370.456279) (xy 380.451147 -370.523644) (xy 383.729187 -370.523644) (xy 383.729188 -370.456338)
			(xy 383.737234 -370.389514) (xy 383.753209 -370.324131) (xy 383.776884 -370.261126) (xy 383.807919 -370.201402)
			(xy 383.845871 -370.145816) (xy 383.86766 -370.120164) (xy 383.873462 -370.113023) (xy 383.879972 -370.095829)
			(xy 383.88036 -370.086636) (xy 383.88036 -369.928902) (xy 383.880766 -369.918728) (xy 383.888554 -369.899929)
			(xy 383.902946 -369.885543) (xy 383.921748 -369.877762) (xy 383.931922 -369.87734) (xy 384.648202 -369.87734)
			(xy 384.65836 -369.877832) (xy 384.67713 -369.885607) (xy 384.691495 -369.899974) (xy 384.699269 -369.918744)
			(xy 384.699764 -369.928902) (xy 384.699764 -370.086636) (xy 384.700165 -370.095824) (xy 384.706686 -370.113008)
			(xy 384.712464 -370.120164) (xy 384.73424 -370.145826) (xy 384.772189 -370.201411) (xy 384.803222 -370.261133)
			(xy 384.826895 -370.324137) (xy 384.842869 -370.389518) (xy 384.850914 -370.456339) (xy 384.850915 -370.523643)
			(xy 384.850915 -370.523644) (xy 388.128977 -370.523644) (xy 388.128979 -370.456338) (xy 388.137024 -370.389514)
			(xy 388.152999 -370.324131) (xy 388.176673 -370.261126) (xy 388.207708 -370.201402) (xy 388.245659 -370.145816)
			(xy 388.267448 -370.120164) (xy 388.273248 -370.113022) (xy 388.279759 -370.095829) (xy 388.280148 -370.086636)
			(xy 388.280148 -369.928902) (xy 388.280566 -369.918729) (xy 388.288352 -369.899933) (xy 388.302739 -369.885547)
			(xy 388.321537 -369.877764) (xy 388.33171 -369.87734) (xy 389.04799 -369.87734) (xy 389.058161 -369.877772)
			(xy 389.076956 -369.885554) (xy 389.091341 -369.899937) (xy 389.099126 -369.918731) (xy 389.099552 -369.928902)
			(xy 389.099552 -370.086636) (xy 389.099956 -370.095824) (xy 389.106475 -370.113007) (xy 389.112252 -370.120164)
			(xy 389.134028 -370.145826) (xy 389.171978 -370.201411) (xy 389.203012 -370.261133) (xy 389.226686 -370.324136)
			(xy 389.24266 -370.389517) (xy 389.250705 -370.456339) (xy 389.250706 -370.523643) (xy 389.250706 -370.523644)
			(xy 418.929008 -370.523644) (xy 418.929009 -370.456338) (xy 418.937055 -370.389513) (xy 418.953031 -370.32413)
			(xy 418.976707 -370.261125) (xy 419.007745 -370.201401) (xy 419.045698 -370.145816) (xy 419.067488 -370.120164)
			(xy 419.073281 -370.113016) (xy 419.079798 -370.095828) (xy 419.080188 -370.086636) (xy 419.080188 -369.928902)
			(xy 419.080567 -369.918724) (xy 419.08836 -369.89992) (xy 419.10276 -369.885533) (xy 419.121572 -369.877757)
			(xy 419.13175 -369.87734) (xy 419.84803 -369.87734) (xy 419.85819 -369.877809) (xy 419.87696 -369.885593)
			(xy 419.891325 -369.899967) (xy 419.899098 -369.918742) (xy 419.899592 -369.928902) (xy 419.899592 -370.086636)
			(xy 419.899986 -370.095825) (xy 419.906511 -370.113009) (xy 419.912292 -370.120164) (xy 419.934067 -370.145826)
			(xy 419.972014 -370.201412) (xy 420.003046 -370.261134) (xy 420.026718 -370.324138) (xy 420.042691 -370.389518)
			(xy 420.050736 -370.456339) (xy 420.050737 -370.523643) (xy 420.05073 -370.523703) (xy 423.328801 -370.523703)
			(xy 423.328802 -370.456279) (xy 423.336878 -370.38934) (xy 423.352915 -370.323851) (xy 423.37668 -370.260753)
			(xy 423.407831 -370.200957) (xy 423.44592 -370.145322) (xy 423.467784 -370.119656) (xy 423.47358 -370.11251)
			(xy 423.480095 -370.09532) (xy 423.480484 -370.086128) (xy 423.480484 -369.928902) (xy 423.48093 -369.91877)
			(xy 423.488665 -369.900041) (xy 423.502964 -369.885683) (xy 423.521662 -369.877871) (xy 423.531792 -369.87734)
			(xy 424.248072 -369.87734) (xy 424.258229 -369.877745) (xy 424.276989 -369.885539) (xy 424.291315 -369.899942)
			(xy 424.299008 -369.918743) (xy 424.29938 -369.928902) (xy 424.29938 -370.086128) (xy 424.299781 -370.095316)
			(xy 424.306302 -370.1125) (xy 424.31208 -370.119656) (xy 424.333933 -370.145331) (xy 424.372023 -370.200963)
			(xy 424.403176 -370.260758) (xy 424.426941 -370.323854) (xy 424.442978 -370.389342) (xy 424.451055 -370.456279)
			(xy 424.451056 -370.523644) (xy 427.729096 -370.523644) (xy 427.729097 -370.456338) (xy 427.737143 -370.389514)
			(xy 427.753118 -370.32413) (xy 427.776794 -370.261125) (xy 427.80783 -370.201402) (xy 427.845783 -370.145816)
			(xy 427.867572 -370.120164) (xy 427.873375 -370.113024) (xy 427.879884 -370.095829) (xy 427.880272 -370.086636)
			(xy 427.880272 -369.928902) (xy 427.880666 -369.918726) (xy 427.888457 -369.899925) (xy 427.902852 -369.885539)
			(xy 427.921658 -369.87776) (xy 427.931834 -369.87734) (xy 428.648114 -369.87734) (xy 428.658273 -369.877822)
			(xy 428.677043 -369.885602) (xy 428.691407 -369.899971) (xy 428.699181 -369.918743) (xy 428.699676 -369.928902)
			(xy 428.699676 -370.086636) (xy 428.700074 -370.095824) (xy 428.706597 -370.113008) (xy 428.712376 -370.120164)
			(xy 428.734152 -370.145826) (xy 428.7721 -370.201411) (xy 428.803133 -370.261134) (xy 428.826806 -370.324137)
			(xy 428.842779 -370.389518) (xy 428.850824 -370.456339) (xy 428.850825 -370.523643) (xy 428.850825 -370.523644)
			(xy 432.128887 -370.523644) (xy 432.128888 -370.456338) (xy 432.136934 -370.389514) (xy 432.152909 -370.324131)
			(xy 432.176584 -370.261126) (xy 432.207619 -370.201402) (xy 432.245571 -370.145816) (xy 432.26736 -370.120164)
			(xy 432.273162 -370.113023) (xy 432.279672 -370.095829) (xy 432.28006 -370.086636) (xy 432.28006 -369.928902)
			(xy 432.280466 -369.918728) (xy 432.288254 -369.899929) (xy 432.302646 -369.885543) (xy 432.321448 -369.877762)
			(xy 432.331622 -369.87734) (xy 433.047902 -369.87734) (xy 433.05806 -369.877832) (xy 433.07683 -369.885607)
			(xy 433.091195 -369.899974) (xy 433.098969 -369.918744) (xy 433.099464 -369.928902) (xy 433.099464 -370.086636)
			(xy 433.099865 -370.095824) (xy 433.106386 -370.113008) (xy 433.112164 -370.120164) (xy 433.13394 -370.145826)
			(xy 433.171889 -370.201411) (xy 433.202922 -370.261133) (xy 433.226595 -370.324137) (xy 433.242569 -370.389518)
			(xy 433.250614 -370.456339) (xy 433.250615 -370.523643) (xy 433.242572 -370.590465) (xy 433.226601 -370.655846)
			(xy 433.20293 -370.71885) (xy 433.171898 -370.778573) (xy 433.133951 -370.83416) (xy 433.112164 -370.859812)
			(xy 433.106375 -370.866963) (xy 433.099857 -370.884149) (xy 433.099464 -370.89334) (xy 433.099464 -371.386862)
			(xy 433.099901 -371.396046) (xy 433.106397 -371.41323) (xy 433.112164 -371.42039) (xy 433.133966 -371.446031)
			(xy 433.171914 -371.501619) (xy 433.202946 -371.561344) (xy 433.226383 -371.623725) (xy 434.329029 -371.623725)
			(xy 434.329032 -371.556418) (xy 434.33708 -371.489593) (xy 434.353056 -371.424209) (xy 434.376732 -371.361203)
			(xy 434.407768 -371.301478) (xy 434.445719 -371.245891) (xy 434.467508 -371.220238) (xy 434.473314 -371.2131)
			(xy 434.479823 -371.195904) (xy 434.480208 -371.18671) (xy 434.480208 -371.028722) (xy 434.48075 -371.018569)
			(xy 434.488512 -370.999806) (xy 434.502863 -370.985441) (xy 434.521618 -370.977661) (xy 434.53177 -370.97716)
			(xy 435.24805 -370.97716) (xy 435.258221 -370.977605) (xy 435.277019 -370.985378) (xy 435.291406 -370.999758)
			(xy 435.299189 -371.018551) (xy 435.299612 -371.028722) (xy 435.299612 -371.18671) (xy 435.300015 -371.195898)
			(xy 435.306533 -371.213082) (xy 435.312312 -371.220238) (xy 435.334064 -371.24592) (xy 435.372017 -371.301501)
			(xy 435.403055 -371.36122) (xy 435.426732 -371.424221) (xy 435.442709 -371.4896) (xy 435.450757 -371.55642)
			(xy 435.45076 -371.623723) (xy 435.442719 -371.690544) (xy 435.426749 -371.755924) (xy 435.403078 -371.818928)
			(xy 435.372046 -371.87865) (xy 435.334099 -371.934235) (xy 435.312312 -371.959886) (xy 435.306498 -371.967019)
			(xy 435.299993 -371.984219) (xy 435.299612 -371.993414) (xy 435.299612 -372.486682) (xy 435.300028 -372.495869)
			(xy 435.306537 -372.513053) (xy 435.312312 -372.52021) (xy 435.334135 -372.545834) (xy 435.372086 -372.601423)
			(xy 435.40312 -372.66115) (xy 435.426793 -372.724159) (xy 435.442765 -372.789545) (xy 435.450807 -372.856371)
			(xy 435.450804 -372.92368) (xy 435.442756 -372.990506) (xy 435.426778 -373.05589) (xy 435.403099 -373.118896)
			(xy 435.372059 -373.178621) (xy 435.334103 -373.234206) (xy 435.312312 -373.259858) (xy 435.30651 -373.266999)
			(xy 435.299998 -373.284193) (xy 435.299612 -373.293386) (xy 435.299612 -373.451374) (xy 435.299213 -373.46155)
			(xy 435.291428 -373.480354) (xy 435.277034 -373.494741) (xy 435.258226 -373.502518) (xy 435.24805 -373.502936)
			(xy 434.53177 -373.502936) (xy 434.521607 -373.502491) (xy 434.502832 -373.494701) (xy 434.488467 -373.480321)
			(xy 434.480698 -373.461537) (xy 434.480208 -373.451374) (xy 434.480208 -373.293386) (xy 434.479803 -373.284198)
			(xy 434.473286 -373.267014) (xy 434.467508 -373.259858) (xy 434.445755 -373.234178) (xy 434.407807 -373.178595)
			(xy 434.376774 -373.118875) (xy 434.3531 -373.055874) (xy 434.337126 -372.990495) (xy 434.32908 -372.923676)
			(xy 434.329077 -372.856375) (xy 434.337117 -372.789555) (xy 434.353085 -372.724175) (xy 434.376753 -372.661172)
			(xy 434.40778 -372.601449) (xy 434.445723 -372.545863) (xy 434.467508 -372.52021) (xy 434.473326 -372.51308)
			(xy 434.479828 -372.495878) (xy 434.480208 -372.486682) (xy 434.480208 -371.993414) (xy 434.479789 -371.984228)
			(xy 434.473281 -371.967043) (xy 434.467508 -371.959886) (xy 434.445684 -371.934264) (xy 434.407738 -371.878673)
			(xy 434.376708 -371.818945) (xy 434.353039 -371.755936) (xy 434.33707 -371.690551) (xy 434.329029 -371.623725)
			(xy 433.226383 -371.623725) (xy 433.226618 -371.62435) (xy 433.24259 -371.689734) (xy 433.250633 -371.756557)
			(xy 433.250632 -371.823864) (xy 433.242586 -371.890687) (xy 433.226612 -371.95607) (xy 433.202938 -372.019075)
			(xy 433.171903 -372.078799) (xy 433.133953 -372.134386) (xy 433.112164 -372.160038) (xy 433.106364 -372.167181)
			(xy 433.099852 -372.184373) (xy 433.099464 -372.193566) (xy 433.099464 -372.351554) (xy 433.098999 -372.361722)
			(xy 433.091229 -372.380516) (xy 433.076856 -372.394902) (xy 433.05807 -372.402689) (xy 433.047902 -372.403116)
			(xy 432.331622 -372.403116) (xy 432.321446 -372.402717) (xy 432.302643 -372.394931) (xy 432.288256 -372.380537)
			(xy 432.280478 -372.36173) (xy 432.28006 -372.351554) (xy 432.28006 -372.193566) (xy 432.279653 -372.184379)
			(xy 432.273135 -372.167195) (xy 432.26736 -372.160038) (xy 432.245586 -372.134375) (xy 432.207635 -372.07879)
			(xy 432.1766 -372.019069) (xy 432.152925 -371.956065) (xy 432.136951 -371.890684) (xy 432.128905 -371.823863)
			(xy 432.128904 -371.756558) (xy 432.136947 -371.689736) (xy 432.152919 -371.624355) (xy 432.176591 -371.561351)
			(xy 432.207624 -371.501628) (xy 432.245573 -371.446042) (xy 432.26736 -371.42039) (xy 432.273151 -371.413241)
			(xy 432.279667 -371.396053) (xy 432.28006 -371.386862) (xy 432.28006 -370.89334) (xy 432.279617 -370.884157)
			(xy 432.273125 -370.866972) (xy 432.26736 -370.859812) (xy 432.24556 -370.83417) (xy 432.20761 -370.778582)
			(xy 432.176576 -370.718858) (xy 432.152903 -370.655852) (xy 432.136931 -370.590468) (xy 432.128887 -370.523644)
			(xy 428.850825 -370.523644) (xy 428.842782 -370.590464) (xy 428.826811 -370.655846) (xy 428.80314 -370.71885)
			(xy 428.772109 -370.778573) (xy 428.734163 -370.83416) (xy 428.712376 -370.859812) (xy 428.706589 -370.866964)
			(xy 428.700069 -370.884149) (xy 428.699676 -370.89334) (xy 428.699676 -371.386862) (xy 428.70011 -371.396047)
			(xy 428.706608 -371.413231) (xy 428.712376 -371.42039) (xy 428.734177 -371.446031) (xy 428.772125 -371.501619)
			(xy 428.803156 -371.561345) (xy 428.826615 -371.623785) (xy 429.928709 -371.623785) (xy 429.928713 -371.556358)
			(xy 429.936793 -371.489417) (xy 429.952833 -371.423925) (xy 429.976602 -371.360827) (xy 430.007759 -371.30103)
			(xy 430.045853 -371.245395) (xy 430.06772 -371.21973) (xy 430.073531 -371.212595) (xy 430.080036 -371.195397)
			(xy 430.08042 -371.186202) (xy 430.08042 -371.028722) (xy 430.080944 -371.018599) (xy 430.088661 -370.999882)
			(xy 430.102935 -370.985526) (xy 430.121608 -370.977702) (xy 430.131728 -370.97716) (xy 430.848008 -370.97716)
			(xy 430.858158 -370.977614) (xy 430.876902 -370.985405) (xy 430.891224 -370.999791) (xy 430.898931 -371.018571)
			(xy 430.899316 -371.028722) (xy 430.899316 -371.186202) (xy 430.899722 -371.19539) (xy 430.906238 -371.212574)
			(xy 430.912016 -371.21973) (xy 430.933842 -371.245426) (xy 430.971931 -371.301057) (xy 431.003082 -371.360849)
			(xy 431.026848 -371.423942) (xy 431.042886 -371.489427) (xy 431.050964 -371.556361) (xy 431.050968 -371.623782)
			(xy 431.042896 -371.690717) (xy 431.026865 -371.756204) (xy 431.003106 -371.819299) (xy 430.97196 -371.879094)
			(xy 430.933877 -371.934729) (xy 430.912016 -371.960394) (xy 430.906241 -371.967555) (xy 430.899713 -371.984733)
			(xy 430.899316 -371.993922) (xy 430.899316 -372.486174) (xy 430.899735 -372.49536) (xy 430.906242 -372.512545)
			(xy 430.912016 -372.519702) (xy 430.933913 -372.54534) (xy 430.971999 -372.600979) (xy 431.003148 -372.660779)
			(xy 431.026909 -372.723879) (xy 431.042942 -372.789371) (xy 431.051015 -372.856313) (xy 431.051012 -372.923739)
			(xy 431.042933 -372.990679) (xy 431.026894 -373.05617) (xy 431.003127 -373.119268) (xy 430.971973 -373.179065)
			(xy 430.933881 -373.2347) (xy 430.912016 -373.260366) (xy 430.906211 -373.267505) (xy 430.899701 -373.2847)
			(xy 430.899316 -373.293894) (xy 430.899316 -373.451374) (xy 430.898851 -373.461504) (xy 430.891124 -373.480233)
			(xy 430.87683 -373.494592) (xy 430.858136 -373.502405) (xy 430.848008 -373.502936) (xy 430.131728 -373.502936)
			(xy 430.12158 -373.502456) (xy 430.102835 -373.494677) (xy 430.088512 -373.480298) (xy 430.080805 -373.461523)
			(xy 430.08042 -373.451374) (xy 430.08042 -373.293894) (xy 430.080008 -373.284707) (xy 430.073495 -373.267523)
			(xy 430.06772 -373.260366) (xy 430.045889 -373.234674) (xy 430.007798 -373.179043) (xy 429.976644 -373.119251)
			(xy 429.952877 -373.056158) (xy 429.936839 -372.990672) (xy 429.92876 -372.923736) (xy 429.928757 -372.856315)
			(xy 429.93683 -372.789379) (xy 429.952862 -372.723891) (xy 429.976624 -372.660796) (xy 430.007771 -372.601)
			(xy 430.045857 -372.545367) (xy 430.06772 -372.519702) (xy 430.073501 -372.512546) (xy 430.080024 -372.495364)
			(xy 430.08042 -372.486174) (xy 430.08042 -371.993922) (xy 430.079995 -371.984737) (xy 430.073491 -371.967552)
			(xy 430.06772 -371.960394) (xy 430.045818 -371.93476) (xy 430.007729 -371.879121) (xy 429.976579 -371.819321)
			(xy 429.952816 -371.75622) (xy 429.936783 -371.690727) (xy 429.928709 -371.623785) (xy 428.826615 -371.623785)
			(xy 428.826828 -371.624351) (xy 428.842799 -371.689734) (xy 428.850842 -371.756558) (xy 428.850841 -371.823863)
			(xy 428.842795 -371.890687) (xy 428.826821 -371.95607) (xy 428.803148 -372.019075) (xy 428.772114 -372.078799)
			(xy 428.734164 -372.134386) (xy 428.712376 -372.160038) (xy 428.706578 -372.167182) (xy 428.700065 -372.184374)
			(xy 428.699676 -372.193566) (xy 428.699676 -372.351554) (xy 428.699199 -372.361721) (xy 428.691432 -372.380512)
			(xy 428.677062 -372.394898) (xy 428.65828 -372.402687) (xy 428.648114 -372.403116) (xy 427.931834 -372.403116)
			(xy 427.921659 -372.402707) (xy 427.902856 -372.394925) (xy 427.888469 -372.380534) (xy 427.880691 -372.361729)
			(xy 427.880272 -372.351554) (xy 427.880272 -372.193566) (xy 427.879884 -372.184376) (xy 427.873356 -372.167192)
			(xy 427.867572 -372.160038) (xy 427.845797 -372.134375) (xy 427.807846 -372.078791) (xy 427.77681 -372.019069)
			(xy 427.753135 -371.956066) (xy 427.73716 -371.890685) (xy 427.729114 -371.823863) (xy 427.729113 -371.756558)
			(xy 427.737156 -371.689736) (xy 427.753129 -371.624354) (xy 427.776801 -371.56135) (xy 427.807835 -371.501627)
			(xy 427.845784 -371.446042) (xy 427.867572 -371.42039) (xy 427.873364 -371.413242) (xy 427.879879 -371.396053)
			(xy 427.880272 -371.386862) (xy 427.880272 -370.89334) (xy 427.879849 -370.884154) (xy 427.873345 -370.866969)
			(xy 427.867572 -370.859812) (xy 427.845772 -370.83417) (xy 427.807821 -370.778583) (xy 427.776786 -370.718858)
			(xy 427.753113 -370.655852) (xy 427.73714 -370.590468) (xy 427.729096 -370.523644) (xy 424.451056 -370.523644)
			(xy 424.451056 -370.523703) (xy 424.442981 -370.59064) (xy 424.426947 -370.656129) (xy 424.403183 -370.719225)
			(xy 424.372033 -370.779021) (xy 424.333944 -370.834655) (xy 424.31208 -370.86032) (xy 424.30629 -370.86747)
			(xy 424.299772 -370.884657) (xy 424.29938 -370.893848) (xy 424.29938 -371.386354) (xy 424.299817 -371.395538)
			(xy 424.306312 -371.412723) (xy 424.31208 -371.419882) (xy 424.333958 -371.445536) (xy 424.372048 -371.501171)
			(xy 424.403199 -371.560969) (xy 424.426835 -371.623725) (xy 425.528941 -371.623725) (xy 425.528945 -371.556418)
			(xy 425.536992 -371.489593) (xy 425.552969 -371.424208) (xy 425.576645 -371.361202) (xy 425.607682 -371.301478)
			(xy 425.645634 -371.24589) (xy 425.667424 -371.220238) (xy 425.673232 -371.213101) (xy 425.679739 -371.195904)
			(xy 425.680124 -371.18671) (xy 425.680124 -371.028722) (xy 425.680582 -371.018554) (xy 425.688357 -370.999762)
			(xy 425.702732 -370.985377) (xy 425.721518 -370.977589) (xy 425.731686 -370.97716) (xy 426.447966 -370.97716)
			(xy 426.458138 -370.977592) (xy 426.476936 -370.98537) (xy 426.491323 -370.999754) (xy 426.499105 -371.01855)
			(xy 426.499528 -371.028722) (xy 426.499528 -371.18671) (xy 426.499927 -371.195898) (xy 426.506448 -371.213083)
			(xy 426.512228 -371.220238) (xy 426.533979 -371.24592) (xy 426.571931 -371.301502) (xy 426.602968 -371.361221)
			(xy 426.626645 -371.424221) (xy 426.642621 -371.4896) (xy 426.650669 -371.55642) (xy 426.650672 -371.623723)
			(xy 426.642631 -371.690543) (xy 426.626661 -371.755924) (xy 426.602991 -371.818927) (xy 426.571961 -371.878649)
			(xy 426.534014 -371.934234) (xy 426.512228 -371.959886) (xy 426.506404 -371.967011) (xy 426.499908 -371.984217)
			(xy 426.499528 -371.993414) (xy 426.499528 -372.486682) (xy 426.49994 -372.495869) (xy 426.506452 -372.513054)
			(xy 426.512228 -372.52021) (xy 426.53405 -372.545834) (xy 426.572 -372.601424) (xy 426.603034 -372.661151)
			(xy 426.626706 -372.724159) (xy 426.642678 -372.789545) (xy 426.65072 -372.856371) (xy 426.650717 -372.92368)
			(xy 426.642669 -372.990505) (xy 426.626691 -373.05589) (xy 426.603013 -373.118896) (xy 426.571974 -373.17862)
			(xy 426.534019 -373.234206) (xy 426.512228 -373.259858) (xy 426.506416 -373.266992) (xy 426.499912 -373.284191)
			(xy 426.499528 -373.293386) (xy 426.499528 -373.451374) (xy 426.499114 -373.461548) (xy 426.491331 -373.480349)
			(xy 426.476942 -373.494736) (xy 426.45814 -373.502515) (xy 426.447966 -373.502936) (xy 425.731686 -373.502936)
			(xy 425.72151 -373.502547) (xy 425.70271 -373.494752) (xy 425.688325 -373.480356) (xy 425.680545 -373.46155)
			(xy 425.680124 -373.451374) (xy 425.680124 -373.293386) (xy 425.679715 -373.284199) (xy 425.6732 -373.267015)
			(xy 425.667424 -373.259858) (xy 425.64567 -373.234178) (xy 425.607722 -373.178595) (xy 425.576688 -373.118875)
			(xy 425.553014 -373.055874) (xy 425.537039 -372.990496) (xy 425.528992 -372.923677) (xy 425.528989 -372.856375)
			(xy 425.53703 -372.789555) (xy 425.552999 -372.724174) (xy 425.576667 -372.661171) (xy 425.607695 -372.601449)
			(xy 425.645639 -372.545863) (xy 425.667424 -372.52021) (xy 425.673244 -372.513082) (xy 425.679744 -372.495878)
			(xy 425.680124 -372.486682) (xy 425.680124 -371.993414) (xy 425.679702 -371.984228) (xy 425.673196 -371.967044)
			(xy 425.667424 -371.959886) (xy 425.645599 -371.934264) (xy 425.607653 -371.878673) (xy 425.576622 -371.818945)
			(xy 425.552952 -371.755937) (xy 425.536982 -371.690551) (xy 425.528941 -371.623725) (xy 424.426835 -371.623725)
			(xy 424.426964 -371.624067) (xy 424.442999 -371.689558) (xy 424.451074 -371.756498) (xy 424.451072 -371.823923)
			(xy 424.442995 -371.890863) (xy 424.426957 -371.956353) (xy 424.403191 -372.01945) (xy 424.372037 -372.079247)
			(xy 424.333946 -372.134881) (xy 424.31208 -372.160546) (xy 424.306279 -372.167688) (xy 424.299768 -372.184881)
			(xy 424.29938 -372.194074) (xy 424.29938 -372.351554) (xy 424.298836 -372.361675) (xy 424.291127 -372.380392)
			(xy 424.276858 -372.394749) (xy 424.25819 -372.402573) (xy 424.248072 -372.403116) (xy 423.531792 -372.403116)
			(xy 423.521639 -372.402685) (xy 423.50289 -372.39489) (xy 423.488568 -372.380496) (xy 423.480865 -372.361709)
			(xy 423.480484 -372.351554) (xy 423.480484 -372.194074) (xy 423.48009 -372.184885) (xy 423.473565 -372.167701)
			(xy 423.467784 -372.160546) (xy 423.445934 -372.134869) (xy 423.407846 -372.079236) (xy 423.376696 -372.019441)
			(xy 423.352932 -371.956346) (xy 423.336896 -371.890858) (xy 423.328819 -371.823922) (xy 423.328818 -371.756499)
			(xy 423.336892 -371.689562) (xy 423.352925 -371.624074) (xy 423.376687 -371.560978) (xy 423.407835 -371.501182)
			(xy 423.445921 -371.445547) (xy 423.467784 -371.419882) (xy 423.473569 -371.412728) (xy 423.480091 -371.395544)
			(xy 423.480484 -371.386354) (xy 423.480484 -370.893848) (xy 423.480055 -370.884663) (xy 423.473555 -370.867478)
			(xy 423.467784 -370.86032) (xy 423.445909 -370.834664) (xy 423.407821 -370.779028) (xy 423.376672 -370.71923)
			(xy 423.352909 -370.656132) (xy 423.336875 -370.590642) (xy 423.328801 -370.523703) (xy 420.05073 -370.523703)
			(xy 420.042694 -370.590464) (xy 420.026724 -370.655845) (xy 420.003054 -370.718849) (xy 419.972023 -370.778573)
			(xy 419.934078 -370.834159) (xy 419.912292 -370.859812) (xy 419.906507 -370.866965) (xy 419.899986 -370.88415)
			(xy 419.899592 -370.89334) (xy 419.899592 -371.386862) (xy 419.900022 -371.396047) (xy 419.906522 -371.413231)
			(xy 419.912292 -371.42039) (xy 419.934093 -371.446031) (xy 419.972039 -371.50162) (xy 420.00307 -371.561345)
			(xy 420.026528 -371.623785) (xy 421.128621 -371.623785) (xy 421.128625 -371.556358) (xy 421.136705 -371.489416)
			(xy 421.152746 -371.423925) (xy 421.176516 -371.360826) (xy 421.207673 -371.301029) (xy 421.245769 -371.245395)
			(xy 421.267636 -371.21973) (xy 421.273449 -371.212597) (xy 421.279953 -371.195397) (xy 421.280336 -371.186202)
			(xy 421.280336 -371.028722) (xy 421.280844 -371.018597) (xy 421.288564 -370.999877) (xy 421.302844 -370.98552)
			(xy 421.321522 -370.9777) (xy 421.331644 -370.97716) (xy 422.047924 -370.97716) (xy 422.058075 -370.977601)
			(xy 422.07682 -370.985397) (xy 422.091141 -370.999787) (xy 422.098847 -371.018569) (xy 422.099232 -371.028722)
			(xy 422.099232 -371.186202) (xy 422.099656 -371.195387) (xy 422.106162 -371.212571) (xy 422.111932 -371.21973)
			(xy 422.133758 -371.245427) (xy 422.171845 -371.301057) (xy 422.202996 -371.36085) (xy 422.226761 -371.423942)
			(xy 422.242798 -371.489427) (xy 422.250876 -371.556361) (xy 422.25088 -371.623781) (xy 422.242808 -371.690717)
			(xy 422.226778 -371.756203) (xy 422.203019 -371.819298) (xy 422.171875 -371.879094) (xy 422.133793 -371.934728)
			(xy 422.111932 -371.960394) (xy 422.106147 -371.967547) (xy 422.099627 -371.984732) (xy 422.099232 -371.993922)
			(xy 422.099232 -372.486174) (xy 422.09967 -372.495358) (xy 422.106166 -372.512542) (xy 422.111932 -372.519702)
			(xy 422.133828 -372.54534) (xy 422.171914 -372.600979) (xy 422.203061 -372.66078) (xy 422.226822 -372.72388)
			(xy 422.242854 -372.789372) (xy 422.250927 -372.856313) (xy 422.250924 -372.923738) (xy 422.242845 -372.990678)
			(xy 422.226807 -373.056169) (xy 422.20304 -373.119267) (xy 422.171888 -373.179064) (xy 422.133797 -373.2347)
			(xy 422.111932 -373.260366) (xy 422.106117 -373.267498) (xy 422.099615 -373.284699) (xy 422.099232 -373.293894)
			(xy 422.099232 -373.451374) (xy 422.098751 -373.461503) (xy 422.091027 -373.480228) (xy 422.076738 -373.494587)
			(xy 422.05805 -373.502402) (xy 422.047924 -373.502936) (xy 421.331644 -373.502936) (xy 421.321497 -373.502443)
			(xy 421.302753 -373.494669) (xy 421.288429 -373.480294) (xy 421.280721 -373.461522) (xy 421.280336 -373.451374)
			(xy 421.280336 -373.293894) (xy 421.279921 -373.284708) (xy 421.27341 -373.267524) (xy 421.267636 -373.260366)
			(xy 421.245804 -373.234674) (xy 421.207712 -373.179044) (xy 421.176558 -373.119252) (xy 421.15279 -373.056158)
			(xy 421.136751 -372.990672) (xy 421.128672 -372.923736) (xy 421.128669 -372.856315) (xy 421.136742 -372.789378)
			(xy 421.152775 -372.72389) (xy 421.176537 -372.660795) (xy 421.207686 -372.601) (xy 421.245773 -372.545367)
			(xy 421.267636 -372.519702) (xy 421.273419 -372.512547) (xy 421.279941 -372.495364) (xy 421.280336 -372.486174)
			(xy 421.280336 -371.993922) (xy 421.279907 -371.984737) (xy 421.273406 -371.967553) (xy 421.267636 -371.960394)
			(xy 421.245733 -371.93476) (xy 421.207643 -371.879122) (xy 421.176492 -371.819322) (xy 421.152729 -371.756221)
			(xy 421.136695 -371.690727) (xy 421.128621 -371.623785) (xy 420.026528 -371.623785) (xy 420.026741 -371.624351)
			(xy 420.042712 -371.689734) (xy 420.050754 -371.756558) (xy 420.050753 -371.823863) (xy 420.042708 -371.890686)
			(xy 420.026734 -371.956069) (xy 420.003061 -372.019074) (xy 419.972028 -372.078798) (xy 419.93408 -372.134385)
			(xy 419.912292 -372.160038) (xy 419.906496 -372.167183) (xy 419.899981 -372.184374) (xy 419.899592 -372.193566)
			(xy 419.899592 -372.351554) (xy 419.899099 -372.361719) (xy 419.891335 -372.380507) (xy 419.876971 -372.394892)
			(xy 419.858194 -372.402684) (xy 419.84803 -372.403116) (xy 419.13175 -372.403116) (xy 419.121576 -372.402694)
			(xy 419.102773 -372.394917) (xy 419.088385 -372.38053) (xy 419.080607 -372.361728) (xy 419.080188 -372.351554)
			(xy 419.080188 -372.193566) (xy 419.079797 -372.184377) (xy 419.07327 -372.167192) (xy 419.067488 -372.160038)
			(xy 419.045713 -372.134375) (xy 419.00776 -372.078791) (xy 418.976724 -372.01907) (xy 418.953048 -371.956067)
			(xy 418.937072 -371.890685) (xy 418.929026 -371.823863) (xy 418.929025 -371.756558) (xy 418.937069 -371.689736)
			(xy 418.953042 -371.624354) (xy 418.976715 -371.561349) (xy 419.007749 -371.501627) (xy 419.0457 -371.446041)
			(xy 419.067488 -371.42039) (xy 419.07327 -371.413234) (xy 419.079794 -371.396052) (xy 419.080188 -371.386862)
			(xy 419.080188 -370.89334) (xy 419.079761 -370.884154) (xy 419.07326 -370.86697) (xy 419.067488 -370.859812)
			(xy 419.045687 -370.83417) (xy 419.007735 -370.778583) (xy 418.9767 -370.718859) (xy 418.953026 -370.655853)
			(xy 418.937052 -370.590469) (xy 418.929008 -370.523644) (xy 389.250706 -370.523644) (xy 389.242663 -370.590465)
			(xy 389.226691 -370.655847) (xy 389.203019 -370.718851) (xy 389.171987 -370.778574) (xy 389.134039 -370.83416)
			(xy 389.112252 -370.859812) (xy 389.106462 -370.866962) (xy 389.099945 -370.884149) (xy 389.099552 -370.89334)
			(xy 389.099552 -371.386862) (xy 389.099991 -371.396046) (xy 389.106486 -371.41323) (xy 389.112252 -371.42039)
			(xy 389.134054 -371.446031) (xy 389.172003 -371.501618) (xy 389.203036 -371.561344) (xy 389.226474 -371.623725)
			(xy 390.32912 -371.623725) (xy 390.329123 -371.556418) (xy 390.337171 -371.489593) (xy 390.353146 -371.42421)
			(xy 390.376822 -371.361204) (xy 390.407857 -371.301479) (xy 390.445807 -371.245891) (xy 390.467596 -371.220238)
			(xy 390.473401 -371.213099) (xy 390.479911 -371.195904) (xy 390.480296 -371.18671) (xy 390.480296 -371.028722)
			(xy 390.48085 -371.018571) (xy 390.48861 -370.99981) (xy 390.502956 -370.985446) (xy 390.521707 -370.977663)
			(xy 390.531858 -370.97716) (xy 391.248138 -370.97716) (xy 391.258301 -370.977603) (xy 391.277075 -370.985394)
			(xy 391.29144 -370.999775) (xy 391.299209 -371.018558) (xy 391.2997 -371.028722) (xy 391.2997 -371.18671)
			(xy 391.300106 -371.195898) (xy 391.306623 -371.213082) (xy 391.3124 -371.220238) (xy 391.334149 -371.245921)
			(xy 391.372097 -371.301504) (xy 391.403129 -371.361224) (xy 391.426803 -371.424224) (xy 391.442777 -371.489602)
			(xy 391.450824 -371.556421) (xy 391.450827 -371.623722) (xy 391.442787 -371.690541) (xy 391.42682 -371.755921)
			(xy 391.403153 -371.818924) (xy 391.372126 -371.878647) (xy 391.334184 -371.934233) (xy 391.3124 -371.959886)
			(xy 391.306584 -371.967018) (xy 391.300081 -371.984219) (xy 391.2997 -371.993414) (xy 391.2997 -372.486682)
			(xy 391.300119 -372.495868) (xy 391.306627 -372.513053) (xy 391.3124 -372.52021) (xy 391.33422 -372.545835)
			(xy 391.372165 -372.601426) (xy 391.403195 -372.661154) (xy 391.426864 -372.724162) (xy 391.442833 -372.789547)
			(xy 391.450874 -372.856372) (xy 391.450871 -372.923679) (xy 391.442824 -372.990503) (xy 391.426849 -373.055887)
			(xy 391.403174 -373.118893) (xy 391.372139 -373.178617) (xy 391.334189 -373.234205) (xy 391.3124 -373.259858)
			(xy 391.306596 -373.266998) (xy 391.300086 -373.284193) (xy 391.2997 -373.293386) (xy 391.2997 -373.451374)
			(xy 391.299146 -373.461525) (xy 391.291388 -373.480287) (xy 391.277041 -373.494652) (xy 391.258289 -373.502434)
			(xy 391.248138 -373.502936) (xy 390.531858 -373.502936) (xy 390.521694 -373.5025) (xy 390.502919 -373.494707)
			(xy 390.488555 -373.480324) (xy 390.480786 -373.461538) (xy 390.480296 -373.451374) (xy 390.480296 -373.293386)
			(xy 390.479893 -373.284198) (xy 390.473374 -373.267014) (xy 390.467596 -373.259858) (xy 390.445843 -373.234178)
			(xy 390.407896 -373.178594) (xy 390.376864 -373.118874) (xy 390.353191 -373.055874) (xy 390.337217 -372.990495)
			(xy 390.329171 -372.923676) (xy 390.329167 -372.856375) (xy 390.337208 -372.789555) (xy 390.353176 -372.724175)
			(xy 390.376843 -372.661173) (xy 390.40787 -372.60145) (xy 390.445812 -372.545863) (xy 390.467596 -372.52021)
			(xy 390.473413 -372.513079) (xy 390.479916 -372.495878) (xy 390.480296 -372.486682) (xy 390.480296 -371.993414)
			(xy 390.47988 -371.984227) (xy 390.47337 -371.967043) (xy 390.467596 -371.959886) (xy 390.445772 -371.934264)
			(xy 390.407827 -371.878672) (xy 390.376798 -371.818944) (xy 390.353129 -371.755936) (xy 390.33716 -371.69055)
			(xy 390.32912 -371.623725) (xy 389.226474 -371.623725) (xy 389.226709 -371.62435) (xy 389.242681 -371.689733)
			(xy 389.250724 -371.756557) (xy 389.250723 -371.823864) (xy 389.242677 -371.890687) (xy 389.226702 -371.956071)
			(xy 389.203028 -372.019076) (xy 389.171992 -372.0788) (xy 389.134041 -372.134386) (xy 389.112252 -372.160038)
			(xy 389.106451 -372.16718) (xy 389.09994 -372.184373) (xy 389.099552 -372.193566) (xy 389.099552 -372.351554)
			(xy 389.099098 -372.361724) (xy 389.091327 -372.380519) (xy 389.07695 -372.394906) (xy 389.05816 -372.402691)
			(xy 389.04799 -372.403116) (xy 388.33171 -372.403116) (xy 388.321533 -372.402727) (xy 388.30273 -372.394937)
			(xy 388.288343 -372.38054) (xy 388.280566 -372.361731) (xy 388.280148 -372.351554) (xy 388.280148 -372.193566)
			(xy 388.279743 -372.184378) (xy 388.273225 -372.167195) (xy 388.267448 -372.160038) (xy 388.245674 -372.134375)
			(xy 388.207724 -372.07879) (xy 388.17669 -372.019068) (xy 388.153016 -371.956065) (xy 388.137042 -371.890684)
			(xy 388.128996 -371.823863) (xy 388.128995 -371.756558) (xy 388.137038 -371.689737) (xy 388.15301 -371.624355)
			(xy 388.176681 -371.561351) (xy 388.207713 -371.501628) (xy 388.245661 -371.446042) (xy 388.267448 -371.42039)
			(xy 388.273237 -371.41324) (xy 388.279755 -371.396053) (xy 388.280148 -371.386862) (xy 388.280148 -370.89334)
			(xy 388.279708 -370.884156) (xy 388.273214 -370.866972) (xy 388.267448 -370.859812) (xy 388.245648 -370.83417)
			(xy 388.207699 -370.778582) (xy 388.176666 -370.718857) (xy 388.152993 -370.655851) (xy 388.137021 -370.590468)
			(xy 388.128977 -370.523644) (xy 384.850915 -370.523644) (xy 384.842872 -370.590465) (xy 384.826901 -370.655846)
			(xy 384.80323 -370.71885) (xy 384.772198 -370.778573) (xy 384.734251 -370.83416) (xy 384.712464 -370.859812)
			(xy 384.706675 -370.866963) (xy 384.700157 -370.884149) (xy 384.699764 -370.89334) (xy 384.699764 -371.386862)
			(xy 384.700201 -371.396046) (xy 384.706697 -371.41323) (xy 384.712464 -371.42039) (xy 384.734266 -371.446031)
			(xy 384.772214 -371.501619) (xy 384.803246 -371.561344) (xy 384.826706 -371.623785) (xy 385.9288 -371.623785)
			(xy 385.928804 -371.556358) (xy 385.936884 -371.489417) (xy 385.952923 -371.423926) (xy 385.976692 -371.360827)
			(xy 386.007848 -371.30103) (xy 386.045941 -371.245395) (xy 386.067808 -371.21973) (xy 386.073618 -371.212594)
			(xy 386.080124 -371.195396) (xy 386.080508 -371.186202) (xy 386.080508 -371.028722) (xy 386.081044 -371.018601)
			(xy 386.088758 -370.999886) (xy 386.103029 -370.98553) (xy 386.121698 -370.977704) (xy 386.131816 -370.97716)
			(xy 386.848096 -370.97716) (xy 386.858245 -370.977624) (xy 386.876989 -370.985411) (xy 386.891311 -370.999794)
			(xy 386.899019 -371.018571) (xy 386.899404 -371.028722) (xy 386.899404 -371.186202) (xy 386.899812 -371.195389)
			(xy 386.906327 -371.212574) (xy 386.912104 -371.21973) (xy 386.93393 -371.245426) (xy 386.97202 -371.301056)
			(xy 387.003172 -371.360848) (xy 387.026938 -371.423941) (xy 387.042976 -371.489426) (xy 387.051055 -371.556361)
			(xy 387.051059 -371.623782) (xy 387.042987 -371.690717) (xy 387.026955 -371.756204) (xy 387.003196 -371.8193)
			(xy 386.972049 -371.879095) (xy 386.933966 -371.934729) (xy 386.912104 -371.960394) (xy 386.906328 -371.967554)
			(xy 386.899801 -371.984733) (xy 386.899404 -371.993922) (xy 386.899404 -372.486174) (xy 386.899826 -372.49536)
			(xy 386.906331 -372.512545) (xy 386.912104 -372.519702) (xy 386.934001 -372.54534) (xy 386.972089 -372.600978)
			(xy 387.003238 -372.660778) (xy 387.027 -372.723879) (xy 387.043033 -372.789371) (xy 387.051106 -372.856312)
			(xy 387.051103 -372.923739) (xy 387.043024 -372.990679) (xy 387.026985 -373.05617) (xy 387.003217 -373.119268)
			(xy 386.972062 -373.179066) (xy 386.93397 -373.234701) (xy 386.912104 -373.260366) (xy 386.906297 -373.267504)
			(xy 386.899789 -373.2847) (xy 386.899404 -373.293894) (xy 386.899404 -373.451374) (xy 386.898854 -373.461494)
			(xy 386.891142 -373.480206) (xy 386.876876 -373.494562) (xy 386.858212 -373.50239) (xy 386.848096 -373.502936)
			(xy 386.131816 -373.502936) (xy 386.121667 -373.502466) (xy 386.102922 -373.494683) (xy 386.0886 -373.480301)
			(xy 386.080893 -373.461524) (xy 386.080508 -373.451374) (xy 386.080508 -373.293894) (xy 386.080099 -373.284707)
			(xy 386.073584 -373.267523) (xy 386.067808 -373.260366) (xy 386.045977 -373.234673) (xy 386.007887 -373.179043)
			(xy 385.976734 -373.119251) (xy 385.952968 -373.056157) (xy 385.93693 -372.990671) (xy 385.928851 -372.923736)
			(xy 385.928848 -372.856315) (xy 385.936921 -372.789379) (xy 385.952953 -372.723892) (xy 385.976713 -372.660796)
			(xy 386.007861 -372.601001) (xy 386.045946 -372.545367) (xy 386.067808 -372.519702) (xy 386.073587 -372.512544)
			(xy 386.080112 -372.495363) (xy 386.080508 -372.486174) (xy 386.080508 -371.993922) (xy 386.080085 -371.984736)
			(xy 386.07358 -371.967552) (xy 386.067808 -371.960394) (xy 386.045906 -371.93476) (xy 386.007818 -371.879121)
			(xy 385.976669 -371.819321) (xy 385.952906 -371.75622) (xy 385.936873 -371.690727) (xy 385.9288 -371.623785)
			(xy 384.826706 -371.623785) (xy 384.826918 -371.62435) (xy 384.84289 -371.689734) (xy 384.850933 -371.756557)
			(xy 384.850932 -371.823864) (xy 384.842886 -371.890687) (xy 384.826912 -371.95607) (xy 384.803238 -372.019075)
			(xy 384.772203 -372.078799) (xy 384.734253 -372.134386) (xy 384.712464 -372.160038) (xy 384.706664 -372.167181)
			(xy 384.700152 -372.184373) (xy 384.699764 -372.193566) (xy 384.699764 -372.351554) (xy 384.699299 -372.361722)
			(xy 384.691529 -372.380516) (xy 384.677156 -372.394902) (xy 384.65837 -372.402689) (xy 384.648202 -372.403116)
			(xy 383.931922 -372.403116) (xy 383.921746 -372.402717) (xy 383.902943 -372.394931) (xy 383.888556 -372.380537)
			(xy 383.880778 -372.36173) (xy 383.88036 -372.351554) (xy 383.88036 -372.193566) (xy 383.879953 -372.184379)
			(xy 383.873435 -372.167195) (xy 383.86766 -372.160038) (xy 383.845886 -372.134375) (xy 383.807935 -372.07879)
			(xy 383.7769 -372.019069) (xy 383.753225 -371.956065) (xy 383.737251 -371.890684) (xy 383.729205 -371.823863)
			(xy 383.729204 -371.756558) (xy 383.737247 -371.689736) (xy 383.753219 -371.624355) (xy 383.776891 -371.561351)
			(xy 383.807924 -371.501628) (xy 383.845873 -371.446042) (xy 383.86766 -371.42039) (xy 383.873451 -371.413241)
			(xy 383.879967 -371.396053) (xy 383.88036 -371.386862) (xy 383.88036 -370.89334) (xy 383.879917 -370.884157)
			(xy 383.873425 -370.866972) (xy 383.86766 -370.859812) (xy 383.84586 -370.83417) (xy 383.80791 -370.778582)
			(xy 383.776876 -370.718858) (xy 383.753203 -370.655852) (xy 383.737231 -370.590468) (xy 383.729187 -370.523644)
			(xy 380.451147 -370.523644) (xy 380.451147 -370.523703) (xy 380.443072 -370.590641) (xy 380.427037 -370.656129)
			(xy 380.403273 -370.719226) (xy 380.372122 -370.779022) (xy 380.334032 -370.834655) (xy 380.312168 -370.86032)
			(xy 380.306376 -370.867469) (xy 380.299859 -370.884657) (xy 380.299468 -370.893848) (xy 380.299468 -371.386354)
			(xy 380.299908 -371.395538) (xy 380.306402 -371.412722) (xy 380.312168 -371.419882) (xy 380.334047 -371.445535)
			(xy 380.372137 -371.501171) (xy 380.403289 -371.560968) (xy 380.426925 -371.623725) (xy 381.529032 -371.623725)
			(xy 381.529035 -371.556418) (xy 381.537083 -371.489593) (xy 381.553059 -371.424209) (xy 381.576735 -371.361203)
			(xy 381.607771 -371.301478) (xy 381.645723 -371.245891) (xy 381.667512 -371.220238) (xy 381.673319 -371.2131)
			(xy 381.679827 -371.195904) (xy 381.680212 -371.18671) (xy 381.680212 -371.028722) (xy 381.680751 -371.018569)
			(xy 381.688513 -370.999805) (xy 381.702865 -370.98544) (xy 381.721621 -370.97766) (xy 381.731774 -370.97716)
			(xy 382.448054 -370.97716) (xy 382.458225 -370.977602) (xy 382.477023 -370.985376) (xy 382.491411 -370.999757)
			(xy 382.499193 -371.018551) (xy 382.499616 -371.028722) (xy 382.499616 -371.18671) (xy 382.500018 -371.195898)
			(xy 382.506537 -371.213083) (xy 382.512316 -371.220238) (xy 382.534068 -371.24592) (xy 382.572021 -371.301501)
			(xy 382.603058 -371.36122) (xy 382.626735 -371.424221) (xy 382.642712 -371.4896) (xy 382.65076 -371.55642)
			(xy 382.650763 -371.623723) (xy 382.642722 -371.690544) (xy 382.626752 -371.755924) (xy 382.603081 -371.818927)
			(xy 382.57205 -371.87865) (xy 382.534103 -371.934234) (xy 382.512316 -371.959886) (xy 382.506502 -371.967019)
			(xy 382.499997 -371.984219) (xy 382.499616 -371.993414) (xy 382.499616 -372.486682) (xy 382.500031 -372.495869)
			(xy 382.506541 -372.513053) (xy 382.512316 -372.52021) (xy 382.534138 -372.545834) (xy 382.572089 -372.601424)
			(xy 382.603123 -372.661151) (xy 382.626796 -372.724159) (xy 382.642768 -372.789545) (xy 382.65081 -372.856371)
			(xy 382.650807 -372.92368) (xy 382.642759 -372.990506) (xy 382.626781 -373.05589) (xy 382.603103 -373.118896)
			(xy 382.572063 -373.17862) (xy 382.534107 -373.234206) (xy 382.512316 -373.259858) (xy 382.506514 -373.267)
			(xy 382.500002 -373.284193) (xy 382.499616 -373.293386) (xy 382.499616 -373.451374) (xy 382.499214 -373.46155)
			(xy 382.491429 -373.480352) (xy 382.477036 -373.49474) (xy 382.45823 -373.502517) (xy 382.448054 -373.502936)
			(xy 381.731774 -373.502936) (xy 381.721611 -373.502487) (xy 381.702837 -373.4947) (xy 381.688471 -373.48032)
			(xy 381.680702 -373.461537) (xy 381.680212 -373.451374) (xy 381.680212 -373.293386) (xy 381.679806 -373.284198)
			(xy 381.673289 -373.267014) (xy 381.667512 -373.259858) (xy 381.645758 -373.234178) (xy 381.60781 -373.178595)
			(xy 381.576777 -373.118875) (xy 381.553104 -373.055874) (xy 381.537129 -372.990496) (xy 381.529083 -372.923676)
			(xy 381.52908 -372.856375) (xy 381.53712 -372.789555) (xy 381.553088 -372.724175) (xy 381.576756 -372.661172)
			(xy 381.607784 -372.601449) (xy 381.645727 -372.545862) (xy 381.667512 -372.52021) (xy 381.673331 -372.51308)
			(xy 381.679832 -372.495878) (xy 381.680212 -372.486682) (xy 381.680212 -371.993414) (xy 381.679792 -371.984228)
			(xy 381.673285 -371.967044) (xy 381.667512 -371.959886) (xy 381.645688 -371.934264) (xy 381.607742 -371.878673)
			(xy 381.576712 -371.818945) (xy 381.553042 -371.755936) (xy 381.537073 -371.690551) (xy 381.529032 -371.623725)
			(xy 380.426925 -371.623725) (xy 380.427054 -371.624067) (xy 380.443089 -371.689558) (xy 380.451165 -371.756498)
			(xy 380.451163 -371.823923) (xy 380.443086 -371.890863) (xy 380.427048 -371.956353) (xy 380.403281 -372.019451)
			(xy 380.372126 -372.079247) (xy 380.334034 -372.134881) (xy 380.312168 -372.160546) (xy 380.306365 -372.167687)
			(xy 380.299855 -372.184881) (xy 380.299468 -372.194074) (xy 380.299468 -372.351554) (xy 380.298936 -372.361677)
			(xy 380.291225 -372.380395) (xy 380.276952 -372.394753) (xy 380.25828 -372.402575) (xy 380.24816 -372.403116)
			(xy 379.53188 -372.403116) (xy 379.521727 -372.402695) (xy 379.502977 -372.394896) (xy 379.488655 -372.3805)
			(xy 379.480953 -372.36171) (xy 379.480572 -372.351554) (xy 379.480572 -372.194074) (xy 379.480181 -372.184885)
			(xy 379.473655 -372.1677) (xy 379.467872 -372.160546) (xy 379.446023 -372.134869) (xy 379.407935 -372.079235)
			(xy 379.376786 -372.019441) (xy 379.353022 -371.956345) (xy 379.336986 -371.890858) (xy 379.32891 -371.823922)
			(xy 379.328909 -371.7565) (xy 379.336983 -371.689563) (xy 379.353016 -371.624075) (xy 379.376777 -371.560979)
			(xy 379.407925 -371.501183) (xy 379.44601 -371.445548) (xy 379.467872 -371.419882) (xy 379.473667 -371.412736)
			(xy 379.480181 -371.395546) (xy 379.480572 -371.386354) (xy 379.480572 -370.893848) (xy 379.480145 -370.884663)
			(xy 379.473644 -370.867478) (xy 379.467872 -370.86032) (xy 379.445997 -370.834664) (xy 379.407911 -370.779027)
			(xy 379.376762 -370.71923) (xy 379.353 -370.656132) (xy 379.336966 -370.590642) (xy 379.328892 -370.523703)
			(xy 376.050821 -370.523703) (xy 376.042785 -370.590464) (xy 376.026814 -370.655846) (xy 376.003143 -370.71885)
			(xy 375.972113 -370.778573) (xy 375.934166 -370.83416) (xy 375.91238 -370.859812) (xy 375.906594 -370.866964)
			(xy 375.900073 -370.884149) (xy 375.89968 -370.89334) (xy 375.89968 -371.386862) (xy 375.900113 -371.396047)
			(xy 375.906611 -371.413231) (xy 375.91238 -371.42039) (xy 375.934181 -371.446031) (xy 375.972128 -371.50162)
			(xy 376.00316 -371.561345) (xy 376.026618 -371.623785) (xy 377.128712 -371.623785) (xy 377.128716 -371.556358)
			(xy 377.136796 -371.489417) (xy 377.152836 -371.423925) (xy 377.176606 -371.360827) (xy 377.207762 -371.301029)
			(xy 377.245857 -371.245395) (xy 377.267724 -371.21973) (xy 377.273536 -371.212596) (xy 377.28004 -371.195397)
			(xy 377.280424 -371.186202) (xy 377.280424 -371.028722) (xy 377.280944 -371.018599) (xy 377.288662 -370.999881)
			(xy 377.302938 -370.985524) (xy 377.321612 -370.977702) (xy 377.331732 -370.97716) (xy 378.048012 -370.97716)
			(xy 378.058162 -370.977611) (xy 378.076907 -370.985403) (xy 378.091229 -370.99979) (xy 378.098935 -371.01857)
			(xy 378.09932 -371.028722) (xy 378.09932 -371.186202) (xy 378.099725 -371.19539) (xy 378.106242 -371.212574)
			(xy 378.11202 -371.21973) (xy 378.133846 -371.245426) (xy 378.171934 -371.301057) (xy 378.203086 -371.360849)
			(xy 378.226851 -371.423942) (xy 378.242889 -371.489427) (xy 378.250967 -371.556361) (xy 378.250971 -371.623782)
			(xy 378.242899 -371.690717) (xy 378.226868 -371.756204) (xy 378.203109 -371.819299) (xy 378.171964 -371.879094)
			(xy 378.133881 -371.934728) (xy 378.11202 -371.960394) (xy 378.106246 -371.967555) (xy 378.099717 -371.984733)
			(xy 378.09932 -371.993922) (xy 378.09932 -372.486174) (xy 378.099738 -372.49536) (xy 378.106246 -372.512545)
			(xy 378.11202 -372.519702) (xy 378.133917 -372.54534) (xy 378.172003 -372.600979) (xy 378.203151 -372.660779)
			(xy 378.226913 -372.723879) (xy 378.242945 -372.789372) (xy 378.251018 -372.856313) (xy 378.251015 -372.923739)
			(xy 378.242936 -372.990679) (xy 378.226897 -373.056169) (xy 378.20313 -373.119268) (xy 378.171977 -373.179065)
			(xy 378.133885 -373.2347) (xy 378.11202 -373.260366) (xy 378.106215 -373.267506) (xy 378.099705 -373.2847)
			(xy 378.09932 -373.293894) (xy 378.09932 -373.451374) (xy 378.098851 -373.461504) (xy 378.091125 -373.480232)
			(xy 378.076832 -373.494591) (xy 378.05814 -373.502404) (xy 378.048012 -373.502936) (xy 377.331732 -373.502936)
			(xy 377.321584 -373.502453) (xy 377.30284 -373.494675) (xy 377.288516 -373.480297) (xy 377.280809 -373.461523)
			(xy 377.280424 -373.451374) (xy 377.280424 -373.293894) (xy 377.280012 -373.284707) (xy 377.273499 -373.267523)
			(xy 377.267724 -373.260366) (xy 377.245893 -373.234674) (xy 377.207801 -373.179044) (xy 377.176648 -373.119251)
			(xy 377.152881 -373.056158) (xy 377.136842 -372.990672) (xy 377.128763 -372.923736) (xy 377.12876 -372.856315)
			(xy 377.136833 -372.789378) (xy 377.152865 -372.723891) (xy 377.176627 -372.660795) (xy 377.207775 -372.601)
			(xy 377.245861 -372.545367) (xy 377.267724 -372.519702) (xy 377.273505 -372.512546) (xy 377.280028 -372.495364)
			(xy 377.280424 -372.486174) (xy 377.280424 -371.993922) (xy 377.279998 -371.984737) (xy 377.273495 -371.967552)
			(xy 377.267724 -371.960394) (xy 377.245822 -371.93476) (xy 377.207733 -371.879122) (xy 377.176582 -371.819321)
			(xy 377.152819 -371.75622) (xy 377.136786 -371.690727) (xy 377.128712 -371.623785) (xy 376.026618 -371.623785)
			(xy 376.026831 -371.624351) (xy 376.042802 -371.689734) (xy 376.050845 -371.756558) (xy 376.050844 -371.823863)
			(xy 376.042799 -371.890687) (xy 376.026825 -371.956069) (xy 376.003151 -372.019074) (xy 375.972117 -372.078799)
			(xy 375.934168 -372.134386) (xy 375.91238 -372.160038) (xy 375.906582 -372.167182) (xy 375.900069 -372.184374)
			(xy 375.89968 -372.193566) (xy 375.89968 -372.351554) (xy 375.899199 -372.36172) (xy 375.891432 -372.380511)
			(xy 375.877064 -372.394896) (xy 375.858284 -372.402686) (xy 375.848118 -372.403116) (xy 375.131838 -372.403116)
			(xy 375.121663 -372.402704) (xy 375.102861 -372.394923) (xy 375.088473 -372.380533) (xy 375.080695 -372.361729)
			(xy 375.080276 -372.351554) (xy 375.080276 -372.193566) (xy 375.079887 -372.184376) (xy 375.073359 -372.167192)
			(xy 375.067576 -372.160038) (xy 375.045801 -372.134375) (xy 375.007849 -372.078791) (xy 374.976813 -372.019069)
			(xy 374.953138 -371.956066) (xy 374.937163 -371.890685) (xy 374.929117 -371.823863) (xy 374.929116 -371.756558)
			(xy 374.937159 -371.689736) (xy 374.953132 -371.624354) (xy 374.976805 -371.56135) (xy 375.007838 -371.501627)
			(xy 375.045788 -371.446042) (xy 375.067576 -371.42039) (xy 375.073357 -371.413233) (xy 375.079882 -371.396052)
			(xy 375.080276 -371.386862) (xy 375.080276 -370.89334) (xy 375.079852 -370.884154) (xy 375.073349 -370.866969)
			(xy 375.067576 -370.859812) (xy 375.045775 -370.83417) (xy 375.007825 -370.778583) (xy 374.97679 -370.718858)
			(xy 374.953116 -370.655852) (xy 374.937143 -370.590469) (xy 374.929099 -370.523644) (xy 345.250797 -370.523644)
			(xy 345.242754 -370.590465) (xy 345.226782 -370.655847) (xy 345.203109 -370.718851) (xy 345.172076 -370.778574)
			(xy 345.134128 -370.83416) (xy 345.11234 -370.859812) (xy 345.106548 -370.86696) (xy 345.100032 -370.884149)
			(xy 345.09964 -370.89334) (xy 345.09964 -371.386862) (xy 345.100082 -371.396046) (xy 345.106575 -371.41323)
			(xy 345.11234 -371.42039) (xy 345.134142 -371.446031) (xy 345.172092 -371.501618) (xy 345.203126 -371.561343)
			(xy 345.226564 -371.623726) (xy 346.329187 -371.623726) (xy 346.32919 -371.556417) (xy 346.337239 -371.489591)
			(xy 346.353217 -371.424206) (xy 346.376896 -371.3612) (xy 346.407936 -371.301476) (xy 346.445893 -371.24589)
			(xy 346.467684 -371.220238) (xy 346.473488 -371.213098) (xy 346.479999 -371.195904) (xy 346.480384 -371.18671)
			(xy 346.480384 -371.028722) (xy 346.480783 -371.018546) (xy 346.488569 -370.999743) (xy 346.502963 -370.985356)
			(xy 346.52177 -370.977578) (xy 346.531946 -370.97716) (xy 347.248226 -370.97716) (xy 347.258388 -370.977612)
			(xy 347.277162 -370.9854) (xy 347.291527 -370.999778) (xy 347.299297 -371.018559) (xy 347.299788 -371.028722)
			(xy 347.299788 -371.18671) (xy 347.300196 -371.195897) (xy 347.306711 -371.213082) (xy 347.312488 -371.220238)
			(xy 347.334237 -371.245921) (xy 347.372185 -371.301504) (xy 347.403219 -371.361224) (xy 347.426893 -371.424224)
			(xy 347.442867 -371.489602) (xy 347.450914 -371.556421) (xy 347.450918 -371.623722) (xy 347.442878 -371.690542)
			(xy 347.426909 -371.755921) (xy 347.403242 -371.818924) (xy 347.372215 -371.878647) (xy 347.334272 -371.934233)
			(xy 347.312488 -371.959886) (xy 347.306671 -371.967017) (xy 347.300169 -371.984218) (xy 347.299788 -371.993414)
			(xy 347.299788 -372.486682) (xy 347.30021 -372.495868) (xy 347.306716 -372.513052) (xy 347.312488 -372.52021)
			(xy 347.334308 -372.545835) (xy 347.372254 -372.601426) (xy 347.403285 -372.661154) (xy 347.426954 -372.724162)
			(xy 347.442924 -372.789547) (xy 347.450965 -372.856372) (xy 347.450962 -372.923679) (xy 347.442915 -372.990504)
			(xy 347.426939 -373.055887) (xy 347.403264 -373.118893) (xy 347.372228 -373.178618) (xy 347.334277 -373.234205)
			(xy 347.312488 -373.259858) (xy 347.306683 -373.266997) (xy 347.300174 -373.284192) (xy 347.299788 -373.293386)
			(xy 347.299788 -373.451374) (xy 347.299246 -373.461527) (xy 347.291485 -373.480291) (xy 347.277134 -373.494656)
			(xy 347.258378 -373.502436) (xy 347.248226 -373.502936) (xy 346.531946 -373.502936) (xy 346.521774 -373.502498)
			(xy 346.502975 -373.494723) (xy 346.488588 -373.480341) (xy 346.480806 -373.461546) (xy 346.480384 -373.451374)
			(xy 346.480384 -373.293386) (xy 346.479984 -373.284198) (xy 346.473464 -373.267013) (xy 346.467684 -373.259858)
			(xy 346.445928 -373.234179) (xy 346.407976 -373.178597) (xy 346.376938 -373.118878) (xy 346.353262 -373.055877)
			(xy 346.337285 -372.990498) (xy 346.329237 -372.923677) (xy 346.329234 -372.856374) (xy 346.337276 -372.789553)
			(xy 346.353247 -372.724172) (xy 346.376917 -372.661169) (xy 346.407949 -372.601447) (xy 346.445897 -372.545862)
			(xy 346.467684 -372.52021) (xy 346.473499 -372.513078) (xy 346.480003 -372.495877) (xy 346.480384 -372.486682)
			(xy 346.480384 -371.993414) (xy 346.479971 -371.984227) (xy 346.47346 -371.967042) (xy 346.467684 -371.959886)
			(xy 346.445858 -371.934265) (xy 346.407907 -371.878675) (xy 346.376873 -371.818948) (xy 346.3532 -371.755939)
			(xy 346.337229 -371.690553) (xy 346.329187 -371.623726) (xy 345.226564 -371.623726) (xy 345.226798 -371.624349)
			(xy 345.242771 -371.689733) (xy 345.250814 -371.756557) (xy 345.250813 -371.823864) (xy 345.242767 -371.890688)
			(xy 345.226792 -371.956071) (xy 345.203117 -372.019076) (xy 345.172081 -372.0788) (xy 345.134129 -372.134386)
			(xy 345.11234 -372.160038) (xy 345.106537 -372.167179) (xy 345.100028 -372.184373) (xy 345.09964 -372.193566)
			(xy 345.09964 -372.351554) (xy 345.099198 -372.361725) (xy 345.091424 -372.380523) (xy 345.077043 -372.394911)
			(xy 345.058249 -372.402693) (xy 345.048078 -372.403116) (xy 344.331798 -372.403116) (xy 344.321621 -372.402737)
			(xy 344.302817 -372.394942) (xy 344.288431 -372.380543) (xy 344.280654 -372.361732) (xy 344.280236 -372.351554)
			(xy 344.280236 -372.193566) (xy 344.279834 -372.184378) (xy 344.273314 -372.167194) (xy 344.267536 -372.160038)
			(xy 344.245762 -372.134374) (xy 344.207813 -372.078789) (xy 344.17678 -372.019067) (xy 344.153106 -371.956064)
			(xy 344.137132 -371.890684) (xy 344.129087 -371.823862) (xy 344.129086 -371.756559) (xy 344.137129 -371.689737)
			(xy 344.1531 -371.624356) (xy 344.176771 -371.561352) (xy 344.207803 -371.501629) (xy 344.245749 -371.446042)
			(xy 344.267536 -371.42039) (xy 344.273324 -371.413239) (xy 344.279843 -371.396053) (xy 344.280236 -371.386862)
			(xy 344.280236 -370.89334) (xy 344.279798 -370.884156) (xy 344.273303 -370.866972) (xy 344.267536 -370.859812)
			(xy 344.245736 -370.83417) (xy 344.207788 -370.778582) (xy 344.176756 -370.718857) (xy 344.153084 -370.655851)
			(xy 344.137112 -370.590468) (xy 344.129068 -370.523644) (xy 340.851006 -370.523644) (xy 340.842963 -370.590465)
			(xy 340.826991 -370.655847) (xy 340.803319 -370.718851) (xy 340.772287 -370.778574) (xy 340.734339 -370.83416)
			(xy 340.712552 -370.859812) (xy 340.706762 -370.866962) (xy 340.700245 -370.884149) (xy 340.699852 -370.89334)
			(xy 340.699852 -371.386862) (xy 340.700291 -371.396046) (xy 340.706786 -371.41323) (xy 340.712552 -371.42039)
			(xy 340.734354 -371.446031) (xy 340.772303 -371.501618) (xy 340.803336 -371.561344) (xy 340.826797 -371.623785)
			(xy 341.928891 -371.623785) (xy 341.928895 -371.556358) (xy 341.936974 -371.489417) (xy 341.953014 -371.423926)
			(xy 341.976782 -371.360828) (xy 342.007937 -371.301031) (xy 342.04603 -371.245395) (xy 342.067896 -371.21973)
			(xy 342.073704 -371.212593) (xy 342.080212 -371.195396) (xy 342.080596 -371.186202) (xy 342.080596 -371.028722)
			(xy 342.081143 -371.018602) (xy 342.088856 -370.99989) (xy 342.103123 -370.985534) (xy 342.121787 -370.977706)
			(xy 342.131904 -370.97716) (xy 342.848184 -370.97716) (xy 342.858332 -370.977634) (xy 342.877076 -370.985417)
			(xy 342.891399 -370.999797) (xy 342.899106 -371.018572) (xy 342.899492 -371.028722) (xy 342.899492 -371.186202)
			(xy 342.899903 -371.195389) (xy 342.906416 -371.212573) (xy 342.912192 -371.21973) (xy 342.934019 -371.245426)
			(xy 342.972109 -371.301056) (xy 343.003262 -371.360848) (xy 343.027029 -371.423941) (xy 343.043067 -371.489426)
			(xy 343.051146 -371.556361) (xy 343.05115 -371.623782) (xy 343.043077 -371.690718) (xy 343.027046 -371.756205)
			(xy 343.003285 -371.8193) (xy 342.972139 -371.879095) (xy 342.934054 -371.934729) (xy 342.912192 -371.960394)
			(xy 342.906415 -371.967553) (xy 342.899889 -371.984733) (xy 342.899492 -371.993922) (xy 342.899492 -372.486174)
			(xy 342.899917 -372.49536) (xy 342.90642 -372.512544) (xy 342.912192 -372.519702) (xy 342.93409 -372.54534)
			(xy 342.972178 -372.600978) (xy 343.003328 -372.660778) (xy 343.02709 -372.723878) (xy 343.043124 -372.789371)
			(xy 343.051197 -372.856312) (xy 343.051194 -372.923739) (xy 343.043114 -372.99068) (xy 343.027075 -373.056171)
			(xy 343.003307 -373.119269) (xy 342.972152 -373.179066) (xy 342.934058 -373.234701) (xy 342.912192 -373.260366)
			(xy 342.906384 -373.267503) (xy 342.899876 -373.2847) (xy 342.899492 -373.293894) (xy 342.899492 -373.451374)
			(xy 342.898953 -373.461495) (xy 342.89124 -373.48021) (xy 342.87697 -373.494566) (xy 342.858302 -373.502392)
			(xy 342.848184 -373.502936) (xy 342.131904 -373.502936) (xy 342.121755 -373.502476) (xy 342.103009 -373.494688)
			(xy 342.088687 -373.480304) (xy 342.080981 -373.461525) (xy 342.080596 -373.451374) (xy 342.080596 -373.293894)
			(xy 342.080189 -373.284706) (xy 342.073673 -373.267522) (xy 342.067896 -373.260366) (xy 342.046066 -373.234673)
			(xy 342.007976 -373.179042) (xy 341.976824 -373.11925) (xy 341.953058 -373.056157) (xy 341.937021 -372.990671)
			(xy 341.928942 -372.923736) (xy 341.928939 -372.856315) (xy 341.937011 -372.789379) (xy 341.953043 -372.723892)
			(xy 341.976803 -372.660797) (xy 342.00795 -372.601001) (xy 342.046034 -372.545367) (xy 342.067896 -372.519702)
			(xy 342.073674 -372.512543) (xy 342.0802 -372.495363) (xy 342.080596 -372.486174) (xy 342.080596 -371.993922)
			(xy 342.080176 -371.984736) (xy 342.073669 -371.967551) (xy 342.067896 -371.960394) (xy 342.045995 -371.934759)
			(xy 342.007908 -371.87912) (xy 341.976759 -371.81932) (xy 341.952997 -371.756219) (xy 341.936964 -371.690726)
			(xy 341.928891 -371.623785) (xy 340.826797 -371.623785) (xy 340.827009 -371.62435) (xy 340.842981 -371.689733)
			(xy 340.851024 -371.756557) (xy 340.851023 -371.823864) (xy 340.842977 -371.890687) (xy 340.827002 -371.956071)
			(xy 340.803328 -372.019076) (xy 340.772292 -372.0788) (xy 340.734341 -372.134386) (xy 340.712552 -372.160038)
			(xy 340.706751 -372.16718) (xy 340.70024 -372.184373) (xy 340.699852 -372.193566) (xy 340.699852 -372.351554)
			(xy 340.699398 -372.361724) (xy 340.691627 -372.380519) (xy 340.67725 -372.394906) (xy 340.65846 -372.402691)
			(xy 340.64829 -372.403116) (xy 339.93201 -372.403116) (xy 339.921833 -372.402727) (xy 339.90303 -372.394937)
			(xy 339.888643 -372.38054) (xy 339.880866 -372.361731) (xy 339.880448 -372.351554) (xy 339.880448 -372.193566)
			(xy 339.880043 -372.184378) (xy 339.873525 -372.167195) (xy 339.867748 -372.160038) (xy 339.845974 -372.134375)
			(xy 339.808024 -372.07879) (xy 339.77699 -372.019068) (xy 339.753316 -371.956065) (xy 339.737342 -371.890684)
			(xy 339.729296 -371.823863) (xy 339.729295 -371.756558) (xy 339.737338 -371.689737) (xy 339.75331 -371.624355)
			(xy 339.776981 -371.561351) (xy 339.808013 -371.501628) (xy 339.845961 -371.446042) (xy 339.867748 -371.42039)
			(xy 339.873537 -371.41324) (xy 339.880055 -371.396053) (xy 339.880448 -371.386862) (xy 339.880448 -370.89334)
			(xy 339.880008 -370.884156) (xy 339.873514 -370.866972) (xy 339.867748 -370.859812) (xy 339.845948 -370.83417)
			(xy 339.807999 -370.778582) (xy 339.776966 -370.718857) (xy 339.753293 -370.655851) (xy 339.737321 -370.590468)
			(xy 339.729277 -370.523644) (xy 336.451238 -370.523644) (xy 336.451238 -370.523703) (xy 336.443163 -370.590641)
			(xy 336.427128 -370.65613) (xy 336.403363 -370.719227) (xy 336.372211 -370.779022) (xy 336.334121 -370.834656)
			(xy 336.312256 -370.86032) (xy 336.306463 -370.867467) (xy 336.299947 -370.884656) (xy 336.299556 -370.893848)
			(xy 336.299556 -371.386354) (xy 336.299998 -371.395538) (xy 336.306491 -371.412722) (xy 336.312256 -371.419882)
			(xy 336.334135 -371.445535) (xy 336.372226 -371.50117) (xy 336.403379 -371.560968) (xy 336.427016 -371.623725)
			(xy 337.529123 -371.623725) (xy 337.529126 -371.556418) (xy 337.537174 -371.489593) (xy 337.55315 -371.424209)
			(xy 337.576825 -371.361204) (xy 337.60786 -371.301479) (xy 337.645811 -371.245891) (xy 337.6676 -371.220238)
			(xy 337.673405 -371.213099) (xy 337.679915 -371.195904) (xy 337.6803 -371.18671) (xy 337.6803 -371.028722)
			(xy 337.68085 -371.01857) (xy 337.68861 -370.999809) (xy 337.702958 -370.985444) (xy 337.721711 -370.977662)
			(xy 337.731862 -370.97716) (xy 338.448142 -370.97716) (xy 338.458305 -370.9776) (xy 338.477079 -370.985392)
			(xy 338.491444 -370.999774) (xy 338.499213 -371.018558) (xy 338.499704 -371.028722) (xy 338.499704 -371.18671)
			(xy 338.500109 -371.195898) (xy 338.506626 -371.213082) (xy 338.512404 -371.220238) (xy 338.534153 -371.245921)
			(xy 338.5721 -371.301504) (xy 338.603133 -371.361224) (xy 338.626806 -371.424224) (xy 338.64278 -371.489602)
			(xy 338.650827 -371.556421) (xy 338.65083 -371.623722) (xy 338.64279 -371.690541) (xy 338.626823 -371.755921)
			(xy 338.603156 -371.818924) (xy 338.57213 -371.878646) (xy 338.534188 -371.934233) (xy 338.512404 -371.959886)
			(xy 338.506589 -371.967018) (xy 338.500085 -371.984219) (xy 338.499704 -371.993414) (xy 338.499704 -372.486682)
			(xy 338.500122 -372.495868) (xy 338.50663 -372.513053) (xy 338.512404 -372.52021) (xy 338.534224 -372.545835)
			(xy 338.572169 -372.601427) (xy 338.603198 -372.661154) (xy 338.626867 -372.724162) (xy 338.642836 -372.789547)
			(xy 338.650877 -372.856372) (xy 338.650874 -372.923679) (xy 338.642827 -372.990503) (xy 338.626852 -373.055887)
			(xy 338.603177 -373.118892) (xy 338.572142 -373.178617) (xy 338.534192 -373.234205) (xy 338.512404 -373.259858)
			(xy 338.506601 -373.266999) (xy 338.50009 -373.284193) (xy 338.499704 -373.293386) (xy 338.499704 -373.451374)
			(xy 338.499147 -373.461525) (xy 338.491388 -373.480286) (xy 338.477043 -373.49465) (xy 338.458292 -373.502433)
			(xy 338.448142 -373.502936) (xy 337.731862 -373.502936) (xy 337.721699 -373.502497) (xy 337.702924 -373.494705)
			(xy 337.688559 -373.480323) (xy 337.68079 -373.461538) (xy 337.6803 -373.451374) (xy 337.6803 -373.293386)
			(xy 337.679896 -373.284198) (xy 337.673378 -373.267014) (xy 337.6676 -373.259858) (xy 337.645847 -373.234178)
			(xy 337.6079 -373.178595) (xy 337.576867 -373.118874) (xy 337.553194 -373.055874) (xy 337.53722 -372.990495)
			(xy 337.529174 -372.923676) (xy 337.52917 -372.856375) (xy 337.537211 -372.789555) (xy 337.553179 -372.724175)
			(xy 337.576846 -372.661172) (xy 337.607873 -372.601449) (xy 337.645816 -372.545863) (xy 337.6676 -372.52021)
			(xy 337.673417 -372.513079) (xy 337.67992 -372.495878) (xy 337.6803 -372.486682) (xy 337.6803 -371.993414)
			(xy 337.679883 -371.984228) (xy 337.673374 -371.967043) (xy 337.6676 -371.959886) (xy 337.645776 -371.934264)
			(xy 337.607831 -371.878672) (xy 337.576802 -371.818944) (xy 337.553133 -371.755936) (xy 337.537163 -371.69055)
			(xy 337.529123 -371.623725) (xy 336.427016 -371.623725) (xy 336.427144 -371.624066) (xy 336.44318 -371.689557)
			(xy 336.451256 -371.756498) (xy 336.451254 -371.823923) (xy 336.443176 -371.890863) (xy 336.427138 -371.956354)
			(xy 336.40337 -372.019451) (xy 336.372216 -372.079248) (xy 336.334122 -372.134881) (xy 336.312256 -372.160546)
			(xy 336.306452 -372.167686) (xy 336.299943 -372.184881) (xy 336.299556 -372.194074) (xy 336.299556 -372.351554)
			(xy 336.299036 -372.361678) (xy 336.291322 -372.380399) (xy 336.277046 -372.394757) (xy 336.258369 -372.402577)
			(xy 336.248248 -372.403116) (xy 335.531968 -372.403116) (xy 335.521814 -372.402705) (xy 335.503064 -372.394902)
			(xy 335.488742 -372.380502) (xy 335.481041 -372.36171) (xy 335.48066 -372.351554) (xy 335.48066 -372.194074)
			(xy 335.480249 -372.184887) (xy 335.473734 -372.167704) (xy 335.46796 -372.160546) (xy 335.446111 -372.134869)
			(xy 335.408025 -372.079235) (xy 335.376876 -372.01944) (xy 335.353112 -371.956345) (xy 335.337077 -371.890858)
			(xy 335.329001 -371.823921) (xy 335.329 -371.7565) (xy 335.337073 -371.689563) (xy 335.353106 -371.624075)
			(xy 335.376867 -371.560979) (xy 335.408014 -371.501183) (xy 335.446098 -371.445548) (xy 335.46796 -371.419882)
			(xy 335.473754 -371.412735) (xy 335.480269 -371.395546) (xy 335.48066 -371.386354) (xy 335.48066 -370.893848)
			(xy 335.480214 -370.884665) (xy 335.473724 -370.867481) (xy 335.46796 -370.86032) (xy 335.446086 -370.834664)
			(xy 335.408 -370.779027) (xy 335.376852 -370.719229) (xy 335.35309 -370.656131) (xy 335.337057 -370.590642)
			(xy 335.328983 -370.523703) (xy 332.050912 -370.523703) (xy 332.042876 -370.590465) (xy 332.026905 -370.655846)
			(xy 332.003233 -370.71885) (xy 331.972202 -370.778573) (xy 331.934255 -370.83416) (xy 331.912468 -370.859812)
			(xy 331.90668 -370.866963) (xy 331.900161 -370.884149) (xy 331.899768 -370.89334) (xy 331.899768 -371.386862)
			(xy 331.900204 -371.396046) (xy 331.906701 -371.41323) (xy 331.912468 -371.42039) (xy 331.934269 -371.446031)
			(xy 331.972217 -371.501619) (xy 332.00325 -371.561344) (xy 332.026709 -371.623785) (xy 333.128803 -371.623785)
			(xy 333.128807 -371.556358) (xy 333.136887 -371.489417) (xy 333.152927 -371.423926) (xy 333.176696 -371.360827)
			(xy 333.207851 -371.30103) (xy 333.245945 -371.245395) (xy 333.267812 -371.21973) (xy 333.273622 -371.212594)
			(xy 333.280128 -371.195397) (xy 333.280512 -371.186202) (xy 333.280512 -371.028722) (xy 333.281044 -371.0186)
			(xy 333.288759 -370.999885) (xy 333.303031 -370.985529) (xy 333.321701 -370.977704) (xy 333.33182 -370.97716)
			(xy 334.0481 -370.97716) (xy 334.058249 -370.977621) (xy 334.076994 -370.985409) (xy 334.091316 -370.999793)
			(xy 334.099023 -371.018571) (xy 334.099408 -371.028722) (xy 334.099408 -371.186202) (xy 334.099815 -371.195389)
			(xy 334.106331 -371.212574) (xy 334.112108 -371.21973) (xy 334.133934 -371.245426) (xy 334.172024 -371.301056)
			(xy 334.203176 -371.360848) (xy 334.226942 -371.423941) (xy 334.242979 -371.489426) (xy 334.251058 -371.556361)
			(xy 334.251062 -371.623782) (xy 334.24299 -371.690717) (xy 334.226958 -371.756204) (xy 334.203199 -371.819299)
			(xy 334.172053 -371.879095) (xy 334.133969 -371.934729) (xy 334.112108 -371.960394) (xy 334.106332 -371.967554)
			(xy 334.099805 -371.984733) (xy 334.099408 -371.993922) (xy 334.099408 -372.486174) (xy 334.099829 -372.49536)
			(xy 334.106335 -372.512545) (xy 334.112108 -372.519702) (xy 334.134005 -372.54534) (xy 334.172092 -372.600978)
			(xy 334.203241 -372.660779) (xy 334.227003 -372.723879) (xy 334.243036 -372.789371) (xy 334.251109 -372.856312)
			(xy 334.251106 -372.923739) (xy 334.243027 -372.990679) (xy 334.226988 -373.05617) (xy 334.20322 -373.119268)
			(xy 334.172066 -373.179065) (xy 334.133974 -373.234701) (xy 334.112108 -373.260366) (xy 334.106302 -373.267504)
			(xy 334.099793 -373.2847) (xy 334.099408 -373.293894) (xy 334.099408 -373.451374) (xy 334.098854 -373.461493)
			(xy 334.091143 -373.480205) (xy 334.076878 -373.49456) (xy 334.058216 -373.502389) (xy 334.0481 -373.502936)
			(xy 333.33182 -373.502936) (xy 333.321672 -373.502463) (xy 333.302927 -373.494681) (xy 333.288604 -373.4803)
			(xy 333.280897 -373.461524) (xy 333.280512 -373.451374) (xy 333.280512 -373.293894) (xy 333.280102 -373.284707)
			(xy 333.273588 -373.267523) (xy 333.267812 -373.260366) (xy 333.245981 -373.234673) (xy 333.20789 -373.179043)
			(xy 333.176738 -373.119251) (xy 333.152971 -373.056157) (xy 333.136933 -372.990672) (xy 333.128854 -372.923736)
			(xy 333.128851 -372.856315) (xy 333.136924 -372.789379) (xy 333.152956 -372.723891) (xy 333.176717 -372.660796)
			(xy 333.207864 -372.601001) (xy 333.24595 -372.545367) (xy 333.267812 -372.519702) (xy 333.273592 -372.512545)
			(xy 333.280116 -372.495363) (xy 333.280512 -372.486174) (xy 333.280512 -371.993922) (xy 333.280088 -371.984736)
			(xy 333.273584 -371.967552) (xy 333.267812 -371.960394) (xy 333.24591 -371.93476) (xy 333.207822 -371.879121)
			(xy 333.176672 -371.819321) (xy 333.15291 -371.75622) (xy 333.136876 -371.690727) (xy 333.128803 -371.623785)
			(xy 332.026709 -371.623785) (xy 332.026921 -371.62435) (xy 332.042893 -371.689734) (xy 332.050936 -371.756558)
			(xy 332.050935 -371.823864) (xy 332.042889 -371.890687) (xy 332.026915 -371.95607) (xy 332.003241 -372.019075)
			(xy 331.972207 -372.078799) (xy 331.934256 -372.134386) (xy 331.912468 -372.160038) (xy 331.906669 -372.167181)
			(xy 331.900156 -372.184373) (xy 331.899768 -372.193566) (xy 331.899768 -372.351554) (xy 331.899299 -372.361722)
			(xy 331.89153 -372.380514) (xy 331.877158 -372.394901) (xy 331.858373 -372.402688) (xy 331.848206 -372.403116)
			(xy 331.131926 -372.403116) (xy 331.12175 -372.402714) (xy 331.102948 -372.394929) (xy 331.08856 -372.380536)
			(xy 331.080783 -372.36173) (xy 331.080364 -372.351554) (xy 331.080364 -372.193566) (xy 331.079956 -372.184379)
			(xy 331.073439 -372.167195) (xy 331.067664 -372.160038) (xy 331.045889 -372.134375) (xy 331.007939 -372.078791)
			(xy 330.976903 -372.019069) (xy 330.953229 -371.956066) (xy 330.937254 -371.890684) (xy 330.929208 -371.823863)
			(xy 330.929207 -371.756558) (xy 330.93725 -371.689736) (xy 330.953222 -371.624355) (xy 330.976895 -371.561351)
			(xy 331.007928 -371.501628) (xy 331.045876 -371.446042) (xy 331.067664 -371.42039) (xy 331.073455 -371.413241)
			(xy 331.079971 -371.396053) (xy 331.080364 -371.386862) (xy 331.080364 -370.89334) (xy 331.07992 -370.884157)
			(xy 331.073428 -370.866973) (xy 331.067664 -370.859812) (xy 331.045864 -370.83417) (xy 331.007914 -370.778582)
			(xy 330.97688 -370.718858) (xy 330.953206 -370.655852) (xy 330.937234 -370.590468) (xy 330.92919 -370.523644)
			(xy 301.250887 -370.523644) (xy 301.250887 -370.523702) (xy 301.242812 -370.590639) (xy 301.226779 -370.656127)
			(xy 301.203017 -370.719224) (xy 301.171869 -370.77902) (xy 301.133783 -370.834654) (xy 301.11192 -370.86032)
			(xy 301.106135 -370.867473) (xy 301.099613 -370.884658) (xy 301.09922 -370.893848) (xy 301.09922 -371.386354)
			(xy 301.099648 -371.395539) (xy 301.106149 -371.412724) (xy 301.11192 -371.419882) (xy 301.133797 -371.445536)
			(xy 301.171884 -371.501173) (xy 301.203033 -371.560971) (xy 301.226688 -371.623785) (xy 302.328773 -371.623785)
			(xy 302.328777 -371.556358) (xy 302.336856 -371.489418) (xy 302.352895 -371.423927) (xy 302.376662 -371.360829)
			(xy 302.407815 -371.301031) (xy 302.445907 -371.245396) (xy 302.467772 -371.21973) (xy 302.47359 -371.2126)
			(xy 302.48009 -371.195398) (xy 302.480472 -371.186202) (xy 302.480472 -371.028722) (xy 302.480945 -371.018593)
			(xy 302.488672 -370.999866) (xy 302.502963 -370.985508) (xy 302.521653 -370.977693) (xy 302.53178 -370.97716)
			(xy 303.24806 -370.97716) (xy 303.258207 -370.977654) (xy 303.27695 -370.985429) (xy 303.291274 -370.999803)
			(xy 303.298982 -371.018574) (xy 303.299368 -371.028722) (xy 303.299368 -371.186202) (xy 303.299784 -371.195388)
			(xy 303.306294 -371.212572) (xy 303.312068 -371.21973) (xy 303.333896 -371.245425) (xy 303.371988 -371.301055)
			(xy 303.403142 -371.360847) (xy 303.42691 -371.42394) (xy 303.442949 -371.489425) (xy 303.451028 -371.556361)
			(xy 303.451031 -371.623782) (xy 303.442959 -371.690718) (xy 303.426926 -371.756206) (xy 303.403165 -371.819301)
			(xy 303.372017 -371.879096) (xy 303.333931 -371.934729) (xy 303.312068 -371.960394) (xy 303.306287 -371.96755)
			(xy 303.299764 -371.984732) (xy 303.299368 -371.993922) (xy 303.299368 -372.486174) (xy 303.299798 -372.495359)
			(xy 303.306299 -372.512543) (xy 303.312068 -372.519702) (xy 303.333966 -372.545339) (xy 303.372056 -372.600977)
			(xy 303.403207 -372.660777) (xy 303.426971 -372.723877) (xy 303.443005 -372.78937) (xy 303.451079 -372.856312)
			(xy 303.451076 -372.923739) (xy 303.442996 -372.99068) (xy 303.426956 -373.056172) (xy 303.403186 -373.11927)
			(xy 303.37203 -373.179067) (xy 303.333935 -373.234701) (xy 303.312068 -373.260366) (xy 303.306257 -373.267501)
			(xy 303.299752 -373.284699) (xy 303.299368 -373.293894) (xy 303.299368 -373.451374) (xy 303.298853 -373.461498)
			(xy 303.291135 -373.480217) (xy 303.276857 -373.494574) (xy 303.258181 -373.502396) (xy 303.24806 -373.502936)
			(xy 302.53178 -373.502936) (xy 302.521629 -373.502496) (xy 302.502883 -373.4947) (xy 302.488562 -373.48031)
			(xy 302.480856 -373.461527) (xy 302.480472 -373.451374) (xy 302.480472 -373.293894) (xy 302.480071 -373.284706)
			(xy 302.473552 -373.267521) (xy 302.467772 -373.260366) (xy 302.445942 -373.234673) (xy 302.407855 -373.179042)
			(xy 302.376704 -373.119249) (xy 302.352939 -373.056156) (xy 302.336902 -372.99067) (xy 302.328824 -372.923736)
			(xy 302.328821 -372.856315) (xy 302.336893 -372.78938) (xy 302.352924 -372.723893) (xy 302.376683 -372.660798)
			(xy 302.407828 -372.601002) (xy 302.445911 -372.545368) (xy 302.467772 -372.519702) (xy 302.473559 -372.51255)
			(xy 302.480077 -372.495364) (xy 302.480472 -372.486174) (xy 302.480472 -371.993922) (xy 302.480058 -371.984735)
			(xy 302.473548 -371.96755) (xy 302.467772 -371.960394) (xy 302.445872 -371.934759) (xy 302.407786 -371.87912)
			(xy 302.376638 -371.819319) (xy 302.352878 -371.756218) (xy 302.336846 -371.690726) (xy 302.328773 -371.623785)
			(xy 301.226688 -371.623785) (xy 301.226795 -371.624069) (xy 301.242829 -371.689559) (xy 301.250904 -371.756498)
			(xy 301.250903 -371.823923) (xy 301.242826 -371.890862) (xy 301.226789 -371.956351) (xy 301.203024 -372.019449)
			(xy 301.171873 -372.079245) (xy 301.133784 -372.13488) (xy 301.11192 -372.160546) (xy 301.106124 -372.167692)
			(xy 301.099608 -372.184882) (xy 301.09922 -372.194074) (xy 301.09922 -372.351554) (xy 301.098734 -372.361683)
			(xy 301.091014 -372.38041) (xy 301.076727 -372.39477) (xy 301.058038 -372.402583) (xy 301.047912 -372.403116)
			(xy 300.331632 -372.403116) (xy 300.321482 -372.402653) (xy 300.302733 -372.394871) (xy 300.288409 -372.380487)
			(xy 300.280705 -372.361706) (xy 300.280324 -372.351554) (xy 300.280324 -372.194074) (xy 300.279921 -372.184886)
			(xy 300.273402 -372.167702) (xy 300.267624 -372.160546) (xy 300.245773 -372.13487) (xy 300.207682 -372.079237)
			(xy 300.17653 -372.019443) (xy 300.152764 -371.956347) (xy 300.136726 -371.890859) (xy 300.128649 -371.823922)
			(xy 300.128648 -371.756499) (xy 300.136723 -371.689561) (xy 300.152757 -371.624073) (xy 300.176521 -371.560976)
			(xy 300.207671 -371.501181) (xy 300.24576 -371.445547) (xy 300.267624 -371.419882) (xy 300.273413 -371.412732)
			(xy 300.279932 -371.395545) (xy 300.280324 -371.386354) (xy 300.280324 -370.893848) (xy 300.279885 -370.884664)
			(xy 300.273391 -370.86748) (xy 300.267624 -370.86032) (xy 300.245747 -370.834665) (xy 300.207657 -370.779029)
			(xy 300.176506 -370.719232) (xy 300.152741 -370.656134) (xy 300.136706 -370.590643) (xy 300.128631 -370.523704)
			(xy 296.851096 -370.523704) (xy 296.843021 -370.590639) (xy 296.826988 -370.656127) (xy 296.803227 -370.719223)
			(xy 296.772079 -370.779019) (xy 296.733994 -370.834654) (xy 296.712132 -370.86032) (xy 296.706336 -370.867465)
			(xy 296.699823 -370.884656) (xy 296.699432 -370.893848) (xy 296.699432 -371.386354) (xy 296.699879 -371.395537)
			(xy 296.706369 -371.412721) (xy 296.712132 -371.419882) (xy 296.734009 -371.445536) (xy 296.772095 -371.501173)
			(xy 296.803243 -371.560971) (xy 296.826876 -371.623726) (xy 297.92898 -371.623726) (xy 297.928984 -371.556417)
			(xy 297.937032 -371.489591) (xy 297.95301 -371.424206) (xy 297.976689 -371.3612) (xy 298.007729 -371.301476)
			(xy 298.045685 -371.245889) (xy 298.067476 -371.220238) (xy 298.073279 -371.213097) (xy 298.07979 -371.195903)
			(xy 298.080176 -371.18671) (xy 298.080176 -371.028722) (xy 298.080583 -371.018547) (xy 298.088368 -370.999746)
			(xy 298.102759 -370.985359) (xy 298.121563 -370.97758) (xy 298.131738 -370.97716) (xy 298.848018 -370.97716)
			(xy 298.858193 -370.97755) (xy 298.876993 -370.985345) (xy 298.891378 -370.999741) (xy 298.899158 -371.018546)
			(xy 298.89958 -371.028722) (xy 298.89958 -371.18671) (xy 298.89999 -371.195897) (xy 298.906504 -371.213081)
			(xy 298.91228 -371.220238) (xy 298.93403 -371.245921) (xy 298.971978 -371.301504) (xy 299.003012 -371.361223)
			(xy 299.026686 -371.424224) (xy 299.042661 -371.489602) (xy 299.050708 -371.556421) (xy 299.050711 -371.623722)
			(xy 299.042671 -371.690542) (xy 299.026703 -371.755922) (xy 299.003035 -371.818925) (xy 298.972008 -371.878647)
			(xy 298.934065 -371.934233) (xy 298.91228 -371.959886) (xy 298.906462 -371.967016) (xy 298.899961 -371.984218)
			(xy 298.89958 -371.993414) (xy 298.89958 -372.486682) (xy 298.900003 -372.495868) (xy 298.906508 -372.513052)
			(xy 298.91228 -372.52021) (xy 298.934101 -372.545835) (xy 298.972047 -372.601426) (xy 299.003078 -372.661153)
			(xy 299.026748 -372.724161) (xy 299.042718 -372.789547) (xy 299.050759 -372.856372) (xy 299.050756 -372.923679)
			(xy 299.042709 -372.990504) (xy 299.026733 -373.055888) (xy 299.003057 -373.118894) (xy 298.972021 -373.178618)
			(xy 298.934069 -373.234206) (xy 298.91228 -373.259858) (xy 298.906474 -373.266996) (xy 298.899966 -373.284192)
			(xy 298.89958 -373.293386) (xy 298.89958 -373.451374) (xy 298.899115 -373.461542) (xy 298.891342 -373.480332)
			(xy 298.876969 -373.494717) (xy 298.858185 -373.502506) (xy 298.848018 -373.502936) (xy 298.131738 -373.502936)
			(xy 298.121566 -373.502504) (xy 298.102767 -373.494727) (xy 298.08838 -373.480343) (xy 298.080598 -373.461546)
			(xy 298.080176 -373.451374) (xy 298.080176 -373.293386) (xy 298.079778 -373.284197) (xy 298.073256 -373.267013)
			(xy 298.067476 -373.259858) (xy 298.045721 -373.234179) (xy 298.007768 -373.178597) (xy 297.976732 -373.118878)
			(xy 297.953055 -373.055877) (xy 297.937079 -372.990497) (xy 297.929031 -372.923677) (xy 297.929028 -372.856374)
			(xy 297.93707 -372.789553) (xy 297.95304 -372.724172) (xy 297.976711 -372.661169) (xy 298.007742 -372.601447)
			(xy 298.045689 -372.545862) (xy 298.067476 -372.52021) (xy 298.073291 -372.513077) (xy 298.079795 -372.495877)
			(xy 298.080176 -372.486682) (xy 298.080176 -371.993414) (xy 298.079765 -371.984227) (xy 298.073252 -371.967042)
			(xy 298.067476 -371.959886) (xy 298.04565 -371.934265) (xy 298.007699 -371.878675) (xy 297.976666 -371.818948)
			(xy 297.952993 -371.755939) (xy 297.937022 -371.690552) (xy 297.92898 -371.623726) (xy 296.826876 -371.623726)
			(xy 296.827005 -371.624069) (xy 296.843039 -371.689559) (xy 296.851113 -371.756498) (xy 296.851112 -371.823923)
			(xy 296.843035 -371.890861) (xy 296.826999 -371.956351) (xy 296.803235 -372.019448) (xy 296.772084 -372.079245)
			(xy 296.733996 -372.13488) (xy 296.712132 -372.160546) (xy 296.706325 -372.167684) (xy 296.699819 -372.18488)
			(xy 296.699432 -372.194074) (xy 296.699432 -372.351554) (xy 296.698935 -372.361681) (xy 296.691217 -372.380407)
			(xy 296.676933 -372.394765) (xy 296.658249 -372.402581) (xy 296.648124 -372.403116) (xy 295.931844 -372.403116)
			(xy 295.921695 -372.402643) (xy 295.902946 -372.394865) (xy 295.888622 -372.380484) (xy 295.880918 -372.361705)
			(xy 295.880536 -372.351554) (xy 295.880536 -372.194074) (xy 295.88013 -372.184887) (xy 295.873613 -372.167703)
			(xy 295.867836 -372.160546) (xy 295.845985 -372.13487) (xy 295.807893 -372.079238) (xy 295.77674 -372.019444)
			(xy 295.752973 -371.956348) (xy 295.736936 -371.89086) (xy 295.728858 -371.823922) (xy 295.728857 -371.756499)
			(xy 295.736932 -371.689561) (xy 295.752967 -371.624072) (xy 295.776731 -371.560976) (xy 295.807882 -371.50118)
			(xy 295.845972 -371.445547) (xy 295.867836 -371.419882) (xy 295.873627 -371.412733) (xy 295.880144 -371.395545)
			(xy 295.880536 -371.386354) (xy 295.880536 -370.893848) (xy 295.880095 -370.884664) (xy 295.873602 -370.86748)
			(xy 295.867836 -370.86032) (xy 295.845959 -370.834665) (xy 295.807868 -370.77903) (xy 295.776716 -370.719233)
			(xy 295.752951 -370.656134) (xy 295.736915 -370.590644) (xy 295.72884 -370.523704) (xy 292.450793 -370.523704)
			(xy 292.442757 -370.590465) (xy 292.426785 -370.655847) (xy 292.403113 -370.718851) (xy 292.37208 -370.778574)
			(xy 292.334131 -370.83416) (xy 292.312344 -370.859812) (xy 292.306553 -370.866961) (xy 292.300036 -370.884149)
			(xy 292.299644 -370.89334) (xy 292.299644 -371.386862) (xy 292.300085 -371.396046) (xy 292.306578 -371.41323)
			(xy 292.312344 -371.42039) (xy 292.334146 -371.44603) (xy 292.372096 -371.501618) (xy 292.403129 -371.561343)
			(xy 292.42659 -371.623785) (xy 293.528685 -371.623785) (xy 293.528689 -371.556358) (xy 293.536768 -371.489418)
			(xy 293.552807 -371.423927) (xy 293.576575 -371.360828) (xy 293.60773 -371.301031) (xy 293.645822 -371.245395)
			(xy 293.667688 -371.21973) (xy 293.673495 -371.212592) (xy 293.680004 -371.195396) (xy 293.680388 -371.186202)
			(xy 293.680388 -371.028722) (xy 293.680943 -371.018603) (xy 293.688654 -370.999892) (xy 293.702919 -370.985537)
			(xy 293.72158 -370.977708) (xy 293.731696 -370.97716) (xy 294.447976 -370.97716) (xy 294.458124 -370.97764)
			(xy 294.476868 -370.98542) (xy 294.491191 -370.999799) (xy 294.498898 -371.018573) (xy 294.499284 -371.028722)
			(xy 294.499284 -371.186202) (xy 294.499697 -371.195389) (xy 294.506209 -371.212573) (xy 294.511984 -371.21973)
			(xy 294.533811 -371.245426) (xy 294.571902 -371.301056) (xy 294.603055 -371.360847) (xy 294.626822 -371.42394)
			(xy 294.642861 -371.489426) (xy 294.65094 -371.556361) (xy 294.650944 -371.623782) (xy 294.642871 -371.690718)
			(xy 294.626839 -371.756205) (xy 294.603079 -371.8193) (xy 294.571932 -371.879095) (xy 294.533846 -371.934729)
			(xy 294.511984 -371.960394) (xy 294.506206 -371.967552) (xy 294.499681 -371.984733) (xy 294.499284 -371.993922)
			(xy 294.499284 -372.486174) (xy 294.49971 -372.495359) (xy 294.506213 -372.512544) (xy 294.511984 -372.519702)
			(xy 294.533882 -372.545339) (xy 294.571971 -372.600978) (xy 294.603121 -372.660777) (xy 294.626884 -372.723878)
			(xy 294.642917 -372.789371) (xy 294.650991 -372.856312) (xy 294.650988 -372.923739) (xy 294.642908 -372.99068)
			(xy 294.626869 -373.056171) (xy 294.6031 -373.119269) (xy 294.571944 -373.179066) (xy 294.533851 -373.234701)
			(xy 294.511984 -373.260366) (xy 294.506175 -373.267502) (xy 294.499668 -373.2847) (xy 294.499284 -373.293894)
			(xy 294.499284 -373.451374) (xy 294.498753 -373.461496) (xy 294.491038 -373.480212) (xy 294.476766 -373.494569)
			(xy 294.458095 -373.502393) (xy 294.447976 -373.502936) (xy 293.731696 -373.502936) (xy 293.721546 -373.502482)
			(xy 293.702801 -373.494692) (xy 293.688479 -373.480306) (xy 293.680773 -373.461526) (xy 293.680388 -373.451374)
			(xy 293.680388 -373.293894) (xy 293.679983 -373.284706) (xy 293.673466 -373.267522) (xy 293.667688 -373.260366)
			(xy 293.645858 -373.234673) (xy 293.607769 -373.179042) (xy 293.576617 -373.11925) (xy 293.552852 -373.056156)
			(xy 293.536814 -372.990671) (xy 293.528736 -372.923736) (xy 293.528733 -372.856315) (xy 293.536805 -372.789379)
			(xy 293.552837 -372.723892) (xy 293.576597 -372.660797) (xy 293.607743 -372.601002) (xy 293.645826 -372.545367)
			(xy 293.667688 -372.519702) (xy 293.673465 -372.512543) (xy 293.679992 -372.495363) (xy 293.680388 -372.486174)
			(xy 293.680388 -371.993922) (xy 293.67997 -371.984736) (xy 293.673462 -371.967551) (xy 293.667688 -371.960394)
			(xy 293.645787 -371.934759) (xy 293.6077 -371.87912) (xy 293.576552 -371.81932) (xy 293.55279 -371.756219)
			(xy 293.536758 -371.690726) (xy 293.528685 -371.623785) (xy 292.42659 -371.623785) (xy 292.426802 -371.624349)
			(xy 292.442775 -371.689733) (xy 292.450818 -371.756557) (xy 292.450817 -371.823864) (xy 292.442771 -371.890688)
			(xy 292.426796 -371.956071) (xy 292.403121 -372.019076) (xy 292.372085 -372.0788) (xy 292.334133 -372.134386)
			(xy 292.312344 -372.160038) (xy 292.306542 -372.167179) (xy 292.300032 -372.184373) (xy 292.299644 -372.193566)
			(xy 292.299644 -372.351554) (xy 292.299198 -372.361725) (xy 292.291425 -372.380522) (xy 292.277046 -372.394909)
			(xy 292.258253 -372.402693) (xy 292.248082 -372.403116) (xy 291.531802 -372.403116) (xy 291.521625 -372.402733)
			(xy 291.502821 -372.394941) (xy 291.488435 -372.380542) (xy 291.480658 -372.361732) (xy 291.48024 -372.351554)
			(xy 291.48024 -372.193566) (xy 291.479837 -372.184378) (xy 291.473317 -372.167194) (xy 291.46754 -372.160038)
			(xy 291.445766 -372.134374) (xy 291.407817 -372.07879) (xy 291.376783 -372.019068) (xy 291.353109 -371.956065)
			(xy 291.337135 -371.890684) (xy 291.32909 -371.823862) (xy 291.329089 -371.756559) (xy 291.337132 -371.689737)
			(xy 291.353103 -371.624356) (xy 291.376774 -371.561352) (xy 291.407806 -371.501628) (xy 291.445753 -371.446042)
			(xy 291.46754 -371.42039) (xy 291.473328 -371.413239) (xy 291.479847 -371.396053) (xy 291.48024 -371.386862)
			(xy 291.48024 -370.89334) (xy 291.479801 -370.884156) (xy 291.473306 -370.866972) (xy 291.46754 -370.859812)
			(xy 291.44574 -370.83417) (xy 291.407792 -370.778582) (xy 291.376759 -370.718857) (xy 291.353087 -370.655851)
			(xy 291.337115 -370.590468) (xy 291.329071 -370.523644) (xy 288.051032 -370.523644) (xy 288.051032 -370.523703)
			(xy 288.042957 -370.590641) (xy 288.026921 -370.65613) (xy 288.003156 -370.719227) (xy 287.972004 -370.779022)
			(xy 287.933913 -370.834656) (xy 287.912048 -370.86032) (xy 287.906254 -370.867467) (xy 287.899739 -370.884656)
			(xy 287.899348 -370.893848) (xy 287.899348 -371.386354) (xy 287.899792 -371.395537) (xy 287.906284 -371.412721)
			(xy 287.912048 -371.419882) (xy 287.933928 -371.445535) (xy 287.972019 -371.50117) (xy 288.003172 -371.560967)
			(xy 288.02681 -371.623726) (xy 289.128893 -371.623726) (xy 289.128896 -371.556417) (xy 289.136945 -371.489591)
			(xy 289.152924 -371.424206) (xy 289.176603 -371.3612) (xy 289.207644 -371.301475) (xy 289.2456 -371.245889)
			(xy 289.267392 -371.220238) (xy 289.273196 -371.213098) (xy 289.279707 -371.195904) (xy 289.280092 -371.18671)
			(xy 289.280092 -371.028722) (xy 289.28065 -371.018571) (xy 289.288409 -370.999811) (xy 289.302754 -370.985447)
			(xy 289.321504 -370.977663) (xy 289.331654 -370.97716) (xy 290.047934 -370.97716) (xy 290.058097 -370.977606)
			(xy 290.076871 -370.985396) (xy 290.091236 -370.999776) (xy 290.099005 -371.018559) (xy 290.099496 -371.028722)
			(xy 290.099496 -371.18671) (xy 290.099902 -371.195898) (xy 290.106419 -371.213082) (xy 290.112196 -371.220238)
			(xy 290.133945 -371.245921) (xy 290.171893 -371.301504) (xy 290.202926 -371.361224) (xy 290.226599 -371.424224)
			(xy 290.242574 -371.489602) (xy 290.250621 -371.556421) (xy 290.250624 -371.623722) (xy 290.242584 -371.690542)
			(xy 290.226616 -371.755921) (xy 290.202949 -371.818924) (xy 290.171922 -371.878647) (xy 290.13398 -371.934233)
			(xy 290.112196 -371.959886) (xy 290.10638 -371.967017) (xy 290.099877 -371.984218) (xy 290.099496 -371.993414)
			(xy 290.099496 -372.486682) (xy 290.099916 -372.495868) (xy 290.106423 -372.513053) (xy 290.112196 -372.52021)
			(xy 290.134016 -372.545835) (xy 290.171962 -372.601426) (xy 290.202991 -372.661154) (xy 290.226661 -372.724162)
			(xy 290.24263 -372.789547) (xy 290.250671 -372.856372) (xy 290.250668 -372.923679) (xy 290.242621 -372.990503)
			(xy 290.226646 -373.055887) (xy 290.202971 -373.118893) (xy 290.171935 -373.178618) (xy 290.133985 -373.234205)
			(xy 290.112196 -373.259858) (xy 290.106392 -373.266998) (xy 290.099882 -373.284192) (xy 290.099496 -373.293386)
			(xy 290.099496 -373.451374) (xy 290.098946 -373.461526) (xy 290.091187 -373.480288) (xy 290.076838 -373.494653)
			(xy 290.058085 -373.502435) (xy 290.047934 -373.502936) (xy 289.331654 -373.502936) (xy 289.32149 -373.502504)
			(xy 289.302715 -373.494709) (xy 289.28835 -373.480325) (xy 289.280582 -373.461539) (xy 289.280092 -373.451374)
			(xy 289.280092 -373.293386) (xy 289.27969 -373.284198) (xy 289.273171 -373.267014) (xy 289.267392 -373.259858)
			(xy 289.245636 -373.234179) (xy 289.207683 -373.178598) (xy 289.176645 -373.118878) (xy 289.152968 -373.055877)
			(xy 289.136991 -372.990498) (xy 289.128943 -372.923677) (xy 289.12894 -372.856374) (xy 289.136982 -372.789553)
			(xy 289.152953 -372.724172) (xy 289.176624 -372.661168) (xy 289.207656 -372.601446) (xy 289.245605 -372.545861)
			(xy 289.267392 -372.52021) (xy 289.273208 -372.513079) (xy 289.279711 -372.495878) (xy 289.280092 -372.486682)
			(xy 289.280092 -371.993414) (xy 289.279677 -371.984227) (xy 289.273167 -371.967043) (xy 289.267392 -371.959886)
			(xy 289.245565 -371.934265) (xy 289.207614 -371.878676) (xy 289.17658 -371.818948) (xy 289.152907 -371.755939)
			(xy 289.136935 -371.690553) (xy 289.128893 -371.623726) (xy 288.02681 -371.623726) (xy 288.026938 -371.624066)
			(xy 288.042974 -371.689557) (xy 288.05105 -371.756498) (xy 288.051048 -371.823923) (xy 288.04297 -371.890864)
			(xy 288.026932 -371.956354) (xy 288.003164 -372.019452) (xy 287.972008 -372.079248) (xy 287.933915 -372.134882)
			(xy 287.912048 -372.160546) (xy 287.906243 -372.167685) (xy 287.899735 -372.18488) (xy 287.899348 -372.194074)
			(xy 287.899348 -372.351554) (xy 287.898835 -372.361679) (xy 287.89112 -372.380402) (xy 287.876842 -372.39476)
			(xy 287.858162 -372.402579) (xy 287.84804 -372.403116) (xy 287.13176 -372.403116) (xy 287.121605 -372.402711)
			(xy 287.102855 -372.394906) (xy 287.088534 -372.380504) (xy 287.080833 -372.361711) (xy 287.080452 -372.351554)
			(xy 287.080452 -372.194074) (xy 287.080043 -372.184887) (xy 287.073527 -372.167703) (xy 287.067752 -372.160546)
			(xy 287.0459 -372.13487) (xy 287.007807 -372.079238) (xy 286.976653 -372.019444) (xy 286.952886 -371.956349)
			(xy 286.936848 -371.89086) (xy 286.92877 -371.823922) (xy 286.928769 -371.756499) (xy 286.936844 -371.68956)
			(xy 286.95288 -371.624072) (xy 286.976645 -371.560975) (xy 287.007797 -371.50118) (xy 287.045887 -371.445546)
			(xy 287.067752 -371.419882) (xy 287.073545 -371.412735) (xy 287.08006 -371.395546) (xy 287.080452 -371.386354)
			(xy 287.080452 -370.893848) (xy 287.080007 -370.884665) (xy 287.073516 -370.867481) (xy 287.067752 -370.86032)
			(xy 287.045874 -370.834665) (xy 287.007783 -370.779031) (xy 286.97663 -370.719233) (xy 286.952864 -370.656135)
			(xy 286.936828 -370.590644) (xy 286.928752 -370.523704) (xy 266.501372 -370.523704) (xy 266.501372 -377.582176)
			(xy 266.500885 -377.607127) (xy 266.493084 -377.656414) (xy 266.47767 -377.703875) (xy 266.455022 -377.748341)
			(xy 266.425698 -377.788717) (xy 266.408408 -377.806712) (xy 265.993118 -378.222002) (xy 265.975118 -378.239283)
			(xy 265.934733 -378.268585) (xy 265.890267 -378.291219) (xy 265.84281 -378.306629) (xy 265.79353 -378.314436)
			(xy 265.768582 -378.314966) (xy 243.004086 -378.314966) (xy 242.979134 -378.314483) (xy 242.929841 -378.306691)
			(xy 242.882374 -378.291283) (xy 242.837902 -378.268641) (xy 242.797519 -378.239321) (xy 242.77955 -378.222002)
			(xy 242.203732 -377.646184) (xy 242.186446 -377.628186) (xy 242.157132 -377.587804) (xy 242.134486 -377.543339)
			(xy 242.119065 -377.495881) (xy 242.111247 -377.446598) (xy 242.110768 -377.421648) (xy 242.110768 -377.180602)
			(xy 242.110345 -377.170532) (xy 242.102627 -377.15193) (xy 242.095782 -377.144534) (xy 242.00104 -377.049792)
			(xy 241.993638 -377.042956) (xy 241.97504 -377.035244) (xy 241.964972 -377.034806) (xy 236.209586 -377.034806)
			(xy 236.184632 -377.034349) (xy 236.135337 -377.026554) (xy 236.087868 -377.011143) (xy 236.043395 -376.988496)
			(xy 236.003012 -376.95917) (xy 235.98505 -376.941842) (xy 235.566712 -376.523504) (xy 235.549426 -376.505506)
			(xy 235.520111 -376.465124) (xy 235.497464 -376.420659) (xy 235.482041 -376.373202) (xy 235.47422 -376.323918)
			(xy 235.473748 -376.298968) (xy 235.473748 -368.60607) (xy 235.474232 -368.581118) (xy 235.482027 -368.531827)
			(xy 235.497437 -368.484363) (xy 235.520081 -368.439892) (xy 235.549403 -368.399512) (xy 235.566712 -368.381534)
			(xy 235.993178 -367.955068) (xy 236.011176 -367.937784) (xy 236.051559 -367.908475) (xy 236.096025 -367.885835)
			(xy 236.143482 -367.870421) (xy 236.192765 -367.862612) (xy 236.217714 -367.862104) (xy 266.741148 -367.862104)
			(xy 266.751214 -367.861672) (xy 266.769806 -367.853946) (xy 266.777216 -367.847118) (xy 267.665708 -366.958626)
			(xy 267.683706 -366.94134) (xy 267.724088 -366.912025) (xy 267.768553 -366.889379) (xy 267.81601 -366.873957)
			(xy 267.865294 -366.866138) (xy 267.890244 -366.865662) (xy 271.438878 -366.865662) (xy 271.446753 -366.865375)
			(xy 271.461763 -366.860601) (xy 271.468342 -366.856264) (xy 271.489932 -366.841477) (xy 271.53635 -366.817318)
			(xy 271.585635 -366.799729) (xy 271.636862 -366.789043) (xy 271.689068 -366.785458) (xy 271.741274 -366.789043)
			(xy 271.792501 -366.799729) (xy 271.841786 -366.817318) (xy 271.888204 -366.841477) (xy 271.909794 -366.856264)
			(xy 271.916379 -366.860593) (xy 271.931383 -366.865383) (xy 271.939258 -366.865662) (xy 455.622152 -366.865662)
			(xy 455.649584 -366.843818) (xy 455.653648 -366.826546) (xy 455.660663 -366.799014) (xy 455.681734 -366.746251)
			(xy 455.710397 -366.697197) (xy 455.746017 -366.652937) (xy 455.787808 -366.614448) (xy 455.834846 -366.582584)
			(xy 455.886088 -366.558047) (xy 455.940403 -366.541382) (xy 455.996589 -366.532956) (xy 456.053403 -366.532956)
			(xy 456.109589 -366.541382) (xy 456.163904 -366.558047) (xy 456.215146 -366.582584) (xy 456.262184 -366.614448)
			(xy 456.303975 -366.652937) (xy 456.339595 -366.697197) (xy 456.368258 -366.746251) (xy 456.389329 -366.799014)
			(xy 456.396344 -366.826546) (xy 456.400408 -366.843818) (xy 456.42784 -366.865662) (xy 458.429868 -366.865662)
			(xy 458.4573 -366.843818) (xy 458.461364 -366.826546) (xy 458.468379 -366.799014) (xy 458.48945 -366.746251)
			(xy 458.518113 -366.697197) (xy 458.553733 -366.652937) (xy 458.595524 -366.614448) (xy 458.642562 -366.582584)
			(xy 458.693804 -366.558047) (xy 458.748119 -366.541382) (xy 458.804305 -366.532956) (xy 458.861119 -366.532956)
			(xy 458.917305 -366.541382) (xy 458.97162 -366.558047) (xy 459.022862 -366.582584) (xy 459.0699 -366.614448)
			(xy 459.111691 -366.652937) (xy 459.147311 -366.697197) (xy 459.175974 -366.746251) (xy 459.197045 -366.799014)
			(xy 459.20406 -366.826546) (xy 459.208124 -366.843818) (xy 459.235556 -366.865662) (xy 466.02523 -366.865662)
			(xy 466.035245 -366.865237) (xy 466.053745 -366.85756) (xy 466.067898 -366.843387) (xy 466.07555 -366.824877)
			(xy 466.07603 -366.814862) (xy 466.07603 -316.782196) (xy 466.075668 -316.773118) (xy 466.069325 -316.756108)
			(xy 466.057412 -316.742408) (xy 466.049614 -316.737746) (xy 465.95919 -316.68847) (xy 465.93125 -316.689486)
			(xy 465.91982 -316.696852) (xy 465.85211 -316.739573) (xy 465.713263 -316.81932) (xy 465.570794 -316.8924)
			(xy 465.425024 -316.95865) (xy 465.276279 -317.017921) (xy 465.124893 -317.070078) (xy 464.971207 -317.115007)
			(xy 464.815565 -317.152605) (xy 464.658316 -317.182788) (xy 464.499815 -317.205489) (xy 464.340416 -317.220656)
			(xy 464.180477 -317.228256) (xy 464.100418 -317.228728) (xy 464.09991 -317.228728) (xy 464.018255 -317.228243)
			(xy 463.855136 -317.220353) (xy 463.692588 -317.204592) (xy 463.530992 -317.180996) (xy 463.370724 -317.14962)
			(xy 463.21216 -317.110538) (xy 463.055668 -317.06384) (xy 462.901616 -317.009637) (xy 462.750362 -316.948054)
			(xy 462.602261 -316.879235) (xy 462.457657 -316.803341) (xy 462.316888 -316.72055) (xy 462.180284 -316.631054)
			(xy 462.048163 -316.535063) (xy 461.920835 -316.432801) (xy 461.798595 -316.324507) (xy 461.681731 -316.210433)
			(xy 461.570514 -316.090847) (xy 461.465205 -315.966027) (xy 461.366049 -315.836264) (xy 461.273278 -315.701863)
			(xy 461.187109 -315.563136) (xy 461.107743 -315.420409) (xy 461.035365 -315.274013) (xy 460.970145 -315.124292)
			(xy 460.912234 -314.971595) (xy 460.861768 -314.816278) (xy 460.818866 -314.658704) (xy 460.783626 -314.499241)
			(xy 460.756131 -314.338262) (xy 460.736447 -314.176143) (xy 460.724617 -314.013262) (xy 460.720671 -313.85)
			(xy 460.724617 -313.686738) (xy 460.736447 -313.523857) (xy 460.756131 -313.361737) (xy 460.783626 -313.200759)
			(xy 460.818866 -313.041296) (xy 460.861768 -312.883722) (xy 460.912234 -312.728405) (xy 460.970145 -312.575708)
			(xy 461.035365 -312.425987) (xy 461.107743 -312.279591) (xy 461.187109 -312.136864) (xy 461.273278 -311.998137)
			(xy 461.366049 -311.863736) (xy 461.465205 -311.733973) (xy 461.570514 -311.609153) (xy 461.681731 -311.489567)
			(xy 461.798595 -311.375493) (xy 461.920835 -311.267199) (xy 462.048163 -311.164937) (xy 462.180284 -311.068946)
			(xy 462.316888 -310.97945) (xy 462.457657 -310.896659) (xy 462.602261 -310.820765) (xy 462.750362 -310.751946)
			(xy 462.901616 -310.690363) (xy 463.055668 -310.63616) (xy 463.21216 -310.589462) (xy 463.370724 -310.55038)
			(xy 463.530992 -310.519004) (xy 463.692588 -310.495408) (xy 463.855136 -310.479647) (xy 464.018255 -310.471757)
			(xy 464.09991 -310.471312) (xy 464.100418 -310.471312) (xy 464.180478 -310.471787) (xy 464.340417 -310.479383)
			(xy 464.499816 -310.494546) (xy 464.658319 -310.517244) (xy 464.815568 -310.547425) (xy 464.971211 -310.585022)
			(xy 465.124898 -310.629949) (xy 465.276284 -310.682106) (xy 465.42503 -310.741377) (xy 465.570801 -310.807627)
			(xy 465.713269 -310.880709) (xy 465.852116 -310.960457) (xy 465.91982 -311.003188) (xy 465.93125 -311.010554)
			(xy 465.95919 -311.01157) (xy 466.049614 -310.962294) (xy 466.057381 -310.957602) (xy 466.069246 -310.943887)
			(xy 466.075617 -310.926909) (xy 466.07603 -310.917844) (xy 466.07603 -246.488458) (xy 466.075545 -246.457292)
			(xy 466.067413 -246.395492) (xy 466.051278 -246.335284) (xy 466.02742 -246.277699) (xy 465.996245 -246.223723)
			(xy 465.958287 -246.17428) (xy 465.936584 -246.151908) (xy 463.308192 -243.523516) (xy 463.307938 -243.523262)
			(xy 463.247151 -243.461732) (xy 463.130988 -243.333555) (xy 463.021255 -243.199833) (xy 462.918215 -243.060888)
			(xy 462.822117 -242.917054) (xy 462.733193 -242.768678) (xy 462.651656 -242.616117) (xy 462.577703 -242.459739)
			(xy 462.511513 -242.299921) (xy 462.453245 -242.137048) (xy 462.403038 -241.971511) (xy 462.361015 -241.803711)
			(xy 462.327275 -241.63405) (xy 462.301902 -241.462939) (xy 462.284955 -241.290788) (xy 462.276476 -241.118013)
			(xy 462.275936 -241.031522) (xy 462.275936 -87.58809) (xy 462.276464 -87.50164) (xy 462.284941 -87.328947)
			(xy 462.301878 -87.156878) (xy 462.327235 -86.985847) (xy 462.360951 -86.816265) (xy 462.402945 -86.648542)
			(xy 462.453116 -86.48308) (xy 462.511342 -86.320278) (xy 462.577484 -86.160529) (xy 462.651382 -86.004216)
			(xy 462.732859 -85.851716) (xy 462.821718 -85.703397) (xy 462.917746 -85.559614) (xy 463.02071 -85.420715)
			(xy 463.130364 -85.287034) (xy 463.246444 -85.158893) (xy 463.307176 -85.097366) (xy 463.307938 -85.096604)
			(xy 465.936584 -82.467958) (xy 465.958275 -82.445601) (xy 465.996222 -82.396201) (xy 466.027395 -82.342269)
			(xy 466.051259 -82.284728) (xy 466.067406 -82.224565) (xy 466.075561 -82.162808) (xy 466.07603 -82.131662)
			(xy 466.07603 -50.43805) (xy 466.075534 -50.428047) (xy 466.067866 -50.409567) (xy 466.053716 -50.395422)
			(xy 466.035233 -50.387762) (xy 466.02523 -50.38725) (xy 14.400784 -50.38725) (xy 14.390716 -50.387677)
			(xy 14.372121 -50.395402) (xy 14.364716 -50.402236) (xy 14.234668 -50.532284) (xy 14.227827 -50.539684)
			(xy 14.220113 -50.558283) (xy 14.219682 -50.568352) (xy 14.219682 -52.600098) (xy 14.227302 -52.626514)
			(xy 14.240697 -52.649161) (xy 14.261822 -52.69735) (xy 14.27613 -52.747984) (xy 14.283352 -52.800102)
			(xy 14.283351 -52.852718) (xy 14.276126 -52.904836) (xy 14.261815 -52.955469) (xy 14.240688 -53.003657)
			(xy 14.227302 -53.02631) (xy 14.219682 -53.052726) (xy 14.219682 -53.235098) (xy 14.227302 -53.261514)
			(xy 14.240697 -53.284161) (xy 14.261822 -53.33235) (xy 14.27613 -53.382984) (xy 14.283352 -53.435102)
			(xy 14.283351 -53.487718) (xy 14.276126 -53.539836) (xy 14.261815 -53.590469) (xy 14.240688 -53.638657)
			(xy 14.227302 -53.66131) (xy 14.219682 -53.687726) (xy 14.219682 -53.870098) (xy 14.227302 -53.896514)
			(xy 14.240697 -53.919161) (xy 14.261822 -53.96735) (xy 14.27613 -54.017984) (xy 14.283352 -54.070102)
			(xy 14.283351 -54.122718) (xy 14.276126 -54.174836) (xy 14.261815 -54.225469) (xy 14.240688 -54.273657)
			(xy 14.227302 -54.29631) (xy 14.219682 -54.322726) (xy 14.219682 -54.505098) (xy 14.227302 -54.531514)
			(xy 14.240697 -54.554161) (xy 14.261822 -54.60235) (xy 14.27613 -54.652984) (xy 14.283352 -54.705102)
			(xy 14.283351 -54.757718) (xy 14.276126 -54.809836) (xy 14.261815 -54.860469) (xy 14.240688 -54.908657)
			(xy 14.227302 -54.93131) (xy 14.219682 -54.957726) (xy 14.219682 -56.60009) (xy 14.227302 -56.626506)
			(xy 14.240698 -56.649153) (xy 14.261823 -56.697343) (xy 14.276133 -56.747976) (xy 14.283356 -56.800095)
			(xy 14.283355 -56.852712) (xy 14.276132 -56.90483) (xy 14.261821 -56.955464) (xy 14.240695 -57.003653)
			(xy 14.227302 -57.026302) (xy 14.219682 -57.052718) (xy 14.219682 -57.23509) (xy 14.227302 -57.261506)
			(xy 14.240656 -57.2841) (xy 14.261723 -57.332171) (xy 14.276011 -57.382672) (xy 14.283251 -57.434654)
			(xy 14.28369 -57.460896) (xy 14.28369 -57.461404) (xy 14.283212 -57.488556) (xy 14.275515 -57.542311)
			(xy 14.260277 -57.594432) (xy 14.237805 -57.643868) (xy 14.208554 -57.689619) (xy 14.173114 -57.730764)
			(xy 14.132201 -57.766469) (xy 14.086639 -57.796016) (xy 14.062202 -57.80786) (xy 14.05382 -57.81167)
			(xy 13.380466 -58.485024) (xy 13.362469 -58.502311) (xy 13.322088 -58.531627) (xy 13.277622 -58.554273)
			(xy 13.230164 -58.569694) (xy 13.18088 -58.57751) (xy 13.15593 -58.577988) (xy 13.126128 -58.577313)
			(xy 13.067569 -58.566196) (xy 13.039598 -58.55589) (xy 13.038582 -58.555382) (xy 13.037566 -58.555128)
			(xy 13.030708 -58.552334) (xy 9.595104 -58.552334) (xy 9.584829 -58.552802) (xy 9.565918 -58.560846)
			(xy 9.551666 -58.575651) (xy 9.547606 -58.5851) (xy 9.537536 -58.610282) (xy 9.511301 -58.657747)
			(xy 9.480531 -58.698471) (xy 229.808523 -58.698471) (xy 229.808523 -58.601777) (xy 229.816508 -58.505414)
			(xy 229.832424 -58.410039) (xy 229.85616 -58.316305) (xy 229.887557 -58.22485) (xy 229.926398 -58.136301)
			(xy 229.972419 -58.051261) (xy 230.025305 -57.970313) (xy 230.084696 -57.894008) (xy 230.150184 -57.822868)
			(xy 230.221324 -57.75738) (xy 230.297629 -57.697989) (xy 230.378577 -57.645103) (xy 230.463617 -57.599082)
			(xy 230.552166 -57.560241) (xy 230.643621 -57.528844) (xy 230.737355 -57.505108) (xy 230.83273 -57.489192)
			(xy 230.929093 -57.481207) (xy 231.025787 -57.481207) (xy 231.12215 -57.489192) (xy 231.217525 -57.505108)
			(xy 231.311259 -57.528844) (xy 231.402714 -57.560241) (xy 231.491263 -57.599082) (xy 231.576303 -57.645103)
			(xy 231.657251 -57.697989) (xy 231.733556 -57.75738) (xy 231.804696 -57.822868) (xy 231.870184 -57.894008)
			(xy 231.929575 -57.970313) (xy 231.982461 -58.051261) (xy 232.028482 -58.136301) (xy 232.067323 -58.22485)
			(xy 232.09872 -58.316305) (xy 232.122456 -58.410039) (xy 232.138372 -58.505414) (xy 232.146357 -58.601777)
			(xy 232.146856 -58.650124) (xy 232.146357 -58.698471) (xy 232.138372 -58.794834) (xy 232.122456 -58.890209)
			(xy 232.09872 -58.983943) (xy 232.067323 -59.075398) (xy 232.028482 -59.163947) (xy 231.982461 -59.248987)
			(xy 231.929575 -59.329935) (xy 231.870184 -59.40624) (xy 231.804696 -59.47738) (xy 231.733556 -59.542868)
			(xy 231.657251 -59.602259) (xy 231.576303 -59.655145) (xy 231.491263 -59.701166) (xy 231.402714 -59.740007)
			(xy 231.311259 -59.771404) (xy 231.217525 -59.79514) (xy 231.12215 -59.811056) (xy 231.025787 -59.819041)
			(xy 230.929093 -59.819041) (xy 230.83273 -59.811056) (xy 230.737355 -59.79514) (xy 230.643621 -59.771404)
			(xy 230.552166 -59.740007) (xy 230.463617 -59.701166) (xy 230.378577 -59.655145) (xy 230.297629 -59.602259)
			(xy 230.221324 -59.542868) (xy 230.150184 -59.47738) (xy 230.084696 -59.40624) (xy 230.025305 -59.329935)
			(xy 229.972419 -59.248987) (xy 229.926398 -59.163947) (xy 229.887557 -59.075398) (xy 229.85616 -58.983943)
			(xy 229.832424 -58.890209) (xy 229.816508 -58.794834) (xy 229.808523 -58.698471) (xy 9.480531 -58.698471)
			(xy 9.478607 -58.701017) (xy 9.440114 -58.739221) (xy 9.396599 -58.771588) (xy 9.348937 -58.797465)
			(xy 9.298091 -58.81633) (xy 9.245086 -58.827803) (xy 9.19099 -58.831654) (xy 9.136894 -58.827803)
			(xy 9.083889 -58.81633) (xy 9.033043 -58.797465) (xy 8.985381 -58.771588) (xy 8.941866 -58.739221)
			(xy 8.903373 -58.701017) (xy 8.870679 -58.657747) (xy 8.844444 -58.610282) (xy 8.834374 -58.5851)
			(xy 8.828786 -58.570114) (xy 8.802878 -58.552334) (xy 1.5748 -58.552334) (xy 1.564781 -58.552754)
			(xy 1.54627 -58.560425) (xy 1.532106 -58.574599) (xy 1.524447 -58.593115) (xy 1.524 -58.603134) (xy 1.524 -60.13196)
			(xy 226.436428 -60.13196) (xy 226.436428 -59.26836) (xy 226.436918 -59.238392) (xy 226.444741 -59.17897)
			(xy 226.460254 -59.121077) (xy 226.48319 -59.065704) (xy 226.513157 -59.013798) (xy 226.549644 -58.966248)
			(xy 226.592024 -58.923868) (xy 226.639574 -58.887381) (xy 226.69148 -58.857414) (xy 226.746853 -58.834478)
			(xy 226.804746 -58.818965) (xy 226.864168 -58.811142) (xy 226.924104 -58.811142) (xy 226.983526 -58.818965)
			(xy 227.041419 -58.834478) (xy 227.096792 -58.857414) (xy 227.148698 -58.887381) (xy 227.196248 -58.923868)
			(xy 227.238628 -58.966248) (xy 227.275115 -59.013798) (xy 227.305082 -59.065704) (xy 227.328018 -59.121077)
			(xy 227.343531 -59.17897) (xy 227.351354 -59.238392) (xy 227.351844 -59.26836) (xy 227.351844 -60.13196)
			(xy 227.351354 -60.161928) (xy 227.343531 -60.22135) (xy 227.328018 -60.279243) (xy 227.305082 -60.334616)
			(xy 227.275115 -60.386522) (xy 227.238628 -60.434072) (xy 227.196248 -60.476452) (xy 227.148698 -60.512939)
			(xy 227.096792 -60.542906) (xy 227.041419 -60.565842) (xy 226.983526 -60.581355) (xy 226.924104 -60.589178)
			(xy 226.864168 -60.589178) (xy 226.804746 -60.581355) (xy 226.746853 -60.565842) (xy 226.69148 -60.542906)
			(xy 226.639574 -60.512939) (xy 226.592024 -60.476452) (xy 226.549644 -60.434072) (xy 226.513157 -60.386522)
			(xy 226.48319 -60.334616) (xy 226.460254 -60.279243) (xy 226.444741 -60.22135) (xy 226.436918 -60.161928)
			(xy 226.436428 -60.13196) (xy 1.524 -60.13196) (xy 1.524 -72.700134) (xy 112.441236 -72.700134) (xy 112.44524 -72.494946)
			(xy 112.457247 -72.29007) (xy 112.477238 -72.085819) (xy 112.505183 -71.882504) (xy 112.541039 -71.680433)
			(xy 112.584753 -71.479915) (xy 112.636256 -71.281256) (xy 112.695471 -71.084757) (xy 112.762307 -70.890718)
			(xy 112.836663 -70.699435) (xy 112.918426 -70.511198) (xy 113.007471 -70.326295) (xy 113.103662 -70.145007)
			(xy 113.206853 -69.96761) (xy 113.316887 -69.794373) (xy 113.433596 -69.625562) (xy 113.556802 -69.461433)
			(xy 113.686319 -69.302236) (xy 113.821948 -69.148214) (xy 113.963483 -68.9996) (xy 114.110708 -68.856622)
			(xy 114.2634 -68.719497) (xy 114.421326 -68.588433) (xy 114.584245 -68.463631) (xy 114.75191 -68.345281)
			(xy 114.924064 -68.233562) (xy 115.100446 -68.128645) (xy 115.280787 -68.03069) (xy 115.464813 -67.939846)
			(xy 115.652243 -67.85625) (xy 115.842792 -67.780031) (xy 116.036169 -67.711305) (xy 116.232081 -67.650176)
			(xy 116.430228 -67.596737) (xy 116.63031 -67.55107) (xy 116.832021 -67.513243) (xy 117.035054 -67.483316)
			(xy 117.239101 -67.461333) (xy 117.44385 -67.447328) (xy 117.648989 -67.441322) (xy 117.854206 -67.443324)
			(xy 118.059189 -67.453332) (xy 118.263626 -67.471329) (xy 118.467204 -67.497289) (xy 118.669615 -67.531172)
			(xy 118.870549 -67.572927) (xy 119.069702 -67.62249) (xy 119.266769 -67.679785) (xy 119.461451 -67.744725)
			(xy 119.653451 -67.817211) (xy 119.842476 -67.897134) (xy 120.028239 -67.98437) (xy 120.210457 -68.078788)
			(xy 120.388853 -68.180243) (xy 120.563154 -68.288582) (xy 120.733096 -68.403638) (xy 120.898419 -68.525238)
			(xy 121.058872 -68.653195) (xy 121.214211 -68.787314) (xy 121.364198 -68.927393) (xy 121.508606 -69.073217)
			(xy 121.647214 -69.224563) (xy 121.779812 -69.381203) (xy 121.906198 -69.542897) (xy 122.026178 -69.709399)
			(xy 122.085091 -69.798271) (xy 229.808523 -69.798271) (xy 229.808523 -69.701577) (xy 229.816508 -69.605214)
			(xy 229.832424 -69.509839) (xy 229.85616 -69.416105) (xy 229.887557 -69.32465) (xy 229.926398 -69.236101)
			(xy 229.972419 -69.151061) (xy 230.025305 -69.070113) (xy 230.084696 -68.993808) (xy 230.150184 -68.922668)
			(xy 230.221324 -68.85718) (xy 230.297629 -68.797789) (xy 230.378577 -68.744903) (xy 230.463617 -68.698882)
			(xy 230.552166 -68.660041) (xy 230.643621 -68.628644) (xy 230.737355 -68.604908) (xy 230.83273 -68.588992)
			(xy 230.929093 -68.581007) (xy 231.025787 -68.581007) (xy 231.12215 -68.588992) (xy 231.217525 -68.604908)
			(xy 231.311259 -68.628644) (xy 231.402714 -68.660041) (xy 231.491263 -68.698882) (xy 231.576303 -68.744903)
			(xy 231.657251 -68.797789) (xy 231.733556 -68.85718) (xy 231.804696 -68.922668) (xy 231.870184 -68.993808)
			(xy 231.929575 -69.070113) (xy 231.982461 -69.151061) (xy 232.028482 -69.236101) (xy 232.067323 -69.32465)
			(xy 232.09872 -69.416105) (xy 232.122456 -69.509839) (xy 232.138372 -69.605214) (xy 232.146357 -69.701577)
			(xy 232.146856 -69.749924) (xy 232.146357 -69.798271) (xy 232.138372 -69.894634) (xy 232.122456 -69.990009)
			(xy 232.09872 -70.083743) (xy 232.067323 -70.175198) (xy 232.028482 -70.263747) (xy 231.982461 -70.348787)
			(xy 231.929575 -70.429735) (xy 231.870184 -70.50604) (xy 231.804696 -70.57718) (xy 231.733556 -70.642668)
			(xy 231.657251 -70.702059) (xy 231.576303 -70.754945) (xy 231.491263 -70.800966) (xy 231.402714 -70.839807)
			(xy 231.311259 -70.871204) (xy 231.217525 -70.89494) (xy 231.12215 -70.910856) (xy 231.025787 -70.918841)
			(xy 230.929093 -70.918841) (xy 230.83273 -70.910856) (xy 230.737355 -70.89494) (xy 230.643621 -70.871204)
			(xy 230.552166 -70.839807) (xy 230.463617 -70.800966) (xy 230.378577 -70.754945) (xy 230.297629 -70.702059)
			(xy 230.221324 -70.642668) (xy 230.150184 -70.57718) (xy 230.084696 -70.50604) (xy 230.025305 -70.429735)
			(xy 229.972419 -70.348787) (xy 229.926398 -70.263747) (xy 229.887557 -70.175198) (xy 229.85616 -70.083743)
			(xy 229.832424 -69.990009) (xy 229.816508 -69.894634) (xy 229.808523 -69.798271) (xy 122.085091 -69.798271)
			(xy 122.139571 -69.880455) (xy 122.246204 -70.055805) (xy 122.345914 -70.235182) (xy 122.43855 -70.418312)
			(xy 122.52397 -70.604918) (xy 122.602044 -70.794714) (xy 122.672654 -70.987412) (xy 122.735691 -71.182718)
			(xy 122.791061 -71.380334) (xy 122.838678 -71.579961) (xy 122.87847 -71.781293) (xy 122.910377 -71.984025)
			(xy 122.93435 -72.187847) (xy 122.950352 -72.39245) (xy 122.958359 -72.59752) (xy 122.958859 -72.69988)
			(xy 344.640924 -72.69988) (xy 344.644928 -72.494692) (xy 344.656935 -72.289816) (xy 344.676926 -72.085565)
			(xy 344.704871 -71.88225) (xy 344.740727 -71.680179) (xy 344.784441 -71.479661) (xy 344.835944 -71.281002)
			(xy 344.895159 -71.084503) (xy 344.961995 -70.890464) (xy 345.036351 -70.699181) (xy 345.118114 -70.510944)
			(xy 345.207159 -70.326041) (xy 345.30335 -70.144753) (xy 345.406541 -69.967356) (xy 345.516575 -69.794119)
			(xy 345.633284 -69.625308) (xy 345.75649 -69.461179) (xy 345.886007 -69.301982) (xy 346.021636 -69.14796)
			(xy 346.163171 -68.999346) (xy 346.310396 -68.856368) (xy 346.463088 -68.719243) (xy 346.621014 -68.588179)
			(xy 346.783933 -68.463377) (xy 346.951598 -68.345027) (xy 347.123752 -68.233308) (xy 347.300134 -68.128391)
			(xy 347.480475 -68.030436) (xy 347.664501 -67.939592) (xy 347.851931 -67.855996) (xy 348.04248 -67.779777)
			(xy 348.235857 -67.711051) (xy 348.431769 -67.649922) (xy 348.629916 -67.596483) (xy 348.829998 -67.550816)
			(xy 349.031709 -67.512989) (xy 349.234742 -67.483062) (xy 349.438789 -67.461079) (xy 349.643538 -67.447074)
			(xy 349.848677 -67.441068) (xy 350.053894 -67.44307) (xy 350.258877 -67.453078) (xy 350.463314 -67.471075)
			(xy 350.666892 -67.497035) (xy 350.869303 -67.530918) (xy 351.070237 -67.572673) (xy 351.26939 -67.622236)
			(xy 351.466457 -67.679531) (xy 351.661139 -67.744471) (xy 351.853139 -67.816957) (xy 352.042164 -67.89688)
			(xy 352.227927 -67.984116) (xy 352.410145 -68.078534) (xy 352.588541 -68.179989) (xy 352.762842 -68.288328)
			(xy 352.932784 -68.403384) (xy 353.098107 -68.524984) (xy 353.25856 -68.652941) (xy 353.413899 -68.78706)
			(xy 353.563886 -68.927139) (xy 353.708294 -69.072963) (xy 353.846902 -69.224309) (xy 353.9795 -69.380949)
			(xy 354.105886 -69.542643) (xy 354.225866 -69.709145) (xy 354.339259 -69.880201) (xy 354.445892 -70.055551)
			(xy 354.545602 -70.234928) (xy 354.638238 -70.418058) (xy 354.723658 -70.604664) (xy 354.801732 -70.79446)
			(xy 354.872342 -70.987158) (xy 354.935379 -71.182464) (xy 354.990749 -71.38008) (xy 355.038366 -71.579707)
			(xy 355.078158 -71.781039) (xy 355.110065 -71.983771) (xy 355.134038 -72.187593) (xy 355.15004 -72.392196)
			(xy 355.158047 -72.597266) (xy 355.158548 -72.69988) (xy 355.158047 -72.802494) (xy 355.15004 -73.007564)
			(xy 355.134038 -73.212167) (xy 355.110065 -73.415989) (xy 355.078158 -73.618721) (xy 355.038366 -73.820053)
			(xy 354.990749 -74.01968) (xy 354.935379 -74.217296) (xy 354.872342 -74.412602) (xy 354.801732 -74.6053)
			(xy 354.723658 -74.795096) (xy 354.638238 -74.981702) (xy 354.545602 -75.164832) (xy 354.445892 -75.344209)
			(xy 354.339259 -75.519559) (xy 354.225866 -75.690615) (xy 354.105886 -75.857117) (xy 353.9795 -76.018811)
			(xy 353.846902 -76.175451) (xy 353.708294 -76.326797) (xy 353.563886 -76.472621) (xy 353.413899 -76.6127)
			(xy 353.25856 -76.746819) (xy 353.098107 -76.874776) (xy 352.932784 -76.996376) (xy 352.762842 -77.111432)
			(xy 352.588541 -77.219771) (xy 352.410145 -77.321226) (xy 352.227927 -77.415644) (xy 352.042164 -77.50288)
			(xy 351.853139 -77.582803) (xy 351.661139 -77.655289) (xy 351.466457 -77.720229) (xy 351.26939 -77.777524)
			(xy 351.070237 -77.827087) (xy 350.869303 -77.868842) (xy 350.666892 -77.902725) (xy 350.463314 -77.928685)
			(xy 350.258877 -77.946682) (xy 350.053894 -77.95669) (xy 349.848677 -77.958692) (xy 349.643538 -77.952686)
			(xy 349.438789 -77.938681) (xy 349.234742 -77.916698) (xy 349.031709 -77.886771) (xy 348.829998 -77.848944)
			(xy 348.629916 -77.803277) (xy 348.431769 -77.749838) (xy 348.235857 -77.688709) (xy 348.04248 -77.619983)
			(xy 347.851931 -77.543764) (xy 347.664501 -77.460168) (xy 347.480475 -77.369324) (xy 347.300134 -77.271369)
			(xy 347.123752 -77.166452) (xy 346.951598 -77.054733) (xy 346.783933 -76.936383) (xy 346.621014 -76.811581)
			(xy 346.463088 -76.680517) (xy 346.310396 -76.543392) (xy 346.163171 -76.400414) (xy 346.021636 -76.2518)
			(xy 345.886007 -76.097778) (xy 345.75649 -75.938581) (xy 345.633284 -75.774452) (xy 345.516575 -75.605641)
			(xy 345.406541 -75.432404) (xy 345.30335 -75.255007) (xy 345.207159 -75.073719) (xy 345.118114 -74.888816)
			(xy 345.036351 -74.700579) (xy 344.961995 -74.509296) (xy 344.895159 -74.315257) (xy 344.835944 -74.118758)
			(xy 344.784441 -73.920099) (xy 344.740727 -73.719581) (xy 344.704871 -73.51751) (xy 344.676926 -73.314195)
			(xy 344.656935 -73.109944) (xy 344.644928 -72.905068) (xy 344.640924 -72.69988) (xy 122.958859 -72.69988)
			(xy 122.95886 -72.700134) (xy 122.958359 -72.802748) (xy 122.950352 -73.007818) (xy 122.93435 -73.212421)
			(xy 122.910377 -73.416243) (xy 122.87847 -73.618975) (xy 122.838678 -73.820307) (xy 122.791061 -74.019934)
			(xy 122.735691 -74.21755) (xy 122.672654 -74.412856) (xy 122.602044 -74.605554) (xy 122.52397 -74.79535)
			(xy 122.43855 -74.981956) (xy 122.345914 -75.165086) (xy 122.277376 -75.288385) (xy 262.150829 -75.288385)
			(xy 262.150829 -75.228415) (xy 262.158657 -75.168959) (xy 262.174178 -75.111033) (xy 262.197128 -75.055628)
			(xy 262.227114 -75.003693) (xy 262.263621 -74.956116) (xy 262.306027 -74.913712) (xy 262.353605 -74.877206)
			(xy 262.405541 -74.847222) (xy 262.460946 -74.824274) (xy 262.518872 -74.808754) (xy 262.578329 -74.800928)
			(xy 262.608314 -74.80046) (xy 263.471914 -74.80046) (xy 263.501899 -74.800907) (xy 263.561356 -74.808736)
			(xy 263.619283 -74.824259) (xy 263.674687 -74.84721) (xy 263.726623 -74.877196) (xy 263.7742 -74.913705)
			(xy 263.816604 -74.956111) (xy 263.853111 -75.003689) (xy 263.883096 -75.055625) (xy 263.906045 -75.111031)
			(xy 263.921566 -75.168958) (xy 263.929394 -75.228415) (xy 263.929394 -75.288385) (xy 263.921566 -75.347842)
			(xy 263.906045 -75.405769) (xy 263.883096 -75.461175) (xy 263.853111 -75.513111) (xy 263.816604 -75.560689)
			(xy 263.7742 -75.603095) (xy 263.726623 -75.639604) (xy 263.674687 -75.66959) (xy 263.619283 -75.692541)
			(xy 263.561356 -75.708064) (xy 263.501899 -75.715893) (xy 263.471914 -75.716384) (xy 262.608314 -75.716384)
			(xy 262.578329 -75.715872) (xy 262.518872 -75.708046) (xy 262.460946 -75.692526) (xy 262.405541 -75.669578)
			(xy 262.353605 -75.639594) (xy 262.306027 -75.603088) (xy 262.263621 -75.560684) (xy 262.227114 -75.513107)
			(xy 262.197128 -75.461172) (xy 262.174178 -75.405767) (xy 262.158657 -75.347841) (xy 262.150829 -75.288385)
			(xy 122.277376 -75.288385) (xy 122.246204 -75.344463) (xy 122.139571 -75.519813) (xy 122.026178 -75.690869)
			(xy 121.906198 -75.857371) (xy 121.779812 -76.019065) (xy 121.647214 -76.175705) (xy 121.508606 -76.327051)
			(xy 121.364198 -76.472875) (xy 121.214211 -76.612954) (xy 121.058872 -76.747073) (xy 120.959794 -76.826085)
			(xy 229.640845 -76.826085) (xy 229.640845 -76.766115) (xy 229.648673 -76.706658) (xy 229.664196 -76.648731)
			(xy 229.687147 -76.593327) (xy 229.717134 -76.541392) (xy 229.753643 -76.493816) (xy 229.796051 -76.451413)
			(xy 229.84363 -76.414908) (xy 229.895568 -76.384926) (xy 229.950975 -76.361981) (xy 230.008903 -76.346464)
			(xy 230.068361 -76.338642) (xy 230.098346 -76.338176) (xy 230.961946 -76.338176) (xy 230.991931 -76.338593)
			(xy 231.051387 -76.346426) (xy 231.109312 -76.361952) (xy 231.164715 -76.384906) (xy 231.216648 -76.414894)
			(xy 231.264223 -76.451404) (xy 231.306626 -76.493811) (xy 231.343131 -76.54139) (xy 231.373114 -76.593326)
			(xy 231.396063 -76.648732) (xy 231.411583 -76.706658) (xy 231.41941 -76.766115) (xy 231.41941 -76.826085)
			(xy 231.411583 -76.885542) (xy 231.396063 -76.943468) (xy 231.373114 -76.998874) (xy 231.343131 -77.05081)
			(xy 231.306626 -77.098389) (xy 231.264223 -77.140796) (xy 231.216648 -77.177306) (xy 231.164715 -77.207294)
			(xy 231.109312 -77.230248) (xy 231.051387 -77.245774) (xy 230.991931 -77.253607) (xy 230.961946 -77.2541)
			(xy 230.098346 -77.2541) (xy 230.068361 -77.253558) (xy 230.008903 -77.245736) (xy 229.950975 -77.230219)
			(xy 229.895568 -77.207274) (xy 229.84363 -77.177292) (xy 229.796051 -77.140787) (xy 229.753643 -77.098384)
			(xy 229.717134 -77.050808) (xy 229.687147 -76.998873) (xy 229.664196 -76.943469) (xy 229.648673 -76.885542)
			(xy 229.640845 -76.826085) (xy 120.959794 -76.826085) (xy 120.898419 -76.87503) (xy 120.733096 -76.99663)
			(xy 120.563154 -77.111686) (xy 120.388853 -77.220025) (xy 120.210457 -77.32148) (xy 120.028239 -77.415898)
			(xy 119.842476 -77.503134) (xy 119.653451 -77.583057) (xy 119.461451 -77.655543) (xy 119.266769 -77.720483)
			(xy 119.069702 -77.777778) (xy 118.870549 -77.827341) (xy 118.669615 -77.869096) (xy 118.467204 -77.902979)
			(xy 118.263626 -77.928939) (xy 118.059189 -77.946936) (xy 117.854206 -77.956944) (xy 117.648989 -77.958946)
			(xy 117.44385 -77.95294) (xy 117.239101 -77.938935) (xy 117.035054 -77.916952) (xy 116.832021 -77.887025)
			(xy 116.63031 -77.849198) (xy 116.430228 -77.803531) (xy 116.232081 -77.750092) (xy 116.036169 -77.688963)
			(xy 115.842792 -77.620237) (xy 115.652243 -77.544018) (xy 115.464813 -77.460422) (xy 115.280787 -77.369578)
			(xy 115.100446 -77.271623) (xy 114.924064 -77.166706) (xy 114.75191 -77.054987) (xy 114.584245 -76.936637)
			(xy 114.421326 -76.811835) (xy 114.2634 -76.680771) (xy 114.110708 -76.543646) (xy 113.963483 -76.400668)
			(xy 113.821948 -76.252054) (xy 113.686319 -76.098032) (xy 113.556802 -75.938835) (xy 113.433596 -75.774706)
			(xy 113.316887 -75.605895) (xy 113.206853 -75.432658) (xy 113.103662 -75.255261) (xy 113.007471 -75.073973)
			(xy 112.918426 -74.88907) (xy 112.836663 -74.700833) (xy 112.762307 -74.50955) (xy 112.695471 -74.315511)
			(xy 112.636256 -74.119012) (xy 112.584753 -73.920353) (xy 112.541039 -73.719835) (xy 112.505183 -73.517764)
			(xy 112.477238 -73.314449) (xy 112.457247 -73.110198) (xy 112.44524 -72.905322) (xy 112.441236 -72.700134)
			(xy 1.524 -72.700134) (xy 1.524 -77.365367) (xy 105.150162 -77.365367) (xy 105.150162 -77.305433)
			(xy 105.157985 -77.246011) (xy 105.173496 -77.188119) (xy 105.19643 -77.132746) (xy 105.226396 -77.08084)
			(xy 105.26288 -77.03329) (xy 105.305258 -76.990908) (xy 105.352805 -76.954419) (xy 105.404708 -76.924449)
			(xy 105.460079 -76.901509) (xy 105.51797 -76.885993) (xy 105.577391 -76.878165) (xy 105.607358 -76.877672)
			(xy 106.470958 -76.877672) (xy 106.500928 -76.878178) (xy 106.560354 -76.885997) (xy 106.618252 -76.901506)
			(xy 106.67363 -76.92444) (xy 106.72554 -76.954406) (xy 106.773095 -76.990892) (xy 106.81548 -77.033273)
			(xy 106.851971 -77.080825) (xy 106.881942 -77.132732) (xy 106.904881 -77.188108) (xy 106.920395 -77.246004)
			(xy 106.928219 -77.305431) (xy 106.928219 -77.365367) (xy 109.150162 -77.365367) (xy 109.150162 -77.305433)
			(xy 109.157984 -77.246012) (xy 109.173495 -77.18812) (xy 109.196429 -77.132748) (xy 109.226394 -77.080843)
			(xy 109.262878 -77.033292) (xy 109.305255 -76.990911) (xy 109.352801 -76.954422) (xy 109.404703 -76.924452)
			(xy 109.460073 -76.901511) (xy 109.517963 -76.885994) (xy 109.577383 -76.878165) (xy 109.60735 -76.877672)
			(xy 110.47095 -76.877672) (xy 110.50092 -76.878178) (xy 110.560347 -76.885996) (xy 110.618246 -76.901504)
			(xy 110.673625 -76.924437) (xy 110.725536 -76.954403) (xy 110.773092 -76.990889) (xy 110.815478 -77.03327)
			(xy 110.851969 -77.080822) (xy 110.881941 -77.13273) (xy 110.90488 -77.188107) (xy 110.920395 -77.246003)
			(xy 110.928219 -77.30543) (xy 110.928219 -77.36537) (xy 110.920395 -77.424797) (xy 110.90488 -77.482693)
			(xy 110.881941 -77.53807) (xy 110.851969 -77.589978) (xy 110.815478 -77.63753) (xy 110.773092 -77.679911)
			(xy 110.725536 -77.716397) (xy 110.673625 -77.746363) (xy 110.618246 -77.769296) (xy 110.560347 -77.784804)
			(xy 110.50092 -77.792622) (xy 110.47095 -77.793088) (xy 109.60735 -77.793088) (xy 109.577383 -77.792635)
			(xy 109.517963 -77.784806) (xy 109.460073 -77.769289) (xy 109.404703 -77.746348) (xy 109.352801 -77.716378)
			(xy 109.305255 -77.679889) (xy 109.262878 -77.637508) (xy 109.226394 -77.589957) (xy 109.196429 -77.538052)
			(xy 109.173495 -77.48268) (xy 109.157984 -77.424788) (xy 109.150162 -77.365367) (xy 106.928219 -77.365367)
			(xy 106.928219 -77.365369) (xy 106.920395 -77.424796) (xy 106.904881 -77.482692) (xy 106.881942 -77.538068)
			(xy 106.851971 -77.589975) (xy 106.81548 -77.637527) (xy 106.773095 -77.679908) (xy 106.72554 -77.716394)
			(xy 106.67363 -77.74636) (xy 106.618252 -77.769294) (xy 106.560354 -77.784803) (xy 106.500928 -77.792622)
			(xy 106.470958 -77.793088) (xy 105.607358 -77.793088) (xy 105.577391 -77.792635) (xy 105.51797 -77.784807)
			(xy 105.460079 -77.769291) (xy 105.404708 -77.746351) (xy 105.352805 -77.716381) (xy 105.305258 -77.679892)
			(xy 105.26288 -77.63751) (xy 105.226396 -77.58996) (xy 105.19643 -77.538054) (xy 105.173496 -77.482681)
			(xy 105.157985 -77.424789) (xy 105.150162 -77.365367) (xy 1.524 -77.365367) (xy 1.524 -78.127367)
			(xy 107.150162 -78.127367) (xy 107.150162 -78.067433) (xy 107.157984 -78.008012) (xy 107.173496 -77.950119)
			(xy 107.19643 -77.894747) (xy 107.226395 -77.842842) (xy 107.262879 -77.795291) (xy 107.305256 -77.752909)
			(xy 107.352803 -77.716421) (xy 107.404706 -77.68645) (xy 107.460076 -77.66351) (xy 107.517966 -77.647993)
			(xy 107.577387 -77.640165) (xy 107.607354 -77.639672) (xy 108.470954 -77.639672) (xy 108.500924 -77.640178)
			(xy 108.560351 -77.647996) (xy 108.618249 -77.663505) (xy 108.673627 -77.686438) (xy 108.725538 -77.716405)
			(xy 108.773094 -77.752891) (xy 108.815479 -77.795272) (xy 108.85197 -77.842823) (xy 108.881941 -77.894731)
			(xy 108.90488 -77.950107) (xy 108.920395 -78.008004) (xy 108.928219 -78.06743) (xy 108.928219 -78.12737)
			(xy 108.920395 -78.186796) (xy 108.90488 -78.244693) (xy 108.881941 -78.300069) (xy 108.85197 -78.351977)
			(xy 108.815479 -78.399528) (xy 108.773093 -78.441909) (xy 108.725538 -78.478395) (xy 108.673627 -78.508362)
			(xy 108.618249 -78.531295) (xy 108.560351 -78.546804) (xy 108.500924 -78.554622) (xy 108.470954 -78.555088)
			(xy 107.607354 -78.555088) (xy 107.577387 -78.554635) (xy 107.517966 -78.546807) (xy 107.460076 -78.53129)
			(xy 107.404706 -78.50835) (xy 107.352803 -78.478379) (xy 107.305256 -78.441891) (xy 107.262879 -78.399509)
			(xy 107.226395 -78.351958) (xy 107.19643 -78.300053) (xy 107.173496 -78.244681) (xy 107.157984 -78.186788)
			(xy 107.150162 -78.127367) (xy 1.524 -78.127367) (xy 1.524 -79.238094) (xy 227.9777 -79.238094) (xy 227.9777 -78.374494)
			(xy 227.97819 -78.344526) (xy 227.986013 -78.285104) (xy 228.001526 -78.227211) (xy 228.024462 -78.171838)
			(xy 228.054429 -78.119932) (xy 228.090916 -78.072382) (xy 228.133296 -78.030002) (xy 228.180846 -77.993515)
			(xy 228.232752 -77.963548) (xy 228.288125 -77.940612) (xy 228.346018 -77.925099) (xy 228.40544 -77.917276)
			(xy 228.465376 -77.917276) (xy 228.524798 -77.925099) (xy 228.582691 -77.940612) (xy 228.638064 -77.963548)
			(xy 228.68997 -77.993515) (xy 228.73752 -78.030002) (xy 228.7799 -78.072382) (xy 228.816387 -78.119932)
			(xy 228.83413 -78.150664) (xy 336.40703 -78.150664) (xy 336.40703 -78.090736) (xy 336.414852 -78.031319)
			(xy 336.430363 -77.973433) (xy 336.453297 -77.918066) (xy 336.483261 -77.866166) (xy 336.519743 -77.818621)
			(xy 336.562119 -77.776245) (xy 336.609664 -77.739762) (xy 336.661564 -77.709797) (xy 336.716931 -77.686864)
			(xy 336.774817 -77.671353) (xy 336.834234 -77.66353) (xy 336.864198 -77.66304) (xy 337.727798 -77.66304)
			(xy 337.75777 -77.663413) (xy 337.817202 -77.671237) (xy 337.875104 -77.686751) (xy 337.930486 -77.709691)
			(xy 337.982399 -77.739663) (xy 338.029957 -77.776155) (xy 338.072344 -77.818542) (xy 338.108836 -77.866099)
			(xy 338.138808 -77.918013) (xy 338.161748 -77.973394) (xy 338.177263 -78.031296) (xy 338.185087 -78.090728)
			(xy 338.185087 -78.150672) (xy 338.177263 -78.210104) (xy 338.161748 -78.268006) (xy 338.138808 -78.323387)
			(xy 338.108836 -78.375301) (xy 338.072344 -78.422858) (xy 338.029957 -78.465245) (xy 337.982399 -78.501737)
			(xy 337.930486 -78.531709) (xy 337.875104 -78.554649) (xy 337.817202 -78.570163) (xy 337.75777 -78.577987)
			(xy 337.727798 -78.578456) (xy 336.864198 -78.578456) (xy 336.834234 -78.57787) (xy 336.774817 -78.570047)
			(xy 336.716931 -78.554536) (xy 336.661564 -78.531603) (xy 336.609664 -78.501638) (xy 336.562119 -78.465155)
			(xy 336.519743 -78.422779) (xy 336.483261 -78.375234) (xy 336.453297 -78.323334) (xy 336.430363 -78.267967)
			(xy 336.414852 -78.210081) (xy 336.40703 -78.150664) (xy 228.83413 -78.150664) (xy 228.846354 -78.171838)
			(xy 228.86929 -78.227211) (xy 228.884803 -78.285104) (xy 228.892626 -78.344526) (xy 228.893116 -78.374494)
			(xy 228.893116 -79.238094) (xy 228.892626 -79.268062) (xy 228.884803 -79.327484) (xy 228.86929 -79.385377)
			(xy 228.846354 -79.44075) (xy 228.816387 -79.492656) (xy 228.7799 -79.540206) (xy 228.73752 -79.582586)
			(xy 228.68997 -79.619073) (xy 228.638064 -79.64904) (xy 228.582691 -79.671976) (xy 228.524798 -79.687489)
			(xy 228.465376 -79.695312) (xy 228.40544 -79.695312) (xy 228.346018 -79.687489) (xy 228.288125 -79.671976)
			(xy 228.232752 -79.64904) (xy 228.180846 -79.619073) (xy 228.133296 -79.582586) (xy 228.090916 -79.540206)
			(xy 228.054429 -79.492656) (xy 228.024462 -79.44075) (xy 228.001526 -79.385377) (xy 227.986013 -79.327484)
			(xy 227.97819 -79.268062) (xy 227.9777 -79.238094) (xy 1.524 -79.238094) (xy 1.524 -82.131662) (xy 1.524528 -82.162804)
			(xy 1.532692 -82.224552) (xy 1.54884 -82.284707) (xy 1.572698 -82.342242) (xy 1.603856 -82.396173)
			(xy 1.641783 -82.445579) (xy 1.663446 -82.467958) (xy 1.678178 -82.482944) (xy 1.678686 -82.483452)
			(xy 3.894875 -84.699856) (xy 13.541002 -84.699856) (xy 13.545006 -84.494668) (xy 13.557013 -84.289792)
			(xy 13.577004 -84.085541) (xy 13.604949 -83.882226) (xy 13.640805 -83.680155) (xy 13.684519 -83.479637)
			(xy 13.736022 -83.280978) (xy 13.795237 -83.084479) (xy 13.862073 -82.89044) (xy 13.936429 -82.699157)
			(xy 14.018192 -82.51092) (xy 14.107237 -82.326017) (xy 14.203428 -82.144729) (xy 14.306619 -81.967332)
			(xy 14.416653 -81.794095) (xy 14.533362 -81.625284) (xy 14.656568 -81.461155) (xy 14.786085 -81.301958)
			(xy 14.921714 -81.147936) (xy 15.063249 -80.999322) (xy 15.210474 -80.856344) (xy 15.363166 -80.719219)
			(xy 15.521092 -80.588155) (xy 15.684011 -80.463353) (xy 15.851676 -80.345003) (xy 16.02383 -80.233284)
			(xy 16.200212 -80.128367) (xy 16.380553 -80.030412) (xy 16.564579 -79.939568) (xy 16.752009 -79.855972)
			(xy 16.942558 -79.779753) (xy 17.135935 -79.711027) (xy 17.331847 -79.649898) (xy 17.529994 -79.596459)
			(xy 17.730076 -79.550792) (xy 17.931787 -79.512965) (xy 18.13482 -79.483038) (xy 18.338867 -79.461055)
			(xy 18.543616 -79.44705) (xy 18.748755 -79.441044) (xy 18.953972 -79.443046) (xy 19.158955 -79.453054)
			(xy 19.363392 -79.471051) (xy 19.56697 -79.497011) (xy 19.769381 -79.530894) (xy 19.970315 -79.572649)
			(xy 20.169468 -79.622212) (xy 20.366535 -79.679507) (xy 20.561217 -79.744447) (xy 20.753217 -79.816933)
			(xy 20.942242 -79.896856) (xy 21.128005 -79.984092) (xy 21.310223 -80.07851) (xy 21.488619 -80.179965)
			(xy 21.494277 -80.183482) (xy 237.540292 -80.183482) (xy 237.540292 -79.319882) (xy 237.540782 -79.289914)
			(xy 237.548605 -79.230492) (xy 237.564118 -79.172599) (xy 237.587054 -79.117226) (xy 237.617021 -79.06532)
			(xy 237.653508 -79.01777) (xy 237.695888 -78.97539) (xy 237.743438 -78.938903) (xy 237.795344 -78.908936)
			(xy 237.850717 -78.886) (xy 237.90861 -78.870487) (xy 237.968032 -78.862664) (xy 238.027968 -78.862664)
			(xy 238.08739 -78.870487) (xy 238.145283 -78.886) (xy 238.200656 -78.908936) (xy 238.207117 -78.912666)
			(xy 334.407009 -78.912666) (xy 334.407009 -78.852734) (xy 334.414832 -78.793315) (xy 334.430343 -78.735425)
			(xy 334.453278 -78.680055) (xy 334.483244 -78.628153) (xy 334.519729 -78.580606) (xy 334.562107 -78.538227)
			(xy 334.609654 -78.501743) (xy 334.661557 -78.471777) (xy 334.716927 -78.448843) (xy 334.774817 -78.433331)
			(xy 334.834236 -78.425509) (xy 334.864202 -78.42504) (xy 335.727802 -78.42504) (xy 335.757773 -78.425434)
			(xy 335.817201 -78.433258) (xy 335.8751 -78.448773) (xy 335.930479 -78.471711) (xy 335.982389 -78.501682)
			(xy 336.029944 -78.538172) (xy 336.072329 -78.580557) (xy 336.108819 -78.628112) (xy 336.13879 -78.680023)
			(xy 336.161728 -78.735402) (xy 336.177242 -78.793301) (xy 336.185066 -78.852729) (xy 336.185066 -78.912664)
			(xy 338.40703 -78.912664) (xy 338.40703 -78.852736) (xy 338.414852 -78.79332) (xy 338.430363 -78.735433)
			(xy 338.453296 -78.680067) (xy 338.48326 -78.628167) (xy 338.519742 -78.580622) (xy 338.562118 -78.538246)
			(xy 338.609662 -78.501763) (xy 338.661561 -78.471799) (xy 338.716928 -78.448865) (xy 338.774814 -78.433353)
			(xy 338.83423 -78.42553) (xy 338.864194 -78.42504) (xy 339.727794 -78.42504) (xy 339.757766 -78.425412)
			(xy 339.817199 -78.433236) (xy 339.875101 -78.44875) (xy 339.930483 -78.47169) (xy 339.982397 -78.501662)
			(xy 340.029955 -78.538153) (xy 340.072343 -78.580541) (xy 340.108835 -78.628098) (xy 340.138808 -78.680011)
			(xy 340.161748 -78.735393) (xy 340.177263 -78.793296) (xy 340.185087 -78.852728) (xy 340.185087 -78.912672)
			(xy 340.177263 -78.972104) (xy 340.161748 -79.030007) (xy 340.138808 -79.085389) (xy 340.108835 -79.137302)
			(xy 340.072343 -79.184859) (xy 340.029955 -79.227247) (xy 339.982397 -79.263738) (xy 339.930483 -79.29371)
			(xy 339.875101 -79.31665) (xy 339.817199 -79.332164) (xy 339.757766 -79.339988) (xy 339.727794 -79.340456)
			(xy 338.864194 -79.340456) (xy 338.83423 -79.33987) (xy 338.774814 -79.332047) (xy 338.716928 -79.316535)
			(xy 338.661561 -79.293601) (xy 338.609662 -79.263637) (xy 338.562118 -79.227154) (xy 338.519742 -79.184778)
			(xy 338.48326 -79.137233) (xy 338.453296 -79.085333) (xy 338.430363 -79.029967) (xy 338.414852 -78.97208)
			(xy 338.40703 -78.912664) (xy 336.185066 -78.912664) (xy 336.185066 -78.912671) (xy 336.177242 -78.972099)
			(xy 336.161728 -79.029998) (xy 336.13879 -79.085377) (xy 336.108819 -79.137288) (xy 336.072329 -79.184843)
			(xy 336.029944 -79.227228) (xy 335.982389 -79.263718) (xy 335.930479 -79.293689) (xy 335.8751 -79.316627)
			(xy 335.817201 -79.332142) (xy 335.757773 -79.339966) (xy 335.727802 -79.340456) (xy 334.864202 -79.340456)
			(xy 334.834236 -79.339891) (xy 334.774817 -79.332069) (xy 334.716927 -79.316557) (xy 334.661557 -79.293623)
			(xy 334.609654 -79.263657) (xy 334.562107 -79.227173) (xy 334.519729 -79.184794) (xy 334.483244 -79.137247)
			(xy 334.453278 -79.085345) (xy 334.430343 -79.029975) (xy 334.414832 -78.972085) (xy 334.407009 -78.912666)
			(xy 238.207117 -78.912666) (xy 238.252562 -78.938903) (xy 238.300112 -78.97539) (xy 238.342492 -79.01777)
			(xy 238.378979 -79.06532) (xy 238.408946 -79.117226) (xy 238.431882 -79.172599) (xy 238.447395 -79.230492)
			(xy 238.455218 -79.289914) (xy 238.455708 -79.319882) (xy 238.455708 -80.183482) (xy 238.455218 -80.21345)
			(xy 238.447395 -80.272872) (xy 238.431882 -80.330765) (xy 238.408946 -80.386138) (xy 238.378979 -80.438044)
			(xy 238.342492 -80.485594) (xy 238.300112 -80.527974) (xy 238.252562 -80.564461) (xy 238.200656 -80.594428)
			(xy 238.145283 -80.617364) (xy 238.08739 -80.632877) (xy 238.027968 -80.6407) (xy 237.968032 -80.6407)
			(xy 237.90861 -80.632877) (xy 237.850717 -80.617364) (xy 237.795344 -80.594428) (xy 237.743438 -80.564461)
			(xy 237.695888 -80.527974) (xy 237.653508 -80.485594) (xy 237.617021 -80.438044) (xy 237.587054 -80.386138)
			(xy 237.564118 -80.330765) (xy 237.548605 -80.272872) (xy 237.540782 -80.21345) (xy 237.540292 -80.183482)
			(xy 21.494277 -80.183482) (xy 21.66292 -80.288304) (xy 21.832862 -80.40336) (xy 21.998185 -80.52496)
			(xy 22.158638 -80.652917) (xy 22.313977 -80.787036) (xy 22.463964 -80.927115) (xy 22.608372 -81.072939)
			(xy 22.74698 -81.224285) (xy 22.879578 -81.380925) (xy 23.005964 -81.542619) (xy 23.125944 -81.709121)
			(xy 23.239337 -81.880177) (xy 23.34597 -82.055527) (xy 23.44568 -82.234904) (xy 23.538316 -82.418034)
			(xy 23.623736 -82.60464) (xy 23.70181 -82.794436) (xy 23.77242 -82.987134) (xy 23.835457 -83.18244)
			(xy 23.890827 -83.380056) (xy 23.938444 -83.579683) (xy 23.978236 -83.781015) (xy 24.010143 -83.983747)
			(xy 24.034116 -84.187569) (xy 24.050118 -84.392172) (xy 24.058125 -84.597242) (xy 24.058626 -84.699856)
			(xy 24.058125 -84.80247) (xy 24.050118 -85.00754) (xy 24.04871 -85.025538) (xy 44.856389 -85.025538)
			(xy 44.856389 -84.896398) (xy 44.864339 -84.767503) (xy 44.880209 -84.639343) (xy 44.903938 -84.512402)
			(xy 44.935437 -84.387163) (xy 44.974586 -84.2641) (xy 45.021237 -84.143681) (xy 45.075212 -84.026362)
			(xy 45.136307 -83.912588) (xy 45.20429 -83.802791) (xy 45.278904 -83.697388) (xy 45.359865 -83.596778)
			(xy 45.446865 -83.501343) (xy 45.539576 -83.411444) (xy 45.637646 -83.327423) (xy 45.740701 -83.249599)
			(xy 45.848352 -83.178267) (xy 45.960191 -83.113697) (xy 46.075792 -83.056135) (xy 46.194717 -83.005798)
			(xy 46.316516 -82.962878) (xy 46.440726 -82.927537) (xy 46.566875 -82.89991) (xy 46.694487 -82.880101)
			(xy 46.823076 -82.868185) (xy 46.952154 -82.864209) (xy 47.081232 -82.868185) (xy 47.209821 -82.880101)
			(xy 47.337433 -82.89991) (xy 47.463582 -82.927537) (xy 47.587792 -82.962878) (xy 47.709591 -83.005798)
			(xy 47.828516 -83.056135) (xy 47.944117 -83.113697) (xy 48.055956 -83.178267) (xy 48.163607 -83.249599)
			(xy 48.266662 -83.327423) (xy 48.303507 -83.35899) (xy 116.623592 -83.35899) (xy 116.623592 -82.49539)
			(xy 116.624082 -82.465422) (xy 116.631905 -82.406) (xy 116.647418 -82.348107) (xy 116.670354 -82.292734)
			(xy 116.700321 -82.240828) (xy 116.736808 -82.193278) (xy 116.779188 -82.150898) (xy 116.826738 -82.114411)
			(xy 116.878644 -82.084444) (xy 116.934017 -82.061508) (xy 116.99191 -82.045995) (xy 117.051332 -82.038172)
			(xy 117.111268 -82.038172) (xy 117.17069 -82.045995) (xy 117.228583 -82.061508) (xy 117.283956 -82.084444)
			(xy 117.335862 -82.114411) (xy 117.383412 -82.150898) (xy 117.425792 -82.193278) (xy 117.462279 -82.240828)
			(xy 117.492246 -82.292734) (xy 117.515182 -82.348107) (xy 117.530695 -82.406) (xy 117.538518 -82.465422)
			(xy 117.539008 -82.49539) (xy 117.539008 -83.35899) (xy 117.538875 -83.367118) (xy 232.68432 -83.367118)
			(xy 232.68432 -82.503518) (xy 232.68481 -82.47355) (xy 232.692633 -82.414128) (xy 232.708146 -82.356235)
			(xy 232.731082 -82.300862) (xy 232.761049 -82.248956) (xy 232.797536 -82.201406) (xy 232.839916 -82.159026)
			(xy 232.887466 -82.122539) (xy 232.939372 -82.092572) (xy 232.994745 -82.069636) (xy 233.052638 -82.054123)
			(xy 233.11206 -82.0463) (xy 233.171996 -82.0463) (xy 233.231418 -82.054123) (xy 233.289311 -82.069636)
			(xy 233.344684 -82.092572) (xy 233.39659 -82.122539) (xy 233.44414 -82.159026) (xy 233.48652 -82.201406)
			(xy 233.523007 -82.248956) (xy 233.552974 -82.300862) (xy 233.568014 -82.337171) (xy 238.132537 -82.337171)
			(xy 238.132537 -82.277229) (xy 238.140362 -82.217799) (xy 238.155876 -82.159898) (xy 238.178816 -82.104519)
			(xy 238.208788 -82.052607) (xy 238.24528 -82.005052) (xy 238.287667 -81.962667) (xy 238.335224 -81.926177)
			(xy 238.387137 -81.896207) (xy 238.442517 -81.87327) (xy 238.500418 -81.857758) (xy 238.559849 -81.849936)
			(xy 238.58982 -81.849468) (xy 239.45342 -81.849468) (xy 239.483385 -81.850007) (xy 239.542803 -81.857832)
			(xy 239.600691 -81.873345) (xy 239.656058 -81.896282) (xy 239.707959 -81.926248) (xy 239.755504 -81.962733)
			(xy 239.769238 -81.976468) (xy 273.798284 -81.976468) (xy 273.798284 -81.112868) (xy 273.798774 -81.0829)
			(xy 273.806597 -81.023478) (xy 273.82211 -80.965585) (xy 273.845046 -80.910212) (xy 273.875013 -80.858306)
			(xy 273.9115 -80.810756) (xy 273.95388 -80.768376) (xy 274.00143 -80.731889) (xy 274.053336 -80.701922)
			(xy 274.108709 -80.678986) (xy 274.166602 -80.663473) (xy 274.226024 -80.65565) (xy 274.28596 -80.65565)
			(xy 274.345382 -80.663473) (xy 274.403275 -80.678986) (xy 274.458648 -80.701922) (xy 274.510554 -80.731889)
			(xy 274.558104 -80.768376) (xy 274.600484 -80.810756) (xy 274.636971 -80.858306) (xy 274.666938 -80.910212)
			(xy 274.689874 -80.965585) (xy 274.705387 -81.023478) (xy 274.71321 -81.0829) (xy 274.7137 -81.112868)
			(xy 274.7137 -81.976468) (xy 274.71321 -82.006436) (xy 274.705387 -82.065858) (xy 274.689874 -82.123751)
			(xy 274.666938 -82.179124) (xy 274.636971 -82.23103) (xy 274.600484 -82.27858) (xy 274.558104 -82.32096)
			(xy 274.510554 -82.357447) (xy 274.458648 -82.387414) (xy 274.403275 -82.41035) (xy 274.345382 -82.425863)
			(xy 274.28596 -82.433686) (xy 274.226024 -82.433686) (xy 274.166602 -82.425863) (xy 274.108709 -82.41035)
			(xy 274.053336 -82.387414) (xy 274.00143 -82.357447) (xy 273.95388 -82.32096) (xy 273.9115 -82.27858)
			(xy 273.875013 -82.23103) (xy 273.845046 -82.179124) (xy 273.82211 -82.123751) (xy 273.806597 -82.065858)
			(xy 273.798774 -82.006436) (xy 273.798284 -81.976468) (xy 239.769238 -81.976468) (xy 239.79788 -82.005111)
			(xy 239.834363 -82.052658) (xy 239.864327 -82.10456) (xy 239.887261 -82.159928) (xy 239.902772 -82.217817)
			(xy 239.910594 -82.277235) (xy 239.910594 -82.337165) (xy 239.902772 -82.396583) (xy 239.887261 -82.454472)
			(xy 239.864327 -82.50984) (xy 239.834363 -82.561742) (xy 239.79788 -82.609289) (xy 239.755504 -82.651667)
			(xy 239.707959 -82.688152) (xy 239.656058 -82.718118) (xy 239.600691 -82.741055) (xy 239.542803 -82.756568)
			(xy 239.483385 -82.764393) (xy 239.45342 -82.764884) (xy 238.58982 -82.764884) (xy 238.559849 -82.764464)
			(xy 238.500418 -82.756642) (xy 238.442517 -82.74113) (xy 238.387137 -82.718193) (xy 238.335224 -82.688223)
			(xy 238.287667 -82.651733) (xy 238.24528 -82.609348) (xy 238.208788 -82.561793) (xy 238.178816 -82.509881)
			(xy 238.155876 -82.454502) (xy 238.140362 -82.396601) (xy 238.132537 -82.337171) (xy 233.568014 -82.337171)
			(xy 233.57591 -82.356235) (xy 233.591423 -82.414128) (xy 233.599246 -82.47355) (xy 233.599736 -82.503518)
			(xy 233.599736 -83.367118) (xy 233.599246 -83.397086) (xy 233.591423 -83.456508) (xy 233.57591 -83.514401)
			(xy 233.552974 -83.569774) (xy 233.523007 -83.62168) (xy 233.48652 -83.66923) (xy 233.44414 -83.71161)
			(xy 233.39659 -83.748097) (xy 233.344684 -83.778064) (xy 233.289311 -83.801) (xy 233.231418 -83.816513)
			(xy 233.171996 -83.824336) (xy 233.11206 -83.824336) (xy 233.052638 -83.816513) (xy 232.994745 -83.801)
			(xy 232.939372 -83.778064) (xy 232.887466 -83.748097) (xy 232.839916 -83.71161) (xy 232.797536 -83.66923)
			(xy 232.761049 -83.62168) (xy 232.731082 -83.569774) (xy 232.708146 -83.514401) (xy 232.692633 -83.456508)
			(xy 232.68481 -83.397086) (xy 232.68432 -83.367118) (xy 117.538875 -83.367118) (xy 117.538518 -83.388958)
			(xy 117.530695 -83.44838) (xy 117.515182 -83.506273) (xy 117.492246 -83.561646) (xy 117.462279 -83.613552)
			(xy 117.425792 -83.661102) (xy 117.383412 -83.703482) (xy 117.335862 -83.739969) (xy 117.283956 -83.769936)
			(xy 117.228583 -83.792872) (xy 117.17069 -83.808385) (xy 117.111268 -83.816208) (xy 117.051332 -83.816208)
			(xy 116.99191 -83.808385) (xy 116.934017 -83.792872) (xy 116.878644 -83.769936) (xy 116.826738 -83.739969)
			(xy 116.779188 -83.703482) (xy 116.736808 -83.661102) (xy 116.700321 -83.613552) (xy 116.670354 -83.561646)
			(xy 116.647418 -83.506273) (xy 116.631905 -83.44838) (xy 116.624082 -83.388958) (xy 116.623592 -83.35899)
			(xy 48.303507 -83.35899) (xy 48.364732 -83.411444) (xy 48.457443 -83.501343) (xy 48.544443 -83.596778)
			(xy 48.625404 -83.697388) (xy 48.700018 -83.802791) (xy 48.768001 -83.912588) (xy 48.829096 -84.026362)
			(xy 48.883071 -84.143681) (xy 48.929722 -84.2641) (xy 48.968871 -84.387163) (xy 49.00037 -84.512402)
			(xy 49.024099 -84.639343) (xy 49.039969 -84.767503) (xy 49.047919 -84.896398) (xy 49.048416 -84.960968)
			(xy 49.047919 -85.025538) (xy 49.039969 -85.154433) (xy 49.024099 -85.282593) (xy 49.009819 -85.358986)
			(xy 117.385592 -85.358986) (xy 117.385592 -84.495386) (xy 117.386082 -84.465418) (xy 117.393905 -84.405996)
			(xy 117.409418 -84.348103) (xy 117.432354 -84.29273) (xy 117.462321 -84.240824) (xy 117.498808 -84.193274)
			(xy 117.541188 -84.150894) (xy 117.588738 -84.114407) (xy 117.640644 -84.08444) (xy 117.696017 -84.061504)
			(xy 117.75391 -84.045991) (xy 117.813332 -84.038168) (xy 117.873268 -84.038168) (xy 117.93269 -84.045991)
			(xy 117.990583 -84.061504) (xy 118.045956 -84.08444) (xy 118.097862 -84.114407) (xy 118.145412 -84.150894)
			(xy 118.187792 -84.193274) (xy 118.224279 -84.240824) (xy 118.254246 -84.29273) (xy 118.277182 -84.348103)
			(xy 118.292695 -84.405996) (xy 118.300518 -84.465418) (xy 118.301008 -84.495386) (xy 118.301008 -85.358986)
			(xy 118.300518 -85.388954) (xy 118.292695 -85.448376) (xy 118.289959 -85.458587) (xy 232.264389 -85.458587)
			(xy 232.264389 -85.398613) (xy 232.272218 -85.339151) (xy 232.28774 -85.28122) (xy 232.310692 -85.225811)
			(xy 232.34068 -85.173871) (xy 232.377191 -85.126291) (xy 232.4196 -85.083883) (xy 232.467181 -85.047373)
			(xy 232.519122 -85.017387) (xy 232.574531 -84.994437) (xy 232.632463 -84.978915) (xy 232.691925 -84.971088)
			(xy 232.721912 -84.97062) (xy 233.585512 -84.97062) (xy 233.615495 -84.971147) (xy 233.674947 -84.978975)
			(xy 233.732868 -84.994497) (xy 233.788268 -85.017445) (xy 233.840199 -85.047429) (xy 233.887772 -85.083934)
			(xy 233.930174 -85.126337) (xy 233.963295 -85.169502) (xy 238.555276 -85.169502) (xy 238.555276 -84.305902)
			(xy 238.555766 -84.275918) (xy 238.563594 -84.216462) (xy 238.579115 -84.158537) (xy 238.602064 -84.103133)
			(xy 238.632048 -84.051199) (xy 238.668554 -84.003623) (xy 238.710959 -83.961218) (xy 238.758535 -83.924712)
			(xy 238.810469 -83.894728) (xy 238.865873 -83.871779) (xy 238.923798 -83.856258) (xy 238.983254 -83.84843)
			(xy 239.043222 -83.84843) (xy 239.102678 -83.856258) (xy 239.160603 -83.871779) (xy 239.216007 -83.894728)
			(xy 239.267941 -83.924712) (xy 239.315517 -83.961218) (xy 239.357922 -84.003623) (xy 239.394428 -84.051199)
			(xy 239.424412 -84.103133) (xy 239.447361 -84.158537) (xy 239.462882 -84.216462) (xy 239.46603 -84.24037)
			(xy 273.951192 -84.24037) (xy 273.951192 -83.37677) (xy 273.951682 -83.346786) (xy 273.95951 -83.28733)
			(xy 273.975031 -83.229405) (xy 273.99798 -83.174001) (xy 274.027964 -83.122067) (xy 274.06447 -83.074491)
			(xy 274.106875 -83.032086) (xy 274.154451 -82.99558) (xy 274.206385 -82.965596) (xy 274.261789 -82.942647)
			(xy 274.319714 -82.927126) (xy 274.37917 -82.919298) (xy 274.439138 -82.919298) (xy 274.498594 -82.927126)
			(xy 274.556519 -82.942647) (xy 274.611923 -82.965596) (xy 274.663857 -82.99558) (xy 274.711433 -83.032086)
			(xy 274.753838 -83.074491) (xy 274.790344 -83.122067) (xy 274.820328 -83.174001) (xy 274.843277 -83.229405)
			(xy 274.858798 -83.28733) (xy 274.866626 -83.346786) (xy 274.867116 -83.37677) (xy 274.867116 -84.144612)
			(xy 345.879928 -84.144612) (xy 345.879928 -83.281012) (xy 345.880418 -83.251028) (xy 345.888246 -83.191572)
			(xy 345.903767 -83.133647) (xy 345.926716 -83.078243) (xy 345.9567 -83.026309) (xy 345.993206 -82.978733)
			(xy 346.035611 -82.936328) (xy 346.083187 -82.899822) (xy 346.135121 -82.869838) (xy 346.190525 -82.846889)
			(xy 346.24845 -82.831368) (xy 346.307906 -82.82354) (xy 346.367874 -82.82354) (xy 346.42733 -82.831368)
			(xy 346.485255 -82.846889) (xy 346.540659 -82.869838) (xy 346.592593 -82.899822) (xy 346.640169 -82.936328)
			(xy 346.682574 -82.978733) (xy 346.71908 -83.026309) (xy 346.749064 -83.078243) (xy 346.772013 -83.133647)
			(xy 346.787534 -83.191572) (xy 346.795362 -83.251028) (xy 346.795852 -83.281012) (xy 346.795852 -84.144612)
			(xy 346.795362 -84.174596) (xy 346.787534 -84.234052) (xy 346.772013 -84.291977) (xy 346.749064 -84.347381)
			(xy 346.71908 -84.399315) (xy 346.682574 -84.446891) (xy 346.640169 -84.489296) (xy 346.592593 -84.525802)
			(xy 346.540659 -84.555786) (xy 346.485255 -84.578735) (xy 346.42733 -84.594256) (xy 346.367874 -84.602084)
			(xy 346.307906 -84.602084) (xy 346.24845 -84.594256) (xy 346.190525 -84.578735) (xy 346.135121 -84.555786)
			(xy 346.083187 -84.525802) (xy 346.035611 -84.489296) (xy 345.993206 -84.446891) (xy 345.9567 -84.399315)
			(xy 345.926716 -84.347381) (xy 345.903767 -84.291977) (xy 345.888246 -84.234052) (xy 345.880418 -84.174596)
			(xy 345.879928 -84.144612) (xy 274.867116 -84.144612) (xy 274.867116 -84.24037) (xy 274.866626 -84.270354)
			(xy 274.858798 -84.32981) (xy 274.843277 -84.387735) (xy 274.820328 -84.443139) (xy 274.790344 -84.495073)
			(xy 274.753838 -84.542649) (xy 274.711433 -84.585054) (xy 274.663857 -84.62156) (xy 274.611923 -84.651544)
			(xy 274.556519 -84.674493) (xy 274.498594 -84.690014) (xy 274.439138 -84.697842) (xy 274.37917 -84.697842)
			(xy 274.319714 -84.690014) (xy 274.261789 -84.674493) (xy 274.206385 -84.651544) (xy 274.154451 -84.62156)
			(xy 274.106875 -84.585054) (xy 274.06447 -84.542649) (xy 274.027964 -84.495073) (xy 273.99798 -84.443139)
			(xy 273.975031 -84.387735) (xy 273.95951 -84.32981) (xy 273.951682 -84.270354) (xy 273.951192 -84.24037)
			(xy 239.46603 -84.24037) (xy 239.47071 -84.275918) (xy 239.4712 -84.305902) (xy 239.4712 -84.699856)
			(xy 443.540904 -84.699856) (xy 443.544908 -84.494668) (xy 443.556915 -84.289792) (xy 443.576906 -84.085541)
			(xy 443.604851 -83.882226) (xy 443.640707 -83.680155) (xy 443.684421 -83.479637) (xy 443.735924 -83.280978)
			(xy 443.795139 -83.084479) (xy 443.861975 -82.89044) (xy 443.936331 -82.699157) (xy 444.018094 -82.51092)
			(xy 444.107139 -82.326017) (xy 444.20333 -82.144729) (xy 444.306521 -81.967332) (xy 444.416555 -81.794095)
			(xy 444.533264 -81.625284) (xy 444.65647 -81.461155) (xy 444.785987 -81.301958) (xy 444.921616 -81.147936)
			(xy 445.063151 -80.999322) (xy 445.210376 -80.856344) (xy 445.363068 -80.719219) (xy 445.520994 -80.588155)
			(xy 445.683913 -80.463353) (xy 445.851578 -80.345003) (xy 446.023732 -80.233284) (xy 446.200114 -80.128367)
			(xy 446.380455 -80.030412) (xy 446.564481 -79.939568) (xy 446.751911 -79.855972) (xy 446.94246 -79.779753)
			(xy 447.135837 -79.711027) (xy 447.331749 -79.649898) (xy 447.529896 -79.596459) (xy 447.729978 -79.550792)
			(xy 447.931689 -79.512965) (xy 448.134722 -79.483038) (xy 448.338769 -79.461055) (xy 448.543518 -79.44705)
			(xy 448.748657 -79.441044) (xy 448.953874 -79.443046) (xy 449.158857 -79.453054) (xy 449.363294 -79.471051)
			(xy 449.566872 -79.497011) (xy 449.769283 -79.530894) (xy 449.970217 -79.572649) (xy 450.16937 -79.622212)
			(xy 450.366437 -79.679507) (xy 450.561119 -79.744447) (xy 450.753119 -79.816933) (xy 450.942144 -79.896856)
			(xy 451.127907 -79.984092) (xy 451.310125 -80.07851) (xy 451.488521 -80.179965) (xy 451.662822 -80.288304)
			(xy 451.832764 -80.40336) (xy 451.998087 -80.52496) (xy 452.15854 -80.652917) (xy 452.313879 -80.787036)
			(xy 452.463866 -80.927115) (xy 452.608274 -81.072939) (xy 452.746882 -81.224285) (xy 452.87948 -81.380925)
			(xy 453.005866 -81.542619) (xy 453.125846 -81.709121) (xy 453.239239 -81.880177) (xy 453.345872 -82.055527)
			(xy 453.445582 -82.234904) (xy 453.538218 -82.418034) (xy 453.623638 -82.60464) (xy 453.701712 -82.794436)
			(xy 453.772322 -82.987134) (xy 453.835359 -83.18244) (xy 453.890729 -83.380056) (xy 453.938346 -83.579683)
			(xy 453.978138 -83.781015) (xy 454.010045 -83.983747) (xy 454.034018 -84.187569) (xy 454.05002 -84.392172)
			(xy 454.058027 -84.597242) (xy 454.058528 -84.699856) (xy 454.058027 -84.80247) (xy 454.05002 -85.00754)
			(xy 454.034018 -85.212143) (xy 454.010045 -85.415965) (xy 453.978138 -85.618697) (xy 453.938346 -85.820029)
			(xy 453.890729 -86.019656) (xy 453.835359 -86.217272) (xy 453.772322 -86.412578) (xy 453.701712 -86.605276)
			(xy 453.623638 -86.795072) (xy 453.538218 -86.981678) (xy 453.445582 -87.164808) (xy 453.345872 -87.344185)
			(xy 453.239239 -87.519535) (xy 453.125846 -87.690591) (xy 453.005866 -87.857093) (xy 452.87948 -88.018787)
			(xy 452.746882 -88.175427) (xy 452.608274 -88.326773) (xy 452.463866 -88.472597) (xy 452.313879 -88.612676)
			(xy 452.15854 -88.746795) (xy 451.998087 -88.874752) (xy 451.832764 -88.996352) (xy 451.662822 -89.111408)
			(xy 451.488521 -89.219747) (xy 451.310125 -89.321202) (xy 451.127907 -89.41562) (xy 450.942144 -89.502856)
			(xy 450.753119 -89.582779) (xy 450.561119 -89.655265) (xy 450.366437 -89.720205) (xy 450.16937 -89.7775)
			(xy 449.970217 -89.827063) (xy 449.769283 -89.868818) (xy 449.566872 -89.902701) (xy 449.363294 -89.928661)
			(xy 449.158857 -89.946658) (xy 448.953874 -89.956666) (xy 448.748657 -89.958668) (xy 448.543518 -89.952662)
			(xy 448.338769 -89.938657) (xy 448.134722 -89.916674) (xy 447.931689 -89.886747) (xy 447.729978 -89.84892)
			(xy 447.529896 -89.803253) (xy 447.331749 -89.749814) (xy 447.135837 -89.688685) (xy 446.94246 -89.619959)
			(xy 446.751911 -89.54374) (xy 446.564481 -89.460144) (xy 446.380455 -89.3693) (xy 446.200114 -89.271345)
			(xy 446.023732 -89.166428) (xy 445.851578 -89.054709) (xy 445.683913 -88.936359) (xy 445.520994 -88.811557)
			(xy 445.363068 -88.680493) (xy 445.210376 -88.543368) (xy 445.063151 -88.40039) (xy 444.921616 -88.251776)
			(xy 444.785987 -88.097754) (xy 444.65647 -87.938557) (xy 444.533264 -87.774428) (xy 444.416555 -87.605617)
			(xy 444.306521 -87.43238) (xy 444.20333 -87.254983) (xy 444.107139 -87.073695) (xy 444.018094 -86.888792)
			(xy 443.936331 -86.700555) (xy 443.861975 -86.509272) (xy 443.795139 -86.315233) (xy 443.735924 -86.118734)
			(xy 443.684421 -85.920075) (xy 443.640707 -85.719557) (xy 443.604851 -85.517486) (xy 443.576906 -85.314171)
			(xy 443.556915 -85.10992) (xy 443.544908 -84.905044) (xy 443.540904 -84.699856) (xy 239.4712 -84.699856)
			(xy 239.4712 -85.169502) (xy 239.47071 -85.199486) (xy 239.462882 -85.258942) (xy 239.447361 -85.316867)
			(xy 239.424412 -85.372271) (xy 239.394428 -85.424205) (xy 239.357922 -85.471781) (xy 239.315517 -85.514186)
			(xy 239.267941 -85.550692) (xy 239.216007 -85.580676) (xy 239.160603 -85.603625) (xy 239.102678 -85.619146)
			(xy 239.043222 -85.626974) (xy 238.983254 -85.626974) (xy 238.923798 -85.619146) (xy 238.865873 -85.603625)
			(xy 238.810469 -85.580676) (xy 238.758535 -85.550692) (xy 238.710959 -85.514186) (xy 238.668554 -85.471781)
			(xy 238.632048 -85.424205) (xy 238.602064 -85.372271) (xy 238.579115 -85.316867) (xy 238.563594 -85.258942)
			(xy 238.555766 -85.199486) (xy 238.555276 -85.169502) (xy 233.963295 -85.169502) (xy 233.966678 -85.173911)
			(xy 233.99666 -85.225842) (xy 234.019607 -85.281243) (xy 234.035127 -85.339165) (xy 234.042954 -85.398617)
			(xy 234.042954 -85.458583) (xy 234.035127 -85.518035) (xy 234.019607 -85.575957) (xy 233.99666 -85.631358)
			(xy 233.966678 -85.683289) (xy 233.930174 -85.730863) (xy 233.887772 -85.773266) (xy 233.840199 -85.809771)
			(xy 233.788268 -85.839755) (xy 233.732868 -85.862703) (xy 233.674947 -85.878225) (xy 233.615495 -85.886053)
			(xy 233.585512 -85.886544) (xy 232.721912 -85.886544) (xy 232.691925 -85.886112) (xy 232.632463 -85.878285)
			(xy 232.574531 -85.862763) (xy 232.519122 -85.839813) (xy 232.467181 -85.809827) (xy 232.4196 -85.773317)
			(xy 232.377191 -85.730909) (xy 232.34068 -85.683329) (xy 232.310692 -85.631389) (xy 232.28774 -85.57598)
			(xy 232.272218 -85.518049) (xy 232.264389 -85.458587) (xy 118.289959 -85.458587) (xy 118.277182 -85.506269)
			(xy 118.254246 -85.561642) (xy 118.224279 -85.613548) (xy 118.187792 -85.661098) (xy 118.145412 -85.703478)
			(xy 118.097862 -85.739965) (xy 118.045956 -85.769932) (xy 117.990583 -85.792868) (xy 117.93269 -85.808381)
			(xy 117.873268 -85.816204) (xy 117.813332 -85.816204) (xy 117.75391 -85.808381) (xy 117.696017 -85.792868)
			(xy 117.640644 -85.769932) (xy 117.588738 -85.739965) (xy 117.541188 -85.703478) (xy 117.498808 -85.661098)
			(xy 117.462321 -85.613548) (xy 117.432354 -85.561642) (xy 117.409418 -85.506269) (xy 117.393905 -85.448376)
			(xy 117.386082 -85.388954) (xy 117.385592 -85.358986) (xy 49.009819 -85.358986) (xy 49.00037 -85.409534)
			(xy 48.968871 -85.534773) (xy 48.929722 -85.657836) (xy 48.883071 -85.778255) (xy 48.829096 -85.895574)
			(xy 48.768001 -86.009348) (xy 48.700018 -86.119145) (xy 48.625404 -86.224548) (xy 48.544443 -86.325158)
			(xy 48.457443 -86.420593) (xy 48.364732 -86.510492) (xy 48.266662 -86.594513) (xy 48.163607 -86.672337)
			(xy 48.055956 -86.743669) (xy 47.944117 -86.808239) (xy 47.937853 -86.811358) (xy 99.84232 -86.811358)
			(xy 99.84232 -85.947758) (xy 99.84281 -85.917774) (xy 99.850638 -85.858318) (xy 99.866159 -85.800393)
			(xy 99.889108 -85.744989) (xy 99.919092 -85.693055) (xy 99.955598 -85.645479) (xy 99.998003 -85.603074)
			(xy 100.045579 -85.566568) (xy 100.097513 -85.536584) (xy 100.152917 -85.513635) (xy 100.210842 -85.498114)
			(xy 100.270298 -85.490286) (xy 100.330266 -85.490286) (xy 100.389722 -85.498114) (xy 100.447647 -85.513635)
			(xy 100.503051 -85.536584) (xy 100.554985 -85.566568) (xy 100.602561 -85.603074) (xy 100.644966 -85.645479)
			(xy 100.681472 -85.693055) (xy 100.711456 -85.744989) (xy 100.734405 -85.800393) (xy 100.749926 -85.858318)
			(xy 100.757754 -85.917774) (xy 100.758244 -85.947758) (xy 100.758244 -86.811358) (xy 100.757754 -86.841342)
			(xy 100.749926 -86.900798) (xy 100.734405 -86.958723) (xy 100.711456 -87.014127) (xy 100.681472 -87.066061)
			(xy 100.644966 -87.113637) (xy 100.602561 -87.156042) (xy 100.554985 -87.192548) (xy 100.503051 -87.222532)
			(xy 100.447647 -87.245481) (xy 100.389722 -87.261002) (xy 100.330266 -87.26883) (xy 100.270298 -87.26883)
			(xy 100.210842 -87.261002) (xy 100.152917 -87.245481) (xy 100.097513 -87.222532) (xy 100.045579 -87.192548)
			(xy 99.998003 -87.156042) (xy 99.955598 -87.113637) (xy 99.919092 -87.066061) (xy 99.889108 -87.014127)
			(xy 99.866159 -86.958723) (xy 99.850638 -86.900798) (xy 99.84281 -86.841342) (xy 99.84232 -86.811358)
			(xy 47.937853 -86.811358) (xy 47.828516 -86.865801) (xy 47.709591 -86.916138) (xy 47.587792 -86.959058)
			(xy 47.463582 -86.994399) (xy 47.337433 -87.022026) (xy 47.209821 -87.041835) (xy 47.081232 -87.053751)
			(xy 46.952154 -87.057728) (xy 46.823076 -87.053751) (xy 46.694487 -87.041835) (xy 46.566875 -87.022026)
			(xy 46.440726 -86.994399) (xy 46.316516 -86.959058) (xy 46.194717 -86.916138) (xy 46.075792 -86.865801)
			(xy 45.960191 -86.808239) (xy 45.848352 -86.743669) (xy 45.740701 -86.672337) (xy 45.637646 -86.594513)
			(xy 45.539576 -86.510492) (xy 45.446865 -86.420593) (xy 45.359865 -86.325158) (xy 45.278904 -86.224548)
			(xy 45.20429 -86.119145) (xy 45.136307 -86.009348) (xy 45.075212 -85.895574) (xy 45.021237 -85.778255)
			(xy 44.974586 -85.657836) (xy 44.935437 -85.534773) (xy 44.903938 -85.409534) (xy 44.880209 -85.282593)
			(xy 44.864339 -85.154433) (xy 44.856389 -85.025538) (xy 24.04871 -85.025538) (xy 24.034116 -85.212143)
			(xy 24.010143 -85.415965) (xy 23.978236 -85.618697) (xy 23.938444 -85.820029) (xy 23.890827 -86.019656)
			(xy 23.835457 -86.217272) (xy 23.77242 -86.412578) (xy 23.70181 -86.605276) (xy 23.623736 -86.795072)
			(xy 23.538316 -86.981678) (xy 23.44568 -87.164808) (xy 23.34597 -87.344185) (xy 23.336972 -87.358982)
			(xy 116.623592 -87.358982) (xy 116.623592 -86.495382) (xy 116.624082 -86.465414) (xy 116.631905 -86.405992)
			(xy 116.647418 -86.348099) (xy 116.670354 -86.292726) (xy 116.700321 -86.24082) (xy 116.736808 -86.19327)
			(xy 116.779188 -86.15089) (xy 116.826738 -86.114403) (xy 116.878644 -86.084436) (xy 116.934017 -86.0615)
			(xy 116.99191 -86.045987) (xy 117.051332 -86.038164) (xy 117.111268 -86.038164) (xy 117.17069 -86.045987)
			(xy 117.228583 -86.0615) (xy 117.283956 -86.084436) (xy 117.335862 -86.114403) (xy 117.383412 -86.15089)
			(xy 117.425792 -86.19327) (xy 117.462279 -86.24082) (xy 117.492246 -86.292726) (xy 117.515182 -86.348099)
			(xy 117.530695 -86.405992) (xy 117.538518 -86.465414) (xy 117.539008 -86.495382) (xy 117.539008 -87.358982)
			(xy 117.538518 -87.38895) (xy 117.531262 -87.444066) (xy 232.194882 -87.444066) (xy 232.194882 -87.384134)
			(xy 232.202704 -87.324714) (xy 232.218215 -87.266824) (xy 232.241149 -87.211454) (xy 232.271114 -87.15955)
			(xy 232.307596 -87.112002) (xy 232.349973 -87.069621) (xy 232.397519 -87.033135) (xy 232.44942 -87.003166)
			(xy 232.504788 -86.980227) (xy 232.562677 -86.964712) (xy 232.622096 -86.956884) (xy 232.652062 -86.956392)
			(xy 233.515662 -86.956392) (xy 233.545633 -86.956859) (xy 233.605062 -86.964678) (xy 233.662961 -86.980188)
			(xy 233.718341 -87.003123) (xy 233.770254 -87.033091) (xy 233.81781 -87.069578) (xy 233.860197 -87.111961)
			(xy 233.896688 -87.159515) (xy 233.92666 -87.211425) (xy 233.9496 -87.266803) (xy 233.965115 -87.324701)
			(xy 233.972939 -87.384129) (xy 233.972939 -87.416385) (xy 234.381521 -87.416385) (xy 234.381521 -87.356415)
			(xy 234.389349 -87.296959) (xy 234.40487 -87.239032) (xy 234.42782 -87.183628) (xy 234.457804 -87.131692)
			(xy 234.494312 -87.084115) (xy 234.536717 -87.04171) (xy 234.584294 -87.005203) (xy 234.636229 -86.975219)
			(xy 234.691634 -86.952269) (xy 234.749561 -86.936748) (xy 234.809017 -86.928921) (xy 234.839002 -86.928452)
			(xy 235.702602 -86.928452) (xy 235.732587 -86.928914) (xy 235.792044 -86.936742) (xy 235.849971 -86.952264)
			(xy 235.905376 -86.975214) (xy 235.957312 -87.005199) (xy 236.004889 -87.041707) (xy 236.047295 -87.084112)
			(xy 236.083802 -87.13169) (xy 236.113787 -87.183626) (xy 236.136737 -87.239031) (xy 236.152258 -87.296958)
			(xy 236.155843 -87.324184) (xy 330.477876 -87.324184) (xy 330.477876 -86.460584) (xy 330.478366 -86.430616)
			(xy 330.486189 -86.371194) (xy 330.501702 -86.313301) (xy 330.524638 -86.257928) (xy 330.554605 -86.206022)
			(xy 330.591092 -86.158472) (xy 330.633472 -86.116092) (xy 330.681022 -86.079605) (xy 330.732928 -86.049638)
			(xy 330.788301 -86.026702) (xy 330.846194 -86.011189) (xy 330.905616 -86.003366) (xy 330.965552 -86.003366)
			(xy 331.024974 -86.011189) (xy 331.082867 -86.026702) (xy 331.13824 -86.049638) (xy 331.190146 -86.079605)
			(xy 331.237696 -86.116092) (xy 331.266212 -86.144608) (xy 346.641928 -86.144608) (xy 346.641928 -85.281008)
			(xy 346.642418 -85.251024) (xy 346.650246 -85.191568) (xy 346.665767 -85.133643) (xy 346.688716 -85.078239)
			(xy 346.7187 -85.026305) (xy 346.755206 -84.978729) (xy 346.797611 -84.936324) (xy 346.845187 -84.899818)
			(xy 346.897121 -84.869834) (xy 346.952525 -84.846885) (xy 347.01045 -84.831364) (xy 347.069906 -84.823536)
			(xy 347.129874 -84.823536) (xy 347.18933 -84.831364) (xy 347.247255 -84.846885) (xy 347.302659 -84.869834)
			(xy 347.354593 -84.899818) (xy 347.402169 -84.936324) (xy 347.444574 -84.978729) (xy 347.48108 -85.026305)
			(xy 347.511064 -85.078239) (xy 347.534013 -85.133643) (xy 347.549534 -85.191568) (xy 347.557362 -85.251024)
			(xy 347.557852 -85.281008) (xy 347.557852 -86.144608) (xy 347.557362 -86.174592) (xy 347.549534 -86.234048)
			(xy 347.534013 -86.291973) (xy 347.511064 -86.347377) (xy 347.48108 -86.399311) (xy 347.444574 -86.446887)
			(xy 347.402169 -86.489292) (xy 347.354593 -86.525798) (xy 347.302659 -86.555782) (xy 347.247255 -86.578731)
			(xy 347.18933 -86.594252) (xy 347.129874 -86.60208) (xy 347.069906 -86.60208) (xy 347.01045 -86.594252)
			(xy 346.952525 -86.578731) (xy 346.897121 -86.555782) (xy 346.845187 -86.525798) (xy 346.797611 -86.489292)
			(xy 346.755206 -86.446887) (xy 346.7187 -86.399311) (xy 346.688716 -86.347377) (xy 346.665767 -86.291973)
			(xy 346.650246 -86.234048) (xy 346.642418 -86.174592) (xy 346.641928 -86.144608) (xy 331.266212 -86.144608)
			(xy 331.280076 -86.158472) (xy 331.316563 -86.206022) (xy 331.34653 -86.257928) (xy 331.369466 -86.313301)
			(xy 331.384979 -86.371194) (xy 331.392802 -86.430616) (xy 331.393292 -86.460584) (xy 331.393292 -87.324184)
			(xy 331.392802 -87.354152) (xy 331.384979 -87.413574) (xy 331.369466 -87.471467) (xy 331.34653 -87.52684)
			(xy 331.316563 -87.578746) (xy 331.280076 -87.626296) (xy 331.237696 -87.668676) (xy 331.190146 -87.705163)
			(xy 331.13824 -87.73513) (xy 331.082867 -87.758066) (xy 331.024974 -87.773579) (xy 330.965552 -87.781402)
			(xy 330.905616 -87.781402) (xy 330.846194 -87.773579) (xy 330.788301 -87.758066) (xy 330.732928 -87.73513)
			(xy 330.681022 -87.705163) (xy 330.633472 -87.668676) (xy 330.591092 -87.626296) (xy 330.554605 -87.578746)
			(xy 330.524638 -87.52684) (xy 330.501702 -87.471467) (xy 330.486189 -87.413574) (xy 330.478366 -87.354152)
			(xy 330.477876 -87.324184) (xy 236.155843 -87.324184) (xy 236.160086 -87.356415) (xy 236.160086 -87.416385)
			(xy 236.152258 -87.475842) (xy 236.136737 -87.533769) (xy 236.113787 -87.589174) (xy 236.083802 -87.64111)
			(xy 236.047295 -87.688688) (xy 236.004889 -87.731093) (xy 235.957312 -87.767601) (xy 235.905376 -87.797586)
			(xy 235.849971 -87.820536) (xy 235.792044 -87.836058) (xy 235.732587 -87.843886) (xy 235.702602 -87.844376)
			(xy 234.839002 -87.844376) (xy 234.809017 -87.843879) (xy 234.749561 -87.836052) (xy 234.691634 -87.820531)
			(xy 234.636229 -87.797581) (xy 234.584294 -87.767597) (xy 234.536717 -87.73109) (xy 234.494312 -87.688685)
			(xy 234.457804 -87.641108) (xy 234.42782 -87.589172) (xy 234.40487 -87.533768) (xy 234.389349 -87.475841)
			(xy 234.381521 -87.416385) (xy 233.972939 -87.416385) (xy 233.972939 -87.444071) (xy 233.965115 -87.503499)
			(xy 233.9496 -87.561397) (xy 233.92666 -87.616775) (xy 233.896688 -87.668685) (xy 233.860197 -87.716239)
			(xy 233.81781 -87.758622) (xy 233.770254 -87.795109) (xy 233.718341 -87.825077) (xy 233.662961 -87.848012)
			(xy 233.605062 -87.863522) (xy 233.545633 -87.871341) (xy 233.515662 -87.871808) (xy 232.652062 -87.871808)
			(xy 232.622096 -87.871316) (xy 232.562677 -87.863488) (xy 232.504788 -87.847973) (xy 232.44942 -87.825034)
			(xy 232.397519 -87.795065) (xy 232.349973 -87.758579) (xy 232.307596 -87.716198) (xy 232.271114 -87.66865)
			(xy 232.241149 -87.616746) (xy 232.218215 -87.561376) (xy 232.202704 -87.503486) (xy 232.194882 -87.444066)
			(xy 117.531262 -87.444066) (xy 117.530695 -87.448372) (xy 117.515182 -87.506265) (xy 117.492246 -87.561638)
			(xy 117.462279 -87.613544) (xy 117.425792 -87.661094) (xy 117.383412 -87.703474) (xy 117.335862 -87.739961)
			(xy 117.283956 -87.769928) (xy 117.228583 -87.792864) (xy 117.17069 -87.808377) (xy 117.111268 -87.8162)
			(xy 117.051332 -87.8162) (xy 116.99191 -87.808377) (xy 116.934017 -87.792864) (xy 116.878644 -87.769928)
			(xy 116.826738 -87.739961) (xy 116.779188 -87.703474) (xy 116.736808 -87.661094) (xy 116.700321 -87.613544)
			(xy 116.670354 -87.561638) (xy 116.647418 -87.506265) (xy 116.631905 -87.448372) (xy 116.624082 -87.38895)
			(xy 116.623592 -87.358982) (xy 23.336972 -87.358982) (xy 23.239337 -87.519535) (xy 23.125944 -87.690591)
			(xy 23.005964 -87.857093) (xy 22.889427 -88.006187) (xy 238.124409 -88.006187) (xy 238.124409 -87.946213)
			(xy 238.132238 -87.886751) (xy 238.147762 -87.82882) (xy 238.170714 -87.773411) (xy 238.200704 -87.721472)
			(xy 238.237216 -87.673892) (xy 238.279627 -87.631486) (xy 238.32721 -87.594978) (xy 238.379152 -87.564994)
			(xy 238.434563 -87.542047) (xy 238.492496 -87.526529) (xy 238.551959 -87.518706) (xy 238.581946 -87.51824)
			(xy 239.445546 -87.51824) (xy 239.475528 -87.518729) (xy 239.53498 -87.526561) (xy 239.5929 -87.542086)
			(xy 239.648299 -87.565038) (xy 239.700228 -87.595024) (xy 239.747799 -87.631531) (xy 239.790199 -87.673935)
			(xy 239.826701 -87.72151) (xy 239.856682 -87.773442) (xy 239.879628 -87.828843) (xy 239.895148 -87.886765)
			(xy 239.902974 -87.946217) (xy 239.902974 -88.006183) (xy 239.895148 -88.065635) (xy 239.879628 -88.123557)
			(xy 239.870911 -88.144604) (xy 345.879928 -88.144604) (xy 345.879928 -87.281004) (xy 345.880418 -87.25102)
			(xy 345.888246 -87.191564) (xy 345.903767 -87.133639) (xy 345.926716 -87.078235) (xy 345.9567 -87.026301)
			(xy 345.993206 -86.978725) (xy 346.035611 -86.93632) (xy 346.083187 -86.899814) (xy 346.135121 -86.86983)
			(xy 346.190525 -86.846881) (xy 346.24845 -86.83136) (xy 346.307906 -86.823532) (xy 346.367874 -86.823532)
			(xy 346.42733 -86.83136) (xy 346.485255 -86.846881) (xy 346.540659 -86.86983) (xy 346.592593 -86.899814)
			(xy 346.640169 -86.93632) (xy 346.682574 -86.978725) (xy 346.71908 -87.026301) (xy 346.749064 -87.078235)
			(xy 346.772013 -87.133639) (xy 346.787534 -87.191564) (xy 346.795362 -87.25102) (xy 346.795852 -87.281004)
			(xy 346.795852 -88.144604) (xy 346.795362 -88.174588) (xy 346.787534 -88.234044) (xy 346.772013 -88.291969)
			(xy 346.749064 -88.347373) (xy 346.71908 -88.399307) (xy 346.682574 -88.446883) (xy 346.640169 -88.489288)
			(xy 346.592593 -88.525794) (xy 346.540659 -88.555778) (xy 346.485255 -88.578727) (xy 346.42733 -88.594248)
			(xy 346.367874 -88.602076) (xy 346.307906 -88.602076) (xy 346.24845 -88.594248) (xy 346.190525 -88.578727)
			(xy 346.135121 -88.555778) (xy 346.083187 -88.525794) (xy 346.035611 -88.489288) (xy 345.993206 -88.446883)
			(xy 345.9567 -88.399307) (xy 345.926716 -88.347373) (xy 345.903767 -88.291969) (xy 345.888246 -88.234044)
			(xy 345.880418 -88.174588) (xy 345.879928 -88.144604) (xy 239.870911 -88.144604) (xy 239.856682 -88.178958)
			(xy 239.826701 -88.23089) (xy 239.790199 -88.278465) (xy 239.747799 -88.320869) (xy 239.700228 -88.357376)
			(xy 239.648299 -88.387362) (xy 239.5929 -88.410314) (xy 239.53498 -88.425839) (xy 239.475528 -88.433671)
			(xy 239.445546 -88.434164) (xy 238.581946 -88.434164) (xy 238.551959 -88.433694) (xy 238.492496 -88.425871)
			(xy 238.434563 -88.410353) (xy 238.379152 -88.387406) (xy 238.32721 -88.357422) (xy 238.279627 -88.320914)
			(xy 238.237216 -88.278508) (xy 238.200704 -88.230928) (xy 238.170714 -88.178989) (xy 238.147762 -88.12358)
			(xy 238.132238 -88.065649) (xy 238.124409 -88.006187) (xy 22.889427 -88.006187) (xy 22.879578 -88.018787)
			(xy 22.74698 -88.175427) (xy 22.608372 -88.326773) (xy 22.463964 -88.472597) (xy 22.313977 -88.612676)
			(xy 22.158638 -88.746795) (xy 21.998185 -88.874752) (xy 21.832862 -88.996352) (xy 21.66292 -89.111408)
			(xy 21.488619 -89.219747) (xy 21.310223 -89.321202) (xy 21.237319 -89.358978) (xy 117.385592 -89.358978)
			(xy 117.385592 -88.495378) (xy 117.386082 -88.46541) (xy 117.393905 -88.405988) (xy 117.409418 -88.348095)
			(xy 117.432354 -88.292722) (xy 117.462321 -88.240816) (xy 117.498808 -88.193266) (xy 117.541188 -88.150886)
			(xy 117.588738 -88.114399) (xy 117.640644 -88.084432) (xy 117.696017 -88.061496) (xy 117.75391 -88.045983)
			(xy 117.813332 -88.03816) (xy 117.873268 -88.03816) (xy 117.93269 -88.045983) (xy 117.990583 -88.061496)
			(xy 118.045956 -88.084432) (xy 118.097862 -88.114399) (xy 118.145412 -88.150886) (xy 118.187792 -88.193266)
			(xy 118.224279 -88.240816) (xy 118.254246 -88.292722) (xy 118.277182 -88.348095) (xy 118.292695 -88.405988)
			(xy 118.300518 -88.46541) (xy 118.301008 -88.495378) (xy 118.301008 -89.358978) (xy 118.300518 -89.388946)
			(xy 118.292695 -89.448368) (xy 118.277182 -89.506261) (xy 118.254246 -89.561634) (xy 118.224279 -89.61354)
			(xy 118.187792 -89.66109) (xy 118.145412 -89.70347) (xy 118.097862 -89.739957) (xy 118.045956 -89.769924)
			(xy 117.990583 -89.79286) (xy 117.93269 -89.808373) (xy 117.873268 -89.816196) (xy 117.813332 -89.816196)
			(xy 117.75391 -89.808373) (xy 117.696017 -89.79286) (xy 117.640644 -89.769924) (xy 117.588738 -89.739957)
			(xy 117.541188 -89.70347) (xy 117.498808 -89.66109) (xy 117.462321 -89.61354) (xy 117.432354 -89.561634)
			(xy 117.409418 -89.506261) (xy 117.393905 -89.448368) (xy 117.386082 -89.388946) (xy 117.385592 -89.358978)
			(xy 21.237319 -89.358978) (xy 21.128005 -89.41562) (xy 20.942242 -89.502856) (xy 20.753217 -89.582779)
			(xy 20.561217 -89.655265) (xy 20.366535 -89.720205) (xy 20.169468 -89.7775) (xy 19.970315 -89.827063)
			(xy 19.769381 -89.868818) (xy 19.56697 -89.902701) (xy 19.363392 -89.928661) (xy 19.158955 -89.946658)
			(xy 18.953972 -89.956666) (xy 18.748755 -89.958668) (xy 18.543616 -89.952662) (xy 18.338867 -89.938657)
			(xy 18.13482 -89.916674) (xy 17.931787 -89.886747) (xy 17.730076 -89.84892) (xy 17.529994 -89.803253)
			(xy 17.331847 -89.749814) (xy 17.135935 -89.688685) (xy 16.942558 -89.619959) (xy 16.752009 -89.54374)
			(xy 16.564579 -89.460144) (xy 16.380553 -89.3693) (xy 16.200212 -89.271345) (xy 16.02383 -89.166428)
			(xy 15.851676 -89.054709) (xy 15.684011 -88.936359) (xy 15.521092 -88.811557) (xy 15.363166 -88.680493)
			(xy 15.210474 -88.543368) (xy 15.063249 -88.40039) (xy 14.921714 -88.251776) (xy 14.786085 -88.097754)
			(xy 14.656568 -87.938557) (xy 14.533362 -87.774428) (xy 14.416653 -87.605617) (xy 14.306619 -87.43238)
			(xy 14.203428 -87.254983) (xy 14.107237 -87.073695) (xy 14.018192 -86.888792) (xy 13.936429 -86.700555)
			(xy 13.862073 -86.509272) (xy 13.795237 -86.315233) (xy 13.736022 -86.118734) (xy 13.684519 -85.920075)
			(xy 13.640805 -85.719557) (xy 13.604949 -85.517486) (xy 13.577004 -85.314171) (xy 13.557013 -85.10992)
			(xy 13.545006 -84.905044) (xy 13.541002 -84.699856) (xy 3.894875 -84.699856) (xy 4.291584 -85.096604)
			(xy 4.352388 -85.158117) (xy 4.468586 -85.286261) (xy 4.578355 -85.419953) (xy 4.681431 -85.558871)
			(xy 4.777564 -85.702681) (xy 4.866525 -85.851035) (xy 4.948097 -86.003576) (xy 5.022085 -86.159936)
			(xy 5.08831 -86.31974) (xy 5.146612 -86.4826) (xy 5.196852 -86.648126) (xy 5.238907 -86.815918) (xy 5.272678 -86.985572)
			(xy 5.298081 -87.156679) (xy 5.315056 -87.328826) (xy 5.323563 -87.501599) (xy 5.324094 -87.58809)
			(xy 5.324094 -90.1446) (xy 346.641928 -90.1446) (xy 346.641928 -89.281) (xy 346.642418 -89.251016)
			(xy 346.650246 -89.19156) (xy 346.665767 -89.133635) (xy 346.688716 -89.078231) (xy 346.7187 -89.026297)
			(xy 346.755206 -88.978721) (xy 346.797611 -88.936316) (xy 346.845187 -88.89981) (xy 346.897121 -88.869826)
			(xy 346.952525 -88.846877) (xy 347.01045 -88.831356) (xy 347.069906 -88.823528) (xy 347.129874 -88.823528)
			(xy 347.18933 -88.831356) (xy 347.247255 -88.846877) (xy 347.302659 -88.869826) (xy 347.354593 -88.89981)
			(xy 347.402169 -88.936316) (xy 347.444574 -88.978721) (xy 347.48108 -89.026297) (xy 347.511064 -89.078231)
			(xy 347.534013 -89.133635) (xy 347.549534 -89.19156) (xy 347.557362 -89.251016) (xy 347.557852 -89.281)
			(xy 347.557852 -90.1446) (xy 347.557362 -90.174584) (xy 347.549534 -90.23404) (xy 347.534013 -90.291965)
			(xy 347.511064 -90.347369) (xy 347.48108 -90.399303) (xy 347.444574 -90.446879) (xy 347.402169 -90.489284)
			(xy 347.354593 -90.52579) (xy 347.302659 -90.555774) (xy 347.247255 -90.578723) (xy 347.18933 -90.594244)
			(xy 347.129874 -90.602072) (xy 347.069906 -90.602072) (xy 347.01045 -90.594244) (xy 346.952525 -90.578723)
			(xy 346.897121 -90.555774) (xy 346.845187 -90.52579) (xy 346.797611 -90.489284) (xy 346.755206 -90.446879)
			(xy 346.7187 -90.399303) (xy 346.688716 -90.347369) (xy 346.665767 -90.291965) (xy 346.650246 -90.23404)
			(xy 346.642418 -90.174584) (xy 346.641928 -90.1446) (xy 5.324094 -90.1446) (xy 5.324094 -94.088485)
			(xy 109.149614 -94.088485) (xy 109.149614 -94.028515) (xy 109.157442 -93.969058) (xy 109.172963 -93.911131)
			(xy 109.195912 -93.855726) (xy 109.225897 -93.80379) (xy 109.262405 -93.756213) (xy 109.30481 -93.713807)
			(xy 109.352387 -93.6773) (xy 109.404322 -93.647314) (xy 109.459727 -93.624364) (xy 109.517654 -93.608843)
			(xy 109.577111 -93.601014) (xy 109.607096 -93.600524) (xy 110.470696 -93.600524) (xy 110.500681 -93.601021)
			(xy 110.560138 -93.608848) (xy 110.618064 -93.624369) (xy 110.673469 -93.647318) (xy 110.725405 -93.677303)
			(xy 110.772982 -93.71381) (xy 110.815388 -93.756215) (xy 110.851895 -93.803792) (xy 110.88188 -93.855727)
			(xy 110.90483 -93.911132) (xy 110.920351 -93.969058) (xy 110.928179 -94.028515) (xy 110.928179 -94.088485)
			(xy 110.920351 -94.147942) (xy 110.90483 -94.205868) (xy 110.88188 -94.261273) (xy 110.851895 -94.313208)
			(xy 110.815388 -94.360785) (xy 110.772982 -94.40319) (xy 110.725405 -94.439697) (xy 110.673469 -94.469682)
			(xy 110.618064 -94.492631) (xy 110.560138 -94.508152) (xy 110.500681 -94.515979) (xy 110.470696 -94.516448)
			(xy 109.607096 -94.516448) (xy 109.577111 -94.515986) (xy 109.517654 -94.508157) (xy 109.459727 -94.492636)
			(xy 109.404322 -94.469686) (xy 109.352387 -94.4397) (xy 109.30481 -94.403193) (xy 109.262405 -94.360787)
			(xy 109.225897 -94.31321) (xy 109.195912 -94.261274) (xy 109.172963 -94.205869) (xy 109.157442 -94.147942)
			(xy 109.149614 -94.088485) (xy 5.324094 -94.088485) (xy 5.324094 -95.214948) (xy 47.274239 -95.214948)
			(xy 47.278194 -95.123111) (xy 47.290029 -95.031954) (xy 47.309656 -94.942151) (xy 47.33693 -94.854369)
			(xy 47.37165 -94.769255) (xy 47.413558 -94.687442) (xy 47.462344 -94.609534) (xy 47.517647 -94.536109)
			(xy 47.579057 -94.467709) (xy 47.646119 -94.404842) (xy 47.718338 -94.347972) (xy 47.795178 -94.297521)
			(xy 47.876071 -94.253862) (xy 47.960417 -94.217319) (xy 48.047593 -94.188162) (xy 48.136952 -94.166608)
			(xy 48.227833 -94.152814) (xy 48.319564 -94.146884) (xy 48.411465 -94.148862) (xy 48.502856 -94.158733)
			(xy 48.59306 -94.176423) (xy 48.681409 -94.201803) (xy 48.767249 -94.234683) (xy 48.849945 -94.274821)
			(xy 48.928885 -94.32192) (xy 49.003483 -94.37563) (xy 49.073189 -94.435554) (xy 49.137484 -94.501248)
			(xy 49.195895 -94.572226) (xy 49.247987 -94.647963) (xy 49.293376 -94.727898) (xy 49.331726 -94.811438)
			(xy 49.362751 -94.897966) (xy 49.386224 -94.986841) (xy 49.40197 -95.077405) (xy 49.409872 -95.168987)
			(xy 49.410366 -95.214948) (xy 71.639189 -95.214948) (xy 71.643144 -95.123111) (xy 71.654979 -95.031954)
			(xy 71.674606 -94.942151) (xy 71.70188 -94.854369) (xy 71.7366 -94.769255) (xy 71.778508 -94.687442)
			(xy 71.827294 -94.609534) (xy 71.882597 -94.536109) (xy 71.944007 -94.467709) (xy 72.011069 -94.404842)
			(xy 72.083288 -94.347972) (xy 72.160128 -94.297521) (xy 72.241021 -94.253862) (xy 72.325367 -94.217319)
			(xy 72.412543 -94.188162) (xy 72.501902 -94.166608) (xy 72.592783 -94.152814) (xy 72.684514 -94.146884)
			(xy 72.776415 -94.148862) (xy 72.867806 -94.158733) (xy 72.95801 -94.176423) (xy 73.046359 -94.201803)
			(xy 73.132199 -94.234683) (xy 73.214895 -94.274821) (xy 73.293835 -94.32192) (xy 73.368433 -94.37563)
			(xy 73.438139 -94.435554) (xy 73.502434 -94.501248) (xy 73.560845 -94.572226) (xy 73.612937 -94.647963)
			(xy 73.658326 -94.727898) (xy 73.696676 -94.811438) (xy 73.727701 -94.897966) (xy 73.751174 -94.986841)
			(xy 73.76692 -95.077405) (xy 73.774822 -95.168987) (xy 73.775316 -95.214948) (xy 73.774822 -95.260909)
			(xy 73.774772 -95.261486) (xy 163.375394 -95.261486) (xy 163.375394 -95.168314) (xy 163.383515 -95.075496)
			(xy 163.399694 -94.983738) (xy 163.423808 -94.893741) (xy 163.455675 -94.806187) (xy 163.495052 -94.721744)
			(xy 163.541638 -94.641054) (xy 163.595079 -94.564731) (xy 163.654969 -94.493357) (xy 163.720852 -94.427473)
			(xy 163.792226 -94.367583) (xy 163.868549 -94.314141) (xy 163.949238 -94.267554) (xy 164.033681 -94.228178)
			(xy 164.121235 -94.19631) (xy 164.211233 -94.172195) (xy 164.30299 -94.156015) (xy 164.395808 -94.147894)
			(xy 164.442394 -94.147386) (xy 164.442648 -94.147386) (xy 164.489237 -94.1478) (xy 164.582061 -94.155925)
			(xy 164.673824 -94.172109) (xy 164.763826 -94.196229) (xy 164.851385 -94.228101) (xy 164.935832 -94.267483)
			(xy 165.016526 -94.314074) (xy 165.092852 -94.367522) (xy 165.164229 -94.427418) (xy 165.230115 -94.493306)
			(xy 165.290008 -94.564687) (xy 165.343451 -94.641015) (xy 165.390039 -94.721711) (xy 165.429417 -94.80616)
			(xy 165.461286 -94.893719) (xy 165.485401 -94.983723) (xy 165.501581 -95.075487) (xy 165.509702 -95.168311)
			(xy 165.509702 -95.214948) (xy 187.739796 -95.214948) (xy 187.743748 -95.123155) (xy 187.755578 -95.032041)
			(xy 187.775195 -94.942281) (xy 187.802457 -94.85454) (xy 187.83716 -94.769468) (xy 187.879048 -94.687693)
			(xy 187.927811 -94.609822) (xy 187.983087 -94.536432) (xy 188.044468 -94.468065) (xy 188.111499 -94.405227)
			(xy 188.183683 -94.348385) (xy 188.260487 -94.297958) (xy 188.341341 -94.25432) (xy 188.425647 -94.217794)
			(xy 188.512781 -94.188651) (xy 188.602098 -94.167106) (xy 188.692936 -94.15332) (xy 188.784623 -94.147393)
			(xy 188.87648 -94.14937) (xy 188.967828 -94.159236) (xy 189.057988 -94.176918) (xy 189.146296 -94.202285)
			(xy 189.232095 -94.23515) (xy 189.314752 -94.275269) (xy 189.393654 -94.322345) (xy 189.468217 -94.376029)
			(xy 189.537889 -94.435925) (xy 189.602154 -94.501588) (xy 189.660537 -94.572532) (xy 189.712604 -94.648233)
			(xy 189.757972 -94.72813) (xy 189.796303 -94.81163) (xy 189.827314 -94.898117) (xy 189.850775 -94.98695)
			(xy 189.866514 -95.07747) (xy 189.874412 -95.169009) (xy 189.874906 -95.214948) (xy 189.874412 -95.260887)
			(xy 189.866514 -95.352426) (xy 189.850775 -95.442946) (xy 189.827314 -95.531779) (xy 189.796303 -95.618266)
			(xy 189.757972 -95.701766) (xy 189.712604 -95.781663) (xy 189.660537 -95.857364) (xy 189.602154 -95.928308)
			(xy 189.537889 -95.993971) (xy 189.468217 -96.053867) (xy 189.393654 -96.107551) (xy 189.314752 -96.154627)
			(xy 189.232095 -96.194746) (xy 189.146296 -96.227611) (xy 189.057988 -96.252978) (xy 188.967828 -96.27066)
			(xy 188.87648 -96.280526) (xy 188.784623 -96.282503) (xy 188.692936 -96.276576) (xy 188.602098 -96.26279)
			(xy 188.512781 -96.241245) (xy 188.425647 -96.212102) (xy 188.341341 -96.175576) (xy 188.260487 -96.131938)
			(xy 188.183683 -96.081511) (xy 188.111499 -96.024669) (xy 188.044468 -95.961831) (xy 187.983087 -95.893464)
			(xy 187.927811 -95.820074) (xy 187.879048 -95.742203) (xy 187.83716 -95.660428) (xy 187.802457 -95.575356)
			(xy 187.775195 -95.487615) (xy 187.755578 -95.397855) (xy 187.743748 -95.306741) (xy 187.739796 -95.214948)
			(xy 165.509702 -95.214948) (xy 165.509702 -95.261489) (xy 165.501581 -95.354313) (xy 165.485401 -95.446077)
			(xy 165.461286 -95.536081) (xy 165.429417 -95.62364) (xy 165.390039 -95.708089) (xy 165.343451 -95.788785)
			(xy 165.290008 -95.865113) (xy 165.230115 -95.936494) (xy 165.164229 -96.002382) (xy 165.092852 -96.062278)
			(xy 165.016526 -96.115726) (xy 164.935832 -96.162317) (xy 164.851385 -96.201699) (xy 164.763826 -96.233571)
			(xy 164.673824 -96.257691) (xy 164.582061 -96.273875) (xy 164.489237 -96.282) (xy 164.442648 -96.28251)
			(xy 164.442394 -96.28251) (xy 164.395808 -96.281906) (xy 164.30299 -96.273785) (xy 164.211233 -96.257605)
			(xy 164.121235 -96.23349) (xy 164.033681 -96.201622) (xy 163.949238 -96.162246) (xy 163.868549 -96.115659)
			(xy 163.792226 -96.062217) (xy 163.720852 -96.002327) (xy 163.654969 -95.936443) (xy 163.595079 -95.865069)
			(xy 163.541638 -95.788746) (xy 163.495052 -95.708056) (xy 163.455675 -95.623613) (xy 163.423808 -95.536059)
			(xy 163.399694 -95.446062) (xy 163.383515 -95.354304) (xy 163.375394 -95.261486) (xy 73.774772 -95.261486)
			(xy 73.76692 -95.352491) (xy 73.751174 -95.443055) (xy 73.727701 -95.53193) (xy 73.696676 -95.618458)
			(xy 73.658326 -95.701998) (xy 73.612937 -95.781933) (xy 73.560845 -95.85767) (xy 73.502434 -95.928648)
			(xy 73.438139 -95.994342) (xy 73.368433 -96.054266) (xy 73.293835 -96.107976) (xy 73.214895 -96.155075)
			(xy 73.132199 -96.195213) (xy 73.046359 -96.228093) (xy 72.95801 -96.253473) (xy 72.867806 -96.271163)
			(xy 72.776415 -96.281034) (xy 72.684514 -96.283012) (xy 72.592783 -96.277082) (xy 72.501902 -96.263288)
			(xy 72.412543 -96.241734) (xy 72.325367 -96.212577) (xy 72.241021 -96.176034) (xy 72.160128 -96.132375)
			(xy 72.083288 -96.081924) (xy 72.011069 -96.025054) (xy 71.944007 -95.962187) (xy 71.882597 -95.893787)
			(xy 71.827294 -95.820362) (xy 71.778508 -95.742454) (xy 71.7366 -95.660641) (xy 71.70188 -95.575527)
			(xy 71.674606 -95.487745) (xy 71.654979 -95.397942) (xy 71.643144 -95.306785) (xy 71.639189 -95.214948)
			(xy 49.410366 -95.214948) (xy 49.409872 -95.260909) (xy 49.40197 -95.352491) (xy 49.386224 -95.443055)
			(xy 49.362751 -95.53193) (xy 49.331726 -95.618458) (xy 49.293376 -95.701998) (xy 49.247987 -95.781933)
			(xy 49.195895 -95.85767) (xy 49.137484 -95.928648) (xy 49.073189 -95.994342) (xy 49.003483 -96.054266)
			(xy 48.928885 -96.107976) (xy 48.849945 -96.155075) (xy 48.767249 -96.195213) (xy 48.681409 -96.228093)
			(xy 48.59306 -96.253473) (xy 48.502856 -96.271163) (xy 48.411465 -96.281034) (xy 48.319564 -96.283012)
			(xy 48.227833 -96.277082) (xy 48.136952 -96.263288) (xy 48.047593 -96.241734) (xy 47.960417 -96.212577)
			(xy 47.876071 -96.176034) (xy 47.795178 -96.132375) (xy 47.718338 -96.081924) (xy 47.646119 -96.025054)
			(xy 47.579057 -95.962187) (xy 47.517647 -95.893787) (xy 47.462344 -95.820362) (xy 47.413558 -95.742454)
			(xy 47.37165 -95.660641) (xy 47.33693 -95.575527) (xy 47.309656 -95.487745) (xy 47.290029 -95.397942)
			(xy 47.278194 -95.306785) (xy 47.274239 -95.214948) (xy 5.324094 -95.214948) (xy 5.324094 -98.700082)
			(xy 203.041004 -98.700082) (xy 203.045008 -98.494894) (xy 203.057015 -98.290018) (xy 203.077006 -98.085767)
			(xy 203.104951 -97.882452) (xy 203.140807 -97.680381) (xy 203.184521 -97.479863) (xy 203.236024 -97.281204)
			(xy 203.295239 -97.084705) (xy 203.362075 -96.890666) (xy 203.436431 -96.699383) (xy 203.518194 -96.511146)
			(xy 203.607239 -96.326243) (xy 203.70343 -96.144955) (xy 203.806621 -95.967558) (xy 203.916655 -95.794321)
			(xy 204.033364 -95.62551) (xy 204.15657 -95.461381) (xy 204.286087 -95.302184) (xy 204.421716 -95.148162)
			(xy 204.563251 -94.999548) (xy 204.710476 -94.85657) (xy 204.863168 -94.719445) (xy 205.021094 -94.588381)
			(xy 205.184013 -94.463579) (xy 205.351678 -94.345229) (xy 205.523832 -94.23351) (xy 205.700214 -94.128593)
			(xy 205.880555 -94.030638) (xy 206.064581 -93.939794) (xy 206.252011 -93.856198) (xy 206.44256 -93.779979)
			(xy 206.635937 -93.711253) (xy 206.831849 -93.650124) (xy 207.029996 -93.596685) (xy 207.230078 -93.551018)
			(xy 207.431789 -93.513191) (xy 207.634822 -93.483264) (xy 207.838869 -93.461281) (xy 208.043618 -93.447276)
			(xy 208.248757 -93.44127) (xy 208.453974 -93.443272) (xy 208.658957 -93.45328) (xy 208.863394 -93.471277)
			(xy 209.066972 -93.497237) (xy 209.269383 -93.53112) (xy 209.470317 -93.572875) (xy 209.66947 -93.622438)
			(xy 209.866537 -93.679733) (xy 210.061219 -93.744673) (xy 210.253219 -93.817159) (xy 210.442244 -93.897082)
			(xy 210.628007 -93.984318) (xy 210.810225 -94.078736) (xy 210.988621 -94.180191) (xy 211.162922 -94.28853)
			(xy 211.332864 -94.403586) (xy 211.498187 -94.525186) (xy 211.65864 -94.653143) (xy 211.813979 -94.787262)
			(xy 211.963966 -94.927341) (xy 212.108374 -95.073165) (xy 212.246982 -95.224511) (xy 212.37958 -95.381151)
			(xy 212.505966 -95.542845) (xy 212.625946 -95.709347) (xy 212.739339 -95.880403) (xy 212.845972 -96.055753)
			(xy 212.945682 -96.23513) (xy 213.038318 -96.41826) (xy 213.123738 -96.604866) (xy 213.201812 -96.794662)
			(xy 213.272422 -96.98736) (xy 213.335459 -97.182666) (xy 213.390829 -97.380282) (xy 213.438446 -97.579909)
			(xy 213.478238 -97.781241) (xy 213.510145 -97.983973) (xy 213.534118 -98.187795) (xy 213.55012 -98.392398)
			(xy 213.558127 -98.597468) (xy 213.558628 -98.700082) (xy 254.040902 -98.700082) (xy 254.044906 -98.494894)
			(xy 254.056913 -98.290018) (xy 254.076904 -98.085767) (xy 254.104849 -97.882452) (xy 254.140705 -97.680381)
			(xy 254.184419 -97.479863) (xy 254.235922 -97.281204) (xy 254.295137 -97.084705) (xy 254.361973 -96.890666)
			(xy 254.436329 -96.699383) (xy 254.518092 -96.511146) (xy 254.607137 -96.326243) (xy 254.703328 -96.144955)
			(xy 254.806519 -95.967558) (xy 254.916553 -95.794321) (xy 255.033262 -95.62551) (xy 255.156468 -95.461381)
			(xy 255.285985 -95.302184) (xy 255.421614 -95.148162) (xy 255.563149 -94.999548) (xy 255.710374 -94.85657)
			(xy 255.863066 -94.719445) (xy 256.020992 -94.588381) (xy 256.183911 -94.463579) (xy 256.351576 -94.345229)
			(xy 256.52373 -94.23351) (xy 256.700112 -94.128593) (xy 256.880453 -94.030638) (xy 257.064479 -93.939794)
			(xy 257.251909 -93.856198) (xy 257.442458 -93.779979) (xy 257.635835 -93.711253) (xy 257.831747 -93.650124)
			(xy 258.029894 -93.596685) (xy 258.229976 -93.551018) (xy 258.431687 -93.513191) (xy 258.63472 -93.483264)
			(xy 258.838767 -93.461281) (xy 259.043516 -93.447276) (xy 259.248655 -93.44127) (xy 259.453872 -93.443272)
			(xy 259.658855 -93.45328) (xy 259.863292 -93.471277) (xy 260.06687 -93.497237) (xy 260.269281 -93.53112)
			(xy 260.470215 -93.572875) (xy 260.669368 -93.622438) (xy 260.866435 -93.679733) (xy 261.061117 -93.744673)
			(xy 261.253117 -93.817159) (xy 261.442142 -93.897082) (xy 261.627905 -93.984318) (xy 261.810123 -94.078736)
			(xy 261.988519 -94.180191) (xy 262.16282 -94.28853) (xy 262.332762 -94.403586) (xy 262.498085 -94.525186)
			(xy 262.658538 -94.653143) (xy 262.813877 -94.787262) (xy 262.963864 -94.927341) (xy 263.108272 -95.073165)
			(xy 263.238122 -95.214948) (xy 279.474181 -95.214948) (xy 279.478136 -95.123111) (xy 279.489971 -95.031954)
			(xy 279.509598 -94.942151) (xy 279.536872 -94.854369) (xy 279.571592 -94.769255) (xy 279.6135 -94.687442)
			(xy 279.662286 -94.609534) (xy 279.717589 -94.536109) (xy 279.778999 -94.467709) (xy 279.846061 -94.404842)
			(xy 279.91828 -94.347972) (xy 279.99512 -94.297521) (xy 280.076013 -94.253862) (xy 280.160359 -94.217319)
			(xy 280.247535 -94.188162) (xy 280.336894 -94.166608) (xy 280.427775 -94.152814) (xy 280.519506 -94.146884)
			(xy 280.611407 -94.148862) (xy 280.702798 -94.158733) (xy 280.793002 -94.176423) (xy 280.881351 -94.201803)
			(xy 280.967191 -94.234683) (xy 281.049887 -94.274821) (xy 281.128827 -94.32192) (xy 281.203425 -94.37563)
			(xy 281.273131 -94.435554) (xy 281.337426 -94.501248) (xy 281.395837 -94.572226) (xy 281.447929 -94.647963)
			(xy 281.493318 -94.727898) (xy 281.531668 -94.811438) (xy 281.562693 -94.897966) (xy 281.586166 -94.986841)
			(xy 281.601912 -95.077405) (xy 281.609814 -95.168987) (xy 281.610308 -95.214948) (xy 303.839131 -95.214948)
			(xy 303.843086 -95.123111) (xy 303.854921 -95.031954) (xy 303.874548 -94.942151) (xy 303.901822 -94.854369)
			(xy 303.936542 -94.769255) (xy 303.97845 -94.687442) (xy 304.027236 -94.609534) (xy 304.082539 -94.536109)
			(xy 304.143949 -94.467709) (xy 304.211011 -94.404842) (xy 304.28323 -94.347972) (xy 304.36007 -94.297521)
			(xy 304.440963 -94.253862) (xy 304.525309 -94.217319) (xy 304.612485 -94.188162) (xy 304.701844 -94.166608)
			(xy 304.792725 -94.152814) (xy 304.884456 -94.146884) (xy 304.976357 -94.148862) (xy 305.067748 -94.158733)
			(xy 305.157952 -94.176423) (xy 305.246301 -94.201803) (xy 305.332141 -94.234683) (xy 305.414837 -94.274821)
			(xy 305.493777 -94.32192) (xy 305.568375 -94.37563) (xy 305.638081 -94.435554) (xy 305.702376 -94.501248)
			(xy 305.760787 -94.572226) (xy 305.812879 -94.647963) (xy 305.858268 -94.727898) (xy 305.896618 -94.811438)
			(xy 305.91901 -94.87389) (xy 338.405861 -94.87389) (xy 338.405861 -94.81391) (xy 338.413691 -94.754443)
			(xy 338.429215 -94.696507) (xy 338.45217 -94.641093) (xy 338.482161 -94.58915) (xy 338.518676 -94.541565)
			(xy 338.561089 -94.499155) (xy 338.608676 -94.462643) (xy 338.660622 -94.432655) (xy 338.716037 -94.409705)
			(xy 338.773975 -94.394184) (xy 338.833442 -94.386359) (xy 338.863432 -94.385892) (xy 339.727032 -94.385892)
			(xy 339.757012 -94.386476) (xy 339.816458 -94.394306) (xy 339.874374 -94.409828) (xy 339.929769 -94.432777)
			(xy 339.981694 -94.462759) (xy 340.029262 -94.499262) (xy 340.071659 -94.541662) (xy 340.108159 -94.589232)
			(xy 340.138137 -94.64116) (xy 340.161082 -94.696556) (xy 340.1766 -94.754473) (xy 340.184426 -94.81392)
			(xy 340.184426 -94.87388) (xy 340.1766 -94.933327) (xy 340.161082 -94.991244) (xy 340.138137 -95.04664)
			(xy 340.108159 -95.098568) (xy 340.071659 -95.146138) (xy 340.029262 -95.188538) (xy 339.994846 -95.214948)
			(xy 395.574279 -95.214948) (xy 395.578234 -95.123111) (xy 395.590069 -95.031954) (xy 395.609696 -94.942151)
			(xy 395.63697 -94.854369) (xy 395.67169 -94.769255) (xy 395.713598 -94.687442) (xy 395.762384 -94.609534)
			(xy 395.817687 -94.536109) (xy 395.879097 -94.467709) (xy 395.946159 -94.404842) (xy 396.018378 -94.347972)
			(xy 396.095218 -94.297521) (xy 396.176111 -94.253862) (xy 396.260457 -94.217319) (xy 396.347633 -94.188162)
			(xy 396.436992 -94.166608) (xy 396.527873 -94.152814) (xy 396.619604 -94.146884) (xy 396.711505 -94.148862)
			(xy 396.802896 -94.158733) (xy 396.8931 -94.176423) (xy 396.981449 -94.201803) (xy 397.067289 -94.234683)
			(xy 397.149985 -94.274821) (xy 397.228925 -94.32192) (xy 397.303523 -94.37563) (xy 397.373229 -94.435554)
			(xy 397.437524 -94.501248) (xy 397.495935 -94.572226) (xy 397.548027 -94.647963) (xy 397.593416 -94.727898)
			(xy 397.631766 -94.811438) (xy 397.662791 -94.897966) (xy 397.686264 -94.986841) (xy 397.70201 -95.077405)
			(xy 397.709912 -95.168987) (xy 397.710406 -95.214948) (xy 419.939229 -95.214948) (xy 419.943184 -95.123111)
			(xy 419.955019 -95.031954) (xy 419.974646 -94.942151) (xy 420.00192 -94.854369) (xy 420.03664 -94.769255)
			(xy 420.078548 -94.687442) (xy 420.127334 -94.609534) (xy 420.182637 -94.536109) (xy 420.244047 -94.467709)
			(xy 420.311109 -94.404842) (xy 420.383328 -94.347972) (xy 420.460168 -94.297521) (xy 420.541061 -94.253862)
			(xy 420.625407 -94.217319) (xy 420.712583 -94.188162) (xy 420.801942 -94.166608) (xy 420.892823 -94.152814)
			(xy 420.984554 -94.146884) (xy 421.076455 -94.148862) (xy 421.167846 -94.158733) (xy 421.25805 -94.176423)
			(xy 421.346399 -94.201803) (xy 421.432239 -94.234683) (xy 421.514935 -94.274821) (xy 421.593875 -94.32192)
			(xy 421.668473 -94.37563) (xy 421.738179 -94.435554) (xy 421.802474 -94.501248) (xy 421.860885 -94.572226)
			(xy 421.912977 -94.647963) (xy 421.958366 -94.727898) (xy 421.996716 -94.811438) (xy 422.027741 -94.897966)
			(xy 422.051214 -94.986841) (xy 422.06696 -95.077405) (xy 422.074862 -95.168987) (xy 422.075356 -95.214948)
			(xy 422.074862 -95.260909) (xy 422.06696 -95.352491) (xy 422.051214 -95.443055) (xy 422.027741 -95.53193)
			(xy 421.996716 -95.618458) (xy 421.958366 -95.701998) (xy 421.912977 -95.781933) (xy 421.860885 -95.85767)
			(xy 421.802474 -95.928648) (xy 421.738179 -95.994342) (xy 421.668473 -96.054266) (xy 421.593875 -96.107976)
			(xy 421.514935 -96.155075) (xy 421.432239 -96.195213) (xy 421.346399 -96.228093) (xy 421.25805 -96.253473)
			(xy 421.167846 -96.271163) (xy 421.076455 -96.281034) (xy 420.984554 -96.283012) (xy 420.892823 -96.277082)
			(xy 420.801942 -96.263288) (xy 420.712583 -96.241734) (xy 420.625407 -96.212577) (xy 420.541061 -96.176034)
			(xy 420.460168 -96.132375) (xy 420.383328 -96.081924) (xy 420.311109 -96.025054) (xy 420.244047 -95.962187)
			(xy 420.182637 -95.893787) (xy 420.127334 -95.820362) (xy 420.078548 -95.742454) (xy 420.03664 -95.660641)
			(xy 420.00192 -95.575527) (xy 419.974646 -95.487745) (xy 419.955019 -95.397942) (xy 419.943184 -95.306785)
			(xy 419.939229 -95.214948) (xy 397.710406 -95.214948) (xy 397.709912 -95.260909) (xy 397.70201 -95.352491)
			(xy 397.686264 -95.443055) (xy 397.662791 -95.53193) (xy 397.631766 -95.618458) (xy 397.593416 -95.701998)
			(xy 397.548027 -95.781933) (xy 397.495935 -95.85767) (xy 397.437524 -95.928648) (xy 397.373229 -95.994342)
			(xy 397.303523 -96.054266) (xy 397.228925 -96.107976) (xy 397.149985 -96.155075) (xy 397.067289 -96.195213)
			(xy 396.981449 -96.228093) (xy 396.8931 -96.253473) (xy 396.802896 -96.271163) (xy 396.711505 -96.281034)
			(xy 396.619604 -96.283012) (xy 396.527873 -96.277082) (xy 396.436992 -96.263288) (xy 396.347633 -96.241734)
			(xy 396.260457 -96.212577) (xy 396.176111 -96.176034) (xy 396.095218 -96.132375) (xy 396.018378 -96.081924)
			(xy 395.946159 -96.025054) (xy 395.879097 -95.962187) (xy 395.817687 -95.893787) (xy 395.762384 -95.820362)
			(xy 395.713598 -95.742454) (xy 395.67169 -95.660641) (xy 395.63697 -95.575527) (xy 395.609696 -95.487745)
			(xy 395.590069 -95.397942) (xy 395.578234 -95.306785) (xy 395.574279 -95.214948) (xy 339.994846 -95.214948)
			(xy 339.981694 -95.225041) (xy 339.929769 -95.255023) (xy 339.874374 -95.277972) (xy 339.816458 -95.293494)
			(xy 339.757012 -95.301324) (xy 339.727032 -95.301816) (xy 338.863432 -95.301816) (xy 338.833442 -95.301441)
			(xy 338.773975 -95.293616) (xy 338.716037 -95.278095) (xy 338.660622 -95.255145) (xy 338.608676 -95.225157)
			(xy 338.561089 -95.188645) (xy 338.518676 -95.146235) (xy 338.482161 -95.09865) (xy 338.45217 -95.046707)
			(xy 338.429215 -94.991293) (xy 338.413691 -94.933357) (xy 338.405861 -94.87389) (xy 305.91901 -94.87389)
			(xy 305.927643 -94.897966) (xy 305.951116 -94.986841) (xy 305.966862 -95.077405) (xy 305.974764 -95.168987)
			(xy 305.975258 -95.214948) (xy 305.974764 -95.260909) (xy 305.966862 -95.352491) (xy 305.951116 -95.443055)
			(xy 305.927643 -95.53193) (xy 305.896618 -95.618458) (xy 305.858268 -95.701998) (xy 305.812879 -95.781933)
			(xy 305.760787 -95.85767) (xy 305.702376 -95.928648) (xy 305.638081 -95.994342) (xy 305.568375 -96.054266)
			(xy 305.493777 -96.107976) (xy 305.414837 -96.155075) (xy 305.332141 -96.195213) (xy 305.246301 -96.228093)
			(xy 305.157952 -96.253473) (xy 305.067748 -96.271163) (xy 304.976357 -96.281034) (xy 304.884456 -96.283012)
			(xy 304.792725 -96.277082) (xy 304.701844 -96.263288) (xy 304.612485 -96.241734) (xy 304.525309 -96.212577)
			(xy 304.440963 -96.176034) (xy 304.36007 -96.132375) (xy 304.28323 -96.081924) (xy 304.211011 -96.025054)
			(xy 304.143949 -95.962187) (xy 304.082539 -95.893787) (xy 304.027236 -95.820362) (xy 303.97845 -95.742454)
			(xy 303.936542 -95.660641) (xy 303.901822 -95.575527) (xy 303.874548 -95.487745) (xy 303.854921 -95.397942)
			(xy 303.843086 -95.306785) (xy 303.839131 -95.214948) (xy 281.610308 -95.214948) (xy 281.609814 -95.260909)
			(xy 281.601912 -95.352491) (xy 281.586166 -95.443055) (xy 281.562693 -95.53193) (xy 281.531668 -95.618458)
			(xy 281.493318 -95.701998) (xy 281.447929 -95.781933) (xy 281.395837 -95.85767) (xy 281.337426 -95.928648)
			(xy 281.273131 -95.994342) (xy 281.203425 -96.054266) (xy 281.128827 -96.107976) (xy 281.049887 -96.155075)
			(xy 280.967191 -96.195213) (xy 280.881351 -96.228093) (xy 280.793002 -96.253473) (xy 280.702798 -96.271163)
			(xy 280.611407 -96.281034) (xy 280.519506 -96.283012) (xy 280.427775 -96.277082) (xy 280.336894 -96.263288)
			(xy 280.247535 -96.241734) (xy 280.160359 -96.212577) (xy 280.076013 -96.176034) (xy 279.99512 -96.132375)
			(xy 279.91828 -96.081924) (xy 279.846061 -96.025054) (xy 279.778999 -95.962187) (xy 279.717589 -95.893787)
			(xy 279.662286 -95.820362) (xy 279.6135 -95.742454) (xy 279.571592 -95.660641) (xy 279.536872 -95.575527)
			(xy 279.509598 -95.487745) (xy 279.489971 -95.397942) (xy 279.478136 -95.306785) (xy 279.474181 -95.214948)
			(xy 263.238122 -95.214948) (xy 263.24688 -95.224511) (xy 263.379478 -95.381151) (xy 263.505864 -95.542845)
			(xy 263.625844 -95.709347) (xy 263.739237 -95.880403) (xy 263.84587 -96.055753) (xy 263.94558 -96.23513)
			(xy 264.038216 -96.41826) (xy 264.123636 -96.604866) (xy 264.20171 -96.794662) (xy 264.27232 -96.98736)
			(xy 264.335357 -97.182666) (xy 264.390727 -97.380282) (xy 264.438344 -97.579909) (xy 264.478136 -97.781241)
			(xy 264.510043 -97.983973) (xy 264.534016 -98.187795) (xy 264.550018 -98.392398) (xy 264.558025 -98.597468)
			(xy 264.558526 -98.700082) (xy 264.558025 -98.802696) (xy 264.550018 -99.007766) (xy 264.534016 -99.212369)
			(xy 264.510043 -99.416191) (xy 264.478136 -99.618923) (xy 264.438344 -99.820255) (xy 264.390727 -100.019882)
			(xy 264.346465 -100.177854) (xy 269.509748 -100.177854) (xy 269.509748 -99.314254) (xy 269.510238 -99.28427)
			(xy 269.518066 -99.224814) (xy 269.533587 -99.166889) (xy 269.556536 -99.111485) (xy 269.58652 -99.059551)
			(xy 269.623026 -99.011975) (xy 269.665431 -98.96957) (xy 269.713007 -98.933064) (xy 269.764941 -98.90308)
			(xy 269.820345 -98.880131) (xy 269.87827 -98.86461) (xy 269.937726 -98.856782) (xy 269.997694 -98.856782)
			(xy 270.05715 -98.86461) (xy 270.115075 -98.880131) (xy 270.170479 -98.90308) (xy 270.222413 -98.933064)
			(xy 270.269989 -98.96957) (xy 270.312394 -99.011975) (xy 270.3489 -99.059551) (xy 270.378884 -99.111485)
			(xy 270.401833 -99.166889) (xy 270.417354 -99.224814) (xy 270.425182 -99.28427) (xy 270.425672 -99.314254)
			(xy 270.425672 -100.17633) (xy 285.8389 -100.17633) (xy 285.8389 -99.31273) (xy 285.83939 -99.282746)
			(xy 285.847218 -99.22329) (xy 285.862739 -99.165365) (xy 285.885688 -99.109961) (xy 285.915672 -99.058027)
			(xy 285.952178 -99.010451) (xy 285.994583 -98.968046) (xy 286.042159 -98.93154) (xy 286.094093 -98.901556)
			(xy 286.149497 -98.878607) (xy 286.207422 -98.863086) (xy 286.266878 -98.855258) (xy 286.326846 -98.855258)
			(xy 286.386302 -98.863086) (xy 286.444227 -98.878607) (xy 286.499631 -98.901556) (xy 286.551565 -98.93154)
			(xy 286.599141 -98.968046) (xy 286.641546 -99.010451) (xy 286.678052 -99.058027) (xy 286.708036 -99.109961)
			(xy 286.730985 -99.165365) (xy 286.746506 -99.22329) (xy 286.754334 -99.282746) (xy 286.754824 -99.31273)
			(xy 286.754824 -100.17633) (xy 286.754799 -100.177854) (xy 385.6101 -100.177854) (xy 385.6101 -99.314254)
			(xy 385.61059 -99.284286) (xy 385.618413 -99.224864) (xy 385.633926 -99.166971) (xy 385.656862 -99.111598)
			(xy 385.686829 -99.059692) (xy 385.723316 -99.012142) (xy 385.765696 -98.969762) (xy 385.813246 -98.933275)
			(xy 385.865152 -98.903308) (xy 385.920525 -98.880372) (xy 385.978418 -98.864859) (xy 386.03784 -98.857036)
			(xy 386.097776 -98.857036) (xy 386.157198 -98.864859) (xy 386.215091 -98.880372) (xy 386.270464 -98.903308)
			(xy 386.32237 -98.933275) (xy 386.36992 -98.969762) (xy 386.4123 -99.012142) (xy 386.448787 -99.059692)
			(xy 386.478754 -99.111598) (xy 386.50169 -99.166971) (xy 386.517203 -99.224864) (xy 386.525026 -99.284286)
			(xy 386.525516 -99.314254) (xy 386.525516 -100.17633) (xy 401.939252 -100.17633) (xy 401.939252 -99.31273)
			(xy 401.939742 -99.282762) (xy 401.947565 -99.22334) (xy 401.963078 -99.165447) (xy 401.986014 -99.110074)
			(xy 402.015981 -99.058168) (xy 402.052468 -99.010618) (xy 402.094848 -98.968238) (xy 402.142398 -98.931751)
			(xy 402.194304 -98.901784) (xy 402.249677 -98.878848) (xy 402.30757 -98.863335) (xy 402.366992 -98.855512)
			(xy 402.426928 -98.855512) (xy 402.48635 -98.863335) (xy 402.544243 -98.878848) (xy 402.599616 -98.901784)
			(xy 402.651522 -98.931751) (xy 402.699072 -98.968238) (xy 402.741452 -99.010618) (xy 402.777939 -99.058168)
			(xy 402.807906 -99.110074) (xy 402.830842 -99.165447) (xy 402.846355 -99.22334) (xy 402.854178 -99.282762)
			(xy 402.854668 -99.31273) (xy 402.854668 -100.17633) (xy 402.854178 -100.206298) (xy 402.846355 -100.26572)
			(xy 402.830842 -100.323613) (xy 402.807906 -100.378986) (xy 402.777939 -100.430892) (xy 402.741452 -100.478442)
			(xy 402.699072 -100.520822) (xy 402.651522 -100.557309) (xy 402.599616 -100.587276) (xy 402.544243 -100.610212)
			(xy 402.48635 -100.625725) (xy 402.426928 -100.633548) (xy 402.366992 -100.633548) (xy 402.30757 -100.625725)
			(xy 402.249677 -100.610212) (xy 402.194304 -100.587276) (xy 402.142398 -100.557309) (xy 402.094848 -100.520822)
			(xy 402.052468 -100.478442) (xy 402.015981 -100.430892) (xy 401.986014 -100.378986) (xy 401.963078 -100.323613)
			(xy 401.947565 -100.26572) (xy 401.939742 -100.206298) (xy 401.939252 -100.17633) (xy 386.525516 -100.17633)
			(xy 386.525516 -100.177854) (xy 386.525026 -100.207822) (xy 386.517203 -100.267244) (xy 386.50169 -100.325137)
			(xy 386.478754 -100.38051) (xy 386.448787 -100.432416) (xy 386.4123 -100.479966) (xy 386.36992 -100.522346)
			(xy 386.32237 -100.558833) (xy 386.270464 -100.5888) (xy 386.215091 -100.611736) (xy 386.157198 -100.627249)
			(xy 386.097776 -100.635072) (xy 386.03784 -100.635072) (xy 385.978418 -100.627249) (xy 385.920525 -100.611736)
			(xy 385.865152 -100.5888) (xy 385.813246 -100.558833) (xy 385.765696 -100.522346) (xy 385.723316 -100.479966)
			(xy 385.686829 -100.432416) (xy 385.656862 -100.38051) (xy 385.633926 -100.325137) (xy 385.618413 -100.267244)
			(xy 385.61059 -100.207822) (xy 385.6101 -100.177854) (xy 286.754799 -100.177854) (xy 286.754334 -100.206314)
			(xy 286.746506 -100.26577) (xy 286.730985 -100.323695) (xy 286.708036 -100.379099) (xy 286.678052 -100.431033)
			(xy 286.641546 -100.478609) (xy 286.599141 -100.521014) (xy 286.551565 -100.55752) (xy 286.499631 -100.587504)
			(xy 286.444227 -100.610453) (xy 286.386302 -100.625974) (xy 286.326846 -100.633802) (xy 286.266878 -100.633802)
			(xy 286.207422 -100.625974) (xy 286.149497 -100.610453) (xy 286.094093 -100.587504) (xy 286.042159 -100.55752)
			(xy 285.994583 -100.521014) (xy 285.952178 -100.478609) (xy 285.915672 -100.431033) (xy 285.885688 -100.379099)
			(xy 285.862739 -100.323695) (xy 285.847218 -100.26577) (xy 285.83939 -100.206314) (xy 285.8389 -100.17633)
			(xy 270.425672 -100.17633) (xy 270.425672 -100.177854) (xy 270.425182 -100.207838) (xy 270.417354 -100.267294)
			(xy 270.401833 -100.325219) (xy 270.378884 -100.380623) (xy 270.3489 -100.432557) (xy 270.312394 -100.480133)
			(xy 270.269989 -100.522538) (xy 270.222413 -100.559044) (xy 270.170479 -100.589028) (xy 270.115075 -100.611977)
			(xy 270.05715 -100.627498) (xy 269.997694 -100.635326) (xy 269.937726 -100.635326) (xy 269.87827 -100.627498)
			(xy 269.820345 -100.611977) (xy 269.764941 -100.589028) (xy 269.713007 -100.559044) (xy 269.665431 -100.522538)
			(xy 269.623026 -100.480133) (xy 269.58652 -100.432557) (xy 269.556536 -100.380623) (xy 269.533587 -100.325219)
			(xy 269.518066 -100.267294) (xy 269.510238 -100.207838) (xy 269.509748 -100.177854) (xy 264.346465 -100.177854)
			(xy 264.335357 -100.217498) (xy 264.27232 -100.412804) (xy 264.20171 -100.605502) (xy 264.123636 -100.795298)
			(xy 264.038216 -100.981904) (xy 263.94558 -101.165034) (xy 263.84587 -101.344411) (xy 263.739237 -101.519761)
			(xy 263.625844 -101.690817) (xy 263.505864 -101.857319) (xy 263.406609 -101.984302) (xy 267.47724 -101.984302)
			(xy 267.47724 -101.120702) (xy 267.47773 -101.090718) (xy 267.485558 -101.031262) (xy 267.501079 -100.973337)
			(xy 267.524028 -100.917933) (xy 267.554012 -100.865999) (xy 267.590518 -100.818423) (xy 267.632923 -100.776018)
			(xy 267.680499 -100.739512) (xy 267.732433 -100.709528) (xy 267.787837 -100.686579) (xy 267.845762 -100.671058)
			(xy 267.905218 -100.66323) (xy 267.965186 -100.66323) (xy 268.024642 -100.671058) (xy 268.082567 -100.686579)
			(xy 268.137971 -100.709528) (xy 268.189905 -100.739512) (xy 268.237481 -100.776018) (xy 268.279886 -100.818423)
			(xy 268.316392 -100.865999) (xy 268.346376 -100.917933) (xy 268.369325 -100.973337) (xy 268.384846 -101.031262)
			(xy 268.392674 -101.090718) (xy 268.393164 -101.120702) (xy 268.393164 -101.976428) (xy 283.9847 -101.976428)
			(xy 283.9847 -101.112828) (xy 283.98519 -101.082844) (xy 283.993018 -101.023388) (xy 284.008539 -100.965463)
			(xy 284.031488 -100.910059) (xy 284.061472 -100.858125) (xy 284.097978 -100.810549) (xy 284.140383 -100.768144)
			(xy 284.187959 -100.731638) (xy 284.239893 -100.701654) (xy 284.295297 -100.678705) (xy 284.353222 -100.663184)
			(xy 284.412678 -100.655356) (xy 284.472646 -100.655356) (xy 284.532102 -100.663184) (xy 284.590027 -100.678705)
			(xy 284.645431 -100.701654) (xy 284.697365 -100.731638) (xy 284.744941 -100.768144) (xy 284.787346 -100.810549)
			(xy 284.823852 -100.858125) (xy 284.853836 -100.910059) (xy 284.876785 -100.965463) (xy 284.892306 -101.023388)
			(xy 284.900134 -101.082844) (xy 284.900624 -101.112828) (xy 284.900624 -101.976428) (xy 284.900495 -101.984302)
			(xy 383.577592 -101.984302) (xy 383.577592 -101.120702) (xy 383.578082 -101.090734) (xy 383.585905 -101.031312)
			(xy 383.601418 -100.973419) (xy 383.624354 -100.918046) (xy 383.654321 -100.86614) (xy 383.690808 -100.81859)
			(xy 383.733188 -100.77621) (xy 383.780738 -100.739723) (xy 383.832644 -100.709756) (xy 383.888017 -100.68682)
			(xy 383.94591 -100.671307) (xy 384.005332 -100.663484) (xy 384.065268 -100.663484) (xy 384.12469 -100.671307)
			(xy 384.182583 -100.68682) (xy 384.237956 -100.709756) (xy 384.289862 -100.739723) (xy 384.337412 -100.77621)
			(xy 384.379792 -100.81859) (xy 384.416279 -100.86614) (xy 384.446246 -100.918046) (xy 384.469182 -100.973419)
			(xy 384.484695 -101.031312) (xy 384.492518 -101.090734) (xy 384.493008 -101.120702) (xy 384.493008 -101.976428)
			(xy 400.085052 -101.976428) (xy 400.085052 -101.112828) (xy 400.085542 -101.08286) (xy 400.093365 -101.023438)
			(xy 400.108878 -100.965545) (xy 400.131814 -100.910172) (xy 400.161781 -100.858266) (xy 400.198268 -100.810716)
			(xy 400.240648 -100.768336) (xy 400.288198 -100.731849) (xy 400.340104 -100.701882) (xy 400.395477 -100.678946)
			(xy 400.45337 -100.663433) (xy 400.512792 -100.65561) (xy 400.572728 -100.65561) (xy 400.63215 -100.663433)
			(xy 400.690043 -100.678946) (xy 400.745416 -100.701882) (xy 400.797322 -100.731849) (xy 400.844872 -100.768336)
			(xy 400.887252 -100.810716) (xy 400.923739 -100.858266) (xy 400.953706 -100.910172) (xy 400.976642 -100.965545)
			(xy 400.992155 -101.023438) (xy 400.999978 -101.08286) (xy 401.000468 -101.112828) (xy 401.000468 -101.976428)
			(xy 400.999978 -102.006396) (xy 400.992155 -102.065818) (xy 400.976642 -102.123711) (xy 400.953706 -102.179084)
			(xy 400.923739 -102.23099) (xy 400.887252 -102.27854) (xy 400.844872 -102.32092) (xy 400.797322 -102.357407)
			(xy 400.745416 -102.387374) (xy 400.690043 -102.41031) (xy 400.63215 -102.425823) (xy 400.572728 -102.433646)
			(xy 400.512792 -102.433646) (xy 400.45337 -102.425823) (xy 400.395477 -102.41031) (xy 400.340104 -102.387374)
			(xy 400.288198 -102.357407) (xy 400.240648 -102.32092) (xy 400.198268 -102.27854) (xy 400.161781 -102.23099)
			(xy 400.131814 -102.179084) (xy 400.108878 -102.123711) (xy 400.093365 -102.065818) (xy 400.085542 -102.006396)
			(xy 400.085052 -101.976428) (xy 384.493008 -101.976428) (xy 384.493008 -101.984302) (xy 384.492518 -102.01427)
			(xy 384.484695 -102.073692) (xy 384.469182 -102.131585) (xy 384.446246 -102.186958) (xy 384.416279 -102.238864)
			(xy 384.379792 -102.286414) (xy 384.337412 -102.328794) (xy 384.289862 -102.365281) (xy 384.237956 -102.395248)
			(xy 384.182583 -102.418184) (xy 384.12469 -102.433697) (xy 384.065268 -102.44152) (xy 384.005332 -102.44152)
			(xy 383.94591 -102.433697) (xy 383.888017 -102.418184) (xy 383.832644 -102.395248) (xy 383.780738 -102.365281)
			(xy 383.733188 -102.328794) (xy 383.690808 -102.286414) (xy 383.654321 -102.238864) (xy 383.624354 -102.186958)
			(xy 383.601418 -102.131585) (xy 383.585905 -102.073692) (xy 383.578082 -102.01427) (xy 383.577592 -101.984302)
			(xy 284.900495 -101.984302) (xy 284.900134 -102.006412) (xy 284.892306 -102.065868) (xy 284.876785 -102.123793)
			(xy 284.853836 -102.179197) (xy 284.823852 -102.231131) (xy 284.787346 -102.278707) (xy 284.744941 -102.321112)
			(xy 284.697365 -102.357618) (xy 284.645431 -102.387602) (xy 284.590027 -102.410551) (xy 284.532102 -102.426072)
			(xy 284.472646 -102.4339) (xy 284.412678 -102.4339) (xy 284.353222 -102.426072) (xy 284.295297 -102.410551)
			(xy 284.239893 -102.387602) (xy 284.187959 -102.357618) (xy 284.140383 -102.321112) (xy 284.097978 -102.278707)
			(xy 284.061472 -102.231131) (xy 284.031488 -102.179197) (xy 284.008539 -102.123793) (xy 283.993018 -102.065868)
			(xy 283.98519 -102.006412) (xy 283.9847 -101.976428) (xy 268.393164 -101.976428) (xy 268.393164 -101.984302)
			(xy 268.392674 -102.014286) (xy 268.384846 -102.073742) (xy 268.369325 -102.131667) (xy 268.346376 -102.187071)
			(xy 268.316392 -102.239005) (xy 268.279886 -102.286581) (xy 268.237481 -102.328986) (xy 268.189905 -102.365492)
			(xy 268.137971 -102.395476) (xy 268.082567 -102.418425) (xy 268.024642 -102.433946) (xy 267.965186 -102.441774)
			(xy 267.905218 -102.441774) (xy 267.845762 -102.433946) (xy 267.787837 -102.418425) (xy 267.732433 -102.395476)
			(xy 267.680499 -102.365492) (xy 267.632923 -102.328986) (xy 267.590518 -102.286581) (xy 267.554012 -102.239005)
			(xy 267.524028 -102.187071) (xy 267.501079 -102.131667) (xy 267.485558 -102.073742) (xy 267.47773 -102.014286)
			(xy 267.47724 -101.984302) (xy 263.406609 -101.984302) (xy 263.379478 -102.019013) (xy 263.24688 -102.175653)
			(xy 263.108272 -102.326999) (xy 262.963864 -102.472823) (xy 262.813877 -102.612902) (xy 262.658538 -102.747021)
			(xy 262.498085 -102.874978) (xy 262.332762 -102.996578) (xy 262.16282 -103.111634) (xy 261.988519 -103.219973)
			(xy 261.810123 -103.321428) (xy 261.627905 -103.415846) (xy 261.442142 -103.503082) (xy 261.253117 -103.583005)
			(xy 261.061117 -103.655491) (xy 260.866435 -103.720431) (xy 260.669368 -103.777726) (xy 260.669087 -103.777796)
			(xy 269.509748 -103.777796) (xy 269.509748 -102.914196) (xy 269.510238 -102.884212) (xy 269.518066 -102.824756)
			(xy 269.533587 -102.766831) (xy 269.556536 -102.711427) (xy 269.58652 -102.659493) (xy 269.623026 -102.611917)
			(xy 269.665431 -102.569512) (xy 269.713007 -102.533006) (xy 269.764941 -102.503022) (xy 269.820345 -102.480073)
			(xy 269.87827 -102.464552) (xy 269.937726 -102.456724) (xy 269.997694 -102.456724) (xy 270.05715 -102.464552)
			(xy 270.115075 -102.480073) (xy 270.170479 -102.503022) (xy 270.222413 -102.533006) (xy 270.269989 -102.569512)
			(xy 270.312394 -102.611917) (xy 270.3489 -102.659493) (xy 270.378884 -102.711427) (xy 270.401833 -102.766831)
			(xy 270.417354 -102.824756) (xy 270.425182 -102.884212) (xy 270.425672 -102.914196) (xy 270.425672 -103.776272)
			(xy 285.8389 -103.776272) (xy 285.8389 -102.912672) (xy 285.83939 -102.882688) (xy 285.847218 -102.823232)
			(xy 285.862739 -102.765307) (xy 285.885688 -102.709903) (xy 285.915672 -102.657969) (xy 285.952178 -102.610393)
			(xy 285.994583 -102.567988) (xy 286.042159 -102.531482) (xy 286.094093 -102.501498) (xy 286.149497 -102.478549)
			(xy 286.207422 -102.463028) (xy 286.266878 -102.4552) (xy 286.326846 -102.4552) (xy 286.386302 -102.463028)
			(xy 286.444227 -102.478549) (xy 286.499631 -102.501498) (xy 286.551565 -102.531482) (xy 286.599141 -102.567988)
			(xy 286.641546 -102.610393) (xy 286.678052 -102.657969) (xy 286.708036 -102.709903) (xy 286.730985 -102.765307)
			(xy 286.746506 -102.823232) (xy 286.754334 -102.882688) (xy 286.754824 -102.912672) (xy 286.754824 -103.776272)
			(xy 286.754799 -103.777796) (xy 385.6101 -103.777796) (xy 385.6101 -102.914196) (xy 385.61059 -102.884228)
			(xy 385.618413 -102.824806) (xy 385.633926 -102.766913) (xy 385.656862 -102.71154) (xy 385.686829 -102.659634)
			(xy 385.723316 -102.612084) (xy 385.765696 -102.569704) (xy 385.813246 -102.533217) (xy 385.865152 -102.50325)
			(xy 385.920525 -102.480314) (xy 385.978418 -102.464801) (xy 386.03784 -102.456978) (xy 386.097776 -102.456978)
			(xy 386.157198 -102.464801) (xy 386.215091 -102.480314) (xy 386.270464 -102.50325) (xy 386.32237 -102.533217)
			(xy 386.36992 -102.569704) (xy 386.4123 -102.612084) (xy 386.448787 -102.659634) (xy 386.478754 -102.71154)
			(xy 386.50169 -102.766913) (xy 386.517203 -102.824806) (xy 386.525026 -102.884228) (xy 386.525516 -102.914196)
			(xy 386.525516 -103.776272) (xy 401.939252 -103.776272) (xy 401.939252 -102.912672) (xy 401.939742 -102.882704)
			(xy 401.947565 -102.823282) (xy 401.963078 -102.765389) (xy 401.986014 -102.710016) (xy 402.015981 -102.65811)
			(xy 402.052468 -102.61056) (xy 402.094848 -102.56818) (xy 402.142398 -102.531693) (xy 402.194304 -102.501726)
			(xy 402.249677 -102.47879) (xy 402.30757 -102.463277) (xy 402.366992 -102.455454) (xy 402.426928 -102.455454)
			(xy 402.48635 -102.463277) (xy 402.544243 -102.47879) (xy 402.599616 -102.501726) (xy 402.651522 -102.531693)
			(xy 402.699072 -102.56818) (xy 402.741452 -102.61056) (xy 402.777939 -102.65811) (xy 402.807906 -102.710016)
			(xy 402.830842 -102.765389) (xy 402.846355 -102.823282) (xy 402.854178 -102.882704) (xy 402.854668 -102.912672)
			(xy 402.854668 -103.776272) (xy 402.854178 -103.80624) (xy 402.846355 -103.865662) (xy 402.830842 -103.923555)
			(xy 402.807906 -103.978928) (xy 402.777939 -104.030834) (xy 402.741452 -104.078384) (xy 402.699072 -104.120764)
			(xy 402.651522 -104.157251) (xy 402.599616 -104.187218) (xy 402.544243 -104.210154) (xy 402.48635 -104.225667)
			(xy 402.426928 -104.23349) (xy 402.366992 -104.23349) (xy 402.30757 -104.225667) (xy 402.249677 -104.210154)
			(xy 402.194304 -104.187218) (xy 402.142398 -104.157251) (xy 402.094848 -104.120764) (xy 402.052468 -104.078384)
			(xy 402.015981 -104.030834) (xy 401.986014 -103.978928) (xy 401.963078 -103.923555) (xy 401.947565 -103.865662)
			(xy 401.939742 -103.80624) (xy 401.939252 -103.776272) (xy 386.525516 -103.776272) (xy 386.525516 -103.777796)
			(xy 386.525026 -103.807764) (xy 386.517203 -103.867186) (xy 386.50169 -103.925079) (xy 386.478754 -103.980452)
			(xy 386.448787 -104.032358) (xy 386.4123 -104.079908) (xy 386.36992 -104.122288) (xy 386.32237 -104.158775)
			(xy 386.270464 -104.188742) (xy 386.215091 -104.211678) (xy 386.157198 -104.227191) (xy 386.097776 -104.235014)
			(xy 386.03784 -104.235014) (xy 385.978418 -104.227191) (xy 385.920525 -104.211678) (xy 385.865152 -104.188742)
			(xy 385.813246 -104.158775) (xy 385.765696 -104.122288) (xy 385.723316 -104.079908) (xy 385.686829 -104.032358)
			(xy 385.656862 -103.980452) (xy 385.633926 -103.925079) (xy 385.618413 -103.867186) (xy 385.61059 -103.807764)
			(xy 385.6101 -103.777796) (xy 286.754799 -103.777796) (xy 286.754334 -103.806256) (xy 286.746506 -103.865712)
			(xy 286.730985 -103.923637) (xy 286.708036 -103.979041) (xy 286.678052 -104.030975) (xy 286.641546 -104.078551)
			(xy 286.599141 -104.120956) (xy 286.551565 -104.157462) (xy 286.499631 -104.187446) (xy 286.444227 -104.210395)
			(xy 286.386302 -104.225916) (xy 286.326846 -104.233744) (xy 286.266878 -104.233744) (xy 286.207422 -104.225916)
			(xy 286.149497 -104.210395) (xy 286.094093 -104.187446) (xy 286.042159 -104.157462) (xy 285.994583 -104.120956)
			(xy 285.952178 -104.078551) (xy 285.915672 -104.030975) (xy 285.885688 -103.979041) (xy 285.862739 -103.923637)
			(xy 285.847218 -103.865712) (xy 285.83939 -103.806256) (xy 285.8389 -103.776272) (xy 270.425672 -103.776272)
			(xy 270.425672 -103.777796) (xy 270.425182 -103.80778) (xy 270.417354 -103.867236) (xy 270.401833 -103.925161)
			(xy 270.378884 -103.980565) (xy 270.3489 -104.032499) (xy 270.312394 -104.080075) (xy 270.269989 -104.12248)
			(xy 270.222413 -104.158986) (xy 270.170479 -104.18897) (xy 270.115075 -104.211919) (xy 270.05715 -104.22744)
			(xy 269.997694 -104.235268) (xy 269.937726 -104.235268) (xy 269.87827 -104.22744) (xy 269.820345 -104.211919)
			(xy 269.764941 -104.18897) (xy 269.713007 -104.158986) (xy 269.665431 -104.12248) (xy 269.623026 -104.080075)
			(xy 269.58652 -104.032499) (xy 269.556536 -103.980565) (xy 269.533587 -103.925161) (xy 269.518066 -103.867236)
			(xy 269.510238 -103.80778) (xy 269.509748 -103.777796) (xy 260.669087 -103.777796) (xy 260.470215 -103.827289)
			(xy 260.269281 -103.869044) (xy 260.06687 -103.902927) (xy 259.863292 -103.928887) (xy 259.658855 -103.946884)
			(xy 259.453872 -103.956892) (xy 259.248655 -103.958894) (xy 259.043516 -103.952888) (xy 258.838767 -103.938883)
			(xy 258.63472 -103.9169) (xy 258.431687 -103.886973) (xy 258.229976 -103.849146) (xy 258.029894 -103.803479)
			(xy 257.831747 -103.75004) (xy 257.635835 -103.688911) (xy 257.442458 -103.620185) (xy 257.251909 -103.543966)
			(xy 257.064479 -103.46037) (xy 256.880453 -103.369526) (xy 256.700112 -103.271571) (xy 256.52373 -103.166654)
			(xy 256.351576 -103.054935) (xy 256.183911 -102.936585) (xy 256.020992 -102.811783) (xy 255.863066 -102.680719)
			(xy 255.710374 -102.543594) (xy 255.563149 -102.400616) (xy 255.421614 -102.252002) (xy 255.285985 -102.09798)
			(xy 255.156468 -101.938783) (xy 255.033262 -101.774654) (xy 254.916553 -101.605843) (xy 254.806519 -101.432606)
			(xy 254.703328 -101.255209) (xy 254.607137 -101.073921) (xy 254.518092 -100.889018) (xy 254.436329 -100.700781)
			(xy 254.361973 -100.509498) (xy 254.295137 -100.315459) (xy 254.235922 -100.11896) (xy 254.184419 -99.920301)
			(xy 254.140705 -99.719783) (xy 254.104849 -99.517712) (xy 254.076904 -99.314397) (xy 254.056913 -99.110146)
			(xy 254.044906 -98.90527) (xy 254.040902 -98.700082) (xy 213.558628 -98.700082) (xy 213.558127 -98.802696)
			(xy 213.55012 -99.007766) (xy 213.534118 -99.212369) (xy 213.510145 -99.416191) (xy 213.478238 -99.618923)
			(xy 213.438446 -99.820255) (xy 213.390829 -100.019882) (xy 213.335459 -100.217498) (xy 213.272422 -100.412804)
			(xy 213.201812 -100.605502) (xy 213.123738 -100.795298) (xy 213.038318 -100.981904) (xy 212.945682 -101.165034)
			(xy 212.845972 -101.344411) (xy 212.739339 -101.519761) (xy 212.625946 -101.690817) (xy 212.505966 -101.857319)
			(xy 212.37958 -102.019013) (xy 212.246982 -102.175653) (xy 212.108374 -102.326999) (xy 211.963966 -102.472823)
			(xy 211.813979 -102.612902) (xy 211.65864 -102.747021) (xy 211.498187 -102.874978) (xy 211.332864 -102.996578)
			(xy 211.162922 -103.111634) (xy 210.988621 -103.219973) (xy 210.810225 -103.321428) (xy 210.628007 -103.415846)
			(xy 210.442244 -103.503082) (xy 210.253219 -103.583005) (xy 210.061219 -103.655491) (xy 209.866537 -103.720431)
			(xy 209.66947 -103.777726) (xy 209.470317 -103.827289) (xy 209.269383 -103.869044) (xy 209.066972 -103.902927)
			(xy 208.863394 -103.928887) (xy 208.658957 -103.946884) (xy 208.453974 -103.956892) (xy 208.248757 -103.958894)
			(xy 208.043618 -103.952888) (xy 207.838869 -103.938883) (xy 207.634822 -103.9169) (xy 207.431789 -103.886973)
			(xy 207.230078 -103.849146) (xy 207.029996 -103.803479) (xy 206.831849 -103.75004) (xy 206.635937 -103.688911)
			(xy 206.44256 -103.620185) (xy 206.252011 -103.543966) (xy 206.064581 -103.46037) (xy 205.880555 -103.369526)
			(xy 205.700214 -103.271571) (xy 205.523832 -103.166654) (xy 205.351678 -103.054935) (xy 205.184013 -102.936585)
			(xy 205.021094 -102.811783) (xy 204.863168 -102.680719) (xy 204.710476 -102.543594) (xy 204.563251 -102.400616)
			(xy 204.421716 -102.252002) (xy 204.286087 -102.09798) (xy 204.15657 -101.938783) (xy 204.033364 -101.774654)
			(xy 203.916655 -101.605843) (xy 203.806621 -101.432606) (xy 203.70343 -101.255209) (xy 203.607239 -101.073921)
			(xy 203.518194 -100.889018) (xy 203.436431 -100.700781) (xy 203.362075 -100.509498) (xy 203.295239 -100.315459)
			(xy 203.236024 -100.11896) (xy 203.184521 -99.920301) (xy 203.140807 -99.719783) (xy 203.104951 -99.517712)
			(xy 203.077006 -99.314397) (xy 203.057015 -99.110146) (xy 203.045008 -98.90527) (xy 203.041004 -98.700082)
			(xy 5.324094 -98.700082) (xy 5.324094 -100.177854) (xy 37.31006 -100.177854) (xy 37.31006 -99.314254)
			(xy 37.31055 -99.284286) (xy 37.318373 -99.224864) (xy 37.333886 -99.166971) (xy 37.356822 -99.111598)
			(xy 37.386789 -99.059692) (xy 37.423276 -99.012142) (xy 37.465656 -98.969762) (xy 37.513206 -98.933275)
			(xy 37.565112 -98.903308) (xy 37.620485 -98.880372) (xy 37.678378 -98.864859) (xy 37.7378 -98.857036)
			(xy 37.797736 -98.857036) (xy 37.857158 -98.864859) (xy 37.915051 -98.880372) (xy 37.970424 -98.903308)
			(xy 38.02233 -98.933275) (xy 38.06988 -98.969762) (xy 38.11226 -99.012142) (xy 38.148747 -99.059692)
			(xy 38.178714 -99.111598) (xy 38.20165 -99.166971) (xy 38.217163 -99.224864) (xy 38.224986 -99.284286)
			(xy 38.225476 -99.314254) (xy 38.225476 -100.17633) (xy 53.639212 -100.17633) (xy 53.639212 -99.31273)
			(xy 53.639702 -99.282762) (xy 53.647525 -99.22334) (xy 53.663038 -99.165447) (xy 53.685974 -99.110074)
			(xy 53.715941 -99.058168) (xy 53.752428 -99.010618) (xy 53.794808 -98.968238) (xy 53.842358 -98.931751)
			(xy 53.894264 -98.901784) (xy 53.949637 -98.878848) (xy 54.00753 -98.863335) (xy 54.066952 -98.855512)
			(xy 54.126888 -98.855512) (xy 54.18631 -98.863335) (xy 54.244203 -98.878848) (xy 54.299576 -98.901784)
			(xy 54.351482 -98.931751) (xy 54.399032 -98.968238) (xy 54.441412 -99.010618) (xy 54.477899 -99.058168)
			(xy 54.507866 -99.110074) (xy 54.530802 -99.165447) (xy 54.546315 -99.22334) (xy 54.554138 -99.282762)
			(xy 54.554628 -99.31273) (xy 54.554628 -100.17633) (xy 54.554603 -100.177854) (xy 153.409904 -100.177854)
			(xy 153.409904 -99.314254) (xy 153.410394 -99.28427) (xy 153.418222 -99.224814) (xy 153.433743 -99.166889)
			(xy 153.456692 -99.111485) (xy 153.486676 -99.059551) (xy 153.523182 -99.011975) (xy 153.565587 -98.96957)
			(xy 153.613163 -98.933064) (xy 153.665097 -98.90308) (xy 153.720501 -98.880131) (xy 153.778426 -98.86461)
			(xy 153.837882 -98.856782) (xy 153.89785 -98.856782) (xy 153.957306 -98.86461) (xy 154.015231 -98.880131)
			(xy 154.070635 -98.90308) (xy 154.122569 -98.933064) (xy 154.170145 -98.96957) (xy 154.21255 -99.011975)
			(xy 154.249056 -99.059551) (xy 154.27904 -99.111485) (xy 154.301989 -99.166889) (xy 154.31751 -99.224814)
			(xy 154.325338 -99.28427) (xy 154.325828 -99.314254) (xy 154.325828 -100.17633) (xy 169.739056 -100.17633)
			(xy 169.739056 -99.31273) (xy 169.739546 -99.282746) (xy 169.747374 -99.22329) (xy 169.762895 -99.165365)
			(xy 169.785844 -99.109961) (xy 169.815828 -99.058027) (xy 169.852334 -99.010451) (xy 169.894739 -98.968046)
			(xy 169.942315 -98.93154) (xy 169.994249 -98.901556) (xy 170.049653 -98.878607) (xy 170.107578 -98.863086)
			(xy 170.167034 -98.855258) (xy 170.227002 -98.855258) (xy 170.286458 -98.863086) (xy 170.344383 -98.878607)
			(xy 170.399787 -98.901556) (xy 170.451721 -98.93154) (xy 170.499297 -98.968046) (xy 170.541702 -99.010451)
			(xy 170.578208 -99.058027) (xy 170.608192 -99.109961) (xy 170.631141 -99.165365) (xy 170.646662 -99.22329)
			(xy 170.65449 -99.282746) (xy 170.65498 -99.31273) (xy 170.65498 -100.17633) (xy 170.65449 -100.206314)
			(xy 170.646662 -100.26577) (xy 170.631141 -100.323695) (xy 170.608192 -100.379099) (xy 170.578208 -100.431033)
			(xy 170.541702 -100.478609) (xy 170.499297 -100.521014) (xy 170.451721 -100.55752) (xy 170.399787 -100.587504)
			(xy 170.344383 -100.610453) (xy 170.286458 -100.625974) (xy 170.227002 -100.633802) (xy 170.167034 -100.633802)
			(xy 170.107578 -100.625974) (xy 170.049653 -100.610453) (xy 169.994249 -100.587504) (xy 169.942315 -100.55752)
			(xy 169.894739 -100.521014) (xy 169.852334 -100.478609) (xy 169.815828 -100.431033) (xy 169.785844 -100.379099)
			(xy 169.762895 -100.323695) (xy 169.747374 -100.26577) (xy 169.739546 -100.206314) (xy 169.739056 -100.17633)
			(xy 154.325828 -100.17633) (xy 154.325828 -100.177854) (xy 154.325338 -100.207838) (xy 154.31751 -100.267294)
			(xy 154.301989 -100.325219) (xy 154.27904 -100.380623) (xy 154.249056 -100.432557) (xy 154.21255 -100.480133)
			(xy 154.170145 -100.522538) (xy 154.122569 -100.559044) (xy 154.070635 -100.589028) (xy 154.015231 -100.611977)
			(xy 153.957306 -100.627498) (xy 153.89785 -100.635326) (xy 153.837882 -100.635326) (xy 153.778426 -100.627498)
			(xy 153.720501 -100.611977) (xy 153.665097 -100.589028) (xy 153.613163 -100.559044) (xy 153.565587 -100.522538)
			(xy 153.523182 -100.480133) (xy 153.486676 -100.432557) (xy 153.456692 -100.380623) (xy 153.433743 -100.325219)
			(xy 153.418222 -100.267294) (xy 153.410394 -100.207838) (xy 153.409904 -100.177854) (xy 54.554603 -100.177854)
			(xy 54.554138 -100.206298) (xy 54.546315 -100.26572) (xy 54.530802 -100.323613) (xy 54.507866 -100.378986)
			(xy 54.477899 -100.430892) (xy 54.441412 -100.478442) (xy 54.399032 -100.520822) (xy 54.351482 -100.557309)
			(xy 54.299576 -100.587276) (xy 54.244203 -100.610212) (xy 54.18631 -100.625725) (xy 54.126888 -100.633548)
			(xy 54.066952 -100.633548) (xy 54.00753 -100.625725) (xy 53.949637 -100.610212) (xy 53.894264 -100.587276)
			(xy 53.842358 -100.557309) (xy 53.794808 -100.520822) (xy 53.752428 -100.478442) (xy 53.715941 -100.430892)
			(xy 53.685974 -100.378986) (xy 53.663038 -100.323613) (xy 53.647525 -100.26572) (xy 53.639702 -100.206298)
			(xy 53.639212 -100.17633) (xy 38.225476 -100.17633) (xy 38.225476 -100.177854) (xy 38.224986 -100.207822)
			(xy 38.217163 -100.267244) (xy 38.20165 -100.325137) (xy 38.178714 -100.38051) (xy 38.148747 -100.432416)
			(xy 38.11226 -100.479966) (xy 38.06988 -100.522346) (xy 38.02233 -100.558833) (xy 37.970424 -100.5888)
			(xy 37.915051 -100.611736) (xy 37.857158 -100.627249) (xy 37.797736 -100.635072) (xy 37.7378 -100.635072)
			(xy 37.678378 -100.627249) (xy 37.620485 -100.611736) (xy 37.565112 -100.5888) (xy 37.513206 -100.558833)
			(xy 37.465656 -100.522346) (xy 37.423276 -100.479966) (xy 37.386789 -100.432416) (xy 37.356822 -100.38051)
			(xy 37.333886 -100.325137) (xy 37.318373 -100.267244) (xy 37.31055 -100.207822) (xy 37.31006 -100.177854)
			(xy 5.324094 -100.177854) (xy 5.324094 -101.984302) (xy 35.277552 -101.984302) (xy 35.277552 -101.120702)
			(xy 35.278042 -101.090734) (xy 35.285865 -101.031312) (xy 35.301378 -100.973419) (xy 35.324314 -100.918046)
			(xy 35.354281 -100.86614) (xy 35.390768 -100.81859) (xy 35.433148 -100.77621) (xy 35.480698 -100.739723)
			(xy 35.532604 -100.709756) (xy 35.587977 -100.68682) (xy 35.64587 -100.671307) (xy 35.705292 -100.663484)
			(xy 35.765228 -100.663484) (xy 35.82465 -100.671307) (xy 35.882543 -100.68682) (xy 35.937916 -100.709756)
			(xy 35.989822 -100.739723) (xy 36.037372 -100.77621) (xy 36.079752 -100.81859) (xy 36.116239 -100.86614)
			(xy 36.146206 -100.918046) (xy 36.169142 -100.973419) (xy 36.184655 -101.031312) (xy 36.192478 -101.090734)
			(xy 36.192968 -101.120702) (xy 36.192968 -101.976428) (xy 51.785012 -101.976428) (xy 51.785012 -101.112828)
			(xy 51.785502 -101.08286) (xy 51.793325 -101.023438) (xy 51.808838 -100.965545) (xy 51.831774 -100.910172)
			(xy 51.861741 -100.858266) (xy 51.898228 -100.810716) (xy 51.940608 -100.768336) (xy 51.988158 -100.731849)
			(xy 52.040064 -100.701882) (xy 52.095437 -100.678946) (xy 52.15333 -100.663433) (xy 52.212752 -100.65561)
			(xy 52.272688 -100.65561) (xy 52.33211 -100.663433) (xy 52.390003 -100.678946) (xy 52.445376 -100.701882)
			(xy 52.497282 -100.731849) (xy 52.544832 -100.768336) (xy 52.587212 -100.810716) (xy 52.623699 -100.858266)
			(xy 52.653666 -100.910172) (xy 52.676602 -100.965545) (xy 52.692115 -101.023438) (xy 52.699938 -101.08286)
			(xy 52.700428 -101.112828) (xy 52.700428 -101.976428) (xy 52.700299 -101.984302) (xy 151.377396 -101.984302)
			(xy 151.377396 -101.120702) (xy 151.377886 -101.090718) (xy 151.385714 -101.031262) (xy 151.401235 -100.973337)
			(xy 151.424184 -100.917933) (xy 151.454168 -100.865999) (xy 151.490674 -100.818423) (xy 151.533079 -100.776018)
			(xy 151.580655 -100.739512) (xy 151.632589 -100.709528) (xy 151.687993 -100.686579) (xy 151.745918 -100.671058)
			(xy 151.805374 -100.66323) (xy 151.865342 -100.66323) (xy 151.924798 -100.671058) (xy 151.982723 -100.686579)
			(xy 152.038127 -100.709528) (xy 152.090061 -100.739512) (xy 152.137637 -100.776018) (xy 152.180042 -100.818423)
			(xy 152.216548 -100.865999) (xy 152.246532 -100.917933) (xy 152.269481 -100.973337) (xy 152.285002 -101.031262)
			(xy 152.29283 -101.090718) (xy 152.29332 -101.120702) (xy 152.29332 -101.976428) (xy 167.884856 -101.976428)
			(xy 167.884856 -101.112828) (xy 167.885346 -101.082844) (xy 167.893174 -101.023388) (xy 167.908695 -100.965463)
			(xy 167.931644 -100.910059) (xy 167.961628 -100.858125) (xy 167.998134 -100.810549) (xy 168.040539 -100.768144)
			(xy 168.088115 -100.731638) (xy 168.140049 -100.701654) (xy 168.195453 -100.678705) (xy 168.253378 -100.663184)
			(xy 168.312834 -100.655356) (xy 168.372802 -100.655356) (xy 168.432258 -100.663184) (xy 168.490183 -100.678705)
			(xy 168.545587 -100.701654) (xy 168.597521 -100.731638) (xy 168.645097 -100.768144) (xy 168.687502 -100.810549)
			(xy 168.724008 -100.858125) (xy 168.753992 -100.910059) (xy 168.776941 -100.965463) (xy 168.792462 -101.023388)
			(xy 168.80029 -101.082844) (xy 168.80078 -101.112828) (xy 168.80078 -101.976428) (xy 168.80029 -102.006412)
			(xy 168.792462 -102.065868) (xy 168.776941 -102.123793) (xy 168.753992 -102.179197) (xy 168.724008 -102.231131)
			(xy 168.687502 -102.278707) (xy 168.645097 -102.321112) (xy 168.597521 -102.357618) (xy 168.545587 -102.387602)
			(xy 168.490183 -102.410551) (xy 168.432258 -102.426072) (xy 168.372802 -102.4339) (xy 168.312834 -102.4339)
			(xy 168.253378 -102.426072) (xy 168.195453 -102.410551) (xy 168.140049 -102.387602) (xy 168.088115 -102.357618)
			(xy 168.040539 -102.321112) (xy 167.998134 -102.278707) (xy 167.961628 -102.231131) (xy 167.931644 -102.179197)
			(xy 167.908695 -102.123793) (xy 167.893174 -102.065868) (xy 167.885346 -102.006412) (xy 167.884856 -101.976428)
			(xy 152.29332 -101.976428) (xy 152.29332 -101.984302) (xy 152.29283 -102.014286) (xy 152.285002 -102.073742)
			(xy 152.269481 -102.131667) (xy 152.246532 -102.187071) (xy 152.216548 -102.239005) (xy 152.180042 -102.286581)
			(xy 152.137637 -102.328986) (xy 152.090061 -102.365492) (xy 152.038127 -102.395476) (xy 151.982723 -102.418425)
			(xy 151.924798 -102.433946) (xy 151.865342 -102.441774) (xy 151.805374 -102.441774) (xy 151.745918 -102.433946)
			(xy 151.687993 -102.418425) (xy 151.632589 -102.395476) (xy 151.580655 -102.365492) (xy 151.533079 -102.328986)
			(xy 151.490674 -102.286581) (xy 151.454168 -102.239005) (xy 151.424184 -102.187071) (xy 151.401235 -102.131667)
			(xy 151.385714 -102.073742) (xy 151.377886 -102.014286) (xy 151.377396 -101.984302) (xy 52.700299 -101.984302)
			(xy 52.699938 -102.006396) (xy 52.692115 -102.065818) (xy 52.676602 -102.123711) (xy 52.653666 -102.179084)
			(xy 52.623699 -102.23099) (xy 52.587212 -102.27854) (xy 52.544832 -102.32092) (xy 52.497282 -102.357407)
			(xy 52.445376 -102.387374) (xy 52.390003 -102.41031) (xy 52.33211 -102.425823) (xy 52.272688 -102.433646)
			(xy 52.212752 -102.433646) (xy 52.15333 -102.425823) (xy 52.095437 -102.41031) (xy 52.040064 -102.387374)
			(xy 51.988158 -102.357407) (xy 51.940608 -102.32092) (xy 51.898228 -102.27854) (xy 51.861741 -102.23099)
			(xy 51.831774 -102.179084) (xy 51.808838 -102.123711) (xy 51.793325 -102.065818) (xy 51.785502 -102.006396)
			(xy 51.785012 -101.976428) (xy 36.192968 -101.976428) (xy 36.192968 -101.984302) (xy 36.192478 -102.01427)
			(xy 36.184655 -102.073692) (xy 36.169142 -102.131585) (xy 36.146206 -102.186958) (xy 36.116239 -102.238864)
			(xy 36.079752 -102.286414) (xy 36.037372 -102.328794) (xy 35.989822 -102.365281) (xy 35.937916 -102.395248)
			(xy 35.882543 -102.418184) (xy 35.82465 -102.433697) (xy 35.765228 -102.44152) (xy 35.705292 -102.44152)
			(xy 35.64587 -102.433697) (xy 35.587977 -102.418184) (xy 35.532604 -102.395248) (xy 35.480698 -102.365281)
			(xy 35.433148 -102.328794) (xy 35.390768 -102.286414) (xy 35.354281 -102.238864) (xy 35.324314 -102.186958)
			(xy 35.301378 -102.131585) (xy 35.285865 -102.073692) (xy 35.278042 -102.01427) (xy 35.277552 -101.984302)
			(xy 5.324094 -101.984302) (xy 5.324094 -103.777796) (xy 37.31006 -103.777796) (xy 37.31006 -102.914196)
			(xy 37.31055 -102.884228) (xy 37.318373 -102.824806) (xy 37.333886 -102.766913) (xy 37.356822 -102.71154)
			(xy 37.386789 -102.659634) (xy 37.423276 -102.612084) (xy 37.465656 -102.569704) (xy 37.513206 -102.533217)
			(xy 37.565112 -102.50325) (xy 37.620485 -102.480314) (xy 37.678378 -102.464801) (xy 37.7378 -102.456978)
			(xy 37.797736 -102.456978) (xy 37.857158 -102.464801) (xy 37.915051 -102.480314) (xy 37.970424 -102.50325)
			(xy 38.02233 -102.533217) (xy 38.06988 -102.569704) (xy 38.11226 -102.612084) (xy 38.148747 -102.659634)
			(xy 38.178714 -102.71154) (xy 38.20165 -102.766913) (xy 38.217163 -102.824806) (xy 38.224986 -102.884228)
			(xy 38.225476 -102.914196) (xy 38.225476 -103.776272) (xy 53.639212 -103.776272) (xy 53.639212 -102.912672)
			(xy 53.639702 -102.882704) (xy 53.647525 -102.823282) (xy 53.663038 -102.765389) (xy 53.685974 -102.710016)
			(xy 53.715941 -102.65811) (xy 53.752428 -102.61056) (xy 53.794808 -102.56818) (xy 53.842358 -102.531693)
			(xy 53.894264 -102.501726) (xy 53.949637 -102.47879) (xy 54.00753 -102.463277) (xy 54.066952 -102.455454)
			(xy 54.126888 -102.455454) (xy 54.18631 -102.463277) (xy 54.244203 -102.47879) (xy 54.299576 -102.501726)
			(xy 54.351482 -102.531693) (xy 54.399032 -102.56818) (xy 54.441412 -102.61056) (xy 54.477899 -102.65811)
			(xy 54.507866 -102.710016) (xy 54.530802 -102.765389) (xy 54.546315 -102.823282) (xy 54.554138 -102.882704)
			(xy 54.554628 -102.912672) (xy 54.554628 -103.776272) (xy 54.554603 -103.777796) (xy 153.409904 -103.777796)
			(xy 153.409904 -102.914196) (xy 153.410394 -102.884212) (xy 153.418222 -102.824756) (xy 153.433743 -102.766831)
			(xy 153.456692 -102.711427) (xy 153.486676 -102.659493) (xy 153.523182 -102.611917) (xy 153.565587 -102.569512)
			(xy 153.613163 -102.533006) (xy 153.665097 -102.503022) (xy 153.720501 -102.480073) (xy 153.778426 -102.464552)
			(xy 153.837882 -102.456724) (xy 153.89785 -102.456724) (xy 153.957306 -102.464552) (xy 154.015231 -102.480073)
			(xy 154.070635 -102.503022) (xy 154.122569 -102.533006) (xy 154.170145 -102.569512) (xy 154.21255 -102.611917)
			(xy 154.249056 -102.659493) (xy 154.27904 -102.711427) (xy 154.301989 -102.766831) (xy 154.31751 -102.824756)
			(xy 154.325338 -102.884212) (xy 154.325828 -102.914196) (xy 154.325828 -103.776272) (xy 169.739056 -103.776272)
			(xy 169.739056 -102.912672) (xy 169.739546 -102.882688) (xy 169.747374 -102.823232) (xy 169.762895 -102.765307)
			(xy 169.785844 -102.709903) (xy 169.815828 -102.657969) (xy 169.852334 -102.610393) (xy 169.894739 -102.567988)
			(xy 169.942315 -102.531482) (xy 169.994249 -102.501498) (xy 170.049653 -102.478549) (xy 170.107578 -102.463028)
			(xy 170.167034 -102.4552) (xy 170.227002 -102.4552) (xy 170.286458 -102.463028) (xy 170.344383 -102.478549)
			(xy 170.399787 -102.501498) (xy 170.451721 -102.531482) (xy 170.499297 -102.567988) (xy 170.541702 -102.610393)
			(xy 170.578208 -102.657969) (xy 170.608192 -102.709903) (xy 170.631141 -102.765307) (xy 170.646662 -102.823232)
			(xy 170.65449 -102.882688) (xy 170.65498 -102.912672) (xy 170.65498 -103.776272) (xy 170.65449 -103.806256)
			(xy 170.646662 -103.865712) (xy 170.631141 -103.923637) (xy 170.608192 -103.979041) (xy 170.578208 -104.030975)
			(xy 170.541702 -104.078551) (xy 170.499297 -104.120956) (xy 170.451721 -104.157462) (xy 170.399787 -104.187446)
			(xy 170.344383 -104.210395) (xy 170.286458 -104.225916) (xy 170.227002 -104.233744) (xy 170.167034 -104.233744)
			(xy 170.107578 -104.225916) (xy 170.049653 -104.210395) (xy 169.994249 -104.187446) (xy 169.942315 -104.157462)
			(xy 169.894739 -104.120956) (xy 169.852334 -104.078551) (xy 169.815828 -104.030975) (xy 169.785844 -103.979041)
			(xy 169.762895 -103.923637) (xy 169.747374 -103.865712) (xy 169.739546 -103.806256) (xy 169.739056 -103.776272)
			(xy 154.325828 -103.776272) (xy 154.325828 -103.777796) (xy 154.325338 -103.80778) (xy 154.31751 -103.867236)
			(xy 154.301989 -103.925161) (xy 154.27904 -103.980565) (xy 154.249056 -104.032499) (xy 154.21255 -104.080075)
			(xy 154.170145 -104.12248) (xy 154.122569 -104.158986) (xy 154.070635 -104.18897) (xy 154.015231 -104.211919)
			(xy 153.957306 -104.22744) (xy 153.89785 -104.235268) (xy 153.837882 -104.235268) (xy 153.778426 -104.22744)
			(xy 153.720501 -104.211919) (xy 153.665097 -104.18897) (xy 153.613163 -104.158986) (xy 153.565587 -104.12248)
			(xy 153.523182 -104.080075) (xy 153.486676 -104.032499) (xy 153.456692 -103.980565) (xy 153.433743 -103.925161)
			(xy 153.418222 -103.867236) (xy 153.410394 -103.80778) (xy 153.409904 -103.777796) (xy 54.554603 -103.777796)
			(xy 54.554138 -103.80624) (xy 54.546315 -103.865662) (xy 54.530802 -103.923555) (xy 54.507866 -103.978928)
			(xy 54.477899 -104.030834) (xy 54.441412 -104.078384) (xy 54.399032 -104.120764) (xy 54.351482 -104.157251)
			(xy 54.299576 -104.187218) (xy 54.244203 -104.210154) (xy 54.18631 -104.225667) (xy 54.126888 -104.23349)
			(xy 54.066952 -104.23349) (xy 54.00753 -104.225667) (xy 53.949637 -104.210154) (xy 53.894264 -104.187218)
			(xy 53.842358 -104.157251) (xy 53.794808 -104.120764) (xy 53.752428 -104.078384) (xy 53.715941 -104.030834)
			(xy 53.685974 -103.978928) (xy 53.663038 -103.923555) (xy 53.647525 -103.865662) (xy 53.639702 -103.80624)
			(xy 53.639212 -103.776272) (xy 38.225476 -103.776272) (xy 38.225476 -103.777796) (xy 38.224986 -103.807764)
			(xy 38.217163 -103.867186) (xy 38.20165 -103.925079) (xy 38.178714 -103.980452) (xy 38.148747 -104.032358)
			(xy 38.11226 -104.079908) (xy 38.06988 -104.122288) (xy 38.02233 -104.158775) (xy 37.970424 -104.188742)
			(xy 37.915051 -104.211678) (xy 37.857158 -104.227191) (xy 37.797736 -104.235014) (xy 37.7378 -104.235014)
			(xy 37.678378 -104.227191) (xy 37.620485 -104.211678) (xy 37.565112 -104.188742) (xy 37.513206 -104.158775)
			(xy 37.465656 -104.122288) (xy 37.423276 -104.079908) (xy 37.386789 -104.032358) (xy 37.356822 -103.980452)
			(xy 37.333886 -103.925079) (xy 37.318373 -103.867186) (xy 37.31055 -103.807764) (xy 37.31006 -103.777796)
			(xy 5.324094 -103.777796) (xy 5.324094 -105.584498) (xy 34.667952 -105.584498) (xy 34.667952 -104.720898)
			(xy 34.668442 -104.69093) (xy 34.676265 -104.631508) (xy 34.691778 -104.573615) (xy 34.714714 -104.518242)
			(xy 34.744681 -104.466336) (xy 34.781168 -104.418786) (xy 34.823548 -104.376406) (xy 34.871098 -104.339919)
			(xy 34.923004 -104.309952) (xy 34.978377 -104.287016) (xy 35.03627 -104.271503) (xy 35.095692 -104.26368)
			(xy 35.155628 -104.26368) (xy 35.21505 -104.271503) (xy 35.272943 -104.287016) (xy 35.328316 -104.309952)
			(xy 35.380222 -104.339919) (xy 35.427772 -104.376406) (xy 35.470152 -104.418786) (xy 35.506639 -104.466336)
			(xy 35.536606 -104.518242) (xy 35.559542 -104.573615) (xy 35.575055 -104.631508) (xy 35.582878 -104.69093)
			(xy 35.583368 -104.720898) (xy 35.583368 -105.57637) (xy 51.785012 -105.57637) (xy 51.785012 -104.71277)
			(xy 51.785502 -104.682802) (xy 51.793325 -104.62338) (xy 51.808838 -104.565487) (xy 51.831774 -104.510114)
			(xy 51.861741 -104.458208) (xy 51.898228 -104.410658) (xy 51.940608 -104.368278) (xy 51.988158 -104.331791)
			(xy 52.040064 -104.301824) (xy 52.095437 -104.278888) (xy 52.15333 -104.263375) (xy 52.212752 -104.255552)
			(xy 52.272688 -104.255552) (xy 52.33211 -104.263375) (xy 52.390003 -104.278888) (xy 52.445376 -104.301824)
			(xy 52.497282 -104.331791) (xy 52.544832 -104.368278) (xy 52.587212 -104.410658) (xy 52.623699 -104.458208)
			(xy 52.653666 -104.510114) (xy 52.676602 -104.565487) (xy 52.692115 -104.62338) (xy 52.699938 -104.682802)
			(xy 52.700428 -104.71277) (xy 52.700428 -105.57637) (xy 52.700295 -105.584498) (xy 150.767796 -105.584498)
			(xy 150.767796 -104.720898) (xy 150.768286 -104.690914) (xy 150.776114 -104.631458) (xy 150.791635 -104.573533)
			(xy 150.814584 -104.518129) (xy 150.844568 -104.466195) (xy 150.881074 -104.418619) (xy 150.923479 -104.376214)
			(xy 150.971055 -104.339708) (xy 151.022989 -104.309724) (xy 151.078393 -104.286775) (xy 151.136318 -104.271254)
			(xy 151.195774 -104.263426) (xy 151.255742 -104.263426) (xy 151.315198 -104.271254) (xy 151.373123 -104.286775)
			(xy 151.428527 -104.309724) (xy 151.480461 -104.339708) (xy 151.528037 -104.376214) (xy 151.570442 -104.418619)
			(xy 151.606948 -104.466195) (xy 151.636932 -104.518129) (xy 151.659881 -104.573533) (xy 151.675402 -104.631458)
			(xy 151.68323 -104.690914) (xy 151.68372 -104.720898) (xy 151.68372 -105.57637) (xy 167.884856 -105.57637)
			(xy 167.884856 -104.71277) (xy 167.885346 -104.682786) (xy 167.893174 -104.62333) (xy 167.908695 -104.565405)
			(xy 167.931644 -104.510001) (xy 167.961628 -104.458067) (xy 167.998134 -104.410491) (xy 168.040539 -104.368086)
			(xy 168.088115 -104.33158) (xy 168.140049 -104.301596) (xy 168.195453 -104.278647) (xy 168.253378 -104.263126)
			(xy 168.312834 -104.255298) (xy 168.372802 -104.255298) (xy 168.432258 -104.263126) (xy 168.490183 -104.278647)
			(xy 168.545587 -104.301596) (xy 168.597521 -104.33158) (xy 168.645097 -104.368086) (xy 168.687502 -104.410491)
			(xy 168.724008 -104.458067) (xy 168.753992 -104.510001) (xy 168.776941 -104.565405) (xy 168.792462 -104.62333)
			(xy 168.80029 -104.682786) (xy 168.80078 -104.71277) (xy 168.80078 -105.57637) (xy 168.800647 -105.584498)
			(xy 266.86764 -105.584498) (xy 266.86764 -104.720898) (xy 266.86813 -104.690914) (xy 266.875958 -104.631458)
			(xy 266.891479 -104.573533) (xy 266.914428 -104.518129) (xy 266.944412 -104.466195) (xy 266.980918 -104.418619)
			(xy 267.023323 -104.376214) (xy 267.070899 -104.339708) (xy 267.122833 -104.309724) (xy 267.178237 -104.286775)
			(xy 267.236162 -104.271254) (xy 267.295618 -104.263426) (xy 267.355586 -104.263426) (xy 267.415042 -104.271254)
			(xy 267.472967 -104.286775) (xy 267.528371 -104.309724) (xy 267.580305 -104.339708) (xy 267.627881 -104.376214)
			(xy 267.670286 -104.418619) (xy 267.706792 -104.466195) (xy 267.736776 -104.518129) (xy 267.759725 -104.573533)
			(xy 267.775246 -104.631458) (xy 267.783074 -104.690914) (xy 267.783564 -104.720898) (xy 267.783564 -105.57637)
			(xy 283.9847 -105.57637) (xy 283.9847 -104.71277) (xy 283.98519 -104.682786) (xy 283.993018 -104.62333)
			(xy 284.008539 -104.565405) (xy 284.031488 -104.510001) (xy 284.061472 -104.458067) (xy 284.097978 -104.410491)
			(xy 284.140383 -104.368086) (xy 284.187959 -104.33158) (xy 284.239893 -104.301596) (xy 284.295297 -104.278647)
			(xy 284.353222 -104.263126) (xy 284.412678 -104.255298) (xy 284.472646 -104.255298) (xy 284.532102 -104.263126)
			(xy 284.590027 -104.278647) (xy 284.645431 -104.301596) (xy 284.697365 -104.33158) (xy 284.744941 -104.368086)
			(xy 284.787346 -104.410491) (xy 284.823852 -104.458067) (xy 284.853836 -104.510001) (xy 284.876785 -104.565405)
			(xy 284.892306 -104.62333) (xy 284.900134 -104.682786) (xy 284.900624 -104.71277) (xy 284.900624 -105.57637)
			(xy 284.900491 -105.584498) (xy 382.967992 -105.584498) (xy 382.967992 -104.720898) (xy 382.968482 -104.69093)
			(xy 382.976305 -104.631508) (xy 382.991818 -104.573615) (xy 383.014754 -104.518242) (xy 383.044721 -104.466336)
			(xy 383.081208 -104.418786) (xy 383.123588 -104.376406) (xy 383.171138 -104.339919) (xy 383.223044 -104.309952)
			(xy 383.278417 -104.287016) (xy 383.33631 -104.271503) (xy 383.395732 -104.26368) (xy 383.455668 -104.26368)
			(xy 383.51509 -104.271503) (xy 383.572983 -104.287016) (xy 383.628356 -104.309952) (xy 383.680262 -104.339919)
			(xy 383.727812 -104.376406) (xy 383.770192 -104.418786) (xy 383.806679 -104.466336) (xy 383.836646 -104.518242)
			(xy 383.859582 -104.573615) (xy 383.875095 -104.631508) (xy 383.882918 -104.69093) (xy 383.883408 -104.720898)
			(xy 383.883408 -105.57637) (xy 400.085052 -105.57637) (xy 400.085052 -104.71277) (xy 400.085542 -104.682802)
			(xy 400.093365 -104.62338) (xy 400.108878 -104.565487) (xy 400.131814 -104.510114) (xy 400.161781 -104.458208)
			(xy 400.198268 -104.410658) (xy 400.240648 -104.368278) (xy 400.288198 -104.331791) (xy 400.340104 -104.301824)
			(xy 400.395477 -104.278888) (xy 400.45337 -104.263375) (xy 400.512792 -104.255552) (xy 400.572728 -104.255552)
			(xy 400.63215 -104.263375) (xy 400.690043 -104.278888) (xy 400.745416 -104.301824) (xy 400.797322 -104.331791)
			(xy 400.844872 -104.368278) (xy 400.887252 -104.410658) (xy 400.923739 -104.458208) (xy 400.953706 -104.510114)
			(xy 400.976642 -104.565487) (xy 400.992155 -104.62338) (xy 400.999978 -104.682802) (xy 401.000468 -104.71277)
			(xy 401.000468 -105.57637) (xy 400.999978 -105.606338) (xy 400.992155 -105.66576) (xy 400.976642 -105.723653)
			(xy 400.953706 -105.779026) (xy 400.923739 -105.830932) (xy 400.887252 -105.878482) (xy 400.844872 -105.920862)
			(xy 400.797322 -105.957349) (xy 400.745416 -105.987316) (xy 400.690043 -106.010252) (xy 400.63215 -106.025765)
			(xy 400.572728 -106.033588) (xy 400.512792 -106.033588) (xy 400.45337 -106.025765) (xy 400.395477 -106.010252)
			(xy 400.340104 -105.987316) (xy 400.288198 -105.957349) (xy 400.240648 -105.920862) (xy 400.198268 -105.878482)
			(xy 400.161781 -105.830932) (xy 400.131814 -105.779026) (xy 400.108878 -105.723653) (xy 400.093365 -105.66576)
			(xy 400.085542 -105.606338) (xy 400.085052 -105.57637) (xy 383.883408 -105.57637) (xy 383.883408 -105.584498)
			(xy 383.882918 -105.614466) (xy 383.875095 -105.673888) (xy 383.859582 -105.731781) (xy 383.836646 -105.787154)
			(xy 383.806679 -105.83906) (xy 383.770192 -105.88661) (xy 383.727812 -105.92899) (xy 383.680262 -105.965477)
			(xy 383.628356 -105.995444) (xy 383.572983 -106.01838) (xy 383.51509 -106.033893) (xy 383.455668 -106.041716)
			(xy 383.395732 -106.041716) (xy 383.33631 -106.033893) (xy 383.278417 -106.01838) (xy 383.223044 -105.995444)
			(xy 383.171138 -105.965477) (xy 383.123588 -105.92899) (xy 383.081208 -105.88661) (xy 383.044721 -105.83906)
			(xy 383.014754 -105.787154) (xy 382.991818 -105.731781) (xy 382.976305 -105.673888) (xy 382.968482 -105.614466)
			(xy 382.967992 -105.584498) (xy 284.900491 -105.584498) (xy 284.900134 -105.606354) (xy 284.892306 -105.66581)
			(xy 284.876785 -105.723735) (xy 284.853836 -105.779139) (xy 284.823852 -105.831073) (xy 284.787346 -105.878649)
			(xy 284.744941 -105.921054) (xy 284.697365 -105.95756) (xy 284.645431 -105.987544) (xy 284.590027 -106.010493)
			(xy 284.532102 -106.026014) (xy 284.472646 -106.033842) (xy 284.412678 -106.033842) (xy 284.353222 -106.026014)
			(xy 284.295297 -106.010493) (xy 284.239893 -105.987544) (xy 284.187959 -105.95756) (xy 284.140383 -105.921054)
			(xy 284.097978 -105.878649) (xy 284.061472 -105.831073) (xy 284.031488 -105.779139) (xy 284.008539 -105.723735)
			(xy 283.993018 -105.66581) (xy 283.98519 -105.606354) (xy 283.9847 -105.57637) (xy 267.783564 -105.57637)
			(xy 267.783564 -105.584498) (xy 267.783074 -105.614482) (xy 267.775246 -105.673938) (xy 267.759725 -105.731863)
			(xy 267.736776 -105.787267) (xy 267.706792 -105.839201) (xy 267.670286 -105.886777) (xy 267.627881 -105.929182)
			(xy 267.580305 -105.965688) (xy 267.528371 -105.995672) (xy 267.472967 -106.018621) (xy 267.415042 -106.034142)
			(xy 267.355586 -106.04197) (xy 267.295618 -106.04197) (xy 267.236162 -106.034142) (xy 267.178237 -106.018621)
			(xy 267.122833 -105.995672) (xy 267.070899 -105.965688) (xy 267.023323 -105.929182) (xy 266.980918 -105.886777)
			(xy 266.944412 -105.839201) (xy 266.914428 -105.787267) (xy 266.891479 -105.731863) (xy 266.875958 -105.673938)
			(xy 266.86813 -105.614482) (xy 266.86764 -105.584498) (xy 168.800647 -105.584498) (xy 168.80029 -105.606354)
			(xy 168.792462 -105.66581) (xy 168.776941 -105.723735) (xy 168.753992 -105.779139) (xy 168.724008 -105.831073)
			(xy 168.687502 -105.878649) (xy 168.645097 -105.921054) (xy 168.597521 -105.95756) (xy 168.545587 -105.987544)
			(xy 168.490183 -106.010493) (xy 168.432258 -106.026014) (xy 168.372802 -106.033842) (xy 168.312834 -106.033842)
			(xy 168.253378 -106.026014) (xy 168.195453 -106.010493) (xy 168.140049 -105.987544) (xy 168.088115 -105.95756)
			(xy 168.040539 -105.921054) (xy 167.998134 -105.878649) (xy 167.961628 -105.831073) (xy 167.931644 -105.779139)
			(xy 167.908695 -105.723735) (xy 167.893174 -105.66581) (xy 167.885346 -105.606354) (xy 167.884856 -105.57637)
			(xy 151.68372 -105.57637) (xy 151.68372 -105.584498) (xy 151.68323 -105.614482) (xy 151.675402 -105.673938)
			(xy 151.659881 -105.731863) (xy 151.636932 -105.787267) (xy 151.606948 -105.839201) (xy 151.570442 -105.886777)
			(xy 151.528037 -105.929182) (xy 151.480461 -105.965688) (xy 151.428527 -105.995672) (xy 151.373123 -106.018621)
			(xy 151.315198 -106.034142) (xy 151.255742 -106.04197) (xy 151.195774 -106.04197) (xy 151.136318 -106.034142)
			(xy 151.078393 -106.018621) (xy 151.022989 -105.995672) (xy 150.971055 -105.965688) (xy 150.923479 -105.929182)
			(xy 150.881074 -105.886777) (xy 150.844568 -105.839201) (xy 150.814584 -105.787267) (xy 150.791635 -105.731863)
			(xy 150.776114 -105.673938) (xy 150.768286 -105.614482) (xy 150.767796 -105.584498) (xy 52.700295 -105.584498)
			(xy 52.699938 -105.606338) (xy 52.692115 -105.66576) (xy 52.676602 -105.723653) (xy 52.653666 -105.779026)
			(xy 52.623699 -105.830932) (xy 52.587212 -105.878482) (xy 52.544832 -105.920862) (xy 52.497282 -105.957349)
			(xy 52.445376 -105.987316) (xy 52.390003 -106.010252) (xy 52.33211 -106.025765) (xy 52.272688 -106.033588)
			(xy 52.212752 -106.033588) (xy 52.15333 -106.025765) (xy 52.095437 -106.010252) (xy 52.040064 -105.987316)
			(xy 51.988158 -105.957349) (xy 51.940608 -105.920862) (xy 51.898228 -105.878482) (xy 51.861741 -105.830932)
			(xy 51.831774 -105.779026) (xy 51.808838 -105.723653) (xy 51.793325 -105.66576) (xy 51.785502 -105.606338)
			(xy 51.785012 -105.57637) (xy 35.583368 -105.57637) (xy 35.583368 -105.584498) (xy 35.582878 -105.614466)
			(xy 35.575055 -105.673888) (xy 35.559542 -105.731781) (xy 35.536606 -105.787154) (xy 35.506639 -105.83906)
			(xy 35.470152 -105.88661) (xy 35.427772 -105.92899) (xy 35.380222 -105.965477) (xy 35.328316 -105.995444)
			(xy 35.272943 -106.01838) (xy 35.21505 -106.033893) (xy 35.155628 -106.041716) (xy 35.095692 -106.041716)
			(xy 35.03627 -106.033893) (xy 34.978377 -106.01838) (xy 34.923004 -105.995444) (xy 34.871098 -105.965477)
			(xy 34.823548 -105.92899) (xy 34.781168 -105.88661) (xy 34.744681 -105.83906) (xy 34.714714 -105.787154)
			(xy 34.691778 -105.731781) (xy 34.676265 -105.673888) (xy 34.668442 -105.614466) (xy 34.667952 -105.584498)
			(xy 5.324094 -105.584498) (xy 5.324094 -107.377738) (xy 37.31006 -107.377738) (xy 37.31006 -106.514138)
			(xy 37.31055 -106.48417) (xy 37.318373 -106.424748) (xy 37.333886 -106.366855) (xy 37.356822 -106.311482)
			(xy 37.386789 -106.259576) (xy 37.423276 -106.212026) (xy 37.465656 -106.169646) (xy 37.513206 -106.133159)
			(xy 37.565112 -106.103192) (xy 37.620485 -106.080256) (xy 37.678378 -106.064743) (xy 37.7378 -106.05692)
			(xy 37.797736 -106.05692) (xy 37.857158 -106.064743) (xy 37.915051 -106.080256) (xy 37.970424 -106.103192)
			(xy 38.02233 -106.133159) (xy 38.06988 -106.169646) (xy 38.11226 -106.212026) (xy 38.148747 -106.259576)
			(xy 38.178714 -106.311482) (xy 38.20165 -106.366855) (xy 38.217163 -106.424748) (xy 38.224986 -106.48417)
			(xy 38.225476 -106.514138) (xy 38.225476 -107.376214) (xy 53.639212 -107.376214) (xy 53.639212 -106.512614)
			(xy 53.639702 -106.482646) (xy 53.647525 -106.423224) (xy 53.663038 -106.365331) (xy 53.685974 -106.309958)
			(xy 53.715941 -106.258052) (xy 53.752428 -106.210502) (xy 53.794808 -106.168122) (xy 53.842358 -106.131635)
			(xy 53.894264 -106.101668) (xy 53.949637 -106.078732) (xy 54.00753 -106.063219) (xy 54.066952 -106.055396)
			(xy 54.126888 -106.055396) (xy 54.18631 -106.063219) (xy 54.244203 -106.078732) (xy 54.299576 -106.101668)
			(xy 54.351482 -106.131635) (xy 54.399032 -106.168122) (xy 54.441412 -106.210502) (xy 54.477899 -106.258052)
			(xy 54.507866 -106.309958) (xy 54.530802 -106.365331) (xy 54.546315 -106.423224) (xy 54.554138 -106.482646)
			(xy 54.554628 -106.512614) (xy 54.554628 -107.376214) (xy 54.554603 -107.377738) (xy 153.409904 -107.377738)
			(xy 153.409904 -106.514138) (xy 153.410394 -106.484154) (xy 153.418222 -106.424698) (xy 153.433743 -106.366773)
			(xy 153.456692 -106.311369) (xy 153.486676 -106.259435) (xy 153.523182 -106.211859) (xy 153.565587 -106.169454)
			(xy 153.613163 -106.132948) (xy 153.665097 -106.102964) (xy 153.720501 -106.080015) (xy 153.778426 -106.064494)
			(xy 153.837882 -106.056666) (xy 153.89785 -106.056666) (xy 153.957306 -106.064494) (xy 154.015231 -106.080015)
			(xy 154.070635 -106.102964) (xy 154.122569 -106.132948) (xy 154.170145 -106.169454) (xy 154.21255 -106.211859)
			(xy 154.249056 -106.259435) (xy 154.27904 -106.311369) (xy 154.301989 -106.366773) (xy 154.31751 -106.424698)
			(xy 154.325338 -106.484154) (xy 154.325828 -106.514138) (xy 154.325828 -107.376214) (xy 169.739056 -107.376214)
			(xy 169.739056 -106.512614) (xy 169.739546 -106.48263) (xy 169.747374 -106.423174) (xy 169.762895 -106.365249)
			(xy 169.785844 -106.309845) (xy 169.815828 -106.257911) (xy 169.852334 -106.210335) (xy 169.894739 -106.16793)
			(xy 169.942315 -106.131424) (xy 169.994249 -106.10144) (xy 170.049653 -106.078491) (xy 170.107578 -106.06297)
			(xy 170.167034 -106.055142) (xy 170.227002 -106.055142) (xy 170.286458 -106.06297) (xy 170.344383 -106.078491)
			(xy 170.399787 -106.10144) (xy 170.451721 -106.131424) (xy 170.499297 -106.16793) (xy 170.541702 -106.210335)
			(xy 170.578208 -106.257911) (xy 170.608192 -106.309845) (xy 170.631141 -106.365249) (xy 170.646662 -106.423174)
			(xy 170.65449 -106.48263) (xy 170.65498 -106.512614) (xy 170.65498 -107.376214) (xy 170.654955 -107.377738)
			(xy 269.509748 -107.377738) (xy 269.509748 -106.514138) (xy 269.510238 -106.484154) (xy 269.518066 -106.424698)
			(xy 269.533587 -106.366773) (xy 269.556536 -106.311369) (xy 269.58652 -106.259435) (xy 269.623026 -106.211859)
			(xy 269.665431 -106.169454) (xy 269.713007 -106.132948) (xy 269.764941 -106.102964) (xy 269.820345 -106.080015)
			(xy 269.87827 -106.064494) (xy 269.937726 -106.056666) (xy 269.997694 -106.056666) (xy 270.05715 -106.064494)
			(xy 270.115075 -106.080015) (xy 270.170479 -106.102964) (xy 270.222413 -106.132948) (xy 270.269989 -106.169454)
			(xy 270.312394 -106.211859) (xy 270.3489 -106.259435) (xy 270.378884 -106.311369) (xy 270.401833 -106.366773)
			(xy 270.417354 -106.424698) (xy 270.425182 -106.484154) (xy 270.425672 -106.514138) (xy 270.425672 -107.376214)
			(xy 285.8389 -107.376214) (xy 285.8389 -106.512614) (xy 285.83939 -106.48263) (xy 285.847218 -106.423174)
			(xy 285.862739 -106.365249) (xy 285.885688 -106.309845) (xy 285.915672 -106.257911) (xy 285.952178 -106.210335)
			(xy 285.994583 -106.16793) (xy 286.042159 -106.131424) (xy 286.094093 -106.10144) (xy 286.149497 -106.078491)
			(xy 286.207422 -106.06297) (xy 286.266878 -106.055142) (xy 286.326846 -106.055142) (xy 286.386302 -106.06297)
			(xy 286.444227 -106.078491) (xy 286.499631 -106.10144) (xy 286.551565 -106.131424) (xy 286.599141 -106.16793)
			(xy 286.641546 -106.210335) (xy 286.678052 -106.257911) (xy 286.708036 -106.309845) (xy 286.730985 -106.365249)
			(xy 286.746506 -106.423174) (xy 286.754334 -106.48263) (xy 286.754824 -106.512614) (xy 286.754824 -107.376214)
			(xy 286.754799 -107.377738) (xy 385.6101 -107.377738) (xy 385.6101 -106.514138) (xy 385.61059 -106.48417)
			(xy 385.618413 -106.424748) (xy 385.633926 -106.366855) (xy 385.656862 -106.311482) (xy 385.686829 -106.259576)
			(xy 385.723316 -106.212026) (xy 385.765696 -106.169646) (xy 385.813246 -106.133159) (xy 385.865152 -106.103192)
			(xy 385.920525 -106.080256) (xy 385.978418 -106.064743) (xy 386.03784 -106.05692) (xy 386.097776 -106.05692)
			(xy 386.157198 -106.064743) (xy 386.215091 -106.080256) (xy 386.270464 -106.103192) (xy 386.32237 -106.133159)
			(xy 386.36992 -106.169646) (xy 386.4123 -106.212026) (xy 386.448787 -106.259576) (xy 386.478754 -106.311482)
			(xy 386.50169 -106.366855) (xy 386.517203 -106.424748) (xy 386.525026 -106.48417) (xy 386.525516 -106.514138)
			(xy 386.525516 -107.376214) (xy 401.939252 -107.376214) (xy 401.939252 -106.512614) (xy 401.939742 -106.482646)
			(xy 401.947565 -106.423224) (xy 401.963078 -106.365331) (xy 401.986014 -106.309958) (xy 402.015981 -106.258052)
			(xy 402.052468 -106.210502) (xy 402.094848 -106.168122) (xy 402.142398 -106.131635) (xy 402.194304 -106.101668)
			(xy 402.249677 -106.078732) (xy 402.30757 -106.063219) (xy 402.366992 -106.055396) (xy 402.426928 -106.055396)
			(xy 402.48635 -106.063219) (xy 402.544243 -106.078732) (xy 402.599616 -106.101668) (xy 402.651522 -106.131635)
			(xy 402.699072 -106.168122) (xy 402.741452 -106.210502) (xy 402.777939 -106.258052) (xy 402.807906 -106.309958)
			(xy 402.830842 -106.365331) (xy 402.846355 -106.423224) (xy 402.854178 -106.482646) (xy 402.854668 -106.512614)
			(xy 402.854668 -107.376214) (xy 402.854178 -107.406182) (xy 402.846355 -107.465604) (xy 402.830842 -107.523497)
			(xy 402.807906 -107.57887) (xy 402.777939 -107.630776) (xy 402.741452 -107.678326) (xy 402.699072 -107.720706)
			(xy 402.651522 -107.757193) (xy 402.599616 -107.78716) (xy 402.544243 -107.810096) (xy 402.48635 -107.825609)
			(xy 402.426928 -107.833432) (xy 402.366992 -107.833432) (xy 402.30757 -107.825609) (xy 402.249677 -107.810096)
			(xy 402.194304 -107.78716) (xy 402.142398 -107.757193) (xy 402.094848 -107.720706) (xy 402.052468 -107.678326)
			(xy 402.015981 -107.630776) (xy 401.986014 -107.57887) (xy 401.963078 -107.523497) (xy 401.947565 -107.465604)
			(xy 401.939742 -107.406182) (xy 401.939252 -107.376214) (xy 386.525516 -107.376214) (xy 386.525516 -107.377738)
			(xy 386.525026 -107.407706) (xy 386.517203 -107.467128) (xy 386.50169 -107.525021) (xy 386.478754 -107.580394)
			(xy 386.448787 -107.6323) (xy 386.4123 -107.67985) (xy 386.36992 -107.72223) (xy 386.32237 -107.758717)
			(xy 386.270464 -107.788684) (xy 386.215091 -107.81162) (xy 386.157198 -107.827133) (xy 386.097776 -107.834956)
			(xy 386.03784 -107.834956) (xy 385.978418 -107.827133) (xy 385.920525 -107.81162) (xy 385.865152 -107.788684)
			(xy 385.813246 -107.758717) (xy 385.765696 -107.72223) (xy 385.723316 -107.67985) (xy 385.686829 -107.6323)
			(xy 385.656862 -107.580394) (xy 385.633926 -107.525021) (xy 385.618413 -107.467128) (xy 385.61059 -107.407706)
			(xy 385.6101 -107.377738) (xy 286.754799 -107.377738) (xy 286.754334 -107.406198) (xy 286.746506 -107.465654)
			(xy 286.730985 -107.523579) (xy 286.708036 -107.578983) (xy 286.678052 -107.630917) (xy 286.641546 -107.678493)
			(xy 286.599141 -107.720898) (xy 286.551565 -107.757404) (xy 286.499631 -107.787388) (xy 286.444227 -107.810337)
			(xy 286.386302 -107.825858) (xy 286.326846 -107.833686) (xy 286.266878 -107.833686) (xy 286.207422 -107.825858)
			(xy 286.149497 -107.810337) (xy 286.094093 -107.787388) (xy 286.042159 -107.757404) (xy 285.994583 -107.720898)
			(xy 285.952178 -107.678493) (xy 285.915672 -107.630917) (xy 285.885688 -107.578983) (xy 285.862739 -107.523579)
			(xy 285.847218 -107.465654) (xy 285.83939 -107.406198) (xy 285.8389 -107.376214) (xy 270.425672 -107.376214)
			(xy 270.425672 -107.377738) (xy 270.425182 -107.407722) (xy 270.417354 -107.467178) (xy 270.401833 -107.525103)
			(xy 270.378884 -107.580507) (xy 270.3489 -107.632441) (xy 270.312394 -107.680017) (xy 270.269989 -107.722422)
			(xy 270.222413 -107.758928) (xy 270.170479 -107.788912) (xy 270.115075 -107.811861) (xy 270.05715 -107.827382)
			(xy 269.997694 -107.83521) (xy 269.937726 -107.83521) (xy 269.87827 -107.827382) (xy 269.820345 -107.811861)
			(xy 269.764941 -107.788912) (xy 269.713007 -107.758928) (xy 269.665431 -107.722422) (xy 269.623026 -107.680017)
			(xy 269.58652 -107.632441) (xy 269.556536 -107.580507) (xy 269.533587 -107.525103) (xy 269.518066 -107.467178)
			(xy 269.510238 -107.407722) (xy 269.509748 -107.377738) (xy 170.654955 -107.377738) (xy 170.65449 -107.406198)
			(xy 170.646662 -107.465654) (xy 170.631141 -107.523579) (xy 170.608192 -107.578983) (xy 170.578208 -107.630917)
			(xy 170.541702 -107.678493) (xy 170.499297 -107.720898) (xy 170.451721 -107.757404) (xy 170.399787 -107.787388)
			(xy 170.344383 -107.810337) (xy 170.286458 -107.825858) (xy 170.227002 -107.833686) (xy 170.167034 -107.833686)
			(xy 170.107578 -107.825858) (xy 170.049653 -107.810337) (xy 169.994249 -107.787388) (xy 169.942315 -107.757404)
			(xy 169.894739 -107.720898) (xy 169.852334 -107.678493) (xy 169.815828 -107.630917) (xy 169.785844 -107.578983)
			(xy 169.762895 -107.523579) (xy 169.747374 -107.465654) (xy 169.739546 -107.406198) (xy 169.739056 -107.376214)
			(xy 154.325828 -107.376214) (xy 154.325828 -107.377738) (xy 154.325338 -107.407722) (xy 154.31751 -107.467178)
			(xy 154.301989 -107.525103) (xy 154.27904 -107.580507) (xy 154.249056 -107.632441) (xy 154.21255 -107.680017)
			(xy 154.170145 -107.722422) (xy 154.122569 -107.758928) (xy 154.070635 -107.788912) (xy 154.015231 -107.811861)
			(xy 153.957306 -107.827382) (xy 153.89785 -107.83521) (xy 153.837882 -107.83521) (xy 153.778426 -107.827382)
			(xy 153.720501 -107.811861) (xy 153.665097 -107.788912) (xy 153.613163 -107.758928) (xy 153.565587 -107.722422)
			(xy 153.523182 -107.680017) (xy 153.486676 -107.632441) (xy 153.456692 -107.580507) (xy 153.433743 -107.525103)
			(xy 153.418222 -107.467178) (xy 153.410394 -107.407722) (xy 153.409904 -107.377738) (xy 54.554603 -107.377738)
			(xy 54.554138 -107.406182) (xy 54.546315 -107.465604) (xy 54.530802 -107.523497) (xy 54.507866 -107.57887)
			(xy 54.477899 -107.630776) (xy 54.441412 -107.678326) (xy 54.399032 -107.720706) (xy 54.351482 -107.757193)
			(xy 54.299576 -107.78716) (xy 54.244203 -107.810096) (xy 54.18631 -107.825609) (xy 54.126888 -107.833432)
			(xy 54.066952 -107.833432) (xy 54.00753 -107.825609) (xy 53.949637 -107.810096) (xy 53.894264 -107.78716)
			(xy 53.842358 -107.757193) (xy 53.794808 -107.720706) (xy 53.752428 -107.678326) (xy 53.715941 -107.630776)
			(xy 53.685974 -107.57887) (xy 53.663038 -107.523497) (xy 53.647525 -107.465604) (xy 53.639702 -107.406182)
			(xy 53.639212 -107.376214) (xy 38.225476 -107.376214) (xy 38.225476 -107.377738) (xy 38.224986 -107.407706)
			(xy 38.217163 -107.467128) (xy 38.20165 -107.525021) (xy 38.178714 -107.580394) (xy 38.148747 -107.6323)
			(xy 38.11226 -107.67985) (xy 38.06988 -107.72223) (xy 38.02233 -107.758717) (xy 37.970424 -107.788684)
			(xy 37.915051 -107.81162) (xy 37.857158 -107.827133) (xy 37.797736 -107.834956) (xy 37.7378 -107.834956)
			(xy 37.678378 -107.827133) (xy 37.620485 -107.81162) (xy 37.565112 -107.788684) (xy 37.513206 -107.758717)
			(xy 37.465656 -107.72223) (xy 37.423276 -107.67985) (xy 37.386789 -107.6323) (xy 37.356822 -107.580394)
			(xy 37.333886 -107.525021) (xy 37.318373 -107.467128) (xy 37.31055 -107.407706) (xy 37.31006 -107.377738)
			(xy 5.324094 -107.377738) (xy 5.324094 -109.18444) (xy 34.667952 -109.18444) (xy 34.667952 -108.32084)
			(xy 34.668442 -108.290872) (xy 34.676265 -108.23145) (xy 34.691778 -108.173557) (xy 34.714714 -108.118184)
			(xy 34.744681 -108.066278) (xy 34.781168 -108.018728) (xy 34.823548 -107.976348) (xy 34.871098 -107.939861)
			(xy 34.923004 -107.909894) (xy 34.978377 -107.886958) (xy 35.03627 -107.871445) (xy 35.095692 -107.863622)
			(xy 35.155628 -107.863622) (xy 35.21505 -107.871445) (xy 35.272943 -107.886958) (xy 35.328316 -107.909894)
			(xy 35.380222 -107.939861) (xy 35.427772 -107.976348) (xy 35.470152 -108.018728) (xy 35.506639 -108.066278)
			(xy 35.536606 -108.118184) (xy 35.559542 -108.173557) (xy 35.575055 -108.23145) (xy 35.582878 -108.290872)
			(xy 35.583368 -108.32084) (xy 35.583368 -109.176312) (xy 51.785012 -109.176312) (xy 51.785012 -108.312712)
			(xy 51.785502 -108.282744) (xy 51.793325 -108.223322) (xy 51.808838 -108.165429) (xy 51.831774 -108.110056)
			(xy 51.861741 -108.05815) (xy 51.898228 -108.0106) (xy 51.940608 -107.96822) (xy 51.988158 -107.931733)
			(xy 52.040064 -107.901766) (xy 52.095437 -107.87883) (xy 52.15333 -107.863317) (xy 52.212752 -107.855494)
			(xy 52.272688 -107.855494) (xy 52.33211 -107.863317) (xy 52.390003 -107.87883) (xy 52.445376 -107.901766)
			(xy 52.497282 -107.931733) (xy 52.544832 -107.96822) (xy 52.587212 -108.0106) (xy 52.623699 -108.05815)
			(xy 52.653666 -108.110056) (xy 52.676602 -108.165429) (xy 52.692115 -108.223322) (xy 52.699938 -108.282744)
			(xy 52.700428 -108.312712) (xy 52.700428 -109.176312) (xy 52.700295 -109.18444) (xy 150.767796 -109.18444)
			(xy 150.767796 -108.32084) (xy 150.768286 -108.290856) (xy 150.776114 -108.2314) (xy 150.791635 -108.173475)
			(xy 150.814584 -108.118071) (xy 150.844568 -108.066137) (xy 150.881074 -108.018561) (xy 150.923479 -107.976156)
			(xy 150.971055 -107.93965) (xy 151.022989 -107.909666) (xy 151.078393 -107.886717) (xy 151.136318 -107.871196)
			(xy 151.195774 -107.863368) (xy 151.255742 -107.863368) (xy 151.315198 -107.871196) (xy 151.373123 -107.886717)
			(xy 151.428527 -107.909666) (xy 151.480461 -107.93965) (xy 151.528037 -107.976156) (xy 151.570442 -108.018561)
			(xy 151.606948 -108.066137) (xy 151.636932 -108.118071) (xy 151.659881 -108.173475) (xy 151.675402 -108.2314)
			(xy 151.68323 -108.290856) (xy 151.68372 -108.32084) (xy 151.68372 -109.176312) (xy 167.884856 -109.176312)
			(xy 167.884856 -108.312712) (xy 167.885346 -108.282728) (xy 167.893174 -108.223272) (xy 167.908695 -108.165347)
			(xy 167.931644 -108.109943) (xy 167.961628 -108.058009) (xy 167.998134 -108.010433) (xy 168.040539 -107.968028)
			(xy 168.088115 -107.931522) (xy 168.140049 -107.901538) (xy 168.195453 -107.878589) (xy 168.253378 -107.863068)
			(xy 168.312834 -107.85524) (xy 168.372802 -107.85524) (xy 168.432258 -107.863068) (xy 168.490183 -107.878589)
			(xy 168.545587 -107.901538) (xy 168.597521 -107.931522) (xy 168.645097 -107.968028) (xy 168.687502 -108.010433)
			(xy 168.724008 -108.058009) (xy 168.753992 -108.109943) (xy 168.776941 -108.165347) (xy 168.792462 -108.223272)
			(xy 168.80029 -108.282728) (xy 168.80078 -108.312712) (xy 168.80078 -109.176312) (xy 168.800647 -109.18444)
			(xy 266.86764 -109.18444) (xy 266.86764 -108.32084) (xy 266.86813 -108.290856) (xy 266.875958 -108.2314)
			(xy 266.891479 -108.173475) (xy 266.914428 -108.118071) (xy 266.944412 -108.066137) (xy 266.980918 -108.018561)
			(xy 267.023323 -107.976156) (xy 267.070899 -107.93965) (xy 267.122833 -107.909666) (xy 267.178237 -107.886717)
			(xy 267.236162 -107.871196) (xy 267.295618 -107.863368) (xy 267.355586 -107.863368) (xy 267.415042 -107.871196)
			(xy 267.472967 -107.886717) (xy 267.528371 -107.909666) (xy 267.580305 -107.93965) (xy 267.627881 -107.976156)
			(xy 267.670286 -108.018561) (xy 267.706792 -108.066137) (xy 267.736776 -108.118071) (xy 267.759725 -108.173475)
			(xy 267.775246 -108.2314) (xy 267.783074 -108.290856) (xy 267.783564 -108.32084) (xy 267.783564 -109.176312)
			(xy 283.9847 -109.176312) (xy 283.9847 -108.312712) (xy 283.98519 -108.282728) (xy 283.993018 -108.223272)
			(xy 284.008539 -108.165347) (xy 284.031488 -108.109943) (xy 284.061472 -108.058009) (xy 284.097978 -108.010433)
			(xy 284.140383 -107.968028) (xy 284.187959 -107.931522) (xy 284.239893 -107.901538) (xy 284.295297 -107.878589)
			(xy 284.353222 -107.863068) (xy 284.412678 -107.85524) (xy 284.472646 -107.85524) (xy 284.532102 -107.863068)
			(xy 284.590027 -107.878589) (xy 284.645431 -107.901538) (xy 284.697365 -107.931522) (xy 284.744941 -107.968028)
			(xy 284.787346 -108.010433) (xy 284.823852 -108.058009) (xy 284.853836 -108.109943) (xy 284.876785 -108.165347)
			(xy 284.892306 -108.223272) (xy 284.900134 -108.282728) (xy 284.900624 -108.312712) (xy 284.900624 -109.176312)
			(xy 284.900491 -109.18444) (xy 382.967992 -109.18444) (xy 382.967992 -108.32084) (xy 382.968482 -108.290872)
			(xy 382.976305 -108.23145) (xy 382.991818 -108.173557) (xy 383.014754 -108.118184) (xy 383.044721 -108.066278)
			(xy 383.081208 -108.018728) (xy 383.123588 -107.976348) (xy 383.171138 -107.939861) (xy 383.223044 -107.909894)
			(xy 383.278417 -107.886958) (xy 383.33631 -107.871445) (xy 383.395732 -107.863622) (xy 383.455668 -107.863622)
			(xy 383.51509 -107.871445) (xy 383.572983 -107.886958) (xy 383.628356 -107.909894) (xy 383.680262 -107.939861)
			(xy 383.727812 -107.976348) (xy 383.770192 -108.018728) (xy 383.806679 -108.066278) (xy 383.836646 -108.118184)
			(xy 383.859582 -108.173557) (xy 383.875095 -108.23145) (xy 383.882918 -108.290872) (xy 383.883408 -108.32084)
			(xy 383.883408 -109.176312) (xy 400.085052 -109.176312) (xy 400.085052 -108.312712) (xy 400.085542 -108.282744)
			(xy 400.093365 -108.223322) (xy 400.108878 -108.165429) (xy 400.131814 -108.110056) (xy 400.161781 -108.05815)
			(xy 400.198268 -108.0106) (xy 400.240648 -107.96822) (xy 400.288198 -107.931733) (xy 400.340104 -107.901766)
			(xy 400.395477 -107.87883) (xy 400.45337 -107.863317) (xy 400.512792 -107.855494) (xy 400.572728 -107.855494)
			(xy 400.63215 -107.863317) (xy 400.690043 -107.87883) (xy 400.745416 -107.901766) (xy 400.797322 -107.931733)
			(xy 400.844872 -107.96822) (xy 400.887252 -108.0106) (xy 400.923739 -108.05815) (xy 400.953706 -108.110056)
			(xy 400.976642 -108.165429) (xy 400.992155 -108.223322) (xy 400.999978 -108.282744) (xy 401.000468 -108.312712)
			(xy 401.000468 -109.176312) (xy 400.999978 -109.20628) (xy 400.992155 -109.265702) (xy 400.976642 -109.323595)
			(xy 400.953706 -109.378968) (xy 400.923739 -109.430874) (xy 400.887252 -109.478424) (xy 400.844872 -109.520804)
			(xy 400.797322 -109.557291) (xy 400.745416 -109.587258) (xy 400.690043 -109.610194) (xy 400.63215 -109.625707)
			(xy 400.572728 -109.63353) (xy 400.512792 -109.63353) (xy 400.45337 -109.625707) (xy 400.395477 -109.610194)
			(xy 400.340104 -109.587258) (xy 400.288198 -109.557291) (xy 400.240648 -109.520804) (xy 400.198268 -109.478424)
			(xy 400.161781 -109.430874) (xy 400.131814 -109.378968) (xy 400.108878 -109.323595) (xy 400.093365 -109.265702)
			(xy 400.085542 -109.20628) (xy 400.085052 -109.176312) (xy 383.883408 -109.176312) (xy 383.883408 -109.18444)
			(xy 383.882918 -109.214408) (xy 383.875095 -109.27383) (xy 383.859582 -109.331723) (xy 383.836646 -109.387096)
			(xy 383.806679 -109.439002) (xy 383.770192 -109.486552) (xy 383.727812 -109.528932) (xy 383.680262 -109.565419)
			(xy 383.628356 -109.595386) (xy 383.572983 -109.618322) (xy 383.51509 -109.633835) (xy 383.455668 -109.641658)
			(xy 383.395732 -109.641658) (xy 383.33631 -109.633835) (xy 383.278417 -109.618322) (xy 383.223044 -109.595386)
			(xy 383.171138 -109.565419) (xy 383.123588 -109.528932) (xy 383.081208 -109.486552) (xy 383.044721 -109.439002)
			(xy 383.014754 -109.387096) (xy 382.991818 -109.331723) (xy 382.976305 -109.27383) (xy 382.968482 -109.214408)
			(xy 382.967992 -109.18444) (xy 284.900491 -109.18444) (xy 284.900134 -109.206296) (xy 284.892306 -109.265752)
			(xy 284.876785 -109.323677) (xy 284.853836 -109.379081) (xy 284.823852 -109.431015) (xy 284.787346 -109.478591)
			(xy 284.744941 -109.520996) (xy 284.697365 -109.557502) (xy 284.645431 -109.587486) (xy 284.590027 -109.610435)
			(xy 284.532102 -109.625956) (xy 284.472646 -109.633784) (xy 284.412678 -109.633784) (xy 284.353222 -109.625956)
			(xy 284.295297 -109.610435) (xy 284.239893 -109.587486) (xy 284.187959 -109.557502) (xy 284.140383 -109.520996)
			(xy 284.097978 -109.478591) (xy 284.061472 -109.431015) (xy 284.031488 -109.379081) (xy 284.008539 -109.323677)
			(xy 283.993018 -109.265752) (xy 283.98519 -109.206296) (xy 283.9847 -109.176312) (xy 267.783564 -109.176312)
			(xy 267.783564 -109.18444) (xy 267.783074 -109.214424) (xy 267.775246 -109.27388) (xy 267.759725 -109.331805)
			(xy 267.736776 -109.387209) (xy 267.706792 -109.439143) (xy 267.670286 -109.486719) (xy 267.627881 -109.529124)
			(xy 267.580305 -109.56563) (xy 267.528371 -109.595614) (xy 267.472967 -109.618563) (xy 267.415042 -109.634084)
			(xy 267.355586 -109.641912) (xy 267.295618 -109.641912) (xy 267.236162 -109.634084) (xy 267.178237 -109.618563)
			(xy 267.122833 -109.595614) (xy 267.070899 -109.56563) (xy 267.023323 -109.529124) (xy 266.980918 -109.486719)
			(xy 266.944412 -109.439143) (xy 266.914428 -109.387209) (xy 266.891479 -109.331805) (xy 266.875958 -109.27388)
			(xy 266.86813 -109.214424) (xy 266.86764 -109.18444) (xy 168.800647 -109.18444) (xy 168.80029 -109.206296)
			(xy 168.792462 -109.265752) (xy 168.776941 -109.323677) (xy 168.753992 -109.379081) (xy 168.724008 -109.431015)
			(xy 168.687502 -109.478591) (xy 168.645097 -109.520996) (xy 168.597521 -109.557502) (xy 168.545587 -109.587486)
			(xy 168.490183 -109.610435) (xy 168.432258 -109.625956) (xy 168.372802 -109.633784) (xy 168.312834 -109.633784)
			(xy 168.253378 -109.625956) (xy 168.195453 -109.610435) (xy 168.140049 -109.587486) (xy 168.088115 -109.557502)
			(xy 168.040539 -109.520996) (xy 167.998134 -109.478591) (xy 167.961628 -109.431015) (xy 167.931644 -109.379081)
			(xy 167.908695 -109.323677) (xy 167.893174 -109.265752) (xy 167.885346 -109.206296) (xy 167.884856 -109.176312)
			(xy 151.68372 -109.176312) (xy 151.68372 -109.18444) (xy 151.68323 -109.214424) (xy 151.675402 -109.27388)
			(xy 151.659881 -109.331805) (xy 151.636932 -109.387209) (xy 151.606948 -109.439143) (xy 151.570442 -109.486719)
			(xy 151.528037 -109.529124) (xy 151.480461 -109.56563) (xy 151.428527 -109.595614) (xy 151.373123 -109.618563)
			(xy 151.315198 -109.634084) (xy 151.255742 -109.641912) (xy 151.195774 -109.641912) (xy 151.136318 -109.634084)
			(xy 151.078393 -109.618563) (xy 151.022989 -109.595614) (xy 150.971055 -109.56563) (xy 150.923479 -109.529124)
			(xy 150.881074 -109.486719) (xy 150.844568 -109.439143) (xy 150.814584 -109.387209) (xy 150.791635 -109.331805)
			(xy 150.776114 -109.27388) (xy 150.768286 -109.214424) (xy 150.767796 -109.18444) (xy 52.700295 -109.18444)
			(xy 52.699938 -109.20628) (xy 52.692115 -109.265702) (xy 52.676602 -109.323595) (xy 52.653666 -109.378968)
			(xy 52.623699 -109.430874) (xy 52.587212 -109.478424) (xy 52.544832 -109.520804) (xy 52.497282 -109.557291)
			(xy 52.445376 -109.587258) (xy 52.390003 -109.610194) (xy 52.33211 -109.625707) (xy 52.272688 -109.63353)
			(xy 52.212752 -109.63353) (xy 52.15333 -109.625707) (xy 52.095437 -109.610194) (xy 52.040064 -109.587258)
			(xy 51.988158 -109.557291) (xy 51.940608 -109.520804) (xy 51.898228 -109.478424) (xy 51.861741 -109.430874)
			(xy 51.831774 -109.378968) (xy 51.808838 -109.323595) (xy 51.793325 -109.265702) (xy 51.785502 -109.20628)
			(xy 51.785012 -109.176312) (xy 35.583368 -109.176312) (xy 35.583368 -109.18444) (xy 35.582878 -109.214408)
			(xy 35.575055 -109.27383) (xy 35.559542 -109.331723) (xy 35.536606 -109.387096) (xy 35.506639 -109.439002)
			(xy 35.470152 -109.486552) (xy 35.427772 -109.528932) (xy 35.380222 -109.565419) (xy 35.328316 -109.595386)
			(xy 35.272943 -109.618322) (xy 35.21505 -109.633835) (xy 35.155628 -109.641658) (xy 35.095692 -109.641658)
			(xy 35.03627 -109.633835) (xy 34.978377 -109.618322) (xy 34.923004 -109.595386) (xy 34.871098 -109.565419)
			(xy 34.823548 -109.528932) (xy 34.781168 -109.486552) (xy 34.744681 -109.439002) (xy 34.714714 -109.387096)
			(xy 34.691778 -109.331723) (xy 34.676265 -109.27383) (xy 34.668442 -109.214408) (xy 34.667952 -109.18444)
			(xy 5.324094 -109.18444) (xy 5.324094 -110.977934) (xy 37.31006 -110.977934) (xy 37.31006 -110.114334)
			(xy 37.31055 -110.084366) (xy 37.318373 -110.024944) (xy 37.333886 -109.967051) (xy 37.356822 -109.911678)
			(xy 37.386789 -109.859772) (xy 37.423276 -109.812222) (xy 37.465656 -109.769842) (xy 37.513206 -109.733355)
			(xy 37.565112 -109.703388) (xy 37.620485 -109.680452) (xy 37.678378 -109.664939) (xy 37.7378 -109.657116)
			(xy 37.797736 -109.657116) (xy 37.857158 -109.664939) (xy 37.915051 -109.680452) (xy 37.970424 -109.703388)
			(xy 38.02233 -109.733355) (xy 38.06988 -109.769842) (xy 38.11226 -109.812222) (xy 38.148747 -109.859772)
			(xy 38.178714 -109.911678) (xy 38.20165 -109.967051) (xy 38.217163 -110.024944) (xy 38.224986 -110.084366)
			(xy 38.225476 -110.114334) (xy 38.225476 -110.97641) (xy 53.639212 -110.97641) (xy 53.639212 -110.11281)
			(xy 53.639702 -110.082842) (xy 53.647525 -110.02342) (xy 53.663038 -109.965527) (xy 53.685974 -109.910154)
			(xy 53.715941 -109.858248) (xy 53.752428 -109.810698) (xy 53.794808 -109.768318) (xy 53.842358 -109.731831)
			(xy 53.894264 -109.701864) (xy 53.949637 -109.678928) (xy 54.00753 -109.663415) (xy 54.066952 -109.655592)
			(xy 54.126888 -109.655592) (xy 54.18631 -109.663415) (xy 54.244203 -109.678928) (xy 54.299576 -109.701864)
			(xy 54.351482 -109.731831) (xy 54.399032 -109.768318) (xy 54.441412 -109.810698) (xy 54.477899 -109.858248)
			(xy 54.507866 -109.910154) (xy 54.530802 -109.965527) (xy 54.546315 -110.02342) (xy 54.554138 -110.082842)
			(xy 54.554628 -110.11281) (xy 54.554628 -110.97641) (xy 54.554603 -110.977934) (xy 153.409904 -110.977934)
			(xy 153.409904 -110.114334) (xy 153.410394 -110.08435) (xy 153.418222 -110.024894) (xy 153.433743 -109.966969)
			(xy 153.456692 -109.911565) (xy 153.486676 -109.859631) (xy 153.523182 -109.812055) (xy 153.565587 -109.76965)
			(xy 153.613163 -109.733144) (xy 153.665097 -109.70316) (xy 153.720501 -109.680211) (xy 153.778426 -109.66469)
			(xy 153.837882 -109.656862) (xy 153.89785 -109.656862) (xy 153.957306 -109.66469) (xy 154.015231 -109.680211)
			(xy 154.070635 -109.70316) (xy 154.122569 -109.733144) (xy 154.170145 -109.76965) (xy 154.21255 -109.812055)
			(xy 154.249056 -109.859631) (xy 154.27904 -109.911565) (xy 154.301989 -109.966969) (xy 154.31751 -110.024894)
			(xy 154.325338 -110.08435) (xy 154.325828 -110.114334) (xy 154.325828 -110.97641) (xy 169.739056 -110.97641)
			(xy 169.739056 -110.11281) (xy 169.739546 -110.082826) (xy 169.747374 -110.02337) (xy 169.762895 -109.965445)
			(xy 169.785844 -109.910041) (xy 169.815828 -109.858107) (xy 169.852334 -109.810531) (xy 169.894739 -109.768126)
			(xy 169.942315 -109.73162) (xy 169.994249 -109.701636) (xy 170.049653 -109.678687) (xy 170.107578 -109.663166)
			(xy 170.167034 -109.655338) (xy 170.227002 -109.655338) (xy 170.286458 -109.663166) (xy 170.344383 -109.678687)
			(xy 170.399787 -109.701636) (xy 170.451721 -109.73162) (xy 170.499297 -109.768126) (xy 170.541702 -109.810531)
			(xy 170.578208 -109.858107) (xy 170.608192 -109.910041) (xy 170.631141 -109.965445) (xy 170.646662 -110.02337)
			(xy 170.65449 -110.082826) (xy 170.65498 -110.11281) (xy 170.65498 -110.97641) (xy 170.654955 -110.977934)
			(xy 269.509748 -110.977934) (xy 269.509748 -110.114334) (xy 269.510238 -110.08435) (xy 269.518066 -110.024894)
			(xy 269.533587 -109.966969) (xy 269.556536 -109.911565) (xy 269.58652 -109.859631) (xy 269.623026 -109.812055)
			(xy 269.665431 -109.76965) (xy 269.713007 -109.733144) (xy 269.764941 -109.70316) (xy 269.820345 -109.680211)
			(xy 269.87827 -109.66469) (xy 269.937726 -109.656862) (xy 269.997694 -109.656862) (xy 270.05715 -109.66469)
			(xy 270.115075 -109.680211) (xy 270.170479 -109.70316) (xy 270.222413 -109.733144) (xy 270.269989 -109.76965)
			(xy 270.312394 -109.812055) (xy 270.3489 -109.859631) (xy 270.378884 -109.911565) (xy 270.401833 -109.966969)
			(xy 270.417354 -110.024894) (xy 270.425182 -110.08435) (xy 270.425672 -110.114334) (xy 270.425672 -110.97641)
			(xy 285.8389 -110.97641) (xy 285.8389 -110.11281) (xy 285.83939 -110.082826) (xy 285.847218 -110.02337)
			(xy 285.862739 -109.965445) (xy 285.885688 -109.910041) (xy 285.915672 -109.858107) (xy 285.952178 -109.810531)
			(xy 285.994583 -109.768126) (xy 286.042159 -109.73162) (xy 286.094093 -109.701636) (xy 286.149497 -109.678687)
			(xy 286.207422 -109.663166) (xy 286.266878 -109.655338) (xy 286.326846 -109.655338) (xy 286.386302 -109.663166)
			(xy 286.444227 -109.678687) (xy 286.499631 -109.701636) (xy 286.551565 -109.73162) (xy 286.599141 -109.768126)
			(xy 286.641546 -109.810531) (xy 286.678052 -109.858107) (xy 286.708036 -109.910041) (xy 286.730985 -109.965445)
			(xy 286.746506 -110.02337) (xy 286.754334 -110.082826) (xy 286.754824 -110.11281) (xy 286.754824 -110.97641)
			(xy 286.754799 -110.977934) (xy 385.6101 -110.977934) (xy 385.6101 -110.114334) (xy 385.61059 -110.084366)
			(xy 385.618413 -110.024944) (xy 385.633926 -109.967051) (xy 385.656862 -109.911678) (xy 385.686829 -109.859772)
			(xy 385.723316 -109.812222) (xy 385.765696 -109.769842) (xy 385.813246 -109.733355) (xy 385.865152 -109.703388)
			(xy 385.920525 -109.680452) (xy 385.978418 -109.664939) (xy 386.03784 -109.657116) (xy 386.097776 -109.657116)
			(xy 386.157198 -109.664939) (xy 386.215091 -109.680452) (xy 386.270464 -109.703388) (xy 386.32237 -109.733355)
			(xy 386.36992 -109.769842) (xy 386.4123 -109.812222) (xy 386.448787 -109.859772) (xy 386.478754 -109.911678)
			(xy 386.50169 -109.967051) (xy 386.517203 -110.024944) (xy 386.525026 -110.084366) (xy 386.525516 -110.114334)
			(xy 386.525516 -110.97641) (xy 401.939252 -110.97641) (xy 401.939252 -110.11281) (xy 401.939742 -110.082842)
			(xy 401.947565 -110.02342) (xy 401.963078 -109.965527) (xy 401.986014 -109.910154) (xy 402.015981 -109.858248)
			(xy 402.052468 -109.810698) (xy 402.094848 -109.768318) (xy 402.142398 -109.731831) (xy 402.194304 -109.701864)
			(xy 402.249677 -109.678928) (xy 402.30757 -109.663415) (xy 402.366992 -109.655592) (xy 402.426928 -109.655592)
			(xy 402.48635 -109.663415) (xy 402.544243 -109.678928) (xy 402.599616 -109.701864) (xy 402.651522 -109.731831)
			(xy 402.699072 -109.768318) (xy 402.741452 -109.810698) (xy 402.777939 -109.858248) (xy 402.807906 -109.910154)
			(xy 402.830842 -109.965527) (xy 402.846355 -110.02342) (xy 402.854178 -110.082842) (xy 402.854668 -110.11281)
			(xy 402.854668 -110.97641) (xy 402.854178 -111.006378) (xy 402.846355 -111.0658) (xy 402.830842 -111.123693)
			(xy 402.807906 -111.179066) (xy 402.777939 -111.230972) (xy 402.741452 -111.278522) (xy 402.699072 -111.320902)
			(xy 402.651522 -111.357389) (xy 402.599616 -111.387356) (xy 402.544243 -111.410292) (xy 402.48635 -111.425805)
			(xy 402.426928 -111.433628) (xy 402.366992 -111.433628) (xy 402.30757 -111.425805) (xy 402.249677 -111.410292)
			(xy 402.194304 -111.387356) (xy 402.142398 -111.357389) (xy 402.094848 -111.320902) (xy 402.052468 -111.278522)
			(xy 402.015981 -111.230972) (xy 401.986014 -111.179066) (xy 401.963078 -111.123693) (xy 401.947565 -111.0658)
			(xy 401.939742 -111.006378) (xy 401.939252 -110.97641) (xy 386.525516 -110.97641) (xy 386.525516 -110.977934)
			(xy 386.525026 -111.007902) (xy 386.517203 -111.067324) (xy 386.50169 -111.125217) (xy 386.478754 -111.18059)
			(xy 386.448787 -111.232496) (xy 386.4123 -111.280046) (xy 386.36992 -111.322426) (xy 386.32237 -111.358913)
			(xy 386.270464 -111.38888) (xy 386.215091 -111.411816) (xy 386.157198 -111.427329) (xy 386.097776 -111.435152)
			(xy 386.03784 -111.435152) (xy 385.978418 -111.427329) (xy 385.920525 -111.411816) (xy 385.865152 -111.38888)
			(xy 385.813246 -111.358913) (xy 385.765696 -111.322426) (xy 385.723316 -111.280046) (xy 385.686829 -111.232496)
			(xy 385.656862 -111.18059) (xy 385.633926 -111.125217) (xy 385.618413 -111.067324) (xy 385.61059 -111.007902)
			(xy 385.6101 -110.977934) (xy 286.754799 -110.977934) (xy 286.754334 -111.006394) (xy 286.746506 -111.06585)
			(xy 286.730985 -111.123775) (xy 286.708036 -111.179179) (xy 286.678052 -111.231113) (xy 286.641546 -111.278689)
			(xy 286.599141 -111.321094) (xy 286.551565 -111.3576) (xy 286.499631 -111.387584) (xy 286.444227 -111.410533)
			(xy 286.386302 -111.426054) (xy 286.326846 -111.433882) (xy 286.266878 -111.433882) (xy 286.207422 -111.426054)
			(xy 286.149497 -111.410533) (xy 286.094093 -111.387584) (xy 286.042159 -111.3576) (xy 285.994583 -111.321094)
			(xy 285.952178 -111.278689) (xy 285.915672 -111.231113) (xy 285.885688 -111.179179) (xy 285.862739 -111.123775)
			(xy 285.847218 -111.06585) (xy 285.83939 -111.006394) (xy 285.8389 -110.97641) (xy 270.425672 -110.97641)
			(xy 270.425672 -110.977934) (xy 270.425182 -111.007918) (xy 270.417354 -111.067374) (xy 270.401833 -111.125299)
			(xy 270.378884 -111.180703) (xy 270.3489 -111.232637) (xy 270.312394 -111.280213) (xy 270.269989 -111.322618)
			(xy 270.222413 -111.359124) (xy 270.170479 -111.389108) (xy 270.115075 -111.412057) (xy 270.05715 -111.427578)
			(xy 269.997694 -111.435406) (xy 269.937726 -111.435406) (xy 269.87827 -111.427578) (xy 269.820345 -111.412057)
			(xy 269.764941 -111.389108) (xy 269.713007 -111.359124) (xy 269.665431 -111.322618) (xy 269.623026 -111.280213)
			(xy 269.58652 -111.232637) (xy 269.556536 -111.180703) (xy 269.533587 -111.125299) (xy 269.518066 -111.067374)
			(xy 269.510238 -111.007918) (xy 269.509748 -110.977934) (xy 170.654955 -110.977934) (xy 170.65449 -111.006394)
			(xy 170.646662 -111.06585) (xy 170.631141 -111.123775) (xy 170.608192 -111.179179) (xy 170.578208 -111.231113)
			(xy 170.541702 -111.278689) (xy 170.499297 -111.321094) (xy 170.451721 -111.3576) (xy 170.399787 -111.387584)
			(xy 170.344383 -111.410533) (xy 170.286458 -111.426054) (xy 170.227002 -111.433882) (xy 170.167034 -111.433882)
			(xy 170.107578 -111.426054) (xy 170.049653 -111.410533) (xy 169.994249 -111.387584) (xy 169.942315 -111.3576)
			(xy 169.894739 -111.321094) (xy 169.852334 -111.278689) (xy 169.815828 -111.231113) (xy 169.785844 -111.179179)
			(xy 169.762895 -111.123775) (xy 169.747374 -111.06585) (xy 169.739546 -111.006394) (xy 169.739056 -110.97641)
			(xy 154.325828 -110.97641) (xy 154.325828 -110.977934) (xy 154.325338 -111.007918) (xy 154.31751 -111.067374)
			(xy 154.301989 -111.125299) (xy 154.27904 -111.180703) (xy 154.249056 -111.232637) (xy 154.21255 -111.280213)
			(xy 154.170145 -111.322618) (xy 154.122569 -111.359124) (xy 154.070635 -111.389108) (xy 154.015231 -111.412057)
			(xy 153.957306 -111.427578) (xy 153.89785 -111.435406) (xy 153.837882 -111.435406) (xy 153.778426 -111.427578)
			(xy 153.720501 -111.412057) (xy 153.665097 -111.389108) (xy 153.613163 -111.359124) (xy 153.565587 -111.322618)
			(xy 153.523182 -111.280213) (xy 153.486676 -111.232637) (xy 153.456692 -111.180703) (xy 153.433743 -111.125299)
			(xy 153.418222 -111.067374) (xy 153.410394 -111.007918) (xy 153.409904 -110.977934) (xy 54.554603 -110.977934)
			(xy 54.554138 -111.006378) (xy 54.546315 -111.0658) (xy 54.530802 -111.123693) (xy 54.507866 -111.179066)
			(xy 54.477899 -111.230972) (xy 54.441412 -111.278522) (xy 54.399032 -111.320902) (xy 54.351482 -111.357389)
			(xy 54.299576 -111.387356) (xy 54.244203 -111.410292) (xy 54.18631 -111.425805) (xy 54.126888 -111.433628)
			(xy 54.066952 -111.433628) (xy 54.00753 -111.425805) (xy 53.949637 -111.410292) (xy 53.894264 -111.387356)
			(xy 53.842358 -111.357389) (xy 53.794808 -111.320902) (xy 53.752428 -111.278522) (xy 53.715941 -111.230972)
			(xy 53.685974 -111.179066) (xy 53.663038 -111.123693) (xy 53.647525 -111.0658) (xy 53.639702 -111.006378)
			(xy 53.639212 -110.97641) (xy 38.225476 -110.97641) (xy 38.225476 -110.977934) (xy 38.224986 -111.007902)
			(xy 38.217163 -111.067324) (xy 38.20165 -111.125217) (xy 38.178714 -111.18059) (xy 38.148747 -111.232496)
			(xy 38.11226 -111.280046) (xy 38.06988 -111.322426) (xy 38.02233 -111.358913) (xy 37.970424 -111.38888)
			(xy 37.915051 -111.411816) (xy 37.857158 -111.427329) (xy 37.797736 -111.435152) (xy 37.7378 -111.435152)
			(xy 37.678378 -111.427329) (xy 37.620485 -111.411816) (xy 37.565112 -111.38888) (xy 37.513206 -111.358913)
			(xy 37.465656 -111.322426) (xy 37.423276 -111.280046) (xy 37.386789 -111.232496) (xy 37.356822 -111.18059)
			(xy 37.333886 -111.125217) (xy 37.318373 -111.067324) (xy 37.31055 -111.007902) (xy 37.31006 -110.977934)
			(xy 5.324094 -110.977934) (xy 5.324094 -112.784382) (xy 34.667952 -112.784382) (xy 34.667952 -111.920782)
			(xy 34.668442 -111.890814) (xy 34.676265 -111.831392) (xy 34.691778 -111.773499) (xy 34.714714 -111.718126)
			(xy 34.744681 -111.66622) (xy 34.781168 -111.61867) (xy 34.823548 -111.57629) (xy 34.871098 -111.539803)
			(xy 34.923004 -111.509836) (xy 34.978377 -111.4869) (xy 35.03627 -111.471387) (xy 35.095692 -111.463564)
			(xy 35.155628 -111.463564) (xy 35.21505 -111.471387) (xy 35.272943 -111.4869) (xy 35.328316 -111.509836)
			(xy 35.380222 -111.539803) (xy 35.427772 -111.57629) (xy 35.470152 -111.61867) (xy 35.506639 -111.66622)
			(xy 35.536606 -111.718126) (xy 35.559542 -111.773499) (xy 35.575055 -111.831392) (xy 35.582878 -111.890814)
			(xy 35.583368 -111.920782) (xy 35.583368 -112.776508) (xy 51.785012 -112.776508) (xy 51.785012 -111.912908)
			(xy 51.785502 -111.88294) (xy 51.793325 -111.823518) (xy 51.808838 -111.765625) (xy 51.831774 -111.710252)
			(xy 51.861741 -111.658346) (xy 51.898228 -111.610796) (xy 51.940608 -111.568416) (xy 51.988158 -111.531929)
			(xy 52.040064 -111.501962) (xy 52.095437 -111.479026) (xy 52.15333 -111.463513) (xy 52.212752 -111.45569)
			(xy 52.272688 -111.45569) (xy 52.33211 -111.463513) (xy 52.390003 -111.479026) (xy 52.445376 -111.501962)
			(xy 52.497282 -111.531929) (xy 52.544832 -111.568416) (xy 52.587212 -111.610796) (xy 52.623699 -111.658346)
			(xy 52.653666 -111.710252) (xy 52.676602 -111.765625) (xy 52.692115 -111.823518) (xy 52.699938 -111.88294)
			(xy 52.700428 -111.912908) (xy 52.700428 -112.776508) (xy 52.700299 -112.784382) (xy 150.767796 -112.784382)
			(xy 150.767796 -111.920782) (xy 150.768286 -111.890798) (xy 150.776114 -111.831342) (xy 150.791635 -111.773417)
			(xy 150.814584 -111.718013) (xy 150.844568 -111.666079) (xy 150.881074 -111.618503) (xy 150.923479 -111.576098)
			(xy 150.971055 -111.539592) (xy 151.022989 -111.509608) (xy 151.078393 -111.486659) (xy 151.136318 -111.471138)
			(xy 151.195774 -111.46331) (xy 151.255742 -111.46331) (xy 151.315198 -111.471138) (xy 151.373123 -111.486659)
			(xy 151.428527 -111.509608) (xy 151.480461 -111.539592) (xy 151.528037 -111.576098) (xy 151.570442 -111.618503)
			(xy 151.606948 -111.666079) (xy 151.636932 -111.718013) (xy 151.659881 -111.773417) (xy 151.675402 -111.831342)
			(xy 151.68323 -111.890798) (xy 151.68372 -111.920782) (xy 151.68372 -112.776508) (xy 167.884856 -112.776508)
			(xy 167.884856 -111.912908) (xy 167.885346 -111.882924) (xy 167.893174 -111.823468) (xy 167.908695 -111.765543)
			(xy 167.931644 -111.710139) (xy 167.961628 -111.658205) (xy 167.998134 -111.610629) (xy 168.040539 -111.568224)
			(xy 168.088115 -111.531718) (xy 168.140049 -111.501734) (xy 168.195453 -111.478785) (xy 168.253378 -111.463264)
			(xy 168.312834 -111.455436) (xy 168.372802 -111.455436) (xy 168.432258 -111.463264) (xy 168.490183 -111.478785)
			(xy 168.545587 -111.501734) (xy 168.597521 -111.531718) (xy 168.645097 -111.568224) (xy 168.687502 -111.610629)
			(xy 168.724008 -111.658205) (xy 168.753992 -111.710139) (xy 168.776941 -111.765543) (xy 168.792462 -111.823468)
			(xy 168.80029 -111.882924) (xy 168.80078 -111.912908) (xy 168.80078 -112.776508) (xy 168.800651 -112.784382)
			(xy 266.86764 -112.784382) (xy 266.86764 -111.920782) (xy 266.86813 -111.890798) (xy 266.875958 -111.831342)
			(xy 266.891479 -111.773417) (xy 266.914428 -111.718013) (xy 266.944412 -111.666079) (xy 266.980918 -111.618503)
			(xy 267.023323 -111.576098) (xy 267.070899 -111.539592) (xy 267.122833 -111.509608) (xy 267.178237 -111.486659)
			(xy 267.236162 -111.471138) (xy 267.295618 -111.46331) (xy 267.355586 -111.46331) (xy 267.415042 -111.471138)
			(xy 267.472967 -111.486659) (xy 267.528371 -111.509608) (xy 267.580305 -111.539592) (xy 267.627881 -111.576098)
			(xy 267.670286 -111.618503) (xy 267.706792 -111.666079) (xy 267.736776 -111.718013) (xy 267.759725 -111.773417)
			(xy 267.775246 -111.831342) (xy 267.783074 -111.890798) (xy 267.783564 -111.920782) (xy 267.783564 -112.776508)
			(xy 283.9847 -112.776508) (xy 283.9847 -111.912908) (xy 283.98519 -111.882924) (xy 283.993018 -111.823468)
			(xy 284.008539 -111.765543) (xy 284.031488 -111.710139) (xy 284.061472 -111.658205) (xy 284.097978 -111.610629)
			(xy 284.140383 -111.568224) (xy 284.187959 -111.531718) (xy 284.239893 -111.501734) (xy 284.295297 -111.478785)
			(xy 284.353222 -111.463264) (xy 284.412678 -111.455436) (xy 284.472646 -111.455436) (xy 284.532102 -111.463264)
			(xy 284.590027 -111.478785) (xy 284.645431 -111.501734) (xy 284.697365 -111.531718) (xy 284.744941 -111.568224)
			(xy 284.787346 -111.610629) (xy 284.823852 -111.658205) (xy 284.853836 -111.710139) (xy 284.876785 -111.765543)
			(xy 284.892306 -111.823468) (xy 284.900134 -111.882924) (xy 284.900624 -111.912908) (xy 284.900624 -112.776508)
			(xy 284.900495 -112.784382) (xy 382.967992 -112.784382) (xy 382.967992 -111.920782) (xy 382.968482 -111.890814)
			(xy 382.976305 -111.831392) (xy 382.991818 -111.773499) (xy 383.014754 -111.718126) (xy 383.044721 -111.66622)
			(xy 383.081208 -111.61867) (xy 383.123588 -111.57629) (xy 383.171138 -111.539803) (xy 383.223044 -111.509836)
			(xy 383.278417 -111.4869) (xy 383.33631 -111.471387) (xy 383.395732 -111.463564) (xy 383.455668 -111.463564)
			(xy 383.51509 -111.471387) (xy 383.572983 -111.4869) (xy 383.628356 -111.509836) (xy 383.680262 -111.539803)
			(xy 383.727812 -111.57629) (xy 383.770192 -111.61867) (xy 383.806679 -111.66622) (xy 383.836646 -111.718126)
			(xy 383.859582 -111.773499) (xy 383.875095 -111.831392) (xy 383.882918 -111.890814) (xy 383.883408 -111.920782)
			(xy 383.883408 -112.776508) (xy 400.085052 -112.776508) (xy 400.085052 -111.912908) (xy 400.085542 -111.88294)
			(xy 400.093365 -111.823518) (xy 400.108878 -111.765625) (xy 400.131814 -111.710252) (xy 400.161781 -111.658346)
			(xy 400.198268 -111.610796) (xy 400.240648 -111.568416) (xy 400.288198 -111.531929) (xy 400.340104 -111.501962)
			(xy 400.395477 -111.479026) (xy 400.45337 -111.463513) (xy 400.512792 -111.45569) (xy 400.572728 -111.45569)
			(xy 400.63215 -111.463513) (xy 400.690043 -111.479026) (xy 400.745416 -111.501962) (xy 400.797322 -111.531929)
			(xy 400.844872 -111.568416) (xy 400.887252 -111.610796) (xy 400.923739 -111.658346) (xy 400.953706 -111.710252)
			(xy 400.976642 -111.765625) (xy 400.992155 -111.823518) (xy 400.999978 -111.88294) (xy 401.000468 -111.912908)
			(xy 401.000468 -112.776508) (xy 400.999978 -112.806476) (xy 400.992155 -112.865898) (xy 400.976642 -112.923791)
			(xy 400.953706 -112.979164) (xy 400.923739 -113.03107) (xy 400.887252 -113.07862) (xy 400.844872 -113.121)
			(xy 400.797322 -113.157487) (xy 400.745416 -113.187454) (xy 400.690043 -113.21039) (xy 400.63215 -113.225903)
			(xy 400.572728 -113.233726) (xy 400.512792 -113.233726) (xy 400.45337 -113.225903) (xy 400.395477 -113.21039)
			(xy 400.340104 -113.187454) (xy 400.288198 -113.157487) (xy 400.240648 -113.121) (xy 400.198268 -113.07862)
			(xy 400.161781 -113.03107) (xy 400.131814 -112.979164) (xy 400.108878 -112.923791) (xy 400.093365 -112.865898)
			(xy 400.085542 -112.806476) (xy 400.085052 -112.776508) (xy 383.883408 -112.776508) (xy 383.883408 -112.784382)
			(xy 383.882918 -112.81435) (xy 383.875095 -112.873772) (xy 383.859582 -112.931665) (xy 383.836646 -112.987038)
			(xy 383.806679 -113.038944) (xy 383.770192 -113.086494) (xy 383.727812 -113.128874) (xy 383.680262 -113.165361)
			(xy 383.628356 -113.195328) (xy 383.572983 -113.218264) (xy 383.51509 -113.233777) (xy 383.455668 -113.2416)
			(xy 383.395732 -113.2416) (xy 383.33631 -113.233777) (xy 383.278417 -113.218264) (xy 383.223044 -113.195328)
			(xy 383.171138 -113.165361) (xy 383.123588 -113.128874) (xy 383.081208 -113.086494) (xy 383.044721 -113.038944)
			(xy 383.014754 -112.987038) (xy 382.991818 -112.931665) (xy 382.976305 -112.873772) (xy 382.968482 -112.81435)
			(xy 382.967992 -112.784382) (xy 284.900495 -112.784382) (xy 284.900134 -112.806492) (xy 284.892306 -112.865948)
			(xy 284.876785 -112.923873) (xy 284.853836 -112.979277) (xy 284.823852 -113.031211) (xy 284.787346 -113.078787)
			(xy 284.744941 -113.121192) (xy 284.697365 -113.157698) (xy 284.645431 -113.187682) (xy 284.590027 -113.210631)
			(xy 284.532102 -113.226152) (xy 284.472646 -113.23398) (xy 284.412678 -113.23398) (xy 284.353222 -113.226152)
			(xy 284.295297 -113.210631) (xy 284.239893 -113.187682) (xy 284.187959 -113.157698) (xy 284.140383 -113.121192)
			(xy 284.097978 -113.078787) (xy 284.061472 -113.031211) (xy 284.031488 -112.979277) (xy 284.008539 -112.923873)
			(xy 283.993018 -112.865948) (xy 283.98519 -112.806492) (xy 283.9847 -112.776508) (xy 267.783564 -112.776508)
			(xy 267.783564 -112.784382) (xy 267.783074 -112.814366) (xy 267.775246 -112.873822) (xy 267.759725 -112.931747)
			(xy 267.736776 -112.987151) (xy 267.706792 -113.039085) (xy 267.670286 -113.086661) (xy 267.627881 -113.129066)
			(xy 267.580305 -113.165572) (xy 267.528371 -113.195556) (xy 267.472967 -113.218505) (xy 267.415042 -113.234026)
			(xy 267.355586 -113.241854) (xy 267.295618 -113.241854) (xy 267.236162 -113.234026) (xy 267.178237 -113.218505)
			(xy 267.122833 -113.195556) (xy 267.070899 -113.165572) (xy 267.023323 -113.129066) (xy 266.980918 -113.086661)
			(xy 266.944412 -113.039085) (xy 266.914428 -112.987151) (xy 266.891479 -112.931747) (xy 266.875958 -112.873822)
			(xy 266.86813 -112.814366) (xy 266.86764 -112.784382) (xy 168.800651 -112.784382) (xy 168.80029 -112.806492)
			(xy 168.792462 -112.865948) (xy 168.776941 -112.923873) (xy 168.753992 -112.979277) (xy 168.724008 -113.031211)
			(xy 168.687502 -113.078787) (xy 168.645097 -113.121192) (xy 168.597521 -113.157698) (xy 168.545587 -113.187682)
			(xy 168.490183 -113.210631) (xy 168.432258 -113.226152) (xy 168.372802 -113.23398) (xy 168.312834 -113.23398)
			(xy 168.253378 -113.226152) (xy 168.195453 -113.210631) (xy 168.140049 -113.187682) (xy 168.088115 -113.157698)
			(xy 168.040539 -113.121192) (xy 167.998134 -113.078787) (xy 167.961628 -113.031211) (xy 167.931644 -112.979277)
			(xy 167.908695 -112.923873) (xy 167.893174 -112.865948) (xy 167.885346 -112.806492) (xy 167.884856 -112.776508)
			(xy 151.68372 -112.776508) (xy 151.68372 -112.784382) (xy 151.68323 -112.814366) (xy 151.675402 -112.873822)
			(xy 151.659881 -112.931747) (xy 151.636932 -112.987151) (xy 151.606948 -113.039085) (xy 151.570442 -113.086661)
			(xy 151.528037 -113.129066) (xy 151.480461 -113.165572) (xy 151.428527 -113.195556) (xy 151.373123 -113.218505)
			(xy 151.315198 -113.234026) (xy 151.255742 -113.241854) (xy 151.195774 -113.241854) (xy 151.136318 -113.234026)
			(xy 151.078393 -113.218505) (xy 151.022989 -113.195556) (xy 150.971055 -113.165572) (xy 150.923479 -113.129066)
			(xy 150.881074 -113.086661) (xy 150.844568 -113.039085) (xy 150.814584 -112.987151) (xy 150.791635 -112.931747)
			(xy 150.776114 -112.873822) (xy 150.768286 -112.814366) (xy 150.767796 -112.784382) (xy 52.700299 -112.784382)
			(xy 52.699938 -112.806476) (xy 52.692115 -112.865898) (xy 52.676602 -112.923791) (xy 52.653666 -112.979164)
			(xy 52.623699 -113.03107) (xy 52.587212 -113.07862) (xy 52.544832 -113.121) (xy 52.497282 -113.157487)
			(xy 52.445376 -113.187454) (xy 52.390003 -113.21039) (xy 52.33211 -113.225903) (xy 52.272688 -113.233726)
			(xy 52.212752 -113.233726) (xy 52.15333 -113.225903) (xy 52.095437 -113.21039) (xy 52.040064 -113.187454)
			(xy 51.988158 -113.157487) (xy 51.940608 -113.121) (xy 51.898228 -113.07862) (xy 51.861741 -113.03107)
			(xy 51.831774 -112.979164) (xy 51.808838 -112.923791) (xy 51.793325 -112.865898) (xy 51.785502 -112.806476)
			(xy 51.785012 -112.776508) (xy 35.583368 -112.776508) (xy 35.583368 -112.784382) (xy 35.582878 -112.81435)
			(xy 35.575055 -112.873772) (xy 35.559542 -112.931665) (xy 35.536606 -112.987038) (xy 35.506639 -113.038944)
			(xy 35.470152 -113.086494) (xy 35.427772 -113.128874) (xy 35.380222 -113.165361) (xy 35.328316 -113.195328)
			(xy 35.272943 -113.218264) (xy 35.21505 -113.233777) (xy 35.155628 -113.2416) (xy 35.095692 -113.2416)
			(xy 35.03627 -113.233777) (xy 34.978377 -113.218264) (xy 34.923004 -113.195328) (xy 34.871098 -113.165361)
			(xy 34.823548 -113.128874) (xy 34.781168 -113.086494) (xy 34.744681 -113.038944) (xy 34.714714 -112.987038)
			(xy 34.691778 -112.931665) (xy 34.676265 -112.873772) (xy 34.668442 -112.81435) (xy 34.667952 -112.784382)
			(xy 5.324094 -112.784382) (xy 5.324094 -117.758718) (xy 74.474832 -117.758718) (xy 74.474832 -116.895118)
			(xy 74.475322 -116.865134) (xy 74.48315 -116.805678) (xy 74.498671 -116.747753) (xy 74.52162 -116.692349)
			(xy 74.551604 -116.640415) (xy 74.58811 -116.592839) (xy 74.630515 -116.550434) (xy 74.678091 -116.513928)
			(xy 74.730025 -116.483944) (xy 74.785429 -116.460995) (xy 74.843354 -116.445474) (xy 74.90281 -116.437646)
			(xy 74.962778 -116.437646) (xy 75.022234 -116.445474) (xy 75.080159 -116.460995) (xy 75.135563 -116.483944)
			(xy 75.187497 -116.513928) (xy 75.235073 -116.550434) (xy 75.277478 -116.592839) (xy 75.313984 -116.640415)
			(xy 75.343968 -116.692349) (xy 75.366917 -116.747753) (xy 75.382438 -116.805678) (xy 75.390266 -116.865134)
			(xy 75.390756 -116.895118) (xy 75.390756 -117.758718) (xy 190.574676 -117.758718) (xy 190.574676 -116.895118)
			(xy 190.575166 -116.865134) (xy 190.582994 -116.805678) (xy 190.598515 -116.747753) (xy 190.621464 -116.692349)
			(xy 190.651448 -116.640415) (xy 190.687954 -116.592839) (xy 190.730359 -116.550434) (xy 190.777935 -116.513928)
			(xy 190.829869 -116.483944) (xy 190.885273 -116.460995) (xy 190.943198 -116.445474) (xy 191.002654 -116.437646)
			(xy 191.062622 -116.437646) (xy 191.122078 -116.445474) (xy 191.180003 -116.460995) (xy 191.235407 -116.483944)
			(xy 191.287341 -116.513928) (xy 191.334917 -116.550434) (xy 191.377322 -116.592839) (xy 191.413828 -116.640415)
			(xy 191.443812 -116.692349) (xy 191.466761 -116.747753) (xy 191.482282 -116.805678) (xy 191.49011 -116.865134)
			(xy 191.4906 -116.895118) (xy 191.4906 -117.758718) (xy 306.675028 -117.758718) (xy 306.675028 -116.895118)
			(xy 306.675518 -116.86515) (xy 306.683341 -116.805728) (xy 306.698854 -116.747835) (xy 306.72179 -116.692462)
			(xy 306.751757 -116.640556) (xy 306.788244 -116.593006) (xy 306.830624 -116.550626) (xy 306.878174 -116.514139)
			(xy 306.93008 -116.484172) (xy 306.985453 -116.461236) (xy 307.043346 -116.445723) (xy 307.102768 -116.4379)
			(xy 307.162704 -116.4379) (xy 307.222126 -116.445723) (xy 307.280019 -116.461236) (xy 307.335392 -116.484172)
			(xy 307.387298 -116.514139) (xy 307.434848 -116.550626) (xy 307.477228 -116.593006) (xy 307.513715 -116.640556)
			(xy 307.543682 -116.692462) (xy 307.566618 -116.747835) (xy 307.582131 -116.805728) (xy 307.589954 -116.86515)
			(xy 307.590444 -116.895118) (xy 307.590444 -117.758718) (xy 307.590436 -117.759226) (xy 422.774872 -117.759226)
			(xy 422.774872 -116.895626) (xy 422.775362 -116.865642) (xy 422.78319 -116.806186) (xy 422.798711 -116.748261)
			(xy 422.82166 -116.692857) (xy 422.851644 -116.640923) (xy 422.88815 -116.593347) (xy 422.930555 -116.550942)
			(xy 422.978131 -116.514436) (xy 423.030065 -116.484452) (xy 423.085469 -116.461503) (xy 423.143394 -116.445982)
			(xy 423.20285 -116.438154) (xy 423.262818 -116.438154) (xy 423.322274 -116.445982) (xy 423.380199 -116.461503)
			(xy 423.435603 -116.484452) (xy 423.487537 -116.514436) (xy 423.535113 -116.550942) (xy 423.577518 -116.593347)
			(xy 423.614024 -116.640923) (xy 423.644008 -116.692857) (xy 423.666957 -116.748261) (xy 423.682478 -116.806186)
			(xy 423.690306 -116.865642) (xy 423.690796 -116.895626) (xy 423.690796 -117.759226) (xy 423.690306 -117.78921)
			(xy 423.682478 -117.848666) (xy 423.666957 -117.906591) (xy 423.644008 -117.961995) (xy 423.614024 -118.013929)
			(xy 423.577518 -118.061505) (xy 423.535113 -118.10391) (xy 423.487537 -118.140416) (xy 423.435603 -118.1704)
			(xy 423.380199 -118.193349) (xy 423.322274 -118.20887) (xy 423.262818 -118.216698) (xy 423.20285 -118.216698)
			(xy 423.143394 -118.20887) (xy 423.085469 -118.193349) (xy 423.030065 -118.1704) (xy 422.978131 -118.140416)
			(xy 422.930555 -118.10391) (xy 422.88815 -118.061505) (xy 422.851644 -118.013929) (xy 422.82166 -117.961995)
			(xy 422.798711 -117.906591) (xy 422.78319 -117.848666) (xy 422.775362 -117.78921) (xy 422.774872 -117.759226)
			(xy 307.590436 -117.759226) (xy 307.589954 -117.788686) (xy 307.582131 -117.848108) (xy 307.566618 -117.906001)
			(xy 307.543682 -117.961374) (xy 307.513715 -118.01328) (xy 307.477228 -118.06083) (xy 307.434848 -118.10321)
			(xy 307.387298 -118.139697) (xy 307.335392 -118.169664) (xy 307.280019 -118.1926) (xy 307.222126 -118.208113)
			(xy 307.162704 -118.215936) (xy 307.102768 -118.215936) (xy 307.043346 -118.208113) (xy 306.985453 -118.1926)
			(xy 306.93008 -118.169664) (xy 306.878174 -118.139697) (xy 306.830624 -118.10321) (xy 306.788244 -118.06083)
			(xy 306.751757 -118.01328) (xy 306.72179 -117.961374) (xy 306.698854 -117.906001) (xy 306.683341 -117.848108)
			(xy 306.675518 -117.788686) (xy 306.675028 -117.758718) (xy 191.4906 -117.758718) (xy 191.49011 -117.788702)
			(xy 191.482282 -117.848158) (xy 191.466761 -117.906083) (xy 191.443812 -117.961487) (xy 191.413828 -118.013421)
			(xy 191.377322 -118.060997) (xy 191.334917 -118.103402) (xy 191.287341 -118.139908) (xy 191.235407 -118.169892)
			(xy 191.180003 -118.192841) (xy 191.122078 -118.208362) (xy 191.062622 -118.21619) (xy 191.002654 -118.21619)
			(xy 190.943198 -118.208362) (xy 190.885273 -118.192841) (xy 190.829869 -118.169892) (xy 190.777935 -118.139908)
			(xy 190.730359 -118.103402) (xy 190.687954 -118.060997) (xy 190.651448 -118.013421) (xy 190.621464 -117.961487)
			(xy 190.598515 -117.906083) (xy 190.582994 -117.848158) (xy 190.575166 -117.788702) (xy 190.574676 -117.758718)
			(xy 75.390756 -117.758718) (xy 75.390266 -117.788702) (xy 75.382438 -117.848158) (xy 75.366917 -117.906083)
			(xy 75.343968 -117.961487) (xy 75.313984 -118.013421) (xy 75.277478 -118.060997) (xy 75.235073 -118.103402)
			(xy 75.187497 -118.139908) (xy 75.135563 -118.169892) (xy 75.080159 -118.192841) (xy 75.022234 -118.208362)
			(xy 74.962778 -118.21619) (xy 74.90281 -118.21619) (xy 74.843354 -118.208362) (xy 74.785429 -118.192841)
			(xy 74.730025 -118.169892) (xy 74.678091 -118.139908) (xy 74.630515 -118.103402) (xy 74.58811 -118.060997)
			(xy 74.551604 -118.013421) (xy 74.52162 -117.961487) (xy 74.498671 -117.906083) (xy 74.48315 -117.848158)
			(xy 74.475322 -117.788702) (xy 74.474832 -117.758718) (xy 5.324094 -117.758718) (xy 5.324094 -120.087898)
			(xy 34.667952 -120.087898) (xy 34.667952 -119.224298) (xy 34.668442 -119.19433) (xy 34.676265 -119.134908)
			(xy 34.691778 -119.077015) (xy 34.714714 -119.021642) (xy 34.744681 -118.969736) (xy 34.781168 -118.922186)
			(xy 34.823548 -118.879806) (xy 34.871098 -118.843319) (xy 34.923004 -118.813352) (xy 34.978377 -118.790416)
			(xy 35.03627 -118.774903) (xy 35.095692 -118.76708) (xy 35.155628 -118.76708) (xy 35.21505 -118.774903)
			(xy 35.272943 -118.790416) (xy 35.328316 -118.813352) (xy 35.380222 -118.843319) (xy 35.427772 -118.879806)
			(xy 35.470152 -118.922186) (xy 35.506639 -118.969736) (xy 35.536606 -119.021642) (xy 35.559542 -119.077015)
			(xy 35.575055 -119.134908) (xy 35.582878 -119.19433) (xy 35.583368 -119.224298) (xy 35.583368 -120.086374)
			(xy 53.639212 -120.086374) (xy 53.639212 -119.222774) (xy 53.639702 -119.192806) (xy 53.647525 -119.133384)
			(xy 53.663038 -119.075491) (xy 53.685974 -119.020118) (xy 53.715941 -118.968212) (xy 53.752428 -118.920662)
			(xy 53.794808 -118.878282) (xy 53.842358 -118.841795) (xy 53.894264 -118.811828) (xy 53.949637 -118.788892)
			(xy 54.00753 -118.773379) (xy 54.066952 -118.765556) (xy 54.126888 -118.765556) (xy 54.18631 -118.773379)
			(xy 54.244203 -118.788892) (xy 54.299576 -118.811828) (xy 54.351482 -118.841795) (xy 54.399032 -118.878282)
			(xy 54.441412 -118.920662) (xy 54.477899 -118.968212) (xy 54.507866 -119.020118) (xy 54.530802 -119.075491)
			(xy 54.546315 -119.133384) (xy 54.554138 -119.192806) (xy 54.554628 -119.222774) (xy 54.554628 -119.567198)
			(xy 66.599308 -119.567198) (xy 66.599308 -118.703598) (xy 66.599798 -118.673614) (xy 66.607626 -118.614158)
			(xy 66.623147 -118.556233) (xy 66.646096 -118.500829) (xy 66.67608 -118.448895) (xy 66.712586 -118.401319)
			(xy 66.754991 -118.358914) (xy 66.802567 -118.322408) (xy 66.854501 -118.292424) (xy 66.909905 -118.269475)
			(xy 66.96783 -118.253954) (xy 67.027286 -118.246126) (xy 67.087254 -118.246126) (xy 67.14671 -118.253954)
			(xy 67.204635 -118.269475) (xy 67.260039 -118.292424) (xy 67.311973 -118.322408) (xy 67.359549 -118.358914)
			(xy 67.401954 -118.401319) (xy 67.43846 -118.448895) (xy 67.468444 -118.500829) (xy 67.491393 -118.556233)
			(xy 67.506914 -118.614158) (xy 67.514742 -118.673614) (xy 67.515232 -118.703598) (xy 67.515232 -119.55907)
			(xy 81.07426 -119.55907) (xy 81.07426 -118.69547) (xy 81.07475 -118.665486) (xy 81.082578 -118.60603)
			(xy 81.098099 -118.548105) (xy 81.121048 -118.492701) (xy 81.151032 -118.440767) (xy 81.187538 -118.393191)
			(xy 81.229943 -118.350786) (xy 81.277519 -118.31428) (xy 81.329453 -118.284296) (xy 81.384857 -118.261347)
			(xy 81.442782 -118.245826) (xy 81.502238 -118.237998) (xy 81.562206 -118.237998) (xy 81.621662 -118.245826)
			(xy 81.679587 -118.261347) (xy 81.734991 -118.284296) (xy 81.786925 -118.31428) (xy 81.834501 -118.350786)
			(xy 81.876906 -118.393191) (xy 81.913412 -118.440767) (xy 81.943396 -118.492701) (xy 81.966345 -118.548105)
			(xy 81.981866 -118.60603) (xy 81.989694 -118.665486) (xy 81.990184 -118.69547) (xy 81.990184 -119.55907)
			(xy 81.989694 -119.589054) (xy 81.981866 -119.64851) (xy 81.966345 -119.706435) (xy 81.943396 -119.761839)
			(xy 81.913412 -119.813773) (xy 81.876906 -119.861349) (xy 81.834501 -119.903754) (xy 81.786925 -119.94026)
			(xy 81.734991 -119.970244) (xy 81.679587 -119.993193) (xy 81.621662 -120.008714) (xy 81.562206 -120.016542)
			(xy 81.502238 -120.016542) (xy 81.442782 -120.008714) (xy 81.384857 -119.993193) (xy 81.329453 -119.970244)
			(xy 81.277519 -119.94026) (xy 81.229943 -119.903754) (xy 81.187538 -119.861349) (xy 81.151032 -119.813773)
			(xy 81.121048 -119.761839) (xy 81.098099 -119.706435) (xy 81.082578 -119.64851) (xy 81.07475 -119.589054)
			(xy 81.07426 -119.55907) (xy 67.515232 -119.55907) (xy 67.515232 -119.567198) (xy 67.514742 -119.597182)
			(xy 67.506914 -119.656638) (xy 67.491393 -119.714563) (xy 67.468444 -119.769967) (xy 67.43846 -119.821901)
			(xy 67.401954 -119.869477) (xy 67.359549 -119.911882) (xy 67.311973 -119.948388) (xy 67.260039 -119.978372)
			(xy 67.204635 -120.001321) (xy 67.14671 -120.016842) (xy 67.087254 -120.02467) (xy 67.027286 -120.02467)
			(xy 66.96783 -120.016842) (xy 66.909905 -120.001321) (xy 66.854501 -119.978372) (xy 66.802567 -119.948388)
			(xy 66.754991 -119.911882) (xy 66.712586 -119.869477) (xy 66.67608 -119.821901) (xy 66.646096 -119.769967)
			(xy 66.623147 -119.714563) (xy 66.607626 -119.656638) (xy 66.599798 -119.597182) (xy 66.599308 -119.567198)
			(xy 54.554628 -119.567198) (xy 54.554628 -120.086374) (xy 54.554138 -120.116342) (xy 54.546315 -120.175764)
			(xy 54.530802 -120.233657) (xy 54.507866 -120.28903) (xy 54.477899 -120.340936) (xy 54.441412 -120.388486)
			(xy 54.399032 -120.430866) (xy 54.351482 -120.467353) (xy 54.299576 -120.49732) (xy 54.244203 -120.520256)
			(xy 54.18631 -120.535769) (xy 54.126888 -120.543592) (xy 54.066952 -120.543592) (xy 54.00753 -120.535769)
			(xy 53.949637 -120.520256) (xy 53.894264 -120.49732) (xy 53.842358 -120.467353) (xy 53.794808 -120.430866)
			(xy 53.752428 -120.388486) (xy 53.715941 -120.340936) (xy 53.685974 -120.28903) (xy 53.663038 -120.233657)
			(xy 53.647525 -120.175764) (xy 53.639702 -120.116342) (xy 53.639212 -120.086374) (xy 35.583368 -120.086374)
			(xy 35.583368 -120.087898) (xy 35.582878 -120.117866) (xy 35.575055 -120.177288) (xy 35.559542 -120.235181)
			(xy 35.536606 -120.290554) (xy 35.506639 -120.34246) (xy 35.470152 -120.39001) (xy 35.427772 -120.43239)
			(xy 35.380222 -120.468877) (xy 35.328316 -120.498844) (xy 35.272943 -120.52178) (xy 35.21505 -120.537293)
			(xy 35.155628 -120.545116) (xy 35.095692 -120.545116) (xy 35.03627 -120.537293) (xy 34.978377 -120.52178)
			(xy 34.923004 -120.498844) (xy 34.871098 -120.468877) (xy 34.823548 -120.43239) (xy 34.781168 -120.39001)
			(xy 34.744681 -120.34246) (xy 34.714714 -120.290554) (xy 34.691778 -120.235181) (xy 34.676265 -120.177288)
			(xy 34.668442 -120.117866) (xy 34.667952 -120.087898) (xy 5.324094 -120.087898) (xy 5.324094 -121.894346)
			(xy 37.31006 -121.894346) (xy 37.31006 -121.030746) (xy 37.31055 -121.000778) (xy 37.318373 -120.941356)
			(xy 37.333886 -120.883463) (xy 37.356822 -120.82809) (xy 37.386789 -120.776184) (xy 37.423276 -120.728634)
			(xy 37.465656 -120.686254) (xy 37.513206 -120.649767) (xy 37.565112 -120.6198) (xy 37.620485 -120.596864)
			(xy 37.678378 -120.581351) (xy 37.7378 -120.573528) (xy 37.797736 -120.573528) (xy 37.857158 -120.581351)
			(xy 37.915051 -120.596864) (xy 37.970424 -120.6198) (xy 38.02233 -120.649767) (xy 38.06988 -120.686254)
			(xy 38.11226 -120.728634) (xy 38.148747 -120.776184) (xy 38.178714 -120.82809) (xy 38.20165 -120.883463)
			(xy 38.217163 -120.941356) (xy 38.224986 -121.000778) (xy 38.225476 -121.030746) (xy 38.225476 -121.886472)
			(xy 51.785012 -121.886472) (xy 51.785012 -121.022872) (xy 51.785502 -120.992904) (xy 51.793325 -120.933482)
			(xy 51.808838 -120.875589) (xy 51.831774 -120.820216) (xy 51.861741 -120.76831) (xy 51.898228 -120.72076)
			(xy 51.940608 -120.67838) (xy 51.988158 -120.641893) (xy 52.040064 -120.611926) (xy 52.095437 -120.58899)
			(xy 52.15333 -120.573477) (xy 52.212752 -120.565654) (xy 52.272688 -120.565654) (xy 52.33211 -120.573477)
			(xy 52.390003 -120.58899) (xy 52.445376 -120.611926) (xy 52.497282 -120.641893) (xy 52.544832 -120.67838)
			(xy 52.587212 -120.72076) (xy 52.623699 -120.76831) (xy 52.653666 -120.820216) (xy 52.676602 -120.875589)
			(xy 52.692115 -120.933482) (xy 52.699938 -120.992904) (xy 52.700428 -121.022872) (xy 52.700428 -121.367296)
			(xy 64.745108 -121.367296) (xy 64.745108 -120.503696) (xy 64.745598 -120.473712) (xy 64.753426 -120.414256)
			(xy 64.768947 -120.356331) (xy 64.791896 -120.300927) (xy 64.82188 -120.248993) (xy 64.858386 -120.201417)
			(xy 64.900791 -120.159012) (xy 64.948367 -120.122506) (xy 65.000301 -120.092522) (xy 65.055705 -120.069573)
			(xy 65.11363 -120.054052) (xy 65.173086 -120.046224) (xy 65.233054 -120.046224) (xy 65.29251 -120.054052)
			(xy 65.350435 -120.069573) (xy 65.405839 -120.092522) (xy 65.457773 -120.122506) (xy 65.505349 -120.159012)
			(xy 65.547754 -120.201417) (xy 65.58426 -120.248993) (xy 65.614244 -120.300927) (xy 65.637193 -120.356331)
			(xy 65.652714 -120.414256) (xy 65.660542 -120.473712) (xy 65.661032 -120.503696) (xy 65.661032 -121.365772)
			(xy 83.716368 -121.365772) (xy 83.716368 -120.502172) (xy 83.716858 -120.472188) (xy 83.724686 -120.412732)
			(xy 83.740207 -120.354807) (xy 83.763156 -120.299403) (xy 83.79314 -120.247469) (xy 83.829646 -120.199893)
			(xy 83.872051 -120.157488) (xy 83.919627 -120.120982) (xy 83.971561 -120.090998) (xy 84.026965 -120.068049)
			(xy 84.08489 -120.052528) (xy 84.144346 -120.0447) (xy 84.204314 -120.0447) (xy 84.26377 -120.052528)
			(xy 84.321695 -120.068049) (xy 84.369615 -120.087898) (xy 150.767796 -120.087898) (xy 150.767796 -119.224298)
			(xy 150.768286 -119.194314) (xy 150.776114 -119.134858) (xy 150.791635 -119.076933) (xy 150.814584 -119.021529)
			(xy 150.844568 -118.969595) (xy 150.881074 -118.922019) (xy 150.923479 -118.879614) (xy 150.971055 -118.843108)
			(xy 151.022989 -118.813124) (xy 151.078393 -118.790175) (xy 151.136318 -118.774654) (xy 151.195774 -118.766826)
			(xy 151.255742 -118.766826) (xy 151.315198 -118.774654) (xy 151.373123 -118.790175) (xy 151.428527 -118.813124)
			(xy 151.480461 -118.843108) (xy 151.528037 -118.879614) (xy 151.570442 -118.922019) (xy 151.606948 -118.969595)
			(xy 151.636932 -119.021529) (xy 151.659881 -119.076933) (xy 151.675402 -119.134858) (xy 151.68323 -119.194314)
			(xy 151.68372 -119.224298) (xy 151.68372 -120.086374) (xy 169.739056 -120.086374) (xy 169.739056 -119.222774)
			(xy 169.739546 -119.19279) (xy 169.747374 -119.133334) (xy 169.762895 -119.075409) (xy 169.785844 -119.020005)
			(xy 169.815828 -118.968071) (xy 169.852334 -118.920495) (xy 169.894739 -118.87809) (xy 169.942315 -118.841584)
			(xy 169.994249 -118.8116) (xy 170.049653 -118.788651) (xy 170.107578 -118.77313) (xy 170.167034 -118.765302)
			(xy 170.227002 -118.765302) (xy 170.286458 -118.77313) (xy 170.344383 -118.788651) (xy 170.399787 -118.8116)
			(xy 170.451721 -118.841584) (xy 170.499297 -118.87809) (xy 170.541702 -118.920495) (xy 170.578208 -118.968071)
			(xy 170.608192 -119.020005) (xy 170.631141 -119.075409) (xy 170.646662 -119.133334) (xy 170.65449 -119.19279)
			(xy 170.65498 -119.222774) (xy 170.65498 -119.567198) (xy 182.69966 -119.567198) (xy 182.69966 -118.703598)
			(xy 182.70015 -118.67363) (xy 182.707973 -118.614208) (xy 182.723486 -118.556315) (xy 182.746422 -118.500942)
			(xy 182.776389 -118.449036) (xy 182.812876 -118.401486) (xy 182.855256 -118.359106) (xy 182.902806 -118.322619)
			(xy 182.954712 -118.292652) (xy 183.010085 -118.269716) (xy 183.067978 -118.254203) (xy 183.1274 -118.24638)
			(xy 183.187336 -118.24638) (xy 183.246758 -118.254203) (xy 183.304651 -118.269716) (xy 183.360024 -118.292652)
			(xy 183.41193 -118.322619) (xy 183.45948 -118.359106) (xy 183.50186 -118.401486) (xy 183.538347 -118.449036)
			(xy 183.568314 -118.500942) (xy 183.59125 -118.556315) (xy 183.606763 -118.614208) (xy 183.614586 -118.67363)
			(xy 183.615076 -118.703598) (xy 183.615076 -119.559324) (xy 197.174612 -119.559324) (xy 197.174612 -118.695724)
			(xy 197.175102 -118.665756) (xy 197.182925 -118.606334) (xy 197.198438 -118.548441) (xy 197.221374 -118.493068)
			(xy 197.251341 -118.441162) (xy 197.287828 -118.393612) (xy 197.330208 -118.351232) (xy 197.377758 -118.314745)
			(xy 197.429664 -118.284778) (xy 197.485037 -118.261842) (xy 197.54293 -118.246329) (xy 197.602352 -118.238506)
			(xy 197.662288 -118.238506) (xy 197.72171 -118.246329) (xy 197.779603 -118.261842) (xy 197.834976 -118.284778)
			(xy 197.886882 -118.314745) (xy 197.934432 -118.351232) (xy 197.976812 -118.393612) (xy 198.013299 -118.441162)
			(xy 198.043266 -118.493068) (xy 198.066202 -118.548441) (xy 198.081715 -118.606334) (xy 198.089538 -118.665756)
			(xy 198.090028 -118.695724) (xy 198.090028 -119.559324) (xy 198.089538 -119.589292) (xy 198.081715 -119.648714)
			(xy 198.066202 -119.706607) (xy 198.043266 -119.76198) (xy 198.013299 -119.813886) (xy 197.976812 -119.861436)
			(xy 197.934432 -119.903816) (xy 197.886882 -119.940303) (xy 197.834976 -119.97027) (xy 197.779603 -119.993206)
			(xy 197.72171 -120.008719) (xy 197.662288 -120.016542) (xy 197.602352 -120.016542) (xy 197.54293 -120.008719)
			(xy 197.485037 -119.993206) (xy 197.429664 -119.97027) (xy 197.377758 -119.940303) (xy 197.330208 -119.903816)
			(xy 197.287828 -119.861436) (xy 197.251341 -119.813886) (xy 197.221374 -119.76198) (xy 197.198438 -119.706607)
			(xy 197.182925 -119.648714) (xy 197.175102 -119.589292) (xy 197.174612 -119.559324) (xy 183.615076 -119.559324)
			(xy 183.615076 -119.567198) (xy 183.614586 -119.597166) (xy 183.606763 -119.656588) (xy 183.59125 -119.714481)
			(xy 183.568314 -119.769854) (xy 183.538347 -119.82176) (xy 183.50186 -119.86931) (xy 183.45948 -119.91169)
			(xy 183.41193 -119.948177) (xy 183.360024 -119.978144) (xy 183.304651 -120.00108) (xy 183.246758 -120.016593)
			(xy 183.187336 -120.024416) (xy 183.1274 -120.024416) (xy 183.067978 -120.016593) (xy 183.010085 -120.00108)
			(xy 182.954712 -119.978144) (xy 182.902806 -119.948177) (xy 182.855256 -119.91169) (xy 182.812876 -119.86931)
			(xy 182.776389 -119.82176) (xy 182.746422 -119.769854) (xy 182.723486 -119.714481) (xy 182.707973 -119.656588)
			(xy 182.70015 -119.597166) (xy 182.69966 -119.567198) (xy 170.65498 -119.567198) (xy 170.65498 -120.086374)
			(xy 170.65449 -120.116358) (xy 170.646662 -120.175814) (xy 170.631141 -120.233739) (xy 170.608192 -120.289143)
			(xy 170.578208 -120.341077) (xy 170.541702 -120.388653) (xy 170.499297 -120.431058) (xy 170.451721 -120.467564)
			(xy 170.399787 -120.497548) (xy 170.344383 -120.520497) (xy 170.286458 -120.536018) (xy 170.227002 -120.543846)
			(xy 170.167034 -120.543846) (xy 170.107578 -120.536018) (xy 170.049653 -120.520497) (xy 169.994249 -120.497548)
			(xy 169.942315 -120.467564) (xy 169.894739 -120.431058) (xy 169.852334 -120.388653) (xy 169.815828 -120.341077)
			(xy 169.785844 -120.289143) (xy 169.762895 -120.233739) (xy 169.747374 -120.175814) (xy 169.739546 -120.116358)
			(xy 169.739056 -120.086374) (xy 151.68372 -120.086374) (xy 151.68372 -120.087898) (xy 151.68323 -120.117882)
			(xy 151.675402 -120.177338) (xy 151.659881 -120.235263) (xy 151.636932 -120.290667) (xy 151.606948 -120.342601)
			(xy 151.570442 -120.390177) (xy 151.528037 -120.432582) (xy 151.480461 -120.469088) (xy 151.428527 -120.499072)
			(xy 151.373123 -120.522021) (xy 151.315198 -120.537542) (xy 151.255742 -120.54537) (xy 151.195774 -120.54537)
			(xy 151.136318 -120.537542) (xy 151.078393 -120.522021) (xy 151.022989 -120.499072) (xy 150.971055 -120.469088)
			(xy 150.923479 -120.432582) (xy 150.881074 -120.390177) (xy 150.844568 -120.342601) (xy 150.814584 -120.290667)
			(xy 150.791635 -120.235263) (xy 150.776114 -120.177338) (xy 150.768286 -120.117882) (xy 150.767796 -120.087898)
			(xy 84.369615 -120.087898) (xy 84.377099 -120.090998) (xy 84.429033 -120.120982) (xy 84.476609 -120.157488)
			(xy 84.519014 -120.199893) (xy 84.55552 -120.247469) (xy 84.585504 -120.299403) (xy 84.608453 -120.354807)
			(xy 84.623974 -120.412732) (xy 84.631802 -120.472188) (xy 84.632292 -120.502172) (xy 84.632292 -121.365772)
			(xy 84.631802 -121.395756) (xy 84.623974 -121.455212) (xy 84.608453 -121.513137) (xy 84.585504 -121.568541)
			(xy 84.55552 -121.620475) (xy 84.519014 -121.668051) (xy 84.476609 -121.710456) (xy 84.429033 -121.746962)
			(xy 84.377099 -121.776946) (xy 84.321695 -121.799895) (xy 84.26377 -121.815416) (xy 84.204314 -121.823244)
			(xy 84.144346 -121.823244) (xy 84.08489 -121.815416) (xy 84.026965 -121.799895) (xy 83.971561 -121.776946)
			(xy 83.919627 -121.746962) (xy 83.872051 -121.710456) (xy 83.829646 -121.668051) (xy 83.79314 -121.620475)
			(xy 83.763156 -121.568541) (xy 83.740207 -121.513137) (xy 83.724686 -121.455212) (xy 83.716858 -121.395756)
			(xy 83.716368 -121.365772) (xy 65.661032 -121.365772) (xy 65.661032 -121.367296) (xy 65.660542 -121.39728)
			(xy 65.652714 -121.456736) (xy 65.637193 -121.514661) (xy 65.614244 -121.570065) (xy 65.58426 -121.621999)
			(xy 65.547754 -121.669575) (xy 65.505349 -121.71198) (xy 65.457773 -121.748486) (xy 65.405839 -121.77847)
			(xy 65.350435 -121.801419) (xy 65.29251 -121.81694) (xy 65.233054 -121.824768) (xy 65.173086 -121.824768)
			(xy 65.11363 -121.81694) (xy 65.055705 -121.801419) (xy 65.000301 -121.77847) (xy 64.948367 -121.748486)
			(xy 64.900791 -121.71198) (xy 64.858386 -121.669575) (xy 64.82188 -121.621999) (xy 64.791896 -121.570065)
			(xy 64.768947 -121.514661) (xy 64.753426 -121.456736) (xy 64.745598 -121.39728) (xy 64.745108 -121.367296)
			(xy 52.700428 -121.367296) (xy 52.700428 -121.886472) (xy 52.699938 -121.91644) (xy 52.692115 -121.975862)
			(xy 52.676602 -122.033755) (xy 52.653666 -122.089128) (xy 52.623699 -122.141034) (xy 52.587212 -122.188584)
			(xy 52.544832 -122.230964) (xy 52.497282 -122.267451) (xy 52.445376 -122.297418) (xy 52.390003 -122.320354)
			(xy 52.33211 -122.335867) (xy 52.272688 -122.34369) (xy 52.212752 -122.34369) (xy 52.15333 -122.335867)
			(xy 52.095437 -122.320354) (xy 52.040064 -122.297418) (xy 51.988158 -122.267451) (xy 51.940608 -122.230964)
			(xy 51.898228 -122.188584) (xy 51.861741 -122.141034) (xy 51.831774 -122.089128) (xy 51.808838 -122.033755)
			(xy 51.793325 -121.975862) (xy 51.785502 -121.91644) (xy 51.785012 -121.886472) (xy 38.225476 -121.886472)
			(xy 38.225476 -121.894346) (xy 38.224986 -121.924314) (xy 38.217163 -121.983736) (xy 38.20165 -122.041629)
			(xy 38.178714 -122.097002) (xy 38.148747 -122.148908) (xy 38.11226 -122.196458) (xy 38.06988 -122.238838)
			(xy 38.02233 -122.275325) (xy 37.970424 -122.305292) (xy 37.915051 -122.328228) (xy 37.857158 -122.343741)
			(xy 37.797736 -122.351564) (xy 37.7378 -122.351564) (xy 37.678378 -122.343741) (xy 37.620485 -122.328228)
			(xy 37.565112 -122.305292) (xy 37.513206 -122.275325) (xy 37.465656 -122.238838) (xy 37.423276 -122.196458)
			(xy 37.386789 -122.148908) (xy 37.356822 -122.097002) (xy 37.333886 -122.041629) (xy 37.318373 -121.983736)
			(xy 37.31055 -121.924314) (xy 37.31006 -121.894346) (xy 5.324094 -121.894346) (xy 5.324094 -123.68784)
			(xy 34.667952 -123.68784) (xy 34.667952 -122.82424) (xy 34.668442 -122.794272) (xy 34.676265 -122.73485)
			(xy 34.691778 -122.676957) (xy 34.714714 -122.621584) (xy 34.744681 -122.569678) (xy 34.781168 -122.522128)
			(xy 34.823548 -122.479748) (xy 34.871098 -122.443261) (xy 34.923004 -122.413294) (xy 34.978377 -122.390358)
			(xy 35.03627 -122.374845) (xy 35.095692 -122.367022) (xy 35.155628 -122.367022) (xy 35.21505 -122.374845)
			(xy 35.272943 -122.390358) (xy 35.328316 -122.413294) (xy 35.380222 -122.443261) (xy 35.427772 -122.479748)
			(xy 35.470152 -122.522128) (xy 35.506639 -122.569678) (xy 35.536606 -122.621584) (xy 35.559542 -122.676957)
			(xy 35.575055 -122.73485) (xy 35.582878 -122.794272) (xy 35.583368 -122.82424) (xy 35.583368 -123.686316)
			(xy 53.639212 -123.686316) (xy 53.639212 -122.822716) (xy 53.639702 -122.792748) (xy 53.647525 -122.733326)
			(xy 53.663038 -122.675433) (xy 53.685974 -122.62006) (xy 53.715941 -122.568154) (xy 53.752428 -122.520604)
			(xy 53.794808 -122.478224) (xy 53.842358 -122.441737) (xy 53.894264 -122.41177) (xy 53.949637 -122.388834)
			(xy 54.00753 -122.373321) (xy 54.066952 -122.365498) (xy 54.126888 -122.365498) (xy 54.18631 -122.373321)
			(xy 54.244203 -122.388834) (xy 54.299576 -122.41177) (xy 54.351482 -122.441737) (xy 54.399032 -122.478224)
			(xy 54.441412 -122.520604) (xy 54.477899 -122.568154) (xy 54.507866 -122.62006) (xy 54.530802 -122.675433)
			(xy 54.546315 -122.733326) (xy 54.554138 -122.792748) (xy 54.554628 -122.822716) (xy 54.554628 -123.16714)
			(xy 66.599308 -123.16714) (xy 66.599308 -122.30354) (xy 66.599798 -122.273556) (xy 66.607626 -122.2141)
			(xy 66.623147 -122.156175) (xy 66.646096 -122.100771) (xy 66.67608 -122.048837) (xy 66.712586 -122.001261)
			(xy 66.754991 -121.958856) (xy 66.802567 -121.92235) (xy 66.854501 -121.892366) (xy 66.909905 -121.869417)
			(xy 66.96783 -121.853896) (xy 67.027286 -121.846068) (xy 67.087254 -121.846068) (xy 67.14671 -121.853896)
			(xy 67.204635 -121.869417) (xy 67.260039 -121.892366) (xy 67.311973 -121.92235) (xy 67.359549 -121.958856)
			(xy 67.401954 -122.001261) (xy 67.43846 -122.048837) (xy 67.468444 -122.100771) (xy 67.491393 -122.156175)
			(xy 67.506914 -122.2141) (xy 67.514742 -122.273556) (xy 67.515232 -122.30354) (xy 67.515232 -123.159266)
			(xy 81.07426 -123.159266) (xy 81.07426 -122.295666) (xy 81.07475 -122.265682) (xy 81.082578 -122.206226)
			(xy 81.098099 -122.148301) (xy 81.121048 -122.092897) (xy 81.151032 -122.040963) (xy 81.187538 -121.993387)
			(xy 81.229943 -121.950982) (xy 81.277519 -121.914476) (xy 81.329453 -121.884492) (xy 81.384857 -121.861543)
			(xy 81.442782 -121.846022) (xy 81.502238 -121.838194) (xy 81.562206 -121.838194) (xy 81.621662 -121.846022)
			(xy 81.679587 -121.861543) (xy 81.734991 -121.884492) (xy 81.752059 -121.894346) (xy 153.409904 -121.894346)
			(xy 153.409904 -121.030746) (xy 153.410394 -121.000762) (xy 153.418222 -120.941306) (xy 153.433743 -120.883381)
			(xy 153.456692 -120.827977) (xy 153.486676 -120.776043) (xy 153.523182 -120.728467) (xy 153.565587 -120.686062)
			(xy 153.613163 -120.649556) (xy 153.665097 -120.619572) (xy 153.720501 -120.596623) (xy 153.778426 -120.581102)
			(xy 153.837882 -120.573274) (xy 153.89785 -120.573274) (xy 153.957306 -120.581102) (xy 154.015231 -120.596623)
			(xy 154.070635 -120.619572) (xy 154.122569 -120.649556) (xy 154.170145 -120.686062) (xy 154.21255 -120.728467)
			(xy 154.249056 -120.776043) (xy 154.27904 -120.827977) (xy 154.301989 -120.883381) (xy 154.31751 -120.941306)
			(xy 154.325338 -121.000762) (xy 154.325828 -121.030746) (xy 154.325828 -121.886472) (xy 167.884856 -121.886472)
			(xy 167.884856 -121.022872) (xy 167.885346 -120.992888) (xy 167.893174 -120.933432) (xy 167.908695 -120.875507)
			(xy 167.931644 -120.820103) (xy 167.961628 -120.768169) (xy 167.998134 -120.720593) (xy 168.040539 -120.678188)
			(xy 168.088115 -120.641682) (xy 168.140049 -120.611698) (xy 168.195453 -120.588749) (xy 168.253378 -120.573228)
			(xy 168.312834 -120.5654) (xy 168.372802 -120.5654) (xy 168.432258 -120.573228) (xy 168.490183 -120.588749)
			(xy 168.545587 -120.611698) (xy 168.597521 -120.641682) (xy 168.645097 -120.678188) (xy 168.687502 -120.720593)
			(xy 168.724008 -120.768169) (xy 168.753992 -120.820103) (xy 168.776941 -120.875507) (xy 168.792462 -120.933432)
			(xy 168.80029 -120.992888) (xy 168.80078 -121.022872) (xy 168.80078 -121.367296) (xy 180.84546 -121.367296)
			(xy 180.84546 -120.503696) (xy 180.84595 -120.473728) (xy 180.853773 -120.414306) (xy 180.869286 -120.356413)
			(xy 180.892222 -120.30104) (xy 180.922189 -120.249134) (xy 180.958676 -120.201584) (xy 181.001056 -120.159204)
			(xy 181.048606 -120.122717) (xy 181.100512 -120.09275) (xy 181.155885 -120.069814) (xy 181.213778 -120.054301)
			(xy 181.2732 -120.046478) (xy 181.333136 -120.046478) (xy 181.392558 -120.054301) (xy 181.450451 -120.069814)
			(xy 181.505824 -120.09275) (xy 181.55773 -120.122717) (xy 181.60528 -120.159204) (xy 181.64766 -120.201584)
			(xy 181.684147 -120.249134) (xy 181.714114 -120.30104) (xy 181.73705 -120.356413) (xy 181.752563 -120.414306)
			(xy 181.760386 -120.473728) (xy 181.760876 -120.503696) (xy 181.760876 -121.365772) (xy 199.81672 -121.365772)
			(xy 199.81672 -120.502172) (xy 199.81721 -120.472204) (xy 199.825033 -120.412782) (xy 199.840546 -120.354889)
			(xy 199.863482 -120.299516) (xy 199.893449 -120.24761) (xy 199.929936 -120.20006) (xy 199.972316 -120.15768)
			(xy 200.019866 -120.121193) (xy 200.071772 -120.091226) (xy 200.127145 -120.06829) (xy 200.185038 -120.052777)
			(xy 200.24446 -120.044954) (xy 200.304396 -120.044954) (xy 200.363818 -120.052777) (xy 200.421711 -120.06829)
			(xy 200.469049 -120.087898) (xy 266.86764 -120.087898) (xy 266.86764 -119.224298) (xy 266.86813 -119.194314)
			(xy 266.875958 -119.134858) (xy 266.891479 -119.076933) (xy 266.914428 -119.021529) (xy 266.944412 -118.969595)
			(xy 266.980918 -118.922019) (xy 267.023323 -118.879614) (xy 267.070899 -118.843108) (xy 267.122833 -118.813124)
			(xy 267.178237 -118.790175) (xy 267.236162 -118.774654) (xy 267.295618 -118.766826) (xy 267.355586 -118.766826)
			(xy 267.415042 -118.774654) (xy 267.472967 -118.790175) (xy 267.528371 -118.813124) (xy 267.580305 -118.843108)
			(xy 267.627881 -118.879614) (xy 267.670286 -118.922019) (xy 267.706792 -118.969595) (xy 267.736776 -119.021529)
			(xy 267.759725 -119.076933) (xy 267.775246 -119.134858) (xy 267.783074 -119.194314) (xy 267.783564 -119.224298)
			(xy 267.783564 -120.086374) (xy 285.8389 -120.086374) (xy 285.8389 -119.222774) (xy 285.83939 -119.19279)
			(xy 285.847218 -119.133334) (xy 285.862739 -119.075409) (xy 285.885688 -119.020005) (xy 285.915672 -118.968071)
			(xy 285.952178 -118.920495) (xy 285.994583 -118.87809) (xy 286.042159 -118.841584) (xy 286.094093 -118.8116)
			(xy 286.149497 -118.788651) (xy 286.207422 -118.77313) (xy 286.266878 -118.765302) (xy 286.326846 -118.765302)
			(xy 286.386302 -118.77313) (xy 286.444227 -118.788651) (xy 286.499631 -118.8116) (xy 286.551565 -118.841584)
			(xy 286.599141 -118.87809) (xy 286.641546 -118.920495) (xy 286.678052 -118.968071) (xy 286.708036 -119.020005)
			(xy 286.730985 -119.075409) (xy 286.746506 -119.133334) (xy 286.754334 -119.19279) (xy 286.754824 -119.222774)
			(xy 286.754824 -119.567198) (xy 298.799504 -119.567198) (xy 298.799504 -118.703598) (xy 298.799994 -118.67363)
			(xy 298.807817 -118.614208) (xy 298.82333 -118.556315) (xy 298.846266 -118.500942) (xy 298.876233 -118.449036)
			(xy 298.91272 -118.401486) (xy 298.9551 -118.359106) (xy 299.00265 -118.322619) (xy 299.054556 -118.292652)
			(xy 299.109929 -118.269716) (xy 299.167822 -118.254203) (xy 299.227244 -118.24638) (xy 299.28718 -118.24638)
			(xy 299.346602 -118.254203) (xy 299.404495 -118.269716) (xy 299.459868 -118.292652) (xy 299.511774 -118.322619)
			(xy 299.559324 -118.359106) (xy 299.601704 -118.401486) (xy 299.638191 -118.449036) (xy 299.668158 -118.500942)
			(xy 299.691094 -118.556315) (xy 299.706607 -118.614208) (xy 299.71443 -118.67363) (xy 299.71492 -118.703598)
			(xy 299.71492 -119.559324) (xy 313.274456 -119.559324) (xy 313.274456 -118.695724) (xy 313.274946 -118.665756)
			(xy 313.282769 -118.606334) (xy 313.298282 -118.548441) (xy 313.321218 -118.493068) (xy 313.351185 -118.441162)
			(xy 313.387672 -118.393612) (xy 313.430052 -118.351232) (xy 313.477602 -118.314745) (xy 313.529508 -118.284778)
			(xy 313.584881 -118.261842) (xy 313.642774 -118.246329) (xy 313.702196 -118.238506) (xy 313.762132 -118.238506)
			(xy 313.821554 -118.246329) (xy 313.879447 -118.261842) (xy 313.93482 -118.284778) (xy 313.986726 -118.314745)
			(xy 314.034276 -118.351232) (xy 314.076656 -118.393612) (xy 314.113143 -118.441162) (xy 314.14311 -118.493068)
			(xy 314.166046 -118.548441) (xy 314.181559 -118.606334) (xy 314.189382 -118.665756) (xy 314.189872 -118.695724)
			(xy 314.189872 -119.559324) (xy 314.189382 -119.589292) (xy 314.181559 -119.648714) (xy 314.166046 -119.706607)
			(xy 314.14311 -119.76198) (xy 314.113143 -119.813886) (xy 314.076656 -119.861436) (xy 314.034276 -119.903816)
			(xy 313.986726 -119.940303) (xy 313.93482 -119.97027) (xy 313.879447 -119.993206) (xy 313.821554 -120.008719)
			(xy 313.762132 -120.016542) (xy 313.702196 -120.016542) (xy 313.642774 -120.008719) (xy 313.584881 -119.993206)
			(xy 313.529508 -119.97027) (xy 313.477602 -119.940303) (xy 313.430052 -119.903816) (xy 313.387672 -119.861436)
			(xy 313.351185 -119.813886) (xy 313.321218 -119.76198) (xy 313.298282 -119.706607) (xy 313.282769 -119.648714)
			(xy 313.274946 -119.589292) (xy 313.274456 -119.559324) (xy 299.71492 -119.559324) (xy 299.71492 -119.567198)
			(xy 299.71443 -119.597166) (xy 299.706607 -119.656588) (xy 299.691094 -119.714481) (xy 299.668158 -119.769854)
			(xy 299.638191 -119.82176) (xy 299.601704 -119.86931) (xy 299.559324 -119.91169) (xy 299.511774 -119.948177)
			(xy 299.459868 -119.978144) (xy 299.404495 -120.00108) (xy 299.346602 -120.016593) (xy 299.28718 -120.024416)
			(xy 299.227244 -120.024416) (xy 299.167822 -120.016593) (xy 299.109929 -120.00108) (xy 299.054556 -119.978144)
			(xy 299.00265 -119.948177) (xy 298.9551 -119.91169) (xy 298.91272 -119.86931) (xy 298.876233 -119.82176)
			(xy 298.846266 -119.769854) (xy 298.82333 -119.714481) (xy 298.807817 -119.656588) (xy 298.799994 -119.597166)
			(xy 298.799504 -119.567198) (xy 286.754824 -119.567198) (xy 286.754824 -120.086374) (xy 286.754334 -120.116358)
			(xy 286.746506 -120.175814) (xy 286.730985 -120.233739) (xy 286.708036 -120.289143) (xy 286.678052 -120.341077)
			(xy 286.641546 -120.388653) (xy 286.599141 -120.431058) (xy 286.551565 -120.467564) (xy 286.499631 -120.497548)
			(xy 286.444227 -120.520497) (xy 286.386302 -120.536018) (xy 286.326846 -120.543846) (xy 286.266878 -120.543846)
			(xy 286.207422 -120.536018) (xy 286.149497 -120.520497) (xy 286.094093 -120.497548) (xy 286.042159 -120.467564)
			(xy 285.994583 -120.431058) (xy 285.952178 -120.388653) (xy 285.915672 -120.341077) (xy 285.885688 -120.289143)
			(xy 285.862739 -120.233739) (xy 285.847218 -120.175814) (xy 285.83939 -120.116358) (xy 285.8389 -120.086374)
			(xy 267.783564 -120.086374) (xy 267.783564 -120.087898) (xy 267.783074 -120.117882) (xy 267.775246 -120.177338)
			(xy 267.759725 -120.235263) (xy 267.736776 -120.290667) (xy 267.706792 -120.342601) (xy 267.670286 -120.390177)
			(xy 267.627881 -120.432582) (xy 267.580305 -120.469088) (xy 267.528371 -120.499072) (xy 267.472967 -120.522021)
			(xy 267.415042 -120.537542) (xy 267.355586 -120.54537) (xy 267.295618 -120.54537) (xy 267.236162 -120.537542)
			(xy 267.178237 -120.522021) (xy 267.122833 -120.499072) (xy 267.070899 -120.469088) (xy 267.023323 -120.432582)
			(xy 266.980918 -120.390177) (xy 266.944412 -120.342601) (xy 266.914428 -120.290667) (xy 266.891479 -120.235263)
			(xy 266.875958 -120.177338) (xy 266.86813 -120.117882) (xy 266.86764 -120.087898) (xy 200.469049 -120.087898)
			(xy 200.477084 -120.091226) (xy 200.52899 -120.121193) (xy 200.57654 -120.15768) (xy 200.61892 -120.20006)
			(xy 200.655407 -120.24761) (xy 200.685374 -120.299516) (xy 200.70831 -120.354889) (xy 200.723823 -120.412782)
			(xy 200.731646 -120.472204) (xy 200.732136 -120.502172) (xy 200.732136 -121.365772) (xy 200.731646 -121.39574)
			(xy 200.723823 -121.455162) (xy 200.70831 -121.513055) (xy 200.685374 -121.568428) (xy 200.655407 -121.620334)
			(xy 200.61892 -121.667884) (xy 200.57654 -121.710264) (xy 200.52899 -121.746751) (xy 200.477084 -121.776718)
			(xy 200.421711 -121.799654) (xy 200.363818 -121.815167) (xy 200.304396 -121.82299) (xy 200.24446 -121.82299)
			(xy 200.185038 -121.815167) (xy 200.127145 -121.799654) (xy 200.071772 -121.776718) (xy 200.019866 -121.746751)
			(xy 199.972316 -121.710264) (xy 199.929936 -121.667884) (xy 199.893449 -121.620334) (xy 199.863482 -121.568428)
			(xy 199.840546 -121.513055) (xy 199.825033 -121.455162) (xy 199.81721 -121.39574) (xy 199.81672 -121.365772)
			(xy 181.760876 -121.365772) (xy 181.760876 -121.367296) (xy 181.760386 -121.397264) (xy 181.752563 -121.456686)
			(xy 181.73705 -121.514579) (xy 181.714114 -121.569952) (xy 181.684147 -121.621858) (xy 181.64766 -121.669408)
			(xy 181.60528 -121.711788) (xy 181.55773 -121.748275) (xy 181.505824 -121.778242) (xy 181.450451 -121.801178)
			(xy 181.392558 -121.816691) (xy 181.333136 -121.824514) (xy 181.2732 -121.824514) (xy 181.213778 -121.816691)
			(xy 181.155885 -121.801178) (xy 181.100512 -121.778242) (xy 181.048606 -121.748275) (xy 181.001056 -121.711788)
			(xy 180.958676 -121.669408) (xy 180.922189 -121.621858) (xy 180.892222 -121.569952) (xy 180.869286 -121.514579)
			(xy 180.853773 -121.456686) (xy 180.84595 -121.397264) (xy 180.84546 -121.367296) (xy 168.80078 -121.367296)
			(xy 168.80078 -121.886472) (xy 168.80029 -121.916456) (xy 168.792462 -121.975912) (xy 168.776941 -122.033837)
			(xy 168.753992 -122.089241) (xy 168.724008 -122.141175) (xy 168.687502 -122.188751) (xy 168.645097 -122.231156)
			(xy 168.597521 -122.267662) (xy 168.545587 -122.297646) (xy 168.490183 -122.320595) (xy 168.432258 -122.336116)
			(xy 168.372802 -122.343944) (xy 168.312834 -122.343944) (xy 168.253378 -122.336116) (xy 168.195453 -122.320595)
			(xy 168.140049 -122.297646) (xy 168.088115 -122.267662) (xy 168.040539 -122.231156) (xy 167.998134 -122.188751)
			(xy 167.961628 -122.141175) (xy 167.931644 -122.089241) (xy 167.908695 -122.033837) (xy 167.893174 -121.975912)
			(xy 167.885346 -121.916456) (xy 167.884856 -121.886472) (xy 154.325828 -121.886472) (xy 154.325828 -121.894346)
			(xy 154.325338 -121.92433) (xy 154.31751 -121.983786) (xy 154.301989 -122.041711) (xy 154.27904 -122.097115)
			(xy 154.249056 -122.149049) (xy 154.21255 -122.196625) (xy 154.170145 -122.23903) (xy 154.122569 -122.275536)
			(xy 154.070635 -122.30552) (xy 154.015231 -122.328469) (xy 153.957306 -122.34399) (xy 153.89785 -122.351818)
			(xy 153.837882 -122.351818) (xy 153.778426 -122.34399) (xy 153.720501 -122.328469) (xy 153.665097 -122.30552)
			(xy 153.613163 -122.275536) (xy 153.565587 -122.23903) (xy 153.523182 -122.196625) (xy 153.486676 -122.149049)
			(xy 153.456692 -122.097115) (xy 153.433743 -122.041711) (xy 153.418222 -121.983786) (xy 153.410394 -121.92433)
			(xy 153.409904 -121.894346) (xy 81.752059 -121.894346) (xy 81.786925 -121.914476) (xy 81.834501 -121.950982)
			(xy 81.876906 -121.993387) (xy 81.913412 -122.040963) (xy 81.943396 -122.092897) (xy 81.966345 -122.148301)
			(xy 81.981866 -122.206226) (xy 81.989694 -122.265682) (xy 81.990184 -122.295666) (xy 81.990184 -123.159266)
			(xy 81.989694 -123.18925) (xy 81.981866 -123.248706) (xy 81.966345 -123.306631) (xy 81.943396 -123.362035)
			(xy 81.913412 -123.413969) (xy 81.876906 -123.461545) (xy 81.834501 -123.50395) (xy 81.786925 -123.540456)
			(xy 81.734991 -123.57044) (xy 81.679587 -123.593389) (xy 81.621662 -123.60891) (xy 81.562206 -123.616738)
			(xy 81.502238 -123.616738) (xy 81.442782 -123.60891) (xy 81.384857 -123.593389) (xy 81.329453 -123.57044)
			(xy 81.277519 -123.540456) (xy 81.229943 -123.50395) (xy 81.187538 -123.461545) (xy 81.151032 -123.413969)
			(xy 81.121048 -123.362035) (xy 81.098099 -123.306631) (xy 81.082578 -123.248706) (xy 81.07475 -123.18925)
			(xy 81.07426 -123.159266) (xy 67.515232 -123.159266) (xy 67.515232 -123.16714) (xy 67.514742 -123.197124)
			(xy 67.506914 -123.25658) (xy 67.491393 -123.314505) (xy 67.468444 -123.369909) (xy 67.43846 -123.421843)
			(xy 67.401954 -123.469419) (xy 67.359549 -123.511824) (xy 67.311973 -123.54833) (xy 67.260039 -123.578314)
			(xy 67.204635 -123.601263) (xy 67.14671 -123.616784) (xy 67.087254 -123.624612) (xy 67.027286 -123.624612)
			(xy 66.96783 -123.616784) (xy 66.909905 -123.601263) (xy 66.854501 -123.578314) (xy 66.802567 -123.54833)
			(xy 66.754991 -123.511824) (xy 66.712586 -123.469419) (xy 66.67608 -123.421843) (xy 66.646096 -123.369909)
			(xy 66.623147 -123.314505) (xy 66.607626 -123.25658) (xy 66.599798 -123.197124) (xy 66.599308 -123.16714)
			(xy 54.554628 -123.16714) (xy 54.554628 -123.686316) (xy 54.554138 -123.716284) (xy 54.546315 -123.775706)
			(xy 54.530802 -123.833599) (xy 54.507866 -123.888972) (xy 54.477899 -123.940878) (xy 54.441412 -123.988428)
			(xy 54.399032 -124.030808) (xy 54.351482 -124.067295) (xy 54.299576 -124.097262) (xy 54.244203 -124.120198)
			(xy 54.18631 -124.135711) (xy 54.126888 -124.143534) (xy 54.066952 -124.143534) (xy 54.00753 -124.135711)
			(xy 53.949637 -124.120198) (xy 53.894264 -124.097262) (xy 53.842358 -124.067295) (xy 53.794808 -124.030808)
			(xy 53.752428 -123.988428) (xy 53.715941 -123.940878) (xy 53.685974 -123.888972) (xy 53.663038 -123.833599)
			(xy 53.647525 -123.775706) (xy 53.639702 -123.716284) (xy 53.639212 -123.686316) (xy 35.583368 -123.686316)
			(xy 35.583368 -123.68784) (xy 35.582878 -123.717808) (xy 35.575055 -123.77723) (xy 35.559542 -123.835123)
			(xy 35.536606 -123.890496) (xy 35.506639 -123.942402) (xy 35.470152 -123.989952) (xy 35.427772 -124.032332)
			(xy 35.380222 -124.068819) (xy 35.328316 -124.098786) (xy 35.272943 -124.121722) (xy 35.21505 -124.137235)
			(xy 35.155628 -124.145058) (xy 35.095692 -124.145058) (xy 35.03627 -124.137235) (xy 34.978377 -124.121722)
			(xy 34.923004 -124.098786) (xy 34.871098 -124.068819) (xy 34.823548 -124.032332) (xy 34.781168 -123.989952)
			(xy 34.744681 -123.942402) (xy 34.714714 -123.890496) (xy 34.691778 -123.835123) (xy 34.676265 -123.77723)
			(xy 34.668442 -123.717808) (xy 34.667952 -123.68784) (xy 5.324094 -123.68784) (xy 5.324094 -125.494542)
			(xy 37.31006 -125.494542) (xy 37.31006 -124.630942) (xy 37.31055 -124.600974) (xy 37.318373 -124.541552)
			(xy 37.333886 -124.483659) (xy 37.356822 -124.428286) (xy 37.386789 -124.37638) (xy 37.423276 -124.32883)
			(xy 37.465656 -124.28645) (xy 37.513206 -124.249963) (xy 37.565112 -124.219996) (xy 37.620485 -124.19706)
			(xy 37.678378 -124.181547) (xy 37.7378 -124.173724) (xy 37.797736 -124.173724) (xy 37.857158 -124.181547)
			(xy 37.915051 -124.19706) (xy 37.970424 -124.219996) (xy 38.02233 -124.249963) (xy 38.06988 -124.28645)
			(xy 38.11226 -124.32883) (xy 38.148747 -124.37638) (xy 38.178714 -124.428286) (xy 38.20165 -124.483659)
			(xy 38.217163 -124.541552) (xy 38.224986 -124.600974) (xy 38.225476 -124.630942) (xy 38.225476 -125.486414)
			(xy 51.785012 -125.486414) (xy 51.785012 -124.622814) (xy 51.785502 -124.592846) (xy 51.793325 -124.533424)
			(xy 51.808838 -124.475531) (xy 51.831774 -124.420158) (xy 51.861741 -124.368252) (xy 51.898228 -124.320702)
			(xy 51.940608 -124.278322) (xy 51.988158 -124.241835) (xy 52.040064 -124.211868) (xy 52.095437 -124.188932)
			(xy 52.15333 -124.173419) (xy 52.212752 -124.165596) (xy 52.272688 -124.165596) (xy 52.33211 -124.173419)
			(xy 52.390003 -124.188932) (xy 52.445376 -124.211868) (xy 52.497282 -124.241835) (xy 52.544832 -124.278322)
			(xy 52.587212 -124.320702) (xy 52.623699 -124.368252) (xy 52.653666 -124.420158) (xy 52.676602 -124.475531)
			(xy 52.692115 -124.533424) (xy 52.699938 -124.592846) (xy 52.700428 -124.622814) (xy 52.700428 -124.967238)
			(xy 64.745108 -124.967238) (xy 64.745108 -124.103638) (xy 64.745598 -124.073654) (xy 64.753426 -124.014198)
			(xy 64.768947 -123.956273) (xy 64.791896 -123.900869) (xy 64.82188 -123.848935) (xy 64.858386 -123.801359)
			(xy 64.900791 -123.758954) (xy 64.948367 -123.722448) (xy 65.000301 -123.692464) (xy 65.055705 -123.669515)
			(xy 65.11363 -123.653994) (xy 65.173086 -123.646166) (xy 65.233054 -123.646166) (xy 65.29251 -123.653994)
			(xy 65.350435 -123.669515) (xy 65.405839 -123.692464) (xy 65.457773 -123.722448) (xy 65.505349 -123.758954)
			(xy 65.547754 -123.801359) (xy 65.58426 -123.848935) (xy 65.614244 -123.900869) (xy 65.637193 -123.956273)
			(xy 65.652714 -124.014198) (xy 65.660542 -124.073654) (xy 65.661032 -124.103638) (xy 65.661032 -124.965714)
			(xy 83.716368 -124.965714) (xy 83.716368 -124.102114) (xy 83.716858 -124.07213) (xy 83.724686 -124.012674)
			(xy 83.740207 -123.954749) (xy 83.763156 -123.899345) (xy 83.79314 -123.847411) (xy 83.829646 -123.799835)
			(xy 83.872051 -123.75743) (xy 83.919627 -123.720924) (xy 83.971561 -123.69094) (xy 84.026965 -123.667991)
			(xy 84.08489 -123.65247) (xy 84.144346 -123.644642) (xy 84.204314 -123.644642) (xy 84.26377 -123.65247)
			(xy 84.321695 -123.667991) (xy 84.369615 -123.68784) (xy 150.767796 -123.68784) (xy 150.767796 -122.82424)
			(xy 150.768286 -122.794256) (xy 150.776114 -122.7348) (xy 150.791635 -122.676875) (xy 150.814584 -122.621471)
			(xy 150.844568 -122.569537) (xy 150.881074 -122.521961) (xy 150.923479 -122.479556) (xy 150.971055 -122.44305)
			(xy 151.022989 -122.413066) (xy 151.078393 -122.390117) (xy 151.136318 -122.374596) (xy 151.195774 -122.366768)
			(xy 151.255742 -122.366768) (xy 151.315198 -122.374596) (xy 151.373123 -122.390117) (xy 151.428527 -122.413066)
			(xy 151.480461 -122.44305) (xy 151.528037 -122.479556) (xy 151.570442 -122.521961) (xy 151.606948 -122.569537)
			(xy 151.636932 -122.621471) (xy 151.659881 -122.676875) (xy 151.675402 -122.7348) (xy 151.68323 -122.794256)
			(xy 151.68372 -122.82424) (xy 151.68372 -123.686316) (xy 169.739056 -123.686316) (xy 169.739056 -122.822716)
			(xy 169.739546 -122.792732) (xy 169.747374 -122.733276) (xy 169.762895 -122.675351) (xy 169.785844 -122.619947)
			(xy 169.815828 -122.568013) (xy 169.852334 -122.520437) (xy 169.894739 -122.478032) (xy 169.942315 -122.441526)
			(xy 169.994249 -122.411542) (xy 170.049653 -122.388593) (xy 170.107578 -122.373072) (xy 170.167034 -122.365244)
			(xy 170.227002 -122.365244) (xy 170.286458 -122.373072) (xy 170.344383 -122.388593) (xy 170.399787 -122.411542)
			(xy 170.451721 -122.441526) (xy 170.499297 -122.478032) (xy 170.541702 -122.520437) (xy 170.578208 -122.568013)
			(xy 170.608192 -122.619947) (xy 170.631141 -122.675351) (xy 170.646662 -122.733276) (xy 170.65449 -122.792732)
			(xy 170.65498 -122.822716) (xy 170.65498 -123.16714) (xy 182.69966 -123.16714) (xy 182.69966 -122.30354)
			(xy 182.70015 -122.273572) (xy 182.707973 -122.21415) (xy 182.723486 -122.156257) (xy 182.746422 -122.100884)
			(xy 182.776389 -122.048978) (xy 182.812876 -122.001428) (xy 182.855256 -121.959048) (xy 182.902806 -121.922561)
			(xy 182.954712 -121.892594) (xy 183.010085 -121.869658) (xy 183.067978 -121.854145) (xy 183.1274 -121.846322)
			(xy 183.187336 -121.846322) (xy 183.246758 -121.854145) (xy 183.304651 -121.869658) (xy 183.360024 -121.892594)
			(xy 183.41193 -121.922561) (xy 183.45948 -121.959048) (xy 183.50186 -122.001428) (xy 183.538347 -122.048978)
			(xy 183.568314 -122.100884) (xy 183.59125 -122.156257) (xy 183.606763 -122.21415) (xy 183.614586 -122.273572)
			(xy 183.615076 -122.30354) (xy 183.615076 -123.159266) (xy 197.174612 -123.159266) (xy 197.174612 -122.295666)
			(xy 197.175102 -122.265698) (xy 197.182925 -122.206276) (xy 197.198438 -122.148383) (xy 197.221374 -122.09301)
			(xy 197.251341 -122.041104) (xy 197.287828 -121.993554) (xy 197.330208 -121.951174) (xy 197.377758 -121.914687)
			(xy 197.429664 -121.88472) (xy 197.485037 -121.861784) (xy 197.54293 -121.846271) (xy 197.602352 -121.838448)
			(xy 197.662288 -121.838448) (xy 197.72171 -121.846271) (xy 197.779603 -121.861784) (xy 197.834976 -121.88472)
			(xy 197.851649 -121.894346) (xy 269.509748 -121.894346) (xy 269.509748 -121.030746) (xy 269.510238 -121.000762)
			(xy 269.518066 -120.941306) (xy 269.533587 -120.883381) (xy 269.556536 -120.827977) (xy 269.58652 -120.776043)
			(xy 269.623026 -120.728467) (xy 269.665431 -120.686062) (xy 269.713007 -120.649556) (xy 269.764941 -120.619572)
			(xy 269.820345 -120.596623) (xy 269.87827 -120.581102) (xy 269.937726 -120.573274) (xy 269.997694 -120.573274)
			(xy 270.05715 -120.581102) (xy 270.115075 -120.596623) (xy 270.170479 -120.619572) (xy 270.222413 -120.649556)
			(xy 270.269989 -120.686062) (xy 270.312394 -120.728467) (xy 270.3489 -120.776043) (xy 270.378884 -120.827977)
			(xy 270.401833 -120.883381) (xy 270.417354 -120.941306) (xy 270.425182 -121.000762) (xy 270.425672 -121.030746)
			(xy 270.425672 -121.886472) (xy 283.9847 -121.886472) (xy 283.9847 -121.022872) (xy 283.98519 -120.992888)
			(xy 283.993018 -120.933432) (xy 284.008539 -120.875507) (xy 284.031488 -120.820103) (xy 284.061472 -120.768169)
			(xy 284.097978 -120.720593) (xy 284.140383 -120.678188) (xy 284.187959 -120.641682) (xy 284.239893 -120.611698)
			(xy 284.295297 -120.588749) (xy 284.353222 -120.573228) (xy 284.412678 -120.5654) (xy 284.472646 -120.5654)
			(xy 284.532102 -120.573228) (xy 284.590027 -120.588749) (xy 284.645431 -120.611698) (xy 284.697365 -120.641682)
			(xy 284.744941 -120.678188) (xy 284.787346 -120.720593) (xy 284.823852 -120.768169) (xy 284.853836 -120.820103)
			(xy 284.876785 -120.875507) (xy 284.892306 -120.933432) (xy 284.900134 -120.992888) (xy 284.900624 -121.022872)
			(xy 284.900624 -121.367296) (xy 296.945304 -121.367296) (xy 296.945304 -120.503696) (xy 296.945794 -120.473728)
			(xy 296.953617 -120.414306) (xy 296.96913 -120.356413) (xy 296.992066 -120.30104) (xy 297.022033 -120.249134)
			(xy 297.05852 -120.201584) (xy 297.1009 -120.159204) (xy 297.14845 -120.122717) (xy 297.200356 -120.09275)
			(xy 297.255729 -120.069814) (xy 297.313622 -120.054301) (xy 297.373044 -120.046478) (xy 297.43298 -120.046478)
			(xy 297.492402 -120.054301) (xy 297.550295 -120.069814) (xy 297.605668 -120.09275) (xy 297.657574 -120.122717)
			(xy 297.705124 -120.159204) (xy 297.747504 -120.201584) (xy 297.783991 -120.249134) (xy 297.813958 -120.30104)
			(xy 297.836894 -120.356413) (xy 297.852407 -120.414306) (xy 297.86023 -120.473728) (xy 297.86072 -120.503696)
			(xy 297.86072 -121.365772) (xy 315.916564 -121.365772) (xy 315.916564 -120.502172) (xy 315.917054 -120.472204)
			(xy 315.924877 -120.412782) (xy 315.94039 -120.354889) (xy 315.963326 -120.299516) (xy 315.993293 -120.24761)
			(xy 316.02978 -120.20006) (xy 316.07216 -120.15768) (xy 316.11971 -120.121193) (xy 316.171616 -120.091226)
			(xy 316.226989 -120.06829) (xy 316.284882 -120.052777) (xy 316.344304 -120.044954) (xy 316.40424 -120.044954)
			(xy 316.463662 -120.052777) (xy 316.521555 -120.06829) (xy 316.568893 -120.087898) (xy 382.967992 -120.087898)
			(xy 382.967992 -119.224298) (xy 382.968482 -119.19433) (xy 382.976305 -119.134908) (xy 382.991818 -119.077015)
			(xy 383.014754 -119.021642) (xy 383.044721 -118.969736) (xy 383.081208 -118.922186) (xy 383.123588 -118.879806)
			(xy 383.171138 -118.843319) (xy 383.223044 -118.813352) (xy 383.278417 -118.790416) (xy 383.33631 -118.774903)
			(xy 383.395732 -118.76708) (xy 383.455668 -118.76708) (xy 383.51509 -118.774903) (xy 383.572983 -118.790416)
			(xy 383.628356 -118.813352) (xy 383.680262 -118.843319) (xy 383.727812 -118.879806) (xy 383.770192 -118.922186)
			(xy 383.806679 -118.969736) (xy 383.836646 -119.021642) (xy 383.859582 -119.077015) (xy 383.875095 -119.134908)
			(xy 383.882918 -119.19433) (xy 383.883408 -119.224298) (xy 383.883408 -120.086374) (xy 401.939252 -120.086374)
			(xy 401.939252 -119.222774) (xy 401.939742 -119.192806) (xy 401.947565 -119.133384) (xy 401.963078 -119.075491)
			(xy 401.986014 -119.020118) (xy 402.015981 -118.968212) (xy 402.052468 -118.920662) (xy 402.094848 -118.878282)
			(xy 402.142398 -118.841795) (xy 402.194304 -118.811828) (xy 402.249677 -118.788892) (xy 402.30757 -118.773379)
			(xy 402.366992 -118.765556) (xy 402.426928 -118.765556) (xy 402.48635 -118.773379) (xy 402.544243 -118.788892)
			(xy 402.599616 -118.811828) (xy 402.651522 -118.841795) (xy 402.699072 -118.878282) (xy 402.741452 -118.920662)
			(xy 402.777939 -118.968212) (xy 402.807906 -119.020118) (xy 402.830842 -119.075491) (xy 402.846355 -119.133384)
			(xy 402.854178 -119.192806) (xy 402.854668 -119.222774) (xy 402.854668 -119.567198) (xy 414.899348 -119.567198)
			(xy 414.899348 -118.703598) (xy 414.899838 -118.673614) (xy 414.907666 -118.614158) (xy 414.923187 -118.556233)
			(xy 414.946136 -118.500829) (xy 414.97612 -118.448895) (xy 415.012626 -118.401319) (xy 415.055031 -118.358914)
			(xy 415.102607 -118.322408) (xy 415.154541 -118.292424) (xy 415.209945 -118.269475) (xy 415.26787 -118.253954)
			(xy 415.327326 -118.246126) (xy 415.387294 -118.246126) (xy 415.44675 -118.253954) (xy 415.504675 -118.269475)
			(xy 415.560079 -118.292424) (xy 415.612013 -118.322408) (xy 415.659589 -118.358914) (xy 415.701994 -118.401319)
			(xy 415.7385 -118.448895) (xy 415.768484 -118.500829) (xy 415.791433 -118.556233) (xy 415.806954 -118.614158)
			(xy 415.814782 -118.673614) (xy 415.815272 -118.703598) (xy 415.815272 -119.559324) (xy 429.3743 -119.559324)
			(xy 429.3743 -118.695724) (xy 429.37479 -118.66574) (xy 429.382618 -118.606284) (xy 429.398139 -118.548359)
			(xy 429.421088 -118.492955) (xy 429.451072 -118.441021) (xy 429.487578 -118.393445) (xy 429.529983 -118.35104)
			(xy 429.577559 -118.314534) (xy 429.629493 -118.28455) (xy 429.684897 -118.261601) (xy 429.742822 -118.24608)
			(xy 429.802278 -118.238252) (xy 429.862246 -118.238252) (xy 429.921702 -118.24608) (xy 429.979627 -118.261601)
			(xy 430.035031 -118.28455) (xy 430.086965 -118.314534) (xy 430.134541 -118.35104) (xy 430.176946 -118.393445)
			(xy 430.213452 -118.441021) (xy 430.243436 -118.492955) (xy 430.266385 -118.548359) (xy 430.281906 -118.606284)
			(xy 430.289734 -118.66574) (xy 430.290224 -118.695724) (xy 430.290224 -119.559324) (xy 430.289734 -119.589308)
			(xy 430.281906 -119.648764) (xy 430.266385 -119.706689) (xy 430.243436 -119.762093) (xy 430.213452 -119.814027)
			(xy 430.176946 -119.861603) (xy 430.134541 -119.904008) (xy 430.086965 -119.940514) (xy 430.035031 -119.970498)
			(xy 429.979627 -119.993447) (xy 429.921702 -120.008968) (xy 429.862246 -120.016796) (xy 429.802278 -120.016796)
			(xy 429.742822 -120.008968) (xy 429.684897 -119.993447) (xy 429.629493 -119.970498) (xy 429.577559 -119.940514)
			(xy 429.529983 -119.904008) (xy 429.487578 -119.861603) (xy 429.451072 -119.814027) (xy 429.421088 -119.762093)
			(xy 429.398139 -119.706689) (xy 429.382618 -119.648764) (xy 429.37479 -119.589308) (xy 429.3743 -119.559324)
			(xy 415.815272 -119.559324) (xy 415.815272 -119.567198) (xy 415.814782 -119.597182) (xy 415.806954 -119.656638)
			(xy 415.791433 -119.714563) (xy 415.768484 -119.769967) (xy 415.7385 -119.821901) (xy 415.701994 -119.869477)
			(xy 415.659589 -119.911882) (xy 415.612013 -119.948388) (xy 415.560079 -119.978372) (xy 415.504675 -120.001321)
			(xy 415.44675 -120.016842) (xy 415.387294 -120.02467) (xy 415.327326 -120.02467) (xy 415.26787 -120.016842)
			(xy 415.209945 -120.001321) (xy 415.154541 -119.978372) (xy 415.102607 -119.948388) (xy 415.055031 -119.911882)
			(xy 415.012626 -119.869477) (xy 414.97612 -119.821901) (xy 414.946136 -119.769967) (xy 414.923187 -119.714563)
			(xy 414.907666 -119.656638) (xy 414.899838 -119.597182) (xy 414.899348 -119.567198) (xy 402.854668 -119.567198)
			(xy 402.854668 -120.086374) (xy 402.854178 -120.116342) (xy 402.846355 -120.175764) (xy 402.830842 -120.233657)
			(xy 402.807906 -120.28903) (xy 402.777939 -120.340936) (xy 402.741452 -120.388486) (xy 402.699072 -120.430866)
			(xy 402.651522 -120.467353) (xy 402.599616 -120.49732) (xy 402.544243 -120.520256) (xy 402.48635 -120.535769)
			(xy 402.426928 -120.543592) (xy 402.366992 -120.543592) (xy 402.30757 -120.535769) (xy 402.249677 -120.520256)
			(xy 402.194304 -120.49732) (xy 402.142398 -120.467353) (xy 402.094848 -120.430866) (xy 402.052468 -120.388486)
			(xy 402.015981 -120.340936) (xy 401.986014 -120.28903) (xy 401.963078 -120.233657) (xy 401.947565 -120.175764)
			(xy 401.939742 -120.116342) (xy 401.939252 -120.086374) (xy 383.883408 -120.086374) (xy 383.883408 -120.087898)
			(xy 383.882918 -120.117866) (xy 383.875095 -120.177288) (xy 383.859582 -120.235181) (xy 383.836646 -120.290554)
			(xy 383.806679 -120.34246) (xy 383.770192 -120.39001) (xy 383.727812 -120.43239) (xy 383.680262 -120.468877)
			(xy 383.628356 -120.498844) (xy 383.572983 -120.52178) (xy 383.51509 -120.537293) (xy 383.455668 -120.545116)
			(xy 383.395732 -120.545116) (xy 383.33631 -120.537293) (xy 383.278417 -120.52178) (xy 383.223044 -120.498844)
			(xy 383.171138 -120.468877) (xy 383.123588 -120.43239) (xy 383.081208 -120.39001) (xy 383.044721 -120.34246)
			(xy 383.014754 -120.290554) (xy 382.991818 -120.235181) (xy 382.976305 -120.177288) (xy 382.968482 -120.117866)
			(xy 382.967992 -120.087898) (xy 316.568893 -120.087898) (xy 316.576928 -120.091226) (xy 316.628834 -120.121193)
			(xy 316.676384 -120.15768) (xy 316.718764 -120.20006) (xy 316.755251 -120.24761) (xy 316.785218 -120.299516)
			(xy 316.808154 -120.354889) (xy 316.823667 -120.412782) (xy 316.83149 -120.472204) (xy 316.83198 -120.502172)
			(xy 316.83198 -121.365772) (xy 316.83149 -121.39574) (xy 316.823667 -121.455162) (xy 316.808154 -121.513055)
			(xy 316.785218 -121.568428) (xy 316.755251 -121.620334) (xy 316.718764 -121.667884) (xy 316.676384 -121.710264)
			(xy 316.628834 -121.746751) (xy 316.576928 -121.776718) (xy 316.521555 -121.799654) (xy 316.463662 -121.815167)
			(xy 316.40424 -121.82299) (xy 316.344304 -121.82299) (xy 316.284882 -121.815167) (xy 316.226989 -121.799654)
			(xy 316.171616 -121.776718) (xy 316.11971 -121.746751) (xy 316.07216 -121.710264) (xy 316.02978 -121.667884)
			(xy 315.993293 -121.620334) (xy 315.963326 -121.568428) (xy 315.94039 -121.513055) (xy 315.924877 -121.455162)
			(xy 315.917054 -121.39574) (xy 315.916564 -121.365772) (xy 297.86072 -121.365772) (xy 297.86072 -121.367296)
			(xy 297.86023 -121.397264) (xy 297.852407 -121.456686) (xy 297.836894 -121.514579) (xy 297.813958 -121.569952)
			(xy 297.783991 -121.621858) (xy 297.747504 -121.669408) (xy 297.705124 -121.711788) (xy 297.657574 -121.748275)
			(xy 297.605668 -121.778242) (xy 297.550295 -121.801178) (xy 297.492402 -121.816691) (xy 297.43298 -121.824514)
			(xy 297.373044 -121.824514) (xy 297.313622 -121.816691) (xy 297.255729 -121.801178) (xy 297.200356 -121.778242)
			(xy 297.14845 -121.748275) (xy 297.1009 -121.711788) (xy 297.05852 -121.669408) (xy 297.022033 -121.621858)
			(xy 296.992066 -121.569952) (xy 296.96913 -121.514579) (xy 296.953617 -121.456686) (xy 296.945794 -121.397264)
			(xy 296.945304 -121.367296) (xy 284.900624 -121.367296) (xy 284.900624 -121.886472) (xy 284.900134 -121.916456)
			(xy 284.892306 -121.975912) (xy 284.876785 -122.033837) (xy 284.853836 -122.089241) (xy 284.823852 -122.141175)
			(xy 284.787346 -122.188751) (xy 284.744941 -122.231156) (xy 284.697365 -122.267662) (xy 284.645431 -122.297646)
			(xy 284.590027 -122.320595) (xy 284.532102 -122.336116) (xy 284.472646 -122.343944) (xy 284.412678 -122.343944)
			(xy 284.353222 -122.336116) (xy 284.295297 -122.320595) (xy 284.239893 -122.297646) (xy 284.187959 -122.267662)
			(xy 284.140383 -122.231156) (xy 284.097978 -122.188751) (xy 284.061472 -122.141175) (xy 284.031488 -122.089241)
			(xy 284.008539 -122.033837) (xy 283.993018 -121.975912) (xy 283.98519 -121.916456) (xy 283.9847 -121.886472)
			(xy 270.425672 -121.886472) (xy 270.425672 -121.894346) (xy 270.425182 -121.92433) (xy 270.417354 -121.983786)
			(xy 270.401833 -122.041711) (xy 270.378884 -122.097115) (xy 270.3489 -122.149049) (xy 270.312394 -122.196625)
			(xy 270.269989 -122.23903) (xy 270.222413 -122.275536) (xy 270.170479 -122.30552) (xy 270.115075 -122.328469)
			(xy 270.05715 -122.34399) (xy 269.997694 -122.351818) (xy 269.937726 -122.351818) (xy 269.87827 -122.34399)
			(xy 269.820345 -122.328469) (xy 269.764941 -122.30552) (xy 269.713007 -122.275536) (xy 269.665431 -122.23903)
			(xy 269.623026 -122.196625) (xy 269.58652 -122.149049) (xy 269.556536 -122.097115) (xy 269.533587 -122.041711)
			(xy 269.518066 -121.983786) (xy 269.510238 -121.92433) (xy 269.509748 -121.894346) (xy 197.851649 -121.894346)
			(xy 197.886882 -121.914687) (xy 197.934432 -121.951174) (xy 197.976812 -121.993554) (xy 198.013299 -122.041104)
			(xy 198.043266 -122.09301) (xy 198.066202 -122.148383) (xy 198.081715 -122.206276) (xy 198.089538 -122.265698)
			(xy 198.090028 -122.295666) (xy 198.090028 -123.159266) (xy 198.089538 -123.189234) (xy 198.081715 -123.248656)
			(xy 198.066202 -123.306549) (xy 198.043266 -123.361922) (xy 198.013299 -123.413828) (xy 197.976812 -123.461378)
			(xy 197.934432 -123.503758) (xy 197.886882 -123.540245) (xy 197.834976 -123.570212) (xy 197.779603 -123.593148)
			(xy 197.72171 -123.608661) (xy 197.662288 -123.616484) (xy 197.602352 -123.616484) (xy 197.54293 -123.608661)
			(xy 197.485037 -123.593148) (xy 197.429664 -123.570212) (xy 197.377758 -123.540245) (xy 197.330208 -123.503758)
			(xy 197.287828 -123.461378) (xy 197.251341 -123.413828) (xy 197.221374 -123.361922) (xy 197.198438 -123.306549)
			(xy 197.182925 -123.248656) (xy 197.175102 -123.189234) (xy 197.174612 -123.159266) (xy 183.615076 -123.159266)
			(xy 183.615076 -123.16714) (xy 183.614586 -123.197108) (xy 183.606763 -123.25653) (xy 183.59125 -123.314423)
			(xy 183.568314 -123.369796) (xy 183.538347 -123.421702) (xy 183.50186 -123.469252) (xy 183.45948 -123.511632)
			(xy 183.41193 -123.548119) (xy 183.360024 -123.578086) (xy 183.304651 -123.601022) (xy 183.246758 -123.616535)
			(xy 183.187336 -123.624358) (xy 183.1274 -123.624358) (xy 183.067978 -123.616535) (xy 183.010085 -123.601022)
			(xy 182.954712 -123.578086) (xy 182.902806 -123.548119) (xy 182.855256 -123.511632) (xy 182.812876 -123.469252)
			(xy 182.776389 -123.421702) (xy 182.746422 -123.369796) (xy 182.723486 -123.314423) (xy 182.707973 -123.25653)
			(xy 182.70015 -123.197108) (xy 182.69966 -123.16714) (xy 170.65498 -123.16714) (xy 170.65498 -123.686316)
			(xy 170.65449 -123.7163) (xy 170.646662 -123.775756) (xy 170.631141 -123.833681) (xy 170.608192 -123.889085)
			(xy 170.578208 -123.941019) (xy 170.541702 -123.988595) (xy 170.499297 -124.031) (xy 170.451721 -124.067506)
			(xy 170.399787 -124.09749) (xy 170.344383 -124.120439) (xy 170.286458 -124.13596) (xy 170.227002 -124.143788)
			(xy 170.167034 -124.143788) (xy 170.107578 -124.13596) (xy 170.049653 -124.120439) (xy 169.994249 -124.09749)
			(xy 169.942315 -124.067506) (xy 169.894739 -124.031) (xy 169.852334 -123.988595) (xy 169.815828 -123.941019)
			(xy 169.785844 -123.889085) (xy 169.762895 -123.833681) (xy 169.747374 -123.775756) (xy 169.739546 -123.7163)
			(xy 169.739056 -123.686316) (xy 151.68372 -123.686316) (xy 151.68372 -123.68784) (xy 151.68323 -123.717824)
			(xy 151.675402 -123.77728) (xy 151.659881 -123.835205) (xy 151.636932 -123.890609) (xy 151.606948 -123.942543)
			(xy 151.570442 -123.990119) (xy 151.528037 -124.032524) (xy 151.480461 -124.06903) (xy 151.428527 -124.099014)
			(xy 151.373123 -124.121963) (xy 151.315198 -124.137484) (xy 151.255742 -124.145312) (xy 151.195774 -124.145312)
			(xy 151.136318 -124.137484) (xy 151.078393 -124.121963) (xy 151.022989 -124.099014) (xy 150.971055 -124.06903)
			(xy 150.923479 -124.032524) (xy 150.881074 -123.990119) (xy 150.844568 -123.942543) (xy 150.814584 -123.890609)
			(xy 150.791635 -123.835205) (xy 150.776114 -123.77728) (xy 150.768286 -123.717824) (xy 150.767796 -123.68784)
			(xy 84.369615 -123.68784) (xy 84.377099 -123.69094) (xy 84.429033 -123.720924) (xy 84.476609 -123.75743)
			(xy 84.519014 -123.799835) (xy 84.55552 -123.847411) (xy 84.585504 -123.899345) (xy 84.608453 -123.954749)
			(xy 84.623974 -124.012674) (xy 84.631802 -124.07213) (xy 84.632292 -124.102114) (xy 84.632292 -124.965714)
			(xy 84.631802 -124.995698) (xy 84.623974 -125.055154) (xy 84.608453 -125.113079) (xy 84.585504 -125.168483)
			(xy 84.55552 -125.220417) (xy 84.519014 -125.267993) (xy 84.476609 -125.310398) (xy 84.429033 -125.346904)
			(xy 84.377099 -125.376888) (xy 84.321695 -125.399837) (xy 84.26377 -125.415358) (xy 84.204314 -125.423186)
			(xy 84.144346 -125.423186) (xy 84.08489 -125.415358) (xy 84.026965 -125.399837) (xy 83.971561 -125.376888)
			(xy 83.919627 -125.346904) (xy 83.872051 -125.310398) (xy 83.829646 -125.267993) (xy 83.79314 -125.220417)
			(xy 83.763156 -125.168483) (xy 83.740207 -125.113079) (xy 83.724686 -125.055154) (xy 83.716858 -124.995698)
			(xy 83.716368 -124.965714) (xy 65.661032 -124.965714) (xy 65.661032 -124.967238) (xy 65.660542 -124.997222)
			(xy 65.652714 -125.056678) (xy 65.637193 -125.114603) (xy 65.614244 -125.170007) (xy 65.58426 -125.221941)
			(xy 65.547754 -125.269517) (xy 65.505349 -125.311922) (xy 65.457773 -125.348428) (xy 65.405839 -125.378412)
			(xy 65.350435 -125.401361) (xy 65.29251 -125.416882) (xy 65.233054 -125.42471) (xy 65.173086 -125.42471)
			(xy 65.11363 -125.416882) (xy 65.055705 -125.401361) (xy 65.000301 -125.378412) (xy 64.948367 -125.348428)
			(xy 64.900791 -125.311922) (xy 64.858386 -125.269517) (xy 64.82188 -125.221941) (xy 64.791896 -125.170007)
			(xy 64.768947 -125.114603) (xy 64.753426 -125.056678) (xy 64.745598 -124.997222) (xy 64.745108 -124.967238)
			(xy 52.700428 -124.967238) (xy 52.700428 -125.486414) (xy 52.700295 -125.494542) (xy 153.409904 -125.494542)
			(xy 153.409904 -124.630942) (xy 153.410394 -124.600958) (xy 153.418222 -124.541502) (xy 153.433743 -124.483577)
			(xy 153.456692 -124.428173) (xy 153.486676 -124.376239) (xy 153.523182 -124.328663) (xy 153.565587 -124.286258)
			(xy 153.613163 -124.249752) (xy 153.665097 -124.219768) (xy 153.720501 -124.196819) (xy 153.778426 -124.181298)
			(xy 153.837882 -124.17347) (xy 153.89785 -124.17347) (xy 153.957306 -124.181298) (xy 154.015231 -124.196819)
			(xy 154.070635 -124.219768) (xy 154.122569 -124.249752) (xy 154.170145 -124.286258) (xy 154.21255 -124.328663)
			(xy 154.249056 -124.376239) (xy 154.27904 -124.428173) (xy 154.301989 -124.483577) (xy 154.31751 -124.541502)
			(xy 154.325338 -124.600958) (xy 154.325828 -124.630942) (xy 154.325828 -125.486414) (xy 167.884856 -125.486414)
			(xy 167.884856 -124.622814) (xy 167.885346 -124.59283) (xy 167.893174 -124.533374) (xy 167.908695 -124.475449)
			(xy 167.931644 -124.420045) (xy 167.961628 -124.368111) (xy 167.998134 -124.320535) (xy 168.040539 -124.27813)
			(xy 168.088115 -124.241624) (xy 168.140049 -124.21164) (xy 168.195453 -124.188691) (xy 168.253378 -124.17317)
			(xy 168.312834 -124.165342) (xy 168.372802 -124.165342) (xy 168.432258 -124.17317) (xy 168.490183 -124.188691)
			(xy 168.545587 -124.21164) (xy 168.597521 -124.241624) (xy 168.645097 -124.27813) (xy 168.687502 -124.320535)
			(xy 168.724008 -124.368111) (xy 168.753992 -124.420045) (xy 168.776941 -124.475449) (xy 168.792462 -124.533374)
			(xy 168.80029 -124.59283) (xy 168.80078 -124.622814) (xy 168.80078 -124.967238) (xy 180.84546 -124.967238)
			(xy 180.84546 -124.103638) (xy 180.84595 -124.07367) (xy 180.853773 -124.014248) (xy 180.869286 -123.956355)
			(xy 180.892222 -123.900982) (xy 180.922189 -123.849076) (xy 180.958676 -123.801526) (xy 181.001056 -123.759146)
			(xy 181.048606 -123.722659) (xy 181.100512 -123.692692) (xy 181.155885 -123.669756) (xy 181.213778 -123.654243)
			(xy 181.2732 -123.64642) (xy 181.333136 -123.64642) (xy 181.392558 -123.654243) (xy 181.450451 -123.669756)
			(xy 181.505824 -123.692692) (xy 181.55773 -123.722659) (xy 181.60528 -123.759146) (xy 181.64766 -123.801526)
			(xy 181.684147 -123.849076) (xy 181.714114 -123.900982) (xy 181.73705 -123.956355) (xy 181.752563 -124.014248)
			(xy 181.760386 -124.07367) (xy 181.760876 -124.103638) (xy 181.760876 -124.965714) (xy 199.81672 -124.965714)
			(xy 199.81672 -124.102114) (xy 199.81721 -124.072146) (xy 199.825033 -124.012724) (xy 199.840546 -123.954831)
			(xy 199.863482 -123.899458) (xy 199.893449 -123.847552) (xy 199.929936 -123.800002) (xy 199.972316 -123.757622)
			(xy 200.019866 -123.721135) (xy 200.071772 -123.691168) (xy 200.127145 -123.668232) (xy 200.185038 -123.652719)
			(xy 200.24446 -123.644896) (xy 200.304396 -123.644896) (xy 200.363818 -123.652719) (xy 200.421711 -123.668232)
			(xy 200.469049 -123.68784) (xy 266.86764 -123.68784) (xy 266.86764 -122.82424) (xy 266.86813 -122.794256)
			(xy 266.875958 -122.7348) (xy 266.891479 -122.676875) (xy 266.914428 -122.621471) (xy 266.944412 -122.569537)
			(xy 266.980918 -122.521961) (xy 267.023323 -122.479556) (xy 267.070899 -122.44305) (xy 267.122833 -122.413066)
			(xy 267.178237 -122.390117) (xy 267.236162 -122.374596) (xy 267.295618 -122.366768) (xy 267.355586 -122.366768)
			(xy 267.415042 -122.374596) (xy 267.472967 -122.390117) (xy 267.528371 -122.413066) (xy 267.580305 -122.44305)
			(xy 267.627881 -122.479556) (xy 267.670286 -122.521961) (xy 267.706792 -122.569537) (xy 267.736776 -122.621471)
			(xy 267.759725 -122.676875) (xy 267.775246 -122.7348) (xy 267.783074 -122.794256) (xy 267.783564 -122.82424)
			(xy 267.783564 -123.686316) (xy 285.8389 -123.686316) (xy 285.8389 -122.822716) (xy 285.83939 -122.792732)
			(xy 285.847218 -122.733276) (xy 285.862739 -122.675351) (xy 285.885688 -122.619947) (xy 285.915672 -122.568013)
			(xy 285.952178 -122.520437) (xy 285.994583 -122.478032) (xy 286.042159 -122.441526) (xy 286.094093 -122.411542)
			(xy 286.149497 -122.388593) (xy 286.207422 -122.373072) (xy 286.266878 -122.365244) (xy 286.326846 -122.365244)
			(xy 286.386302 -122.373072) (xy 286.444227 -122.388593) (xy 286.499631 -122.411542) (xy 286.551565 -122.441526)
			(xy 286.599141 -122.478032) (xy 286.641546 -122.520437) (xy 286.678052 -122.568013) (xy 286.708036 -122.619947)
			(xy 286.730985 -122.675351) (xy 286.746506 -122.733276) (xy 286.754334 -122.792732) (xy 286.754824 -122.822716)
			(xy 286.754824 -123.16714) (xy 298.799504 -123.16714) (xy 298.799504 -122.30354) (xy 298.799994 -122.273572)
			(xy 298.807817 -122.21415) (xy 298.82333 -122.156257) (xy 298.846266 -122.100884) (xy 298.876233 -122.048978)
			(xy 298.91272 -122.001428) (xy 298.9551 -121.959048) (xy 299.00265 -121.922561) (xy 299.054556 -121.892594)
			(xy 299.109929 -121.869658) (xy 299.167822 -121.854145) (xy 299.227244 -121.846322) (xy 299.28718 -121.846322)
			(xy 299.346602 -121.854145) (xy 299.404495 -121.869658) (xy 299.459868 -121.892594) (xy 299.511774 -121.922561)
			(xy 299.559324 -121.959048) (xy 299.601704 -122.001428) (xy 299.638191 -122.048978) (xy 299.668158 -122.100884)
			(xy 299.691094 -122.156257) (xy 299.706607 -122.21415) (xy 299.71443 -122.273572) (xy 299.71492 -122.30354)
			(xy 299.71492 -123.159266) (xy 313.274456 -123.159266) (xy 313.274456 -122.295666) (xy 313.274946 -122.265698)
			(xy 313.282769 -122.206276) (xy 313.298282 -122.148383) (xy 313.321218 -122.09301) (xy 313.351185 -122.041104)
			(xy 313.387672 -121.993554) (xy 313.430052 -121.951174) (xy 313.477602 -121.914687) (xy 313.529508 -121.88472)
			(xy 313.584881 -121.861784) (xy 313.642774 -121.846271) (xy 313.702196 -121.838448) (xy 313.762132 -121.838448)
			(xy 313.821554 -121.846271) (xy 313.879447 -121.861784) (xy 313.93482 -121.88472) (xy 313.951493 -121.894346)
			(xy 385.6101 -121.894346) (xy 385.6101 -121.030746) (xy 385.61059 -121.000778) (xy 385.618413 -120.941356)
			(xy 385.633926 -120.883463) (xy 385.656862 -120.82809) (xy 385.686829 -120.776184) (xy 385.723316 -120.728634)
			(xy 385.765696 -120.686254) (xy 385.813246 -120.649767) (xy 385.865152 -120.6198) (xy 385.920525 -120.596864)
			(xy 385.978418 -120.581351) (xy 386.03784 -120.573528) (xy 386.097776 -120.573528) (xy 386.157198 -120.581351)
			(xy 386.215091 -120.596864) (xy 386.270464 -120.6198) (xy 386.32237 -120.649767) (xy 386.36992 -120.686254)
			(xy 386.4123 -120.728634) (xy 386.448787 -120.776184) (xy 386.478754 -120.82809) (xy 386.50169 -120.883463)
			(xy 386.517203 -120.941356) (xy 386.525026 -121.000778) (xy 386.525516 -121.030746) (xy 386.525516 -121.886472)
			(xy 400.085052 -121.886472) (xy 400.085052 -121.022872) (xy 400.085542 -120.992904) (xy 400.093365 -120.933482)
			(xy 400.108878 -120.875589) (xy 400.131814 -120.820216) (xy 400.161781 -120.76831) (xy 400.198268 -120.72076)
			(xy 400.240648 -120.67838) (xy 400.288198 -120.641893) (xy 400.340104 -120.611926) (xy 400.395477 -120.58899)
			(xy 400.45337 -120.573477) (xy 400.512792 -120.565654) (xy 400.572728 -120.565654) (xy 400.63215 -120.573477)
			(xy 400.690043 -120.58899) (xy 400.745416 -120.611926) (xy 400.797322 -120.641893) (xy 400.844872 -120.67838)
			(xy 400.887252 -120.72076) (xy 400.923739 -120.76831) (xy 400.953706 -120.820216) (xy 400.976642 -120.875589)
			(xy 400.992155 -120.933482) (xy 400.999978 -120.992904) (xy 401.000468 -121.022872) (xy 401.000468 -121.367296)
			(xy 413.045148 -121.367296) (xy 413.045148 -120.503696) (xy 413.045638 -120.473712) (xy 413.053466 -120.414256)
			(xy 413.068987 -120.356331) (xy 413.091936 -120.300927) (xy 413.12192 -120.248993) (xy 413.158426 -120.201417)
			(xy 413.200831 -120.159012) (xy 413.248407 -120.122506) (xy 413.300341 -120.092522) (xy 413.355745 -120.069573)
			(xy 413.41367 -120.054052) (xy 413.473126 -120.046224) (xy 413.533094 -120.046224) (xy 413.59255 -120.054052)
			(xy 413.650475 -120.069573) (xy 413.705879 -120.092522) (xy 413.757813 -120.122506) (xy 413.805389 -120.159012)
			(xy 413.847794 -120.201417) (xy 413.8843 -120.248993) (xy 413.914284 -120.300927) (xy 413.937233 -120.356331)
			(xy 413.952754 -120.414256) (xy 413.960582 -120.473712) (xy 413.961072 -120.503696) (xy 413.961072 -121.365772)
			(xy 432.016408 -121.365772) (xy 432.016408 -120.502172) (xy 432.016898 -120.472188) (xy 432.024726 -120.412732)
			(xy 432.040247 -120.354807) (xy 432.063196 -120.299403) (xy 432.09318 -120.247469) (xy 432.129686 -120.199893)
			(xy 432.172091 -120.157488) (xy 432.219667 -120.120982) (xy 432.271601 -120.090998) (xy 432.327005 -120.068049)
			(xy 432.38493 -120.052528) (xy 432.444386 -120.0447) (xy 432.504354 -120.0447) (xy 432.56381 -120.052528)
			(xy 432.621735 -120.068049) (xy 432.677139 -120.090998) (xy 432.729073 -120.120982) (xy 432.776649 -120.157488)
			(xy 432.819054 -120.199893) (xy 432.85556 -120.247469) (xy 432.885544 -120.299403) (xy 432.908493 -120.354807)
			(xy 432.924014 -120.412732) (xy 432.931842 -120.472188) (xy 432.932332 -120.502172) (xy 432.932332 -121.365772)
			(xy 432.931842 -121.395756) (xy 432.924014 -121.455212) (xy 432.908493 -121.513137) (xy 432.885544 -121.568541)
			(xy 432.85556 -121.620475) (xy 432.819054 -121.668051) (xy 432.776649 -121.710456) (xy 432.729073 -121.746962)
			(xy 432.677139 -121.776946) (xy 432.621735 -121.799895) (xy 432.56381 -121.815416) (xy 432.504354 -121.823244)
			(xy 432.444386 -121.823244) (xy 432.38493 -121.815416) (xy 432.327005 -121.799895) (xy 432.271601 -121.776946)
			(xy 432.219667 -121.746962) (xy 432.172091 -121.710456) (xy 432.129686 -121.668051) (xy 432.09318 -121.620475)
			(xy 432.063196 -121.568541) (xy 432.040247 -121.513137) (xy 432.024726 -121.455212) (xy 432.016898 -121.395756)
			(xy 432.016408 -121.365772) (xy 413.961072 -121.365772) (xy 413.961072 -121.367296) (xy 413.960582 -121.39728)
			(xy 413.952754 -121.456736) (xy 413.937233 -121.514661) (xy 413.914284 -121.570065) (xy 413.8843 -121.621999)
			(xy 413.847794 -121.669575) (xy 413.805389 -121.71198) (xy 413.757813 -121.748486) (xy 413.705879 -121.77847)
			(xy 413.650475 -121.801419) (xy 413.59255 -121.81694) (xy 413.533094 -121.824768) (xy 413.473126 -121.824768)
			(xy 413.41367 -121.81694) (xy 413.355745 -121.801419) (xy 413.300341 -121.77847) (xy 413.248407 -121.748486)
			(xy 413.200831 -121.71198) (xy 413.158426 -121.669575) (xy 413.12192 -121.621999) (xy 413.091936 -121.570065)
			(xy 413.068987 -121.514661) (xy 413.053466 -121.456736) (xy 413.045638 -121.39728) (xy 413.045148 -121.367296)
			(xy 401.000468 -121.367296) (xy 401.000468 -121.886472) (xy 400.999978 -121.91644) (xy 400.992155 -121.975862)
			(xy 400.976642 -122.033755) (xy 400.953706 -122.089128) (xy 400.923739 -122.141034) (xy 400.887252 -122.188584)
			(xy 400.844872 -122.230964) (xy 400.797322 -122.267451) (xy 400.745416 -122.297418) (xy 400.690043 -122.320354)
			(xy 400.63215 -122.335867) (xy 400.572728 -122.34369) (xy 400.512792 -122.34369) (xy 400.45337 -122.335867)
			(xy 400.395477 -122.320354) (xy 400.340104 -122.297418) (xy 400.288198 -122.267451) (xy 400.240648 -122.230964)
			(xy 400.198268 -122.188584) (xy 400.161781 -122.141034) (xy 400.131814 -122.089128) (xy 400.108878 -122.033755)
			(xy 400.093365 -121.975862) (xy 400.085542 -121.91644) (xy 400.085052 -121.886472) (xy 386.525516 -121.886472)
			(xy 386.525516 -121.894346) (xy 386.525026 -121.924314) (xy 386.517203 -121.983736) (xy 386.50169 -122.041629)
			(xy 386.478754 -122.097002) (xy 386.448787 -122.148908) (xy 386.4123 -122.196458) (xy 386.36992 -122.238838)
			(xy 386.32237 -122.275325) (xy 386.270464 -122.305292) (xy 386.215091 -122.328228) (xy 386.157198 -122.343741)
			(xy 386.097776 -122.351564) (xy 386.03784 -122.351564) (xy 385.978418 -122.343741) (xy 385.920525 -122.328228)
			(xy 385.865152 -122.305292) (xy 385.813246 -122.275325) (xy 385.765696 -122.238838) (xy 385.723316 -122.196458)
			(xy 385.686829 -122.148908) (xy 385.656862 -122.097002) (xy 385.633926 -122.041629) (xy 385.618413 -121.983736)
			(xy 385.61059 -121.924314) (xy 385.6101 -121.894346) (xy 313.951493 -121.894346) (xy 313.986726 -121.914687)
			(xy 314.034276 -121.951174) (xy 314.076656 -121.993554) (xy 314.113143 -122.041104) (xy 314.14311 -122.09301)
			(xy 314.166046 -122.148383) (xy 314.181559 -122.206276) (xy 314.189382 -122.265698) (xy 314.189872 -122.295666)
			(xy 314.189872 -123.159266) (xy 314.189382 -123.189234) (xy 314.181559 -123.248656) (xy 314.166046 -123.306549)
			(xy 314.14311 -123.361922) (xy 314.113143 -123.413828) (xy 314.076656 -123.461378) (xy 314.034276 -123.503758)
			(xy 313.986726 -123.540245) (xy 313.93482 -123.570212) (xy 313.879447 -123.593148) (xy 313.821554 -123.608661)
			(xy 313.762132 -123.616484) (xy 313.702196 -123.616484) (xy 313.642774 -123.608661) (xy 313.584881 -123.593148)
			(xy 313.529508 -123.570212) (xy 313.477602 -123.540245) (xy 313.430052 -123.503758) (xy 313.387672 -123.461378)
			(xy 313.351185 -123.413828) (xy 313.321218 -123.361922) (xy 313.298282 -123.306549) (xy 313.282769 -123.248656)
			(xy 313.274946 -123.189234) (xy 313.274456 -123.159266) (xy 299.71492 -123.159266) (xy 299.71492 -123.16714)
			(xy 299.71443 -123.197108) (xy 299.706607 -123.25653) (xy 299.691094 -123.314423) (xy 299.668158 -123.369796)
			(xy 299.638191 -123.421702) (xy 299.601704 -123.469252) (xy 299.559324 -123.511632) (xy 299.511774 -123.548119)
			(xy 299.459868 -123.578086) (xy 299.404495 -123.601022) (xy 299.346602 -123.616535) (xy 299.28718 -123.624358)
			(xy 299.227244 -123.624358) (xy 299.167822 -123.616535) (xy 299.109929 -123.601022) (xy 299.054556 -123.578086)
			(xy 299.00265 -123.548119) (xy 298.9551 -123.511632) (xy 298.91272 -123.469252) (xy 298.876233 -123.421702)
			(xy 298.846266 -123.369796) (xy 298.82333 -123.314423) (xy 298.807817 -123.25653) (xy 298.799994 -123.197108)
			(xy 298.799504 -123.16714) (xy 286.754824 -123.16714) (xy 286.754824 -123.686316) (xy 286.754334 -123.7163)
			(xy 286.746506 -123.775756) (xy 286.730985 -123.833681) (xy 286.708036 -123.889085) (xy 286.678052 -123.941019)
			(xy 286.641546 -123.988595) (xy 286.599141 -124.031) (xy 286.551565 -124.067506) (xy 286.499631 -124.09749)
			(xy 286.444227 -124.120439) (xy 286.386302 -124.13596) (xy 286.326846 -124.143788) (xy 286.266878 -124.143788)
			(xy 286.207422 -124.13596) (xy 286.149497 -124.120439) (xy 286.094093 -124.09749) (xy 286.042159 -124.067506)
			(xy 285.994583 -124.031) (xy 285.952178 -123.988595) (xy 285.915672 -123.941019) (xy 285.885688 -123.889085)
			(xy 285.862739 -123.833681) (xy 285.847218 -123.775756) (xy 285.83939 -123.7163) (xy 285.8389 -123.686316)
			(xy 267.783564 -123.686316) (xy 267.783564 -123.68784) (xy 267.783074 -123.717824) (xy 267.775246 -123.77728)
			(xy 267.759725 -123.835205) (xy 267.736776 -123.890609) (xy 267.706792 -123.942543) (xy 267.670286 -123.990119)
			(xy 267.627881 -124.032524) (xy 267.580305 -124.06903) (xy 267.528371 -124.099014) (xy 267.472967 -124.121963)
			(xy 267.415042 -124.137484) (xy 267.355586 -124.145312) (xy 267.295618 -124.145312) (xy 267.236162 -124.137484)
			(xy 267.178237 -124.121963) (xy 267.122833 -124.099014) (xy 267.070899 -124.06903) (xy 267.023323 -124.032524)
			(xy 266.980918 -123.990119) (xy 266.944412 -123.942543) (xy 266.914428 -123.890609) (xy 266.891479 -123.835205)
			(xy 266.875958 -123.77728) (xy 266.86813 -123.717824) (xy 266.86764 -123.68784) (xy 200.469049 -123.68784)
			(xy 200.477084 -123.691168) (xy 200.52899 -123.721135) (xy 200.57654 -123.757622) (xy 200.61892 -123.800002)
			(xy 200.655407 -123.847552) (xy 200.685374 -123.899458) (xy 200.70831 -123.954831) (xy 200.723823 -124.012724)
			(xy 200.731646 -124.072146) (xy 200.732136 -124.102114) (xy 200.732136 -124.965714) (xy 200.731646 -124.995682)
			(xy 200.723823 -125.055104) (xy 200.70831 -125.112997) (xy 200.685374 -125.16837) (xy 200.655407 -125.220276)
			(xy 200.61892 -125.267826) (xy 200.57654 -125.310206) (xy 200.52899 -125.346693) (xy 200.477084 -125.37666)
			(xy 200.421711 -125.399596) (xy 200.363818 -125.415109) (xy 200.304396 -125.422932) (xy 200.24446 -125.422932)
			(xy 200.185038 -125.415109) (xy 200.127145 -125.399596) (xy 200.071772 -125.37666) (xy 200.019866 -125.346693)
			(xy 199.972316 -125.310206) (xy 199.929936 -125.267826) (xy 199.893449 -125.220276) (xy 199.863482 -125.16837)
			(xy 199.840546 -125.112997) (xy 199.825033 -125.055104) (xy 199.81721 -124.995682) (xy 199.81672 -124.965714)
			(xy 181.760876 -124.965714) (xy 181.760876 -124.967238) (xy 181.760386 -124.997206) (xy 181.752563 -125.056628)
			(xy 181.73705 -125.114521) (xy 181.714114 -125.169894) (xy 181.684147 -125.2218) (xy 181.64766 -125.26935)
			(xy 181.60528 -125.31173) (xy 181.55773 -125.348217) (xy 181.505824 -125.378184) (xy 181.450451 -125.40112)
			(xy 181.392558 -125.416633) (xy 181.333136 -125.424456) (xy 181.2732 -125.424456) (xy 181.213778 -125.416633)
			(xy 181.155885 -125.40112) (xy 181.100512 -125.378184) (xy 181.048606 -125.348217) (xy 181.001056 -125.31173)
			(xy 180.958676 -125.26935) (xy 180.922189 -125.2218) (xy 180.892222 -125.169894) (xy 180.869286 -125.114521)
			(xy 180.853773 -125.056628) (xy 180.84595 -124.997206) (xy 180.84546 -124.967238) (xy 168.80078 -124.967238)
			(xy 168.80078 -125.486414) (xy 168.800647 -125.494542) (xy 269.509748 -125.494542) (xy 269.509748 -124.630942)
			(xy 269.510238 -124.600958) (xy 269.518066 -124.541502) (xy 269.533587 -124.483577) (xy 269.556536 -124.428173)
			(xy 269.58652 -124.376239) (xy 269.623026 -124.328663) (xy 269.665431 -124.286258) (xy 269.713007 -124.249752)
			(xy 269.764941 -124.219768) (xy 269.820345 -124.196819) (xy 269.87827 -124.181298) (xy 269.937726 -124.17347)
			(xy 269.997694 -124.17347) (xy 270.05715 -124.181298) (xy 270.115075 -124.196819) (xy 270.170479 -124.219768)
			(xy 270.222413 -124.249752) (xy 270.269989 -124.286258) (xy 270.312394 -124.328663) (xy 270.3489 -124.376239)
			(xy 270.378884 -124.428173) (xy 270.401833 -124.483577) (xy 270.417354 -124.541502) (xy 270.425182 -124.600958)
			(xy 270.425672 -124.630942) (xy 270.425672 -125.486414) (xy 283.9847 -125.486414) (xy 283.9847 -124.622814)
			(xy 283.98519 -124.59283) (xy 283.993018 -124.533374) (xy 284.008539 -124.475449) (xy 284.031488 -124.420045)
			(xy 284.061472 -124.368111) (xy 284.097978 -124.320535) (xy 284.140383 -124.27813) (xy 284.187959 -124.241624)
			(xy 284.239893 -124.21164) (xy 284.295297 -124.188691) (xy 284.353222 -124.17317) (xy 284.412678 -124.165342)
			(xy 284.472646 -124.165342) (xy 284.532102 -124.17317) (xy 284.590027 -124.188691) (xy 284.645431 -124.21164)
			(xy 284.697365 -124.241624) (xy 284.744941 -124.27813) (xy 284.787346 -124.320535) (xy 284.823852 -124.368111)
			(xy 284.853836 -124.420045) (xy 284.876785 -124.475449) (xy 284.892306 -124.533374) (xy 284.900134 -124.59283)
			(xy 284.900624 -124.622814) (xy 284.900624 -124.967238) (xy 296.945304 -124.967238) (xy 296.945304 -124.103638)
			(xy 296.945794 -124.07367) (xy 296.953617 -124.014248) (xy 296.96913 -123.956355) (xy 296.992066 -123.900982)
			(xy 297.022033 -123.849076) (xy 297.05852 -123.801526) (xy 297.1009 -123.759146) (xy 297.14845 -123.722659)
			(xy 297.200356 -123.692692) (xy 297.255729 -123.669756) (xy 297.313622 -123.654243) (xy 297.373044 -123.64642)
			(xy 297.43298 -123.64642) (xy 297.492402 -123.654243) (xy 297.550295 -123.669756) (xy 297.605668 -123.692692)
			(xy 297.657574 -123.722659) (xy 297.705124 -123.759146) (xy 297.747504 -123.801526) (xy 297.783991 -123.849076)
			(xy 297.813958 -123.900982) (xy 297.836894 -123.956355) (xy 297.852407 -124.014248) (xy 297.86023 -124.07367)
			(xy 297.86072 -124.103638) (xy 297.86072 -124.965714) (xy 315.916564 -124.965714) (xy 315.916564 -124.102114)
			(xy 315.917054 -124.072146) (xy 315.924877 -124.012724) (xy 315.94039 -123.954831) (xy 315.963326 -123.899458)
			(xy 315.993293 -123.847552) (xy 316.02978 -123.800002) (xy 316.07216 -123.757622) (xy 316.11971 -123.721135)
			(xy 316.171616 -123.691168) (xy 316.226989 -123.668232) (xy 316.284882 -123.652719) (xy 316.344304 -123.644896)
			(xy 316.40424 -123.644896) (xy 316.463662 -123.652719) (xy 316.521555 -123.668232) (xy 316.568893 -123.68784)
			(xy 382.967992 -123.68784) (xy 382.967992 -122.82424) (xy 382.968482 -122.794272) (xy 382.976305 -122.73485)
			(xy 382.991818 -122.676957) (xy 383.014754 -122.621584) (xy 383.044721 -122.569678) (xy 383.081208 -122.522128)
			(xy 383.123588 -122.479748) (xy 383.171138 -122.443261) (xy 383.223044 -122.413294) (xy 383.278417 -122.390358)
			(xy 383.33631 -122.374845) (xy 383.395732 -122.367022) (xy 383.455668 -122.367022) (xy 383.51509 -122.374845)
			(xy 383.572983 -122.390358) (xy 383.628356 -122.413294) (xy 383.680262 -122.443261) (xy 383.727812 -122.479748)
			(xy 383.770192 -122.522128) (xy 383.806679 -122.569678) (xy 383.836646 -122.621584) (xy 383.859582 -122.676957)
			(xy 383.875095 -122.73485) (xy 383.882918 -122.794272) (xy 383.883408 -122.82424) (xy 383.883408 -123.686316)
			(xy 401.939252 -123.686316) (xy 401.939252 -122.822716) (xy 401.939742 -122.792748) (xy 401.947565 -122.733326)
			(xy 401.963078 -122.675433) (xy 401.986014 -122.62006) (xy 402.015981 -122.568154) (xy 402.052468 -122.520604)
			(xy 402.094848 -122.478224) (xy 402.142398 -122.441737) (xy 402.194304 -122.41177) (xy 402.249677 -122.388834)
			(xy 402.30757 -122.373321) (xy 402.366992 -122.365498) (xy 402.426928 -122.365498) (xy 402.48635 -122.373321)
			(xy 402.544243 -122.388834) (xy 402.599616 -122.41177) (xy 402.651522 -122.441737) (xy 402.699072 -122.478224)
			(xy 402.741452 -122.520604) (xy 402.777939 -122.568154) (xy 402.807906 -122.62006) (xy 402.830842 -122.675433)
			(xy 402.846355 -122.733326) (xy 402.854178 -122.792748) (xy 402.854668 -122.822716) (xy 402.854668 -123.16714)
			(xy 414.899348 -123.16714) (xy 414.899348 -122.30354) (xy 414.899838 -122.273556) (xy 414.907666 -122.2141)
			(xy 414.923187 -122.156175) (xy 414.946136 -122.100771) (xy 414.97612 -122.048837) (xy 415.012626 -122.001261)
			(xy 415.055031 -121.958856) (xy 415.102607 -121.92235) (xy 415.154541 -121.892366) (xy 415.209945 -121.869417)
			(xy 415.26787 -121.853896) (xy 415.327326 -121.846068) (xy 415.387294 -121.846068) (xy 415.44675 -121.853896)
			(xy 415.504675 -121.869417) (xy 415.560079 -121.892366) (xy 415.612013 -121.92235) (xy 415.659589 -121.958856)
			(xy 415.701994 -122.001261) (xy 415.7385 -122.048837) (xy 415.768484 -122.100771) (xy 415.791433 -122.156175)
			(xy 415.806954 -122.2141) (xy 415.814782 -122.273556) (xy 415.815272 -122.30354) (xy 415.815272 -123.159266)
			(xy 429.3743 -123.159266) (xy 429.3743 -122.295666) (xy 429.37479 -122.265682) (xy 429.382618 -122.206226)
			(xy 429.398139 -122.148301) (xy 429.421088 -122.092897) (xy 429.451072 -122.040963) (xy 429.487578 -121.993387)
			(xy 429.529983 -121.950982) (xy 429.577559 -121.914476) (xy 429.629493 -121.884492) (xy 429.684897 -121.861543)
			(xy 429.742822 -121.846022) (xy 429.802278 -121.838194) (xy 429.862246 -121.838194) (xy 429.921702 -121.846022)
			(xy 429.979627 -121.861543) (xy 430.035031 -121.884492) (xy 430.086965 -121.914476) (xy 430.134541 -121.950982)
			(xy 430.176946 -121.993387) (xy 430.213452 -122.040963) (xy 430.243436 -122.092897) (xy 430.266385 -122.148301)
			(xy 430.281906 -122.206226) (xy 430.289734 -122.265682) (xy 430.290224 -122.295666) (xy 430.290224 -123.159266)
			(xy 430.289734 -123.18925) (xy 430.281906 -123.248706) (xy 430.266385 -123.306631) (xy 430.243436 -123.362035)
			(xy 430.213452 -123.413969) (xy 430.176946 -123.461545) (xy 430.134541 -123.50395) (xy 430.086965 -123.540456)
			(xy 430.035031 -123.57044) (xy 429.979627 -123.593389) (xy 429.921702 -123.60891) (xy 429.862246 -123.616738)
			(xy 429.802278 -123.616738) (xy 429.742822 -123.60891) (xy 429.684897 -123.593389) (xy 429.629493 -123.57044)
			(xy 429.577559 -123.540456) (xy 429.529983 -123.50395) (xy 429.487578 -123.461545) (xy 429.451072 -123.413969)
			(xy 429.421088 -123.362035) (xy 429.398139 -123.306631) (xy 429.382618 -123.248706) (xy 429.37479 -123.18925)
			(xy 429.3743 -123.159266) (xy 415.815272 -123.159266) (xy 415.815272 -123.16714) (xy 415.814782 -123.197124)
			(xy 415.806954 -123.25658) (xy 415.791433 -123.314505) (xy 415.768484 -123.369909) (xy 415.7385 -123.421843)
			(xy 415.701994 -123.469419) (xy 415.659589 -123.511824) (xy 415.612013 -123.54833) (xy 415.560079 -123.578314)
			(xy 415.504675 -123.601263) (xy 415.44675 -123.616784) (xy 415.387294 -123.624612) (xy 415.327326 -123.624612)
			(xy 415.26787 -123.616784) (xy 415.209945 -123.601263) (xy 415.154541 -123.578314) (xy 415.102607 -123.54833)
			(xy 415.055031 -123.511824) (xy 415.012626 -123.469419) (xy 414.97612 -123.421843) (xy 414.946136 -123.369909)
			(xy 414.923187 -123.314505) (xy 414.907666 -123.25658) (xy 414.899838 -123.197124) (xy 414.899348 -123.16714)
			(xy 402.854668 -123.16714) (xy 402.854668 -123.686316) (xy 402.854178 -123.716284) (xy 402.846355 -123.775706)
			(xy 402.830842 -123.833599) (xy 402.807906 -123.888972) (xy 402.777939 -123.940878) (xy 402.741452 -123.988428)
			(xy 402.699072 -124.030808) (xy 402.651522 -124.067295) (xy 402.599616 -124.097262) (xy 402.544243 -124.120198)
			(xy 402.48635 -124.135711) (xy 402.426928 -124.143534) (xy 402.366992 -124.143534) (xy 402.30757 -124.135711)
			(xy 402.249677 -124.120198) (xy 402.194304 -124.097262) (xy 402.142398 -124.067295) (xy 402.094848 -124.030808)
			(xy 402.052468 -123.988428) (xy 402.015981 -123.940878) (xy 401.986014 -123.888972) (xy 401.963078 -123.833599)
			(xy 401.947565 -123.775706) (xy 401.939742 -123.716284) (xy 401.939252 -123.686316) (xy 383.883408 -123.686316)
			(xy 383.883408 -123.68784) (xy 383.882918 -123.717808) (xy 383.875095 -123.77723) (xy 383.859582 -123.835123)
			(xy 383.836646 -123.890496) (xy 383.806679 -123.942402) (xy 383.770192 -123.989952) (xy 383.727812 -124.032332)
			(xy 383.680262 -124.068819) (xy 383.628356 -124.098786) (xy 383.572983 -124.121722) (xy 383.51509 -124.137235)
			(xy 383.455668 -124.145058) (xy 383.395732 -124.145058) (xy 383.33631 -124.137235) (xy 383.278417 -124.121722)
			(xy 383.223044 -124.098786) (xy 383.171138 -124.068819) (xy 383.123588 -124.032332) (xy 383.081208 -123.989952)
			(xy 383.044721 -123.942402) (xy 383.014754 -123.890496) (xy 382.991818 -123.835123) (xy 382.976305 -123.77723)
			(xy 382.968482 -123.717808) (xy 382.967992 -123.68784) (xy 316.568893 -123.68784) (xy 316.576928 -123.691168)
			(xy 316.628834 -123.721135) (xy 316.676384 -123.757622) (xy 316.718764 -123.800002) (xy 316.755251 -123.847552)
			(xy 316.785218 -123.899458) (xy 316.808154 -123.954831) (xy 316.823667 -124.012724) (xy 316.83149 -124.072146)
			(xy 316.83198 -124.102114) (xy 316.83198 -124.965714) (xy 316.83149 -124.995682) (xy 316.823667 -125.055104)
			(xy 316.808154 -125.112997) (xy 316.785218 -125.16837) (xy 316.755251 -125.220276) (xy 316.718764 -125.267826)
			(xy 316.676384 -125.310206) (xy 316.628834 -125.346693) (xy 316.576928 -125.37666) (xy 316.521555 -125.399596)
			(xy 316.463662 -125.415109) (xy 316.40424 -125.422932) (xy 316.344304 -125.422932) (xy 316.284882 -125.415109)
			(xy 316.226989 -125.399596) (xy 316.171616 -125.37666) (xy 316.11971 -125.346693) (xy 316.07216 -125.310206)
			(xy 316.02978 -125.267826) (xy 315.993293 -125.220276) (xy 315.963326 -125.16837) (xy 315.94039 -125.112997)
			(xy 315.924877 -125.055104) (xy 315.917054 -124.995682) (xy 315.916564 -124.965714) (xy 297.86072 -124.965714)
			(xy 297.86072 -124.967238) (xy 297.86023 -124.997206) (xy 297.852407 -125.056628) (xy 297.836894 -125.114521)
			(xy 297.813958 -125.169894) (xy 297.783991 -125.2218) (xy 297.747504 -125.26935) (xy 297.705124 -125.31173)
			(xy 297.657574 -125.348217) (xy 297.605668 -125.378184) (xy 297.550295 -125.40112) (xy 297.492402 -125.416633)
			(xy 297.43298 -125.424456) (xy 297.373044 -125.424456) (xy 297.313622 -125.416633) (xy 297.255729 -125.40112)
			(xy 297.200356 -125.378184) (xy 297.14845 -125.348217) (xy 297.1009 -125.31173) (xy 297.05852 -125.26935)
			(xy 297.022033 -125.2218) (xy 296.992066 -125.169894) (xy 296.96913 -125.114521) (xy 296.953617 -125.056628)
			(xy 296.945794 -124.997206) (xy 296.945304 -124.967238) (xy 284.900624 -124.967238) (xy 284.900624 -125.486414)
			(xy 284.900491 -125.494542) (xy 385.6101 -125.494542) (xy 385.6101 -124.630942) (xy 385.61059 -124.600974)
			(xy 385.618413 -124.541552) (xy 385.633926 -124.483659) (xy 385.656862 -124.428286) (xy 385.686829 -124.37638)
			(xy 385.723316 -124.32883) (xy 385.765696 -124.28645) (xy 385.813246 -124.249963) (xy 385.865152 -124.219996)
			(xy 385.920525 -124.19706) (xy 385.978418 -124.181547) (xy 386.03784 -124.173724) (xy 386.097776 -124.173724)
			(xy 386.157198 -124.181547) (xy 386.215091 -124.19706) (xy 386.270464 -124.219996) (xy 386.32237 -124.249963)
			(xy 386.36992 -124.28645) (xy 386.4123 -124.32883) (xy 386.448787 -124.37638) (xy 386.478754 -124.428286)
			(xy 386.50169 -124.483659) (xy 386.517203 -124.541552) (xy 386.525026 -124.600974) (xy 386.525516 -124.630942)
			(xy 386.525516 -125.486414) (xy 400.085052 -125.486414) (xy 400.085052 -124.622814) (xy 400.085542 -124.592846)
			(xy 400.093365 -124.533424) (xy 400.108878 -124.475531) (xy 400.131814 -124.420158) (xy 400.161781 -124.368252)
			(xy 400.198268 -124.320702) (xy 400.240648 -124.278322) (xy 400.288198 -124.241835) (xy 400.340104 -124.211868)
			(xy 400.395477 -124.188932) (xy 400.45337 -124.173419) (xy 400.512792 -124.165596) (xy 400.572728 -124.165596)
			(xy 400.63215 -124.173419) (xy 400.690043 -124.188932) (xy 400.745416 -124.211868) (xy 400.797322 -124.241835)
			(xy 400.844872 -124.278322) (xy 400.887252 -124.320702) (xy 400.923739 -124.368252) (xy 400.953706 -124.420158)
			(xy 400.976642 -124.475531) (xy 400.992155 -124.533424) (xy 400.999978 -124.592846) (xy 401.000468 -124.622814)
			(xy 401.000468 -124.967238) (xy 413.045148 -124.967238) (xy 413.045148 -124.103638) (xy 413.045638 -124.073654)
			(xy 413.053466 -124.014198) (xy 413.068987 -123.956273) (xy 413.091936 -123.900869) (xy 413.12192 -123.848935)
			(xy 413.158426 -123.801359) (xy 413.200831 -123.758954) (xy 413.248407 -123.722448) (xy 413.300341 -123.692464)
			(xy 413.355745 -123.669515) (xy 413.41367 -123.653994) (xy 413.473126 -123.646166) (xy 413.533094 -123.646166)
			(xy 413.59255 -123.653994) (xy 413.650475 -123.669515) (xy 413.705879 -123.692464) (xy 413.757813 -123.722448)
			(xy 413.805389 -123.758954) (xy 413.847794 -123.801359) (xy 413.8843 -123.848935) (xy 413.914284 -123.900869)
			(xy 413.937233 -123.956273) (xy 413.952754 -124.014198) (xy 413.960582 -124.073654) (xy 413.961072 -124.103638)
			(xy 413.961072 -124.965714) (xy 432.016408 -124.965714) (xy 432.016408 -124.102114) (xy 432.016898 -124.07213)
			(xy 432.024726 -124.012674) (xy 432.040247 -123.954749) (xy 432.063196 -123.899345) (xy 432.09318 -123.847411)
			(xy 432.129686 -123.799835) (xy 432.172091 -123.75743) (xy 432.219667 -123.720924) (xy 432.271601 -123.69094)
			(xy 432.327005 -123.667991) (xy 432.38493 -123.65247) (xy 432.444386 -123.644642) (xy 432.504354 -123.644642)
			(xy 432.56381 -123.65247) (xy 432.621735 -123.667991) (xy 432.677139 -123.69094) (xy 432.729073 -123.720924)
			(xy 432.776649 -123.75743) (xy 432.819054 -123.799835) (xy 432.85556 -123.847411) (xy 432.885544 -123.899345)
			(xy 432.908493 -123.954749) (xy 432.924014 -124.012674) (xy 432.931842 -124.07213) (xy 432.932332 -124.102114)
			(xy 432.932332 -124.965714) (xy 432.931842 -124.995698) (xy 432.924014 -125.055154) (xy 432.908493 -125.113079)
			(xy 432.885544 -125.168483) (xy 432.85556 -125.220417) (xy 432.819054 -125.267993) (xy 432.776649 -125.310398)
			(xy 432.729073 -125.346904) (xy 432.677139 -125.376888) (xy 432.621735 -125.399837) (xy 432.56381 -125.415358)
			(xy 432.504354 -125.423186) (xy 432.444386 -125.423186) (xy 432.38493 -125.415358) (xy 432.327005 -125.399837)
			(xy 432.271601 -125.376888) (xy 432.219667 -125.346904) (xy 432.172091 -125.310398) (xy 432.129686 -125.267993)
			(xy 432.09318 -125.220417) (xy 432.063196 -125.168483) (xy 432.040247 -125.113079) (xy 432.024726 -125.055154)
			(xy 432.016898 -124.995698) (xy 432.016408 -124.965714) (xy 413.961072 -124.965714) (xy 413.961072 -124.967238)
			(xy 413.960582 -124.997222) (xy 413.952754 -125.056678) (xy 413.937233 -125.114603) (xy 413.914284 -125.170007)
			(xy 413.8843 -125.221941) (xy 413.847794 -125.269517) (xy 413.805389 -125.311922) (xy 413.757813 -125.348428)
			(xy 413.705879 -125.378412) (xy 413.650475 -125.401361) (xy 413.59255 -125.416882) (xy 413.533094 -125.42471)
			(xy 413.473126 -125.42471) (xy 413.41367 -125.416882) (xy 413.355745 -125.401361) (xy 413.300341 -125.378412)
			(xy 413.248407 -125.348428) (xy 413.200831 -125.311922) (xy 413.158426 -125.269517) (xy 413.12192 -125.221941)
			(xy 413.091936 -125.170007) (xy 413.068987 -125.114603) (xy 413.053466 -125.056678) (xy 413.045638 -124.997222)
			(xy 413.045148 -124.967238) (xy 401.000468 -124.967238) (xy 401.000468 -125.486414) (xy 400.999978 -125.516382)
			(xy 400.992155 -125.575804) (xy 400.976642 -125.633697) (xy 400.953706 -125.68907) (xy 400.923739 -125.740976)
			(xy 400.887252 -125.788526) (xy 400.844872 -125.830906) (xy 400.797322 -125.867393) (xy 400.745416 -125.89736)
			(xy 400.690043 -125.920296) (xy 400.63215 -125.935809) (xy 400.572728 -125.943632) (xy 400.512792 -125.943632)
			(xy 400.45337 -125.935809) (xy 400.395477 -125.920296) (xy 400.340104 -125.89736) (xy 400.288198 -125.867393)
			(xy 400.240648 -125.830906) (xy 400.198268 -125.788526) (xy 400.161781 -125.740976) (xy 400.131814 -125.68907)
			(xy 400.108878 -125.633697) (xy 400.093365 -125.575804) (xy 400.085542 -125.516382) (xy 400.085052 -125.486414)
			(xy 386.525516 -125.486414) (xy 386.525516 -125.494542) (xy 386.525026 -125.52451) (xy 386.517203 -125.583932)
			(xy 386.50169 -125.641825) (xy 386.478754 -125.697198) (xy 386.448787 -125.749104) (xy 386.4123 -125.796654)
			(xy 386.36992 -125.839034) (xy 386.32237 -125.875521) (xy 386.270464 -125.905488) (xy 386.215091 -125.928424)
			(xy 386.157198 -125.943937) (xy 386.097776 -125.95176) (xy 386.03784 -125.95176) (xy 385.978418 -125.943937)
			(xy 385.920525 -125.928424) (xy 385.865152 -125.905488) (xy 385.813246 -125.875521) (xy 385.765696 -125.839034)
			(xy 385.723316 -125.796654) (xy 385.686829 -125.749104) (xy 385.656862 -125.697198) (xy 385.633926 -125.641825)
			(xy 385.618413 -125.583932) (xy 385.61059 -125.52451) (xy 385.6101 -125.494542) (xy 284.900491 -125.494542)
			(xy 284.900134 -125.516398) (xy 284.892306 -125.575854) (xy 284.876785 -125.633779) (xy 284.853836 -125.689183)
			(xy 284.823852 -125.741117) (xy 284.787346 -125.788693) (xy 284.744941 -125.831098) (xy 284.697365 -125.867604)
			(xy 284.645431 -125.897588) (xy 284.590027 -125.920537) (xy 284.532102 -125.936058) (xy 284.472646 -125.943886)
			(xy 284.412678 -125.943886) (xy 284.353222 -125.936058) (xy 284.295297 -125.920537) (xy 284.239893 -125.897588)
			(xy 284.187959 -125.867604) (xy 284.140383 -125.831098) (xy 284.097978 -125.788693) (xy 284.061472 -125.741117)
			(xy 284.031488 -125.689183) (xy 284.008539 -125.633779) (xy 283.993018 -125.575854) (xy 283.98519 -125.516398)
			(xy 283.9847 -125.486414) (xy 270.425672 -125.486414) (xy 270.425672 -125.494542) (xy 270.425182 -125.524526)
			(xy 270.417354 -125.583982) (xy 270.401833 -125.641907) (xy 270.378884 -125.697311) (xy 270.3489 -125.749245)
			(xy 270.312394 -125.796821) (xy 270.269989 -125.839226) (xy 270.222413 -125.875732) (xy 270.170479 -125.905716)
			(xy 270.115075 -125.928665) (xy 270.05715 -125.944186) (xy 269.997694 -125.952014) (xy 269.937726 -125.952014)
			(xy 269.87827 -125.944186) (xy 269.820345 -125.928665) (xy 269.764941 -125.905716) (xy 269.713007 -125.875732)
			(xy 269.665431 -125.839226) (xy 269.623026 -125.796821) (xy 269.58652 -125.749245) (xy 269.556536 -125.697311)
			(xy 269.533587 -125.641907) (xy 269.518066 -125.583982) (xy 269.510238 -125.524526) (xy 269.509748 -125.494542)
			(xy 168.800647 -125.494542) (xy 168.80029 -125.516398) (xy 168.792462 -125.575854) (xy 168.776941 -125.633779)
			(xy 168.753992 -125.689183) (xy 168.724008 -125.741117) (xy 168.687502 -125.788693) (xy 168.645097 -125.831098)
			(xy 168.597521 -125.867604) (xy 168.545587 -125.897588) (xy 168.490183 -125.920537) (xy 168.432258 -125.936058)
			(xy 168.372802 -125.943886) (xy 168.312834 -125.943886) (xy 168.253378 -125.936058) (xy 168.195453 -125.920537)
			(xy 168.140049 -125.897588) (xy 168.088115 -125.867604) (xy 168.040539 -125.831098) (xy 167.998134 -125.788693)
			(xy 167.961628 -125.741117) (xy 167.931644 -125.689183) (xy 167.908695 -125.633779) (xy 167.893174 -125.575854)
			(xy 167.885346 -125.516398) (xy 167.884856 -125.486414) (xy 154.325828 -125.486414) (xy 154.325828 -125.494542)
			(xy 154.325338 -125.524526) (xy 154.31751 -125.583982) (xy 154.301989 -125.641907) (xy 154.27904 -125.697311)
			(xy 154.249056 -125.749245) (xy 154.21255 -125.796821) (xy 154.170145 -125.839226) (xy 154.122569 -125.875732)
			(xy 154.070635 -125.905716) (xy 154.015231 -125.928665) (xy 153.957306 -125.944186) (xy 153.89785 -125.952014)
			(xy 153.837882 -125.952014) (xy 153.778426 -125.944186) (xy 153.720501 -125.928665) (xy 153.665097 -125.905716)
			(xy 153.613163 -125.875732) (xy 153.565587 -125.839226) (xy 153.523182 -125.796821) (xy 153.486676 -125.749245)
			(xy 153.456692 -125.697311) (xy 153.433743 -125.641907) (xy 153.418222 -125.583982) (xy 153.410394 -125.524526)
			(xy 153.409904 -125.494542) (xy 52.700295 -125.494542) (xy 52.699938 -125.516382) (xy 52.692115 -125.575804)
			(xy 52.676602 -125.633697) (xy 52.653666 -125.68907) (xy 52.623699 -125.740976) (xy 52.587212 -125.788526)
			(xy 52.544832 -125.830906) (xy 52.497282 -125.867393) (xy 52.445376 -125.89736) (xy 52.390003 -125.920296)
			(xy 52.33211 -125.935809) (xy 52.272688 -125.943632) (xy 52.212752 -125.943632) (xy 52.15333 -125.935809)
			(xy 52.095437 -125.920296) (xy 52.040064 -125.89736) (xy 51.988158 -125.867393) (xy 51.940608 -125.830906)
			(xy 51.898228 -125.788526) (xy 51.861741 -125.740976) (xy 51.831774 -125.68907) (xy 51.808838 -125.633697)
			(xy 51.793325 -125.575804) (xy 51.785502 -125.516382) (xy 51.785012 -125.486414) (xy 38.225476 -125.486414)
			(xy 38.225476 -125.494542) (xy 38.224986 -125.52451) (xy 38.217163 -125.583932) (xy 38.20165 -125.641825)
			(xy 38.178714 -125.697198) (xy 38.148747 -125.749104) (xy 38.11226 -125.796654) (xy 38.06988 -125.839034)
			(xy 38.02233 -125.875521) (xy 37.970424 -125.905488) (xy 37.915051 -125.928424) (xy 37.857158 -125.943937)
			(xy 37.797736 -125.95176) (xy 37.7378 -125.95176) (xy 37.678378 -125.943937) (xy 37.620485 -125.928424)
			(xy 37.565112 -125.905488) (xy 37.513206 -125.875521) (xy 37.465656 -125.839034) (xy 37.423276 -125.796654)
			(xy 37.386789 -125.749104) (xy 37.356822 -125.697198) (xy 37.333886 -125.641825) (xy 37.318373 -125.583932)
			(xy 37.31055 -125.52451) (xy 37.31006 -125.494542) (xy 5.324094 -125.494542) (xy 5.324094 -131.297934)
			(xy 34.667952 -131.297934) (xy 34.667952 -130.434334) (xy 34.668442 -130.404366) (xy 34.676265 -130.344944)
			(xy 34.691778 -130.287051) (xy 34.714714 -130.231678) (xy 34.744681 -130.179772) (xy 34.781168 -130.132222)
			(xy 34.823548 -130.089842) (xy 34.871098 -130.053355) (xy 34.923004 -130.023388) (xy 34.978377 -130.000452)
			(xy 35.03627 -129.984939) (xy 35.095692 -129.977116) (xy 35.155628 -129.977116) (xy 35.21505 -129.984939)
			(xy 35.272943 -130.000452) (xy 35.328316 -130.023388) (xy 35.380222 -130.053355) (xy 35.427772 -130.089842)
			(xy 35.470152 -130.132222) (xy 35.506639 -130.179772) (xy 35.536606 -130.231678) (xy 35.559542 -130.287051)
			(xy 35.575055 -130.344944) (xy 35.582878 -130.404366) (xy 35.583368 -130.434334) (xy 35.583368 -131.29641)
			(xy 53.639212 -131.29641) (xy 53.639212 -130.43281) (xy 53.639702 -130.402842) (xy 53.647525 -130.34342)
			(xy 53.663038 -130.285527) (xy 53.685974 -130.230154) (xy 53.715941 -130.178248) (xy 53.752428 -130.130698)
			(xy 53.794808 -130.088318) (xy 53.842358 -130.051831) (xy 53.894264 -130.021864) (xy 53.949637 -129.998928)
			(xy 54.00753 -129.983415) (xy 54.066952 -129.975592) (xy 54.126888 -129.975592) (xy 54.18631 -129.983415)
			(xy 54.244203 -129.998928) (xy 54.299576 -130.021864) (xy 54.351482 -130.051831) (xy 54.399032 -130.088318)
			(xy 54.441412 -130.130698) (xy 54.477899 -130.178248) (xy 54.507866 -130.230154) (xy 54.530802 -130.285527)
			(xy 54.546315 -130.34342) (xy 54.554138 -130.402842) (xy 54.554628 -130.43281) (xy 54.554628 -130.777234)
			(xy 66.599308 -130.777234) (xy 66.599308 -129.913634) (xy 66.599798 -129.88365) (xy 66.607626 -129.824194)
			(xy 66.623147 -129.766269) (xy 66.646096 -129.710865) (xy 66.67608 -129.658931) (xy 66.712586 -129.611355)
			(xy 66.754991 -129.56895) (xy 66.802567 -129.532444) (xy 66.854501 -129.50246) (xy 66.909905 -129.479511)
			(xy 66.96783 -129.46399) (xy 67.027286 -129.456162) (xy 67.087254 -129.456162) (xy 67.14671 -129.46399)
			(xy 67.204635 -129.479511) (xy 67.260039 -129.50246) (xy 67.311973 -129.532444) (xy 67.359549 -129.56895)
			(xy 67.401954 -129.611355) (xy 67.43846 -129.658931) (xy 67.468444 -129.710865) (xy 67.491393 -129.766269)
			(xy 67.506914 -129.824194) (xy 67.514742 -129.88365) (xy 67.515232 -129.913634) (xy 67.515232 -130.769106)
			(xy 81.07426 -130.769106) (xy 81.07426 -129.905506) (xy 81.07475 -129.875522) (xy 81.082578 -129.816066)
			(xy 81.098099 -129.758141) (xy 81.121048 -129.702737) (xy 81.151032 -129.650803) (xy 81.187538 -129.603227)
			(xy 81.229943 -129.560822) (xy 81.277519 -129.524316) (xy 81.329453 -129.494332) (xy 81.384857 -129.471383)
			(xy 81.442782 -129.455862) (xy 81.502238 -129.448034) (xy 81.562206 -129.448034) (xy 81.621662 -129.455862)
			(xy 81.679587 -129.471383) (xy 81.734991 -129.494332) (xy 81.786925 -129.524316) (xy 81.834501 -129.560822)
			(xy 81.876906 -129.603227) (xy 81.913412 -129.650803) (xy 81.943396 -129.702737) (xy 81.966345 -129.758141)
			(xy 81.981866 -129.816066) (xy 81.989694 -129.875522) (xy 81.990184 -129.905506) (xy 81.990184 -130.769106)
			(xy 81.989694 -130.79909) (xy 81.981866 -130.858546) (xy 81.966345 -130.916471) (xy 81.943396 -130.971875)
			(xy 81.913412 -131.023809) (xy 81.876906 -131.071385) (xy 81.834501 -131.11379) (xy 81.786925 -131.150296)
			(xy 81.734991 -131.18028) (xy 81.679587 -131.203229) (xy 81.621662 -131.21875) (xy 81.562206 -131.226578)
			(xy 81.502238 -131.226578) (xy 81.442782 -131.21875) (xy 81.384857 -131.203229) (xy 81.329453 -131.18028)
			(xy 81.277519 -131.150296) (xy 81.229943 -131.11379) (xy 81.187538 -131.071385) (xy 81.151032 -131.023809)
			(xy 81.121048 -130.971875) (xy 81.098099 -130.916471) (xy 81.082578 -130.858546) (xy 81.07475 -130.79909)
			(xy 81.07426 -130.769106) (xy 67.515232 -130.769106) (xy 67.515232 -130.777234) (xy 67.514742 -130.807218)
			(xy 67.506914 -130.866674) (xy 67.491393 -130.924599) (xy 67.468444 -130.980003) (xy 67.43846 -131.031937)
			(xy 67.401954 -131.079513) (xy 67.359549 -131.121918) (xy 67.311973 -131.158424) (xy 67.260039 -131.188408)
			(xy 67.204635 -131.211357) (xy 67.14671 -131.226878) (xy 67.087254 -131.234706) (xy 67.027286 -131.234706)
			(xy 66.96783 -131.226878) (xy 66.909905 -131.211357) (xy 66.854501 -131.188408) (xy 66.802567 -131.158424)
			(xy 66.754991 -131.121918) (xy 66.712586 -131.079513) (xy 66.67608 -131.031937) (xy 66.646096 -130.980003)
			(xy 66.623147 -130.924599) (xy 66.607626 -130.866674) (xy 66.599798 -130.807218) (xy 66.599308 -130.777234)
			(xy 54.554628 -130.777234) (xy 54.554628 -131.29641) (xy 54.554138 -131.326378) (xy 54.546315 -131.3858)
			(xy 54.530802 -131.443693) (xy 54.507866 -131.499066) (xy 54.477899 -131.550972) (xy 54.441412 -131.598522)
			(xy 54.399032 -131.640902) (xy 54.351482 -131.677389) (xy 54.299576 -131.707356) (xy 54.244203 -131.730292)
			(xy 54.18631 -131.745805) (xy 54.126888 -131.753628) (xy 54.066952 -131.753628) (xy 54.00753 -131.745805)
			(xy 53.949637 -131.730292) (xy 53.894264 -131.707356) (xy 53.842358 -131.677389) (xy 53.794808 -131.640902)
			(xy 53.752428 -131.598522) (xy 53.715941 -131.550972) (xy 53.685974 -131.499066) (xy 53.663038 -131.443693)
			(xy 53.647525 -131.3858) (xy 53.639702 -131.326378) (xy 53.639212 -131.29641) (xy 35.583368 -131.29641)
			(xy 35.583368 -131.297934) (xy 35.582878 -131.327902) (xy 35.575055 -131.387324) (xy 35.559542 -131.445217)
			(xy 35.536606 -131.50059) (xy 35.506639 -131.552496) (xy 35.470152 -131.600046) (xy 35.427772 -131.642426)
			(xy 35.380222 -131.678913) (xy 35.328316 -131.70888) (xy 35.272943 -131.731816) (xy 35.21505 -131.747329)
			(xy 35.155628 -131.755152) (xy 35.095692 -131.755152) (xy 35.03627 -131.747329) (xy 34.978377 -131.731816)
			(xy 34.923004 -131.70888) (xy 34.871098 -131.678913) (xy 34.823548 -131.642426) (xy 34.781168 -131.600046)
			(xy 34.744681 -131.552496) (xy 34.714714 -131.50059) (xy 34.691778 -131.445217) (xy 34.676265 -131.387324)
			(xy 34.668442 -131.327902) (xy 34.667952 -131.297934) (xy 5.324094 -131.297934) (xy 5.324094 -133.104382)
			(xy 37.31006 -133.104382) (xy 37.31006 -132.240782) (xy 37.31055 -132.210814) (xy 37.318373 -132.151392)
			(xy 37.333886 -132.093499) (xy 37.356822 -132.038126) (xy 37.386789 -131.98622) (xy 37.423276 -131.93867)
			(xy 37.465656 -131.89629) (xy 37.513206 -131.859803) (xy 37.565112 -131.829836) (xy 37.620485 -131.8069)
			(xy 37.678378 -131.791387) (xy 37.7378 -131.783564) (xy 37.797736 -131.783564) (xy 37.857158 -131.791387)
			(xy 37.915051 -131.8069) (xy 37.970424 -131.829836) (xy 38.02233 -131.859803) (xy 38.06988 -131.89629)
			(xy 38.11226 -131.93867) (xy 38.148747 -131.98622) (xy 38.178714 -132.038126) (xy 38.20165 -132.093499)
			(xy 38.217163 -132.151392) (xy 38.224986 -132.210814) (xy 38.225476 -132.240782) (xy 38.225476 -133.096508)
			(xy 51.785012 -133.096508) (xy 51.785012 -132.232908) (xy 51.785502 -132.20294) (xy 51.793325 -132.143518)
			(xy 51.808838 -132.085625) (xy 51.831774 -132.030252) (xy 51.861741 -131.978346) (xy 51.898228 -131.930796)
			(xy 51.940608 -131.888416) (xy 51.988158 -131.851929) (xy 52.040064 -131.821962) (xy 52.095437 -131.799026)
			(xy 52.15333 -131.783513) (xy 52.212752 -131.77569) (xy 52.272688 -131.77569) (xy 52.33211 -131.783513)
			(xy 52.390003 -131.799026) (xy 52.445376 -131.821962) (xy 52.497282 -131.851929) (xy 52.544832 -131.888416)
			(xy 52.587212 -131.930796) (xy 52.623699 -131.978346) (xy 52.653666 -132.030252) (xy 52.676602 -132.085625)
			(xy 52.692115 -132.143518) (xy 52.699938 -132.20294) (xy 52.700428 -132.232908) (xy 52.700428 -132.577332)
			(xy 64.745108 -132.577332) (xy 64.745108 -131.713732) (xy 64.745598 -131.683748) (xy 64.753426 -131.624292)
			(xy 64.768947 -131.566367) (xy 64.791896 -131.510963) (xy 64.82188 -131.459029) (xy 64.858386 -131.411453)
			(xy 64.900791 -131.369048) (xy 64.948367 -131.332542) (xy 65.000301 -131.302558) (xy 65.055705 -131.279609)
			(xy 65.11363 -131.264088) (xy 65.173086 -131.25626) (xy 65.233054 -131.25626) (xy 65.29251 -131.264088)
			(xy 65.350435 -131.279609) (xy 65.405839 -131.302558) (xy 65.457773 -131.332542) (xy 65.505349 -131.369048)
			(xy 65.547754 -131.411453) (xy 65.58426 -131.459029) (xy 65.614244 -131.510963) (xy 65.637193 -131.566367)
			(xy 65.652714 -131.624292) (xy 65.660542 -131.683748) (xy 65.661032 -131.713732) (xy 65.661032 -132.575808)
			(xy 83.716368 -132.575808) (xy 83.716368 -131.712208) (xy 83.716858 -131.682224) (xy 83.724686 -131.622768)
			(xy 83.740207 -131.564843) (xy 83.763156 -131.509439) (xy 83.79314 -131.457505) (xy 83.829646 -131.409929)
			(xy 83.872051 -131.367524) (xy 83.919627 -131.331018) (xy 83.971561 -131.301034) (xy 84.026965 -131.278085)
			(xy 84.08489 -131.262564) (xy 84.144346 -131.254736) (xy 84.204314 -131.254736) (xy 84.26377 -131.262564)
			(xy 84.321695 -131.278085) (xy 84.369615 -131.297934) (xy 150.767796 -131.297934) (xy 150.767796 -130.434334)
			(xy 150.768286 -130.40435) (xy 150.776114 -130.344894) (xy 150.791635 -130.286969) (xy 150.814584 -130.231565)
			(xy 150.844568 -130.179631) (xy 150.881074 -130.132055) (xy 150.923479 -130.08965) (xy 150.971055 -130.053144)
			(xy 151.022989 -130.02316) (xy 151.078393 -130.000211) (xy 151.136318 -129.98469) (xy 151.195774 -129.976862)
			(xy 151.255742 -129.976862) (xy 151.315198 -129.98469) (xy 151.373123 -130.000211) (xy 151.428527 -130.02316)
			(xy 151.480461 -130.053144) (xy 151.528037 -130.08965) (xy 151.570442 -130.132055) (xy 151.606948 -130.179631)
			(xy 151.636932 -130.231565) (xy 151.659881 -130.286969) (xy 151.675402 -130.344894) (xy 151.68323 -130.40435)
			(xy 151.68372 -130.434334) (xy 151.68372 -131.29641) (xy 169.739056 -131.29641) (xy 169.739056 -130.43281)
			(xy 169.739546 -130.402826) (xy 169.747374 -130.34337) (xy 169.762895 -130.285445) (xy 169.785844 -130.230041)
			(xy 169.815828 -130.178107) (xy 169.852334 -130.130531) (xy 169.894739 -130.088126) (xy 169.942315 -130.05162)
			(xy 169.994249 -130.021636) (xy 170.049653 -129.998687) (xy 170.107578 -129.983166) (xy 170.167034 -129.975338)
			(xy 170.227002 -129.975338) (xy 170.286458 -129.983166) (xy 170.344383 -129.998687) (xy 170.399787 -130.021636)
			(xy 170.451721 -130.05162) (xy 170.499297 -130.088126) (xy 170.541702 -130.130531) (xy 170.578208 -130.178107)
			(xy 170.608192 -130.230041) (xy 170.631141 -130.285445) (xy 170.646662 -130.34337) (xy 170.65449 -130.402826)
			(xy 170.65498 -130.43281) (xy 170.65498 -130.777234) (xy 182.69966 -130.777234) (xy 182.69966 -129.913634)
			(xy 182.70015 -129.883666) (xy 182.707973 -129.824244) (xy 182.723486 -129.766351) (xy 182.746422 -129.710978)
			(xy 182.776389 -129.659072) (xy 182.812876 -129.611522) (xy 182.855256 -129.569142) (xy 182.902806 -129.532655)
			(xy 182.954712 -129.502688) (xy 183.010085 -129.479752) (xy 183.067978 -129.464239) (xy 183.1274 -129.456416)
			(xy 183.187336 -129.456416) (xy 183.246758 -129.464239) (xy 183.304651 -129.479752) (xy 183.360024 -129.502688)
			(xy 183.41193 -129.532655) (xy 183.45948 -129.569142) (xy 183.50186 -129.611522) (xy 183.538347 -129.659072)
			(xy 183.568314 -129.710978) (xy 183.59125 -129.766351) (xy 183.606763 -129.824244) (xy 183.614586 -129.883666)
			(xy 183.615076 -129.913634) (xy 183.615076 -130.769106) (xy 197.174612 -130.769106) (xy 197.174612 -129.905506)
			(xy 197.175102 -129.875538) (xy 197.182925 -129.816116) (xy 197.198438 -129.758223) (xy 197.221374 -129.70285)
			(xy 197.251341 -129.650944) (xy 197.287828 -129.603394) (xy 197.330208 -129.561014) (xy 197.377758 -129.524527)
			(xy 197.429664 -129.49456) (xy 197.485037 -129.471624) (xy 197.54293 -129.456111) (xy 197.602352 -129.448288)
			(xy 197.662288 -129.448288) (xy 197.72171 -129.456111) (xy 197.779603 -129.471624) (xy 197.834976 -129.49456)
			(xy 197.886882 -129.524527) (xy 197.934432 -129.561014) (xy 197.976812 -129.603394) (xy 198.013299 -129.650944)
			(xy 198.043266 -129.70285) (xy 198.066202 -129.758223) (xy 198.081715 -129.816116) (xy 198.089538 -129.875538)
			(xy 198.090028 -129.905506) (xy 198.090028 -130.769106) (xy 198.089538 -130.799074) (xy 198.081715 -130.858496)
			(xy 198.066202 -130.916389) (xy 198.043266 -130.971762) (xy 198.013299 -131.023668) (xy 197.976812 -131.071218)
			(xy 197.934432 -131.113598) (xy 197.886882 -131.150085) (xy 197.834976 -131.180052) (xy 197.779603 -131.202988)
			(xy 197.72171 -131.218501) (xy 197.662288 -131.226324) (xy 197.602352 -131.226324) (xy 197.54293 -131.218501)
			(xy 197.485037 -131.202988) (xy 197.429664 -131.180052) (xy 197.377758 -131.150085) (xy 197.330208 -131.113598)
			(xy 197.287828 -131.071218) (xy 197.251341 -131.023668) (xy 197.221374 -130.971762) (xy 197.198438 -130.916389)
			(xy 197.182925 -130.858496) (xy 197.175102 -130.799074) (xy 197.174612 -130.769106) (xy 183.615076 -130.769106)
			(xy 183.615076 -130.777234) (xy 183.614586 -130.807202) (xy 183.606763 -130.866624) (xy 183.59125 -130.924517)
			(xy 183.568314 -130.97989) (xy 183.538347 -131.031796) (xy 183.50186 -131.079346) (xy 183.45948 -131.121726)
			(xy 183.41193 -131.158213) (xy 183.360024 -131.18818) (xy 183.304651 -131.211116) (xy 183.246758 -131.226629)
			(xy 183.187336 -131.234452) (xy 183.1274 -131.234452) (xy 183.067978 -131.226629) (xy 183.010085 -131.211116)
			(xy 182.954712 -131.18818) (xy 182.902806 -131.158213) (xy 182.855256 -131.121726) (xy 182.812876 -131.079346)
			(xy 182.776389 -131.031796) (xy 182.746422 -130.97989) (xy 182.723486 -130.924517) (xy 182.707973 -130.866624)
			(xy 182.70015 -130.807202) (xy 182.69966 -130.777234) (xy 170.65498 -130.777234) (xy 170.65498 -131.29641)
			(xy 170.65449 -131.326394) (xy 170.646662 -131.38585) (xy 170.631141 -131.443775) (xy 170.608192 -131.499179)
			(xy 170.578208 -131.551113) (xy 170.541702 -131.598689) (xy 170.499297 -131.641094) (xy 170.451721 -131.6776)
			(xy 170.399787 -131.707584) (xy 170.344383 -131.730533) (xy 170.286458 -131.746054) (xy 170.227002 -131.753882)
			(xy 170.167034 -131.753882) (xy 170.107578 -131.746054) (xy 170.049653 -131.730533) (xy 169.994249 -131.707584)
			(xy 169.942315 -131.6776) (xy 169.894739 -131.641094) (xy 169.852334 -131.598689) (xy 169.815828 -131.551113)
			(xy 169.785844 -131.499179) (xy 169.762895 -131.443775) (xy 169.747374 -131.38585) (xy 169.739546 -131.326394)
			(xy 169.739056 -131.29641) (xy 151.68372 -131.29641) (xy 151.68372 -131.297934) (xy 151.68323 -131.327918)
			(xy 151.675402 -131.387374) (xy 151.659881 -131.445299) (xy 151.636932 -131.500703) (xy 151.606948 -131.552637)
			(xy 151.570442 -131.600213) (xy 151.528037 -131.642618) (xy 151.480461 -131.679124) (xy 151.428527 -131.709108)
			(xy 151.373123 -131.732057) (xy 151.315198 -131.747578) (xy 151.255742 -131.755406) (xy 151.195774 -131.755406)
			(xy 151.136318 -131.747578) (xy 151.078393 -131.732057) (xy 151.022989 -131.709108) (xy 150.971055 -131.679124)
			(xy 150.923479 -131.642618) (xy 150.881074 -131.600213) (xy 150.844568 -131.552637) (xy 150.814584 -131.500703)
			(xy 150.791635 -131.445299) (xy 150.776114 -131.387374) (xy 150.768286 -131.327918) (xy 150.767796 -131.297934)
			(xy 84.369615 -131.297934) (xy 84.377099 -131.301034) (xy 84.429033 -131.331018) (xy 84.476609 -131.367524)
			(xy 84.519014 -131.409929) (xy 84.55552 -131.457505) (xy 84.585504 -131.509439) (xy 84.608453 -131.564843)
			(xy 84.623974 -131.622768) (xy 84.631802 -131.682224) (xy 84.632292 -131.712208) (xy 84.632292 -132.575808)
			(xy 84.631802 -132.605792) (xy 84.623974 -132.665248) (xy 84.608453 -132.723173) (xy 84.585504 -132.778577)
			(xy 84.55552 -132.830511) (xy 84.519014 -132.878087) (xy 84.476609 -132.920492) (xy 84.429033 -132.956998)
			(xy 84.377099 -132.986982) (xy 84.321695 -133.009931) (xy 84.26377 -133.025452) (xy 84.204314 -133.03328)
			(xy 84.144346 -133.03328) (xy 84.08489 -133.025452) (xy 84.026965 -133.009931) (xy 83.971561 -132.986982)
			(xy 83.919627 -132.956998) (xy 83.872051 -132.920492) (xy 83.829646 -132.878087) (xy 83.79314 -132.830511)
			(xy 83.763156 -132.778577) (xy 83.740207 -132.723173) (xy 83.724686 -132.665248) (xy 83.716858 -132.605792)
			(xy 83.716368 -132.575808) (xy 65.661032 -132.575808) (xy 65.661032 -132.577332) (xy 65.660542 -132.607316)
			(xy 65.652714 -132.666772) (xy 65.637193 -132.724697) (xy 65.614244 -132.780101) (xy 65.58426 -132.832035)
			(xy 65.547754 -132.879611) (xy 65.505349 -132.922016) (xy 65.457773 -132.958522) (xy 65.405839 -132.988506)
			(xy 65.350435 -133.011455) (xy 65.29251 -133.026976) (xy 65.233054 -133.034804) (xy 65.173086 -133.034804)
			(xy 65.11363 -133.026976) (xy 65.055705 -133.011455) (xy 65.000301 -132.988506) (xy 64.948367 -132.958522)
			(xy 64.900791 -132.922016) (xy 64.858386 -132.879611) (xy 64.82188 -132.832035) (xy 64.791896 -132.780101)
			(xy 64.768947 -132.724697) (xy 64.753426 -132.666772) (xy 64.745598 -132.607316) (xy 64.745108 -132.577332)
			(xy 52.700428 -132.577332) (xy 52.700428 -133.096508) (xy 52.699938 -133.126476) (xy 52.692115 -133.185898)
			(xy 52.676602 -133.243791) (xy 52.653666 -133.299164) (xy 52.623699 -133.35107) (xy 52.587212 -133.39862)
			(xy 52.544832 -133.441) (xy 52.497282 -133.477487) (xy 52.445376 -133.507454) (xy 52.390003 -133.53039)
			(xy 52.33211 -133.545903) (xy 52.272688 -133.553726) (xy 52.212752 -133.553726) (xy 52.15333 -133.545903)
			(xy 52.095437 -133.53039) (xy 52.040064 -133.507454) (xy 51.988158 -133.477487) (xy 51.940608 -133.441)
			(xy 51.898228 -133.39862) (xy 51.861741 -133.35107) (xy 51.831774 -133.299164) (xy 51.808838 -133.243791)
			(xy 51.793325 -133.185898) (xy 51.785502 -133.126476) (xy 51.785012 -133.096508) (xy 38.225476 -133.096508)
			(xy 38.225476 -133.104382) (xy 38.224986 -133.13435) (xy 38.217163 -133.193772) (xy 38.20165 -133.251665)
			(xy 38.178714 -133.307038) (xy 38.148747 -133.358944) (xy 38.11226 -133.406494) (xy 38.06988 -133.448874)
			(xy 38.02233 -133.485361) (xy 37.970424 -133.515328) (xy 37.915051 -133.538264) (xy 37.857158 -133.553777)
			(xy 37.797736 -133.5616) (xy 37.7378 -133.5616) (xy 37.678378 -133.553777) (xy 37.620485 -133.538264)
			(xy 37.565112 -133.515328) (xy 37.513206 -133.485361) (xy 37.465656 -133.448874) (xy 37.423276 -133.406494)
			(xy 37.386789 -133.358944) (xy 37.356822 -133.307038) (xy 37.333886 -133.251665) (xy 37.318373 -133.193772)
			(xy 37.31055 -133.13435) (xy 37.31006 -133.104382) (xy 5.324094 -133.104382) (xy 5.324094 -134.897876)
			(xy 34.667952 -134.897876) (xy 34.667952 -134.034276) (xy 34.668442 -134.004308) (xy 34.676265 -133.944886)
			(xy 34.691778 -133.886993) (xy 34.714714 -133.83162) (xy 34.744681 -133.779714) (xy 34.781168 -133.732164)
			(xy 34.823548 -133.689784) (xy 34.871098 -133.653297) (xy 34.923004 -133.62333) (xy 34.978377 -133.600394)
			(xy 35.03627 -133.584881) (xy 35.095692 -133.577058) (xy 35.155628 -133.577058) (xy 35.21505 -133.584881)
			(xy 35.272943 -133.600394) (xy 35.328316 -133.62333) (xy 35.380222 -133.653297) (xy 35.427772 -133.689784)
			(xy 35.470152 -133.732164) (xy 35.506639 -133.779714) (xy 35.536606 -133.83162) (xy 35.559542 -133.886993)
			(xy 35.575055 -133.944886) (xy 35.582878 -134.004308) (xy 35.583368 -134.034276) (xy 35.583368 -134.896352)
			(xy 53.639212 -134.896352) (xy 53.639212 -134.032752) (xy 53.639702 -134.002784) (xy 53.647525 -133.943362)
			(xy 53.663038 -133.885469) (xy 53.685974 -133.830096) (xy 53.715941 -133.77819) (xy 53.752428 -133.73064)
			(xy 53.794808 -133.68826) (xy 53.842358 -133.651773) (xy 53.894264 -133.621806) (xy 53.949637 -133.59887)
			(xy 54.00753 -133.583357) (xy 54.066952 -133.575534) (xy 54.126888 -133.575534) (xy 54.18631 -133.583357)
			(xy 54.244203 -133.59887) (xy 54.299576 -133.621806) (xy 54.351482 -133.651773) (xy 54.399032 -133.68826)
			(xy 54.441412 -133.73064) (xy 54.477899 -133.77819) (xy 54.507866 -133.830096) (xy 54.530802 -133.885469)
			(xy 54.546315 -133.943362) (xy 54.554138 -134.002784) (xy 54.554628 -134.032752) (xy 54.554628 -134.377176)
			(xy 66.599308 -134.377176) (xy 66.599308 -133.513576) (xy 66.599798 -133.483592) (xy 66.607626 -133.424136)
			(xy 66.623147 -133.366211) (xy 66.646096 -133.310807) (xy 66.67608 -133.258873) (xy 66.712586 -133.211297)
			(xy 66.754991 -133.168892) (xy 66.802567 -133.132386) (xy 66.854501 -133.102402) (xy 66.909905 -133.079453)
			(xy 66.96783 -133.063932) (xy 67.027286 -133.056104) (xy 67.087254 -133.056104) (xy 67.14671 -133.063932)
			(xy 67.204635 -133.079453) (xy 67.260039 -133.102402) (xy 67.311973 -133.132386) (xy 67.359549 -133.168892)
			(xy 67.401954 -133.211297) (xy 67.43846 -133.258873) (xy 67.468444 -133.310807) (xy 67.491393 -133.366211)
			(xy 67.506914 -133.424136) (xy 67.514742 -133.483592) (xy 67.515232 -133.513576) (xy 67.515232 -134.369302)
			(xy 81.07426 -134.369302) (xy 81.07426 -133.505702) (xy 81.07475 -133.475718) (xy 81.082578 -133.416262)
			(xy 81.098099 -133.358337) (xy 81.121048 -133.302933) (xy 81.151032 -133.250999) (xy 81.187538 -133.203423)
			(xy 81.229943 -133.161018) (xy 81.277519 -133.124512) (xy 81.329453 -133.094528) (xy 81.384857 -133.071579)
			(xy 81.442782 -133.056058) (xy 81.502238 -133.04823) (xy 81.562206 -133.04823) (xy 81.621662 -133.056058)
			(xy 81.679587 -133.071579) (xy 81.734991 -133.094528) (xy 81.752059 -133.104382) (xy 153.409904 -133.104382)
			(xy 153.409904 -132.240782) (xy 153.410394 -132.210798) (xy 153.418222 -132.151342) (xy 153.433743 -132.093417)
			(xy 153.456692 -132.038013) (xy 153.486676 -131.986079) (xy 153.523182 -131.938503) (xy 153.565587 -131.896098)
			(xy 153.613163 -131.859592) (xy 153.665097 -131.829608) (xy 153.720501 -131.806659) (xy 153.778426 -131.791138)
			(xy 153.837882 -131.78331) (xy 153.89785 -131.78331) (xy 153.957306 -131.791138) (xy 154.015231 -131.806659)
			(xy 154.070635 -131.829608) (xy 154.122569 -131.859592) (xy 154.170145 -131.896098) (xy 154.21255 -131.938503)
			(xy 154.249056 -131.986079) (xy 154.27904 -132.038013) (xy 154.301989 -132.093417) (xy 154.31751 -132.151342)
			(xy 154.325338 -132.210798) (xy 154.325828 -132.240782) (xy 154.325828 -133.096508) (xy 167.884856 -133.096508)
			(xy 167.884856 -132.232908) (xy 167.885346 -132.202924) (xy 167.893174 -132.143468) (xy 167.908695 -132.085543)
			(xy 167.931644 -132.030139) (xy 167.961628 -131.978205) (xy 167.998134 -131.930629) (xy 168.040539 -131.888224)
			(xy 168.088115 -131.851718) (xy 168.140049 -131.821734) (xy 168.195453 -131.798785) (xy 168.253378 -131.783264)
			(xy 168.312834 -131.775436) (xy 168.372802 -131.775436) (xy 168.432258 -131.783264) (xy 168.490183 -131.798785)
			(xy 168.545587 -131.821734) (xy 168.597521 -131.851718) (xy 168.645097 -131.888224) (xy 168.687502 -131.930629)
			(xy 168.724008 -131.978205) (xy 168.753992 -132.030139) (xy 168.776941 -132.085543) (xy 168.792462 -132.143468)
			(xy 168.80029 -132.202924) (xy 168.80078 -132.232908) (xy 168.80078 -132.577332) (xy 180.84546 -132.577332)
			(xy 180.84546 -131.713732) (xy 180.84595 -131.683764) (xy 180.853773 -131.624342) (xy 180.869286 -131.566449)
			(xy 180.892222 -131.511076) (xy 180.922189 -131.45917) (xy 180.958676 -131.41162) (xy 181.001056 -131.36924)
			(xy 181.048606 -131.332753) (xy 181.100512 -131.302786) (xy 181.155885 -131.27985) (xy 181.213778 -131.264337)
			(xy 181.2732 -131.256514) (xy 181.333136 -131.256514) (xy 181.392558 -131.264337) (xy 181.450451 -131.27985)
			(xy 181.505824 -131.302786) (xy 181.55773 -131.332753) (xy 181.60528 -131.36924) (xy 181.64766 -131.41162)
			(xy 181.684147 -131.45917) (xy 181.714114 -131.511076) (xy 181.73705 -131.566449) (xy 181.752563 -131.624342)
			(xy 181.760386 -131.683764) (xy 181.760876 -131.713732) (xy 181.760876 -132.575808) (xy 199.81672 -132.575808)
			(xy 199.81672 -131.712208) (xy 199.81721 -131.68224) (xy 199.825033 -131.622818) (xy 199.840546 -131.564925)
			(xy 199.863482 -131.509552) (xy 199.893449 -131.457646) (xy 199.929936 -131.410096) (xy 199.972316 -131.367716)
			(xy 200.019866 -131.331229) (xy 200.071772 -131.301262) (xy 200.127145 -131.278326) (xy 200.185038 -131.262813)
			(xy 200.24446 -131.25499) (xy 200.304396 -131.25499) (xy 200.363818 -131.262813) (xy 200.421711 -131.278326)
			(xy 200.469049 -131.297934) (xy 266.86764 -131.297934) (xy 266.86764 -130.434334) (xy 266.86813 -130.40435)
			(xy 266.875958 -130.344894) (xy 266.891479 -130.286969) (xy 266.914428 -130.231565) (xy 266.944412 -130.179631)
			(xy 266.980918 -130.132055) (xy 267.023323 -130.08965) (xy 267.070899 -130.053144) (xy 267.122833 -130.02316)
			(xy 267.178237 -130.000211) (xy 267.236162 -129.98469) (xy 267.295618 -129.976862) (xy 267.355586 -129.976862)
			(xy 267.415042 -129.98469) (xy 267.472967 -130.000211) (xy 267.528371 -130.02316) (xy 267.580305 -130.053144)
			(xy 267.627881 -130.08965) (xy 267.670286 -130.132055) (xy 267.706792 -130.179631) (xy 267.736776 -130.231565)
			(xy 267.759725 -130.286969) (xy 267.775246 -130.344894) (xy 267.783074 -130.40435) (xy 267.783564 -130.434334)
			(xy 267.783564 -131.29641) (xy 285.8389 -131.29641) (xy 285.8389 -130.43281) (xy 285.83939 -130.402826)
			(xy 285.847218 -130.34337) (xy 285.862739 -130.285445) (xy 285.885688 -130.230041) (xy 285.915672 -130.178107)
			(xy 285.952178 -130.130531) (xy 285.994583 -130.088126) (xy 286.042159 -130.05162) (xy 286.094093 -130.021636)
			(xy 286.149497 -129.998687) (xy 286.207422 -129.983166) (xy 286.266878 -129.975338) (xy 286.326846 -129.975338)
			(xy 286.386302 -129.983166) (xy 286.444227 -129.998687) (xy 286.499631 -130.021636) (xy 286.551565 -130.05162)
			(xy 286.599141 -130.088126) (xy 286.641546 -130.130531) (xy 286.678052 -130.178107) (xy 286.708036 -130.230041)
			(xy 286.730985 -130.285445) (xy 286.746506 -130.34337) (xy 286.754334 -130.402826) (xy 286.754824 -130.43281)
			(xy 286.754824 -130.777234) (xy 298.799504 -130.777234) (xy 298.799504 -129.913634) (xy 298.799994 -129.883666)
			(xy 298.807817 -129.824244) (xy 298.82333 -129.766351) (xy 298.846266 -129.710978) (xy 298.876233 -129.659072)
			(xy 298.91272 -129.611522) (xy 298.9551 -129.569142) (xy 299.00265 -129.532655) (xy 299.054556 -129.502688)
			(xy 299.109929 -129.479752) (xy 299.167822 -129.464239) (xy 299.227244 -129.456416) (xy 299.28718 -129.456416)
			(xy 299.346602 -129.464239) (xy 299.404495 -129.479752) (xy 299.459868 -129.502688) (xy 299.511774 -129.532655)
			(xy 299.559324 -129.569142) (xy 299.601704 -129.611522) (xy 299.638191 -129.659072) (xy 299.668158 -129.710978)
			(xy 299.691094 -129.766351) (xy 299.706607 -129.824244) (xy 299.71443 -129.883666) (xy 299.71492 -129.913634)
			(xy 299.71492 -130.769106) (xy 313.274456 -130.769106) (xy 313.274456 -129.905506) (xy 313.274946 -129.875538)
			(xy 313.282769 -129.816116) (xy 313.298282 -129.758223) (xy 313.321218 -129.70285) (xy 313.351185 -129.650944)
			(xy 313.387672 -129.603394) (xy 313.430052 -129.561014) (xy 313.477602 -129.524527) (xy 313.529508 -129.49456)
			(xy 313.584881 -129.471624) (xy 313.642774 -129.456111) (xy 313.702196 -129.448288) (xy 313.762132 -129.448288)
			(xy 313.821554 -129.456111) (xy 313.879447 -129.471624) (xy 313.93482 -129.49456) (xy 313.986726 -129.524527)
			(xy 314.034276 -129.561014) (xy 314.076656 -129.603394) (xy 314.113143 -129.650944) (xy 314.14311 -129.70285)
			(xy 314.166046 -129.758223) (xy 314.181559 -129.816116) (xy 314.189382 -129.875538) (xy 314.189872 -129.905506)
			(xy 314.189872 -130.769106) (xy 314.189382 -130.799074) (xy 314.181559 -130.858496) (xy 314.166046 -130.916389)
			(xy 314.14311 -130.971762) (xy 314.113143 -131.023668) (xy 314.076656 -131.071218) (xy 314.034276 -131.113598)
			(xy 313.986726 -131.150085) (xy 313.93482 -131.180052) (xy 313.879447 -131.202988) (xy 313.821554 -131.218501)
			(xy 313.762132 -131.226324) (xy 313.702196 -131.226324) (xy 313.642774 -131.218501) (xy 313.584881 -131.202988)
			(xy 313.529508 -131.180052) (xy 313.477602 -131.150085) (xy 313.430052 -131.113598) (xy 313.387672 -131.071218)
			(xy 313.351185 -131.023668) (xy 313.321218 -130.971762) (xy 313.298282 -130.916389) (xy 313.282769 -130.858496)
			(xy 313.274946 -130.799074) (xy 313.274456 -130.769106) (xy 299.71492 -130.769106) (xy 299.71492 -130.777234)
			(xy 299.71443 -130.807202) (xy 299.706607 -130.866624) (xy 299.691094 -130.924517) (xy 299.668158 -130.97989)
			(xy 299.638191 -131.031796) (xy 299.601704 -131.079346) (xy 299.559324 -131.121726) (xy 299.511774 -131.158213)
			(xy 299.459868 -131.18818) (xy 299.404495 -131.211116) (xy 299.346602 -131.226629) (xy 299.28718 -131.234452)
			(xy 299.227244 -131.234452) (xy 299.167822 -131.226629) (xy 299.109929 -131.211116) (xy 299.054556 -131.18818)
			(xy 299.00265 -131.158213) (xy 298.9551 -131.121726) (xy 298.91272 -131.079346) (xy 298.876233 -131.031796)
			(xy 298.846266 -130.97989) (xy 298.82333 -130.924517) (xy 298.807817 -130.866624) (xy 298.799994 -130.807202)
			(xy 298.799504 -130.777234) (xy 286.754824 -130.777234) (xy 286.754824 -131.29641) (xy 286.754334 -131.326394)
			(xy 286.746506 -131.38585) (xy 286.730985 -131.443775) (xy 286.708036 -131.499179) (xy 286.678052 -131.551113)
			(xy 286.641546 -131.598689) (xy 286.599141 -131.641094) (xy 286.551565 -131.6776) (xy 286.499631 -131.707584)
			(xy 286.444227 -131.730533) (xy 286.386302 -131.746054) (xy 286.326846 -131.753882) (xy 286.266878 -131.753882)
			(xy 286.207422 -131.746054) (xy 286.149497 -131.730533) (xy 286.094093 -131.707584) (xy 286.042159 -131.6776)
			(xy 285.994583 -131.641094) (xy 285.952178 -131.598689) (xy 285.915672 -131.551113) (xy 285.885688 -131.499179)
			(xy 285.862739 -131.443775) (xy 285.847218 -131.38585) (xy 285.83939 -131.326394) (xy 285.8389 -131.29641)
			(xy 267.783564 -131.29641) (xy 267.783564 -131.297934) (xy 267.783074 -131.327918) (xy 267.775246 -131.387374)
			(xy 267.759725 -131.445299) (xy 267.736776 -131.500703) (xy 267.706792 -131.552637) (xy 267.670286 -131.600213)
			(xy 267.627881 -131.642618) (xy 267.580305 -131.679124) (xy 267.528371 -131.709108) (xy 267.472967 -131.732057)
			(xy 267.415042 -131.747578) (xy 267.355586 -131.755406) (xy 267.295618 -131.755406) (xy 267.236162 -131.747578)
			(xy 267.178237 -131.732057) (xy 267.122833 -131.709108) (xy 267.070899 -131.679124) (xy 267.023323 -131.642618)
			(xy 266.980918 -131.600213) (xy 266.944412 -131.552637) (xy 266.914428 -131.500703) (xy 266.891479 -131.445299)
			(xy 266.875958 -131.387374) (xy 266.86813 -131.327918) (xy 266.86764 -131.297934) (xy 200.469049 -131.297934)
			(xy 200.477084 -131.301262) (xy 200.52899 -131.331229) (xy 200.57654 -131.367716) (xy 200.61892 -131.410096)
			(xy 200.655407 -131.457646) (xy 200.685374 -131.509552) (xy 200.70831 -131.564925) (xy 200.723823 -131.622818)
			(xy 200.731646 -131.68224) (xy 200.732136 -131.712208) (xy 200.732136 -132.575808) (xy 200.731646 -132.605776)
			(xy 200.723823 -132.665198) (xy 200.70831 -132.723091) (xy 200.685374 -132.778464) (xy 200.655407 -132.83037)
			(xy 200.61892 -132.87792) (xy 200.57654 -132.9203) (xy 200.52899 -132.956787) (xy 200.477084 -132.986754)
			(xy 200.421711 -133.00969) (xy 200.363818 -133.025203) (xy 200.304396 -133.033026) (xy 200.24446 -133.033026)
			(xy 200.185038 -133.025203) (xy 200.127145 -133.00969) (xy 200.071772 -132.986754) (xy 200.019866 -132.956787)
			(xy 199.972316 -132.9203) (xy 199.929936 -132.87792) (xy 199.893449 -132.83037) (xy 199.863482 -132.778464)
			(xy 199.840546 -132.723091) (xy 199.825033 -132.665198) (xy 199.81721 -132.605776) (xy 199.81672 -132.575808)
			(xy 181.760876 -132.575808) (xy 181.760876 -132.577332) (xy 181.760386 -132.6073) (xy 181.752563 -132.666722)
			(xy 181.73705 -132.724615) (xy 181.714114 -132.779988) (xy 181.684147 -132.831894) (xy 181.64766 -132.879444)
			(xy 181.60528 -132.921824) (xy 181.55773 -132.958311) (xy 181.505824 -132.988278) (xy 181.450451 -133.011214)
			(xy 181.392558 -133.026727) (xy 181.333136 -133.03455) (xy 181.2732 -133.03455) (xy 181.213778 -133.026727)
			(xy 181.155885 -133.011214) (xy 181.100512 -132.988278) (xy 181.048606 -132.958311) (xy 181.001056 -132.921824)
			(xy 180.958676 -132.879444) (xy 180.922189 -132.831894) (xy 180.892222 -132.779988) (xy 180.869286 -132.724615)
			(xy 180.853773 -132.666722) (xy 180.84595 -132.6073) (xy 180.84546 -132.577332) (xy 168.80078 -132.577332)
			(xy 168.80078 -133.096508) (xy 168.80029 -133.126492) (xy 168.792462 -133.185948) (xy 168.776941 -133.243873)
			(xy 168.753992 -133.299277) (xy 168.724008 -133.351211) (xy 168.687502 -133.398787) (xy 168.645097 -133.441192)
			(xy 168.597521 -133.477698) (xy 168.545587 -133.507682) (xy 168.490183 -133.530631) (xy 168.432258 -133.546152)
			(xy 168.372802 -133.55398) (xy 168.312834 -133.55398) (xy 168.253378 -133.546152) (xy 168.195453 -133.530631)
			(xy 168.140049 -133.507682) (xy 168.088115 -133.477698) (xy 168.040539 -133.441192) (xy 167.998134 -133.398787)
			(xy 167.961628 -133.351211) (xy 167.931644 -133.299277) (xy 167.908695 -133.243873) (xy 167.893174 -133.185948)
			(xy 167.885346 -133.126492) (xy 167.884856 -133.096508) (xy 154.325828 -133.096508) (xy 154.325828 -133.104382)
			(xy 154.325338 -133.134366) (xy 154.31751 -133.193822) (xy 154.301989 -133.251747) (xy 154.27904 -133.307151)
			(xy 154.249056 -133.359085) (xy 154.21255 -133.406661) (xy 154.170145 -133.449066) (xy 154.122569 -133.485572)
			(xy 154.070635 -133.515556) (xy 154.015231 -133.538505) (xy 153.957306 -133.554026) (xy 153.89785 -133.561854)
			(xy 153.837882 -133.561854) (xy 153.778426 -133.554026) (xy 153.720501 -133.538505) (xy 153.665097 -133.515556)
			(xy 153.613163 -133.485572) (xy 153.565587 -133.449066) (xy 153.523182 -133.406661) (xy 153.486676 -133.359085)
			(xy 153.456692 -133.307151) (xy 153.433743 -133.251747) (xy 153.418222 -133.193822) (xy 153.410394 -133.134366)
			(xy 153.409904 -133.104382) (xy 81.752059 -133.104382) (xy 81.786925 -133.124512) (xy 81.834501 -133.161018)
			(xy 81.876906 -133.203423) (xy 81.913412 -133.250999) (xy 81.943396 -133.302933) (xy 81.966345 -133.358337)
			(xy 81.981866 -133.416262) (xy 81.989694 -133.475718) (xy 81.990184 -133.505702) (xy 81.990184 -134.369302)
			(xy 81.989694 -134.399286) (xy 81.981866 -134.458742) (xy 81.966345 -134.516667) (xy 81.943396 -134.572071)
			(xy 81.913412 -134.624005) (xy 81.876906 -134.671581) (xy 81.834501 -134.713986) (xy 81.786925 -134.750492)
			(xy 81.734991 -134.780476) (xy 81.679587 -134.803425) (xy 81.621662 -134.818946) (xy 81.562206 -134.826774)
			(xy 81.502238 -134.826774) (xy 81.442782 -134.818946) (xy 81.384857 -134.803425) (xy 81.329453 -134.780476)
			(xy 81.277519 -134.750492) (xy 81.229943 -134.713986) (xy 81.187538 -134.671581) (xy 81.151032 -134.624005)
			(xy 81.121048 -134.572071) (xy 81.098099 -134.516667) (xy 81.082578 -134.458742) (xy 81.07475 -134.399286)
			(xy 81.07426 -134.369302) (xy 67.515232 -134.369302) (xy 67.515232 -134.377176) (xy 67.514742 -134.40716)
			(xy 67.506914 -134.466616) (xy 67.491393 -134.524541) (xy 67.468444 -134.579945) (xy 67.43846 -134.631879)
			(xy 67.401954 -134.679455) (xy 67.359549 -134.72186) (xy 67.311973 -134.758366) (xy 67.260039 -134.78835)
			(xy 67.204635 -134.811299) (xy 67.14671 -134.82682) (xy 67.087254 -134.834648) (xy 67.027286 -134.834648)
			(xy 66.96783 -134.82682) (xy 66.909905 -134.811299) (xy 66.854501 -134.78835) (xy 66.802567 -134.758366)
			(xy 66.754991 -134.72186) (xy 66.712586 -134.679455) (xy 66.67608 -134.631879) (xy 66.646096 -134.579945)
			(xy 66.623147 -134.524541) (xy 66.607626 -134.466616) (xy 66.599798 -134.40716) (xy 66.599308 -134.377176)
			(xy 54.554628 -134.377176) (xy 54.554628 -134.896352) (xy 54.554138 -134.92632) (xy 54.546315 -134.985742)
			(xy 54.530802 -135.043635) (xy 54.507866 -135.099008) (xy 54.477899 -135.150914) (xy 54.441412 -135.198464)
			(xy 54.399032 -135.240844) (xy 54.351482 -135.277331) (xy 54.299576 -135.307298) (xy 54.244203 -135.330234)
			(xy 54.18631 -135.345747) (xy 54.126888 -135.35357) (xy 54.066952 -135.35357) (xy 54.00753 -135.345747)
			(xy 53.949637 -135.330234) (xy 53.894264 -135.307298) (xy 53.842358 -135.277331) (xy 53.794808 -135.240844)
			(xy 53.752428 -135.198464) (xy 53.715941 -135.150914) (xy 53.685974 -135.099008) (xy 53.663038 -135.043635)
			(xy 53.647525 -134.985742) (xy 53.639702 -134.92632) (xy 53.639212 -134.896352) (xy 35.583368 -134.896352)
			(xy 35.583368 -134.897876) (xy 35.582878 -134.927844) (xy 35.575055 -134.987266) (xy 35.559542 -135.045159)
			(xy 35.536606 -135.100532) (xy 35.506639 -135.152438) (xy 35.470152 -135.199988) (xy 35.427772 -135.242368)
			(xy 35.380222 -135.278855) (xy 35.328316 -135.308822) (xy 35.272943 -135.331758) (xy 35.21505 -135.347271)
			(xy 35.155628 -135.355094) (xy 35.095692 -135.355094) (xy 35.03627 -135.347271) (xy 34.978377 -135.331758)
			(xy 34.923004 -135.308822) (xy 34.871098 -135.278855) (xy 34.823548 -135.242368) (xy 34.781168 -135.199988)
			(xy 34.744681 -135.152438) (xy 34.714714 -135.100532) (xy 34.691778 -135.045159) (xy 34.676265 -134.987266)
			(xy 34.668442 -134.927844) (xy 34.667952 -134.897876) (xy 5.324094 -134.897876) (xy 5.324094 -136.704324)
			(xy 37.31006 -136.704324) (xy 37.31006 -135.840724) (xy 37.31055 -135.810756) (xy 37.318373 -135.751334)
			(xy 37.333886 -135.693441) (xy 37.356822 -135.638068) (xy 37.386789 -135.586162) (xy 37.423276 -135.538612)
			(xy 37.465656 -135.496232) (xy 37.513206 -135.459745) (xy 37.565112 -135.429778) (xy 37.620485 -135.406842)
			(xy 37.678378 -135.391329) (xy 37.7378 -135.383506) (xy 37.797736 -135.383506) (xy 37.857158 -135.391329)
			(xy 37.915051 -135.406842) (xy 37.970424 -135.429778) (xy 38.02233 -135.459745) (xy 38.06988 -135.496232)
			(xy 38.11226 -135.538612) (xy 38.148747 -135.586162) (xy 38.178714 -135.638068) (xy 38.20165 -135.693441)
			(xy 38.217163 -135.751334) (xy 38.224986 -135.810756) (xy 38.225476 -135.840724) (xy 38.225476 -136.69645)
			(xy 51.785012 -136.69645) (xy 51.785012 -135.83285) (xy 51.785502 -135.802882) (xy 51.793325 -135.74346)
			(xy 51.808838 -135.685567) (xy 51.831774 -135.630194) (xy 51.861741 -135.578288) (xy 51.898228 -135.530738)
			(xy 51.940608 -135.488358) (xy 51.988158 -135.451871) (xy 52.040064 -135.421904) (xy 52.095437 -135.398968)
			(xy 52.15333 -135.383455) (xy 52.212752 -135.375632) (xy 52.272688 -135.375632) (xy 52.33211 -135.383455)
			(xy 52.390003 -135.398968) (xy 52.445376 -135.421904) (xy 52.497282 -135.451871) (xy 52.544832 -135.488358)
			(xy 52.587212 -135.530738) (xy 52.623699 -135.578288) (xy 52.653666 -135.630194) (xy 52.676602 -135.685567)
			(xy 52.692115 -135.74346) (xy 52.699938 -135.802882) (xy 52.700428 -135.83285) (xy 52.700428 -136.177274)
			(xy 64.745108 -136.177274) (xy 64.745108 -135.313674) (xy 64.745598 -135.28369) (xy 64.753426 -135.224234)
			(xy 64.768947 -135.166309) (xy 64.791896 -135.110905) (xy 64.82188 -135.058971) (xy 64.858386 -135.011395)
			(xy 64.900791 -134.96899) (xy 64.948367 -134.932484) (xy 65.000301 -134.9025) (xy 65.055705 -134.879551)
			(xy 65.11363 -134.86403) (xy 65.173086 -134.856202) (xy 65.233054 -134.856202) (xy 65.29251 -134.86403)
			(xy 65.350435 -134.879551) (xy 65.405839 -134.9025) (xy 65.457773 -134.932484) (xy 65.505349 -134.96899)
			(xy 65.547754 -135.011395) (xy 65.58426 -135.058971) (xy 65.614244 -135.110905) (xy 65.637193 -135.166309)
			(xy 65.652714 -135.224234) (xy 65.660542 -135.28369) (xy 65.661032 -135.313674) (xy 65.661032 -136.17575)
			(xy 83.716368 -136.17575) (xy 83.716368 -135.31215) (xy 83.716858 -135.282166) (xy 83.724686 -135.22271)
			(xy 83.740207 -135.164785) (xy 83.763156 -135.109381) (xy 83.79314 -135.057447) (xy 83.829646 -135.009871)
			(xy 83.872051 -134.967466) (xy 83.919627 -134.93096) (xy 83.971561 -134.900976) (xy 84.026965 -134.878027)
			(xy 84.08489 -134.862506) (xy 84.144346 -134.854678) (xy 84.204314 -134.854678) (xy 84.26377 -134.862506)
			(xy 84.321695 -134.878027) (xy 84.369615 -134.897876) (xy 150.767796 -134.897876) (xy 150.767796 -134.034276)
			(xy 150.768286 -134.004292) (xy 150.776114 -133.944836) (xy 150.791635 -133.886911) (xy 150.814584 -133.831507)
			(xy 150.844568 -133.779573) (xy 150.881074 -133.731997) (xy 150.923479 -133.689592) (xy 150.971055 -133.653086)
			(xy 151.022989 -133.623102) (xy 151.078393 -133.600153) (xy 151.136318 -133.584632) (xy 151.195774 -133.576804)
			(xy 151.255742 -133.576804) (xy 151.315198 -133.584632) (xy 151.373123 -133.600153) (xy 151.428527 -133.623102)
			(xy 151.480461 -133.653086) (xy 151.528037 -133.689592) (xy 151.570442 -133.731997) (xy 151.606948 -133.779573)
			(xy 151.636932 -133.831507) (xy 151.659881 -133.886911) (xy 151.675402 -133.944836) (xy 151.68323 -134.004292)
			(xy 151.68372 -134.034276) (xy 151.68372 -134.896352) (xy 169.739056 -134.896352) (xy 169.739056 -134.032752)
			(xy 169.739546 -134.002768) (xy 169.747374 -133.943312) (xy 169.762895 -133.885387) (xy 169.785844 -133.829983)
			(xy 169.815828 -133.778049) (xy 169.852334 -133.730473) (xy 169.894739 -133.688068) (xy 169.942315 -133.651562)
			(xy 169.994249 -133.621578) (xy 170.049653 -133.598629) (xy 170.107578 -133.583108) (xy 170.167034 -133.57528)
			(xy 170.227002 -133.57528) (xy 170.286458 -133.583108) (xy 170.344383 -133.598629) (xy 170.399787 -133.621578)
			(xy 170.451721 -133.651562) (xy 170.499297 -133.688068) (xy 170.541702 -133.730473) (xy 170.578208 -133.778049)
			(xy 170.608192 -133.829983) (xy 170.631141 -133.885387) (xy 170.646662 -133.943312) (xy 170.65449 -134.002768)
			(xy 170.65498 -134.032752) (xy 170.65498 -134.377176) (xy 182.69966 -134.377176) (xy 182.69966 -133.513576)
			(xy 182.70015 -133.483608) (xy 182.707973 -133.424186) (xy 182.723486 -133.366293) (xy 182.746422 -133.31092)
			(xy 182.776389 -133.259014) (xy 182.812876 -133.211464) (xy 182.855256 -133.169084) (xy 182.902806 -133.132597)
			(xy 182.954712 -133.10263) (xy 183.010085 -133.079694) (xy 183.067978 -133.064181) (xy 183.1274 -133.056358)
			(xy 183.187336 -133.056358) (xy 183.246758 -133.064181) (xy 183.304651 -133.079694) (xy 183.360024 -133.10263)
			(xy 183.41193 -133.132597) (xy 183.45948 -133.169084) (xy 183.50186 -133.211464) (xy 183.538347 -133.259014)
			(xy 183.568314 -133.31092) (xy 183.59125 -133.366293) (xy 183.606763 -133.424186) (xy 183.614586 -133.483608)
			(xy 183.615076 -133.513576) (xy 183.615076 -134.369302) (xy 197.174612 -134.369302) (xy 197.174612 -133.505702)
			(xy 197.175102 -133.475734) (xy 197.182925 -133.416312) (xy 197.198438 -133.358419) (xy 197.221374 -133.303046)
			(xy 197.251341 -133.25114) (xy 197.287828 -133.20359) (xy 197.330208 -133.16121) (xy 197.377758 -133.124723)
			(xy 197.429664 -133.094756) (xy 197.485037 -133.07182) (xy 197.54293 -133.056307) (xy 197.602352 -133.048484)
			(xy 197.662288 -133.048484) (xy 197.72171 -133.056307) (xy 197.779603 -133.07182) (xy 197.834976 -133.094756)
			(xy 197.851649 -133.104382) (xy 269.509748 -133.104382) (xy 269.509748 -132.240782) (xy 269.510238 -132.210798)
			(xy 269.518066 -132.151342) (xy 269.533587 -132.093417) (xy 269.556536 -132.038013) (xy 269.58652 -131.986079)
			(xy 269.623026 -131.938503) (xy 269.665431 -131.896098) (xy 269.713007 -131.859592) (xy 269.764941 -131.829608)
			(xy 269.820345 -131.806659) (xy 269.87827 -131.791138) (xy 269.937726 -131.78331) (xy 269.997694 -131.78331)
			(xy 270.05715 -131.791138) (xy 270.115075 -131.806659) (xy 270.170479 -131.829608) (xy 270.222413 -131.859592)
			(xy 270.269989 -131.896098) (xy 270.312394 -131.938503) (xy 270.3489 -131.986079) (xy 270.378884 -132.038013)
			(xy 270.401833 -132.093417) (xy 270.417354 -132.151342) (xy 270.425182 -132.210798) (xy 270.425672 -132.240782)
			(xy 270.425672 -133.096508) (xy 283.9847 -133.096508) (xy 283.9847 -132.232908) (xy 283.98519 -132.202924)
			(xy 283.993018 -132.143468) (xy 284.008539 -132.085543) (xy 284.031488 -132.030139) (xy 284.061472 -131.978205)
			(xy 284.097978 -131.930629) (xy 284.140383 -131.888224) (xy 284.187959 -131.851718) (xy 284.239893 -131.821734)
			(xy 284.295297 -131.798785) (xy 284.353222 -131.783264) (xy 284.412678 -131.775436) (xy 284.472646 -131.775436)
			(xy 284.532102 -131.783264) (xy 284.590027 -131.798785) (xy 284.645431 -131.821734) (xy 284.697365 -131.851718)
			(xy 284.744941 -131.888224) (xy 284.787346 -131.930629) (xy 284.823852 -131.978205) (xy 284.853836 -132.030139)
			(xy 284.876785 -132.085543) (xy 284.892306 -132.143468) (xy 284.900134 -132.202924) (xy 284.900624 -132.232908)
			(xy 284.900624 -132.577332) (xy 296.945304 -132.577332) (xy 296.945304 -131.713732) (xy 296.945794 -131.683764)
			(xy 296.953617 -131.624342) (xy 296.96913 -131.566449) (xy 296.992066 -131.511076) (xy 297.022033 -131.45917)
			(xy 297.05852 -131.41162) (xy 297.1009 -131.36924) (xy 297.14845 -131.332753) (xy 297.200356 -131.302786)
			(xy 297.255729 -131.27985) (xy 297.313622 -131.264337) (xy 297.373044 -131.256514) (xy 297.43298 -131.256514)
			(xy 297.492402 -131.264337) (xy 297.550295 -131.27985) (xy 297.605668 -131.302786) (xy 297.657574 -131.332753)
			(xy 297.705124 -131.36924) (xy 297.747504 -131.41162) (xy 297.783991 -131.45917) (xy 297.813958 -131.511076)
			(xy 297.836894 -131.566449) (xy 297.852407 -131.624342) (xy 297.86023 -131.683764) (xy 297.86072 -131.713732)
			(xy 297.86072 -132.575808) (xy 315.916564 -132.575808) (xy 315.916564 -131.712208) (xy 315.917054 -131.68224)
			(xy 315.924877 -131.622818) (xy 315.94039 -131.564925) (xy 315.963326 -131.509552) (xy 315.993293 -131.457646)
			(xy 316.02978 -131.410096) (xy 316.07216 -131.367716) (xy 316.11971 -131.331229) (xy 316.171616 -131.301262)
			(xy 316.226989 -131.278326) (xy 316.284882 -131.262813) (xy 316.344304 -131.25499) (xy 316.40424 -131.25499)
			(xy 316.463662 -131.262813) (xy 316.521555 -131.278326) (xy 316.568893 -131.297934) (xy 382.967992 -131.297934)
			(xy 382.967992 -130.434334) (xy 382.968482 -130.404366) (xy 382.976305 -130.344944) (xy 382.991818 -130.287051)
			(xy 383.014754 -130.231678) (xy 383.044721 -130.179772) (xy 383.081208 -130.132222) (xy 383.123588 -130.089842)
			(xy 383.171138 -130.053355) (xy 383.223044 -130.023388) (xy 383.278417 -130.000452) (xy 383.33631 -129.984939)
			(xy 383.395732 -129.977116) (xy 383.455668 -129.977116) (xy 383.51509 -129.984939) (xy 383.572983 -130.000452)
			(xy 383.628356 -130.023388) (xy 383.680262 -130.053355) (xy 383.727812 -130.089842) (xy 383.770192 -130.132222)
			(xy 383.806679 -130.179772) (xy 383.836646 -130.231678) (xy 383.859582 -130.287051) (xy 383.875095 -130.344944)
			(xy 383.882918 -130.404366) (xy 383.883408 -130.434334) (xy 383.883408 -131.29641) (xy 401.939252 -131.29641)
			(xy 401.939252 -130.43281) (xy 401.939742 -130.402842) (xy 401.947565 -130.34342) (xy 401.963078 -130.285527)
			(xy 401.986014 -130.230154) (xy 402.015981 -130.178248) (xy 402.052468 -130.130698) (xy 402.094848 -130.088318)
			(xy 402.142398 -130.051831) (xy 402.194304 -130.021864) (xy 402.249677 -129.998928) (xy 402.30757 -129.983415)
			(xy 402.366992 -129.975592) (xy 402.426928 -129.975592) (xy 402.48635 -129.983415) (xy 402.544243 -129.998928)
			(xy 402.599616 -130.021864) (xy 402.651522 -130.051831) (xy 402.699072 -130.088318) (xy 402.741452 -130.130698)
			(xy 402.777939 -130.178248) (xy 402.807906 -130.230154) (xy 402.830842 -130.285527) (xy 402.846355 -130.34342)
			(xy 402.854178 -130.402842) (xy 402.854668 -130.43281) (xy 402.854668 -130.777234) (xy 414.899348 -130.777234)
			(xy 414.899348 -129.913634) (xy 414.899838 -129.88365) (xy 414.907666 -129.824194) (xy 414.923187 -129.766269)
			(xy 414.946136 -129.710865) (xy 414.97612 -129.658931) (xy 415.012626 -129.611355) (xy 415.055031 -129.56895)
			(xy 415.102607 -129.532444) (xy 415.154541 -129.50246) (xy 415.209945 -129.479511) (xy 415.26787 -129.46399)
			(xy 415.327326 -129.456162) (xy 415.387294 -129.456162) (xy 415.44675 -129.46399) (xy 415.504675 -129.479511)
			(xy 415.560079 -129.50246) (xy 415.612013 -129.532444) (xy 415.659589 -129.56895) (xy 415.701994 -129.611355)
			(xy 415.7385 -129.658931) (xy 415.768484 -129.710865) (xy 415.791433 -129.766269) (xy 415.806954 -129.824194)
			(xy 415.814782 -129.88365) (xy 415.815272 -129.913634) (xy 415.815272 -130.769106) (xy 429.3743 -130.769106)
			(xy 429.3743 -129.905506) (xy 429.37479 -129.875522) (xy 429.382618 -129.816066) (xy 429.398139 -129.758141)
			(xy 429.421088 -129.702737) (xy 429.451072 -129.650803) (xy 429.487578 -129.603227) (xy 429.529983 -129.560822)
			(xy 429.577559 -129.524316) (xy 429.629493 -129.494332) (xy 429.684897 -129.471383) (xy 429.742822 -129.455862)
			(xy 429.802278 -129.448034) (xy 429.862246 -129.448034) (xy 429.921702 -129.455862) (xy 429.979627 -129.471383)
			(xy 430.035031 -129.494332) (xy 430.086965 -129.524316) (xy 430.134541 -129.560822) (xy 430.176946 -129.603227)
			(xy 430.213452 -129.650803) (xy 430.243436 -129.702737) (xy 430.266385 -129.758141) (xy 430.281906 -129.816066)
			(xy 430.289734 -129.875522) (xy 430.290224 -129.905506) (xy 430.290224 -130.769106) (xy 430.289734 -130.79909)
			(xy 430.281906 -130.858546) (xy 430.266385 -130.916471) (xy 430.243436 -130.971875) (xy 430.213452 -131.023809)
			(xy 430.176946 -131.071385) (xy 430.134541 -131.11379) (xy 430.086965 -131.150296) (xy 430.035031 -131.18028)
			(xy 429.979627 -131.203229) (xy 429.921702 -131.21875) (xy 429.862246 -131.226578) (xy 429.802278 -131.226578)
			(xy 429.742822 -131.21875) (xy 429.684897 -131.203229) (xy 429.629493 -131.18028) (xy 429.577559 -131.150296)
			(xy 429.529983 -131.11379) (xy 429.487578 -131.071385) (xy 429.451072 -131.023809) (xy 429.421088 -130.971875)
			(xy 429.398139 -130.916471) (xy 429.382618 -130.858546) (xy 429.37479 -130.79909) (xy 429.3743 -130.769106)
			(xy 415.815272 -130.769106) (xy 415.815272 -130.777234) (xy 415.814782 -130.807218) (xy 415.806954 -130.866674)
			(xy 415.791433 -130.924599) (xy 415.768484 -130.980003) (xy 415.7385 -131.031937) (xy 415.701994 -131.079513)
			(xy 415.659589 -131.121918) (xy 415.612013 -131.158424) (xy 415.560079 -131.188408) (xy 415.504675 -131.211357)
			(xy 415.44675 -131.226878) (xy 415.387294 -131.234706) (xy 415.327326 -131.234706) (xy 415.26787 -131.226878)
			(xy 415.209945 -131.211357) (xy 415.154541 -131.188408) (xy 415.102607 -131.158424) (xy 415.055031 -131.121918)
			(xy 415.012626 -131.079513) (xy 414.97612 -131.031937) (xy 414.946136 -130.980003) (xy 414.923187 -130.924599)
			(xy 414.907666 -130.866674) (xy 414.899838 -130.807218) (xy 414.899348 -130.777234) (xy 402.854668 -130.777234)
			(xy 402.854668 -131.29641) (xy 402.854178 -131.326378) (xy 402.846355 -131.3858) (xy 402.830842 -131.443693)
			(xy 402.807906 -131.499066) (xy 402.777939 -131.550972) (xy 402.741452 -131.598522) (xy 402.699072 -131.640902)
			(xy 402.651522 -131.677389) (xy 402.599616 -131.707356) (xy 402.544243 -131.730292) (xy 402.48635 -131.745805)
			(xy 402.426928 -131.753628) (xy 402.366992 -131.753628) (xy 402.30757 -131.745805) (xy 402.249677 -131.730292)
			(xy 402.194304 -131.707356) (xy 402.142398 -131.677389) (xy 402.094848 -131.640902) (xy 402.052468 -131.598522)
			(xy 402.015981 -131.550972) (xy 401.986014 -131.499066) (xy 401.963078 -131.443693) (xy 401.947565 -131.3858)
			(xy 401.939742 -131.326378) (xy 401.939252 -131.29641) (xy 383.883408 -131.29641) (xy 383.883408 -131.297934)
			(xy 383.882918 -131.327902) (xy 383.875095 -131.387324) (xy 383.859582 -131.445217) (xy 383.836646 -131.50059)
			(xy 383.806679 -131.552496) (xy 383.770192 -131.600046) (xy 383.727812 -131.642426) (xy 383.680262 -131.678913)
			(xy 383.628356 -131.70888) (xy 383.572983 -131.731816) (xy 383.51509 -131.747329) (xy 383.455668 -131.755152)
			(xy 383.395732 -131.755152) (xy 383.33631 -131.747329) (xy 383.278417 -131.731816) (xy 383.223044 -131.70888)
			(xy 383.171138 -131.678913) (xy 383.123588 -131.642426) (xy 383.081208 -131.600046) (xy 383.044721 -131.552496)
			(xy 383.014754 -131.50059) (xy 382.991818 -131.445217) (xy 382.976305 -131.387324) (xy 382.968482 -131.327902)
			(xy 382.967992 -131.297934) (xy 316.568893 -131.297934) (xy 316.576928 -131.301262) (xy 316.628834 -131.331229)
			(xy 316.676384 -131.367716) (xy 316.718764 -131.410096) (xy 316.755251 -131.457646) (xy 316.785218 -131.509552)
			(xy 316.808154 -131.564925) (xy 316.823667 -131.622818) (xy 316.83149 -131.68224) (xy 316.83198 -131.712208)
			(xy 316.83198 -132.575808) (xy 316.83149 -132.605776) (xy 316.823667 -132.665198) (xy 316.808154 -132.723091)
			(xy 316.785218 -132.778464) (xy 316.755251 -132.83037) (xy 316.718764 -132.87792) (xy 316.676384 -132.9203)
			(xy 316.628834 -132.956787) (xy 316.576928 -132.986754) (xy 316.521555 -133.00969) (xy 316.463662 -133.025203)
			(xy 316.40424 -133.033026) (xy 316.344304 -133.033026) (xy 316.284882 -133.025203) (xy 316.226989 -133.00969)
			(xy 316.171616 -132.986754) (xy 316.11971 -132.956787) (xy 316.07216 -132.9203) (xy 316.02978 -132.87792)
			(xy 315.993293 -132.83037) (xy 315.963326 -132.778464) (xy 315.94039 -132.723091) (xy 315.924877 -132.665198)
			(xy 315.917054 -132.605776) (xy 315.916564 -132.575808) (xy 297.86072 -132.575808) (xy 297.86072 -132.577332)
			(xy 297.86023 -132.6073) (xy 297.852407 -132.666722) (xy 297.836894 -132.724615) (xy 297.813958 -132.779988)
			(xy 297.783991 -132.831894) (xy 297.747504 -132.879444) (xy 297.705124 -132.921824) (xy 297.657574 -132.958311)
			(xy 297.605668 -132.988278) (xy 297.550295 -133.011214) (xy 297.492402 -133.026727) (xy 297.43298 -133.03455)
			(xy 297.373044 -133.03455) (xy 297.313622 -133.026727) (xy 297.255729 -133.011214) (xy 297.200356 -132.988278)
			(xy 297.14845 -132.958311) (xy 297.1009 -132.921824) (xy 297.05852 -132.879444) (xy 297.022033 -132.831894)
			(xy 296.992066 -132.779988) (xy 296.96913 -132.724615) (xy 296.953617 -132.666722) (xy 296.945794 -132.6073)
			(xy 296.945304 -132.577332) (xy 284.900624 -132.577332) (xy 284.900624 -133.096508) (xy 284.900134 -133.126492)
			(xy 284.892306 -133.185948) (xy 284.876785 -133.243873) (xy 284.853836 -133.299277) (xy 284.823852 -133.351211)
			(xy 284.787346 -133.398787) (xy 284.744941 -133.441192) (xy 284.697365 -133.477698) (xy 284.645431 -133.507682)
			(xy 284.590027 -133.530631) (xy 284.532102 -133.546152) (xy 284.472646 -133.55398) (xy 284.412678 -133.55398)
			(xy 284.353222 -133.546152) (xy 284.295297 -133.530631) (xy 284.239893 -133.507682) (xy 284.187959 -133.477698)
			(xy 284.140383 -133.441192) (xy 284.097978 -133.398787) (xy 284.061472 -133.351211) (xy 284.031488 -133.299277)
			(xy 284.008539 -133.243873) (xy 283.993018 -133.185948) (xy 283.98519 -133.126492) (xy 283.9847 -133.096508)
			(xy 270.425672 -133.096508) (xy 270.425672 -133.104382) (xy 270.425182 -133.134366) (xy 270.417354 -133.193822)
			(xy 270.401833 -133.251747) (xy 270.378884 -133.307151) (xy 270.3489 -133.359085) (xy 270.312394 -133.406661)
			(xy 270.269989 -133.449066) (xy 270.222413 -133.485572) (xy 270.170479 -133.515556) (xy 270.115075 -133.538505)
			(xy 270.05715 -133.554026) (xy 269.997694 -133.561854) (xy 269.937726 -133.561854) (xy 269.87827 -133.554026)
			(xy 269.820345 -133.538505) (xy 269.764941 -133.515556) (xy 269.713007 -133.485572) (xy 269.665431 -133.449066)
			(xy 269.623026 -133.406661) (xy 269.58652 -133.359085) (xy 269.556536 -133.307151) (xy 269.533587 -133.251747)
			(xy 269.518066 -133.193822) (xy 269.510238 -133.134366) (xy 269.509748 -133.104382) (xy 197.851649 -133.104382)
			(xy 197.886882 -133.124723) (xy 197.934432 -133.16121) (xy 197.976812 -133.20359) (xy 198.013299 -133.25114)
			(xy 198.043266 -133.303046) (xy 198.066202 -133.358419) (xy 198.081715 -133.416312) (xy 198.089538 -133.475734)
			(xy 198.090028 -133.505702) (xy 198.090028 -134.369302) (xy 198.089538 -134.39927) (xy 198.081715 -134.458692)
			(xy 198.066202 -134.516585) (xy 198.043266 -134.571958) (xy 198.013299 -134.623864) (xy 197.976812 -134.671414)
			(xy 197.934432 -134.713794) (xy 197.886882 -134.750281) (xy 197.834976 -134.780248) (xy 197.779603 -134.803184)
			(xy 197.72171 -134.818697) (xy 197.662288 -134.82652) (xy 197.602352 -134.82652) (xy 197.54293 -134.818697)
			(xy 197.485037 -134.803184) (xy 197.429664 -134.780248) (xy 197.377758 -134.750281) (xy 197.330208 -134.713794)
			(xy 197.287828 -134.671414) (xy 197.251341 -134.623864) (xy 197.221374 -134.571958) (xy 197.198438 -134.516585)
			(xy 197.182925 -134.458692) (xy 197.175102 -134.39927) (xy 197.174612 -134.369302) (xy 183.615076 -134.369302)
			(xy 183.615076 -134.377176) (xy 183.614586 -134.407144) (xy 183.606763 -134.466566) (xy 183.59125 -134.524459)
			(xy 183.568314 -134.579832) (xy 183.538347 -134.631738) (xy 183.50186 -134.679288) (xy 183.45948 -134.721668)
			(xy 183.41193 -134.758155) (xy 183.360024 -134.788122) (xy 183.304651 -134.811058) (xy 183.246758 -134.826571)
			(xy 183.187336 -134.834394) (xy 183.1274 -134.834394) (xy 183.067978 -134.826571) (xy 183.010085 -134.811058)
			(xy 182.954712 -134.788122) (xy 182.902806 -134.758155) (xy 182.855256 -134.721668) (xy 182.812876 -134.679288)
			(xy 182.776389 -134.631738) (xy 182.746422 -134.579832) (xy 182.723486 -134.524459) (xy 182.707973 -134.466566)
			(xy 182.70015 -134.407144) (xy 182.69966 -134.377176) (xy 170.65498 -134.377176) (xy 170.65498 -134.896352)
			(xy 170.65449 -134.926336) (xy 170.646662 -134.985792) (xy 170.631141 -135.043717) (xy 170.608192 -135.099121)
			(xy 170.578208 -135.151055) (xy 170.541702 -135.198631) (xy 170.499297 -135.241036) (xy 170.451721 -135.277542)
			(xy 170.399787 -135.307526) (xy 170.344383 -135.330475) (xy 170.286458 -135.345996) (xy 170.227002 -135.353824)
			(xy 170.167034 -135.353824) (xy 170.107578 -135.345996) (xy 170.049653 -135.330475) (xy 169.994249 -135.307526)
			(xy 169.942315 -135.277542) (xy 169.894739 -135.241036) (xy 169.852334 -135.198631) (xy 169.815828 -135.151055)
			(xy 169.785844 -135.099121) (xy 169.762895 -135.043717) (xy 169.747374 -134.985792) (xy 169.739546 -134.926336)
			(xy 169.739056 -134.896352) (xy 151.68372 -134.896352) (xy 151.68372 -134.897876) (xy 151.68323 -134.92786)
			(xy 151.675402 -134.987316) (xy 151.659881 -135.045241) (xy 151.636932 -135.100645) (xy 151.606948 -135.152579)
			(xy 151.570442 -135.200155) (xy 151.528037 -135.24256) (xy 151.480461 -135.279066) (xy 151.428527 -135.30905)
			(xy 151.373123 -135.331999) (xy 151.315198 -135.34752) (xy 151.255742 -135.355348) (xy 151.195774 -135.355348)
			(xy 151.136318 -135.34752) (xy 151.078393 -135.331999) (xy 151.022989 -135.30905) (xy 150.971055 -135.279066)
			(xy 150.923479 -135.24256) (xy 150.881074 -135.200155) (xy 150.844568 -135.152579) (xy 150.814584 -135.100645)
			(xy 150.791635 -135.045241) (xy 150.776114 -134.987316) (xy 150.768286 -134.92786) (xy 150.767796 -134.897876)
			(xy 84.369615 -134.897876) (xy 84.377099 -134.900976) (xy 84.429033 -134.93096) (xy 84.476609 -134.967466)
			(xy 84.519014 -135.009871) (xy 84.55552 -135.057447) (xy 84.585504 -135.109381) (xy 84.608453 -135.164785)
			(xy 84.623974 -135.22271) (xy 84.631802 -135.282166) (xy 84.632292 -135.31215) (xy 84.632292 -136.17575)
			(xy 84.631802 -136.205734) (xy 84.623974 -136.26519) (xy 84.608453 -136.323115) (xy 84.585504 -136.378519)
			(xy 84.55552 -136.430453) (xy 84.519014 -136.478029) (xy 84.476609 -136.520434) (xy 84.429033 -136.55694)
			(xy 84.377099 -136.586924) (xy 84.321695 -136.609873) (xy 84.26377 -136.625394) (xy 84.204314 -136.633222)
			(xy 84.144346 -136.633222) (xy 84.08489 -136.625394) (xy 84.026965 -136.609873) (xy 83.971561 -136.586924)
			(xy 83.919627 -136.55694) (xy 83.872051 -136.520434) (xy 83.829646 -136.478029) (xy 83.79314 -136.430453)
			(xy 83.763156 -136.378519) (xy 83.740207 -136.323115) (xy 83.724686 -136.26519) (xy 83.716858 -136.205734)
			(xy 83.716368 -136.17575) (xy 65.661032 -136.17575) (xy 65.661032 -136.177274) (xy 65.660542 -136.207258)
			(xy 65.652714 -136.266714) (xy 65.637193 -136.324639) (xy 65.614244 -136.380043) (xy 65.58426 -136.431977)
			(xy 65.547754 -136.479553) (xy 65.505349 -136.521958) (xy 65.457773 -136.558464) (xy 65.405839 -136.588448)
			(xy 65.350435 -136.611397) (xy 65.29251 -136.626918) (xy 65.233054 -136.634746) (xy 65.173086 -136.634746)
			(xy 65.11363 -136.626918) (xy 65.055705 -136.611397) (xy 65.000301 -136.588448) (xy 64.948367 -136.558464)
			(xy 64.900791 -136.521958) (xy 64.858386 -136.479553) (xy 64.82188 -136.431977) (xy 64.791896 -136.380043)
			(xy 64.768947 -136.324639) (xy 64.753426 -136.266714) (xy 64.745598 -136.207258) (xy 64.745108 -136.177274)
			(xy 52.700428 -136.177274) (xy 52.700428 -136.69645) (xy 52.700299 -136.704324) (xy 153.409904 -136.704324)
			(xy 153.409904 -135.840724) (xy 153.410394 -135.81074) (xy 153.418222 -135.751284) (xy 153.433743 -135.693359)
			(xy 153.456692 -135.637955) (xy 153.486676 -135.586021) (xy 153.523182 -135.538445) (xy 153.565587 -135.49604)
			(xy 153.613163 -135.459534) (xy 153.665097 -135.42955) (xy 153.720501 -135.406601) (xy 153.778426 -135.39108)
			(xy 153.837882 -135.383252) (xy 153.89785 -135.383252) (xy 153.957306 -135.39108) (xy 154.015231 -135.406601)
			(xy 154.070635 -135.42955) (xy 154.122569 -135.459534) (xy 154.170145 -135.49604) (xy 154.21255 -135.538445)
			(xy 154.249056 -135.586021) (xy 154.27904 -135.637955) (xy 154.301989 -135.693359) (xy 154.31751 -135.751284)
			(xy 154.325338 -135.81074) (xy 154.325828 -135.840724) (xy 154.325828 -136.69645) (xy 167.884856 -136.69645)
			(xy 167.884856 -135.83285) (xy 167.885346 -135.802866) (xy 167.893174 -135.74341) (xy 167.908695 -135.685485)
			(xy 167.931644 -135.630081) (xy 167.961628 -135.578147) (xy 167.998134 -135.530571) (xy 168.040539 -135.488166)
			(xy 168.088115 -135.45166) (xy 168.140049 -135.421676) (xy 168.195453 -135.398727) (xy 168.253378 -135.383206)
			(xy 168.312834 -135.375378) (xy 168.372802 -135.375378) (xy 168.432258 -135.383206) (xy 168.490183 -135.398727)
			(xy 168.545587 -135.421676) (xy 168.597521 -135.45166) (xy 168.645097 -135.488166) (xy 168.687502 -135.530571)
			(xy 168.724008 -135.578147) (xy 168.753992 -135.630081) (xy 168.776941 -135.685485) (xy 168.792462 -135.74341)
			(xy 168.80029 -135.802866) (xy 168.80078 -135.83285) (xy 168.80078 -136.177274) (xy 180.84546 -136.177274)
			(xy 180.84546 -135.313674) (xy 180.84595 -135.283706) (xy 180.853773 -135.224284) (xy 180.869286 -135.166391)
			(xy 180.892222 -135.111018) (xy 180.922189 -135.059112) (xy 180.958676 -135.011562) (xy 181.001056 -134.969182)
			(xy 181.048606 -134.932695) (xy 181.100512 -134.902728) (xy 181.155885 -134.879792) (xy 181.213778 -134.864279)
			(xy 181.2732 -134.856456) (xy 181.333136 -134.856456) (xy 181.392558 -134.864279) (xy 181.450451 -134.879792)
			(xy 181.505824 -134.902728) (xy 181.55773 -134.932695) (xy 181.60528 -134.969182) (xy 181.64766 -135.011562)
			(xy 181.684147 -135.059112) (xy 181.714114 -135.111018) (xy 181.73705 -135.166391) (xy 181.752563 -135.224284)
			(xy 181.760386 -135.283706) (xy 181.760876 -135.313674) (xy 181.760876 -136.17575) (xy 199.81672 -136.17575)
			(xy 199.81672 -135.31215) (xy 199.81721 -135.282182) (xy 199.825033 -135.22276) (xy 199.840546 -135.164867)
			(xy 199.863482 -135.109494) (xy 199.893449 -135.057588) (xy 199.929936 -135.010038) (xy 199.972316 -134.967658)
			(xy 200.019866 -134.931171) (xy 200.071772 -134.901204) (xy 200.127145 -134.878268) (xy 200.185038 -134.862755)
			(xy 200.24446 -134.854932) (xy 200.304396 -134.854932) (xy 200.363818 -134.862755) (xy 200.421711 -134.878268)
			(xy 200.469049 -134.897876) (xy 266.86764 -134.897876) (xy 266.86764 -134.034276) (xy 266.86813 -134.004292)
			(xy 266.875958 -133.944836) (xy 266.891479 -133.886911) (xy 266.914428 -133.831507) (xy 266.944412 -133.779573)
			(xy 266.980918 -133.731997) (xy 267.023323 -133.689592) (xy 267.070899 -133.653086) (xy 267.122833 -133.623102)
			(xy 267.178237 -133.600153) (xy 267.236162 -133.584632) (xy 267.295618 -133.576804) (xy 267.355586 -133.576804)
			(xy 267.415042 -133.584632) (xy 267.472967 -133.600153) (xy 267.528371 -133.623102) (xy 267.580305 -133.653086)
			(xy 267.627881 -133.689592) (xy 267.670286 -133.731997) (xy 267.706792 -133.779573) (xy 267.736776 -133.831507)
			(xy 267.759725 -133.886911) (xy 267.775246 -133.944836) (xy 267.783074 -134.004292) (xy 267.783564 -134.034276)
			(xy 267.783564 -134.896352) (xy 285.8389 -134.896352) (xy 285.8389 -134.032752) (xy 285.83939 -134.002768)
			(xy 285.847218 -133.943312) (xy 285.862739 -133.885387) (xy 285.885688 -133.829983) (xy 285.915672 -133.778049)
			(xy 285.952178 -133.730473) (xy 285.994583 -133.688068) (xy 286.042159 -133.651562) (xy 286.094093 -133.621578)
			(xy 286.149497 -133.598629) (xy 286.207422 -133.583108) (xy 286.266878 -133.57528) (xy 286.326846 -133.57528)
			(xy 286.386302 -133.583108) (xy 286.444227 -133.598629) (xy 286.499631 -133.621578) (xy 286.551565 -133.651562)
			(xy 286.599141 -133.688068) (xy 286.641546 -133.730473) (xy 286.678052 -133.778049) (xy 286.708036 -133.829983)
			(xy 286.730985 -133.885387) (xy 286.746506 -133.943312) (xy 286.754334 -134.002768) (xy 286.754824 -134.032752)
			(xy 286.754824 -134.377176) (xy 298.799504 -134.377176) (xy 298.799504 -133.513576) (xy 298.799994 -133.483608)
			(xy 298.807817 -133.424186) (xy 298.82333 -133.366293) (xy 298.846266 -133.31092) (xy 298.876233 -133.259014)
			(xy 298.91272 -133.211464) (xy 298.9551 -133.169084) (xy 299.00265 -133.132597) (xy 299.054556 -133.10263)
			(xy 299.109929 -133.079694) (xy 299.167822 -133.064181) (xy 299.227244 -133.056358) (xy 299.28718 -133.056358)
			(xy 299.346602 -133.064181) (xy 299.404495 -133.079694) (xy 299.459868 -133.10263) (xy 299.511774 -133.132597)
			(xy 299.559324 -133.169084) (xy 299.601704 -133.211464) (xy 299.638191 -133.259014) (xy 299.668158 -133.31092)
			(xy 299.691094 -133.366293) (xy 299.706607 -133.424186) (xy 299.71443 -133.483608) (xy 299.71492 -133.513576)
			(xy 299.71492 -134.369302) (xy 313.274456 -134.369302) (xy 313.274456 -133.505702) (xy 313.274946 -133.475734)
			(xy 313.282769 -133.416312) (xy 313.298282 -133.358419) (xy 313.321218 -133.303046) (xy 313.351185 -133.25114)
			(xy 313.387672 -133.20359) (xy 313.430052 -133.16121) (xy 313.477602 -133.124723) (xy 313.529508 -133.094756)
			(xy 313.584881 -133.07182) (xy 313.642774 -133.056307) (xy 313.702196 -133.048484) (xy 313.762132 -133.048484)
			(xy 313.821554 -133.056307) (xy 313.879447 -133.07182) (xy 313.93482 -133.094756) (xy 313.951493 -133.104382)
			(xy 385.6101 -133.104382) (xy 385.6101 -132.240782) (xy 385.61059 -132.210814) (xy 385.618413 -132.151392)
			(xy 385.633926 -132.093499) (xy 385.656862 -132.038126) (xy 385.686829 -131.98622) (xy 385.723316 -131.93867)
			(xy 385.765696 -131.89629) (xy 385.813246 -131.859803) (xy 385.865152 -131.829836) (xy 385.920525 -131.8069)
			(xy 385.978418 -131.791387) (xy 386.03784 -131.783564) (xy 386.097776 -131.783564) (xy 386.157198 -131.791387)
			(xy 386.215091 -131.8069) (xy 386.270464 -131.829836) (xy 386.32237 -131.859803) (xy 386.36992 -131.89629)
			(xy 386.4123 -131.93867) (xy 386.448787 -131.98622) (xy 386.478754 -132.038126) (xy 386.50169 -132.093499)
			(xy 386.517203 -132.151392) (xy 386.525026 -132.210814) (xy 386.525516 -132.240782) (xy 386.525516 -133.096508)
			(xy 400.085052 -133.096508) (xy 400.085052 -132.232908) (xy 400.085542 -132.20294) (xy 400.093365 -132.143518)
			(xy 400.108878 -132.085625) (xy 400.131814 -132.030252) (xy 400.161781 -131.978346) (xy 400.198268 -131.930796)
			(xy 400.240648 -131.888416) (xy 400.288198 -131.851929) (xy 400.340104 -131.821962) (xy 400.395477 -131.799026)
			(xy 400.45337 -131.783513) (xy 400.512792 -131.77569) (xy 400.572728 -131.77569) (xy 400.63215 -131.783513)
			(xy 400.690043 -131.799026) (xy 400.745416 -131.821962) (xy 400.797322 -131.851929) (xy 400.844872 -131.888416)
			(xy 400.887252 -131.930796) (xy 400.923739 -131.978346) (xy 400.953706 -132.030252) (xy 400.976642 -132.085625)
			(xy 400.992155 -132.143518) (xy 400.999978 -132.20294) (xy 401.000468 -132.232908) (xy 401.000468 -132.577332)
			(xy 413.045148 -132.577332) (xy 413.045148 -131.713732) (xy 413.045638 -131.683748) (xy 413.053466 -131.624292)
			(xy 413.068987 -131.566367) (xy 413.091936 -131.510963) (xy 413.12192 -131.459029) (xy 413.158426 -131.411453)
			(xy 413.200831 -131.369048) (xy 413.248407 -131.332542) (xy 413.300341 -131.302558) (xy 413.355745 -131.279609)
			(xy 413.41367 -131.264088) (xy 413.473126 -131.25626) (xy 413.533094 -131.25626) (xy 413.59255 -131.264088)
			(xy 413.650475 -131.279609) (xy 413.705879 -131.302558) (xy 413.757813 -131.332542) (xy 413.805389 -131.369048)
			(xy 413.847794 -131.411453) (xy 413.8843 -131.459029) (xy 413.914284 -131.510963) (xy 413.937233 -131.566367)
			(xy 413.952754 -131.624292) (xy 413.960582 -131.683748) (xy 413.961072 -131.713732) (xy 413.961072 -132.575808)
			(xy 432.016408 -132.575808) (xy 432.016408 -131.712208) (xy 432.016898 -131.682224) (xy 432.024726 -131.622768)
			(xy 432.040247 -131.564843) (xy 432.063196 -131.509439) (xy 432.09318 -131.457505) (xy 432.129686 -131.409929)
			(xy 432.172091 -131.367524) (xy 432.219667 -131.331018) (xy 432.271601 -131.301034) (xy 432.327005 -131.278085)
			(xy 432.38493 -131.262564) (xy 432.444386 -131.254736) (xy 432.504354 -131.254736) (xy 432.56381 -131.262564)
			(xy 432.621735 -131.278085) (xy 432.677139 -131.301034) (xy 432.729073 -131.331018) (xy 432.776649 -131.367524)
			(xy 432.819054 -131.409929) (xy 432.85556 -131.457505) (xy 432.885544 -131.509439) (xy 432.908493 -131.564843)
			(xy 432.924014 -131.622768) (xy 432.931842 -131.682224) (xy 432.932332 -131.712208) (xy 432.932332 -132.575808)
			(xy 432.931842 -132.605792) (xy 432.924014 -132.665248) (xy 432.908493 -132.723173) (xy 432.885544 -132.778577)
			(xy 432.85556 -132.830511) (xy 432.819054 -132.878087) (xy 432.776649 -132.920492) (xy 432.729073 -132.956998)
			(xy 432.677139 -132.986982) (xy 432.621735 -133.009931) (xy 432.56381 -133.025452) (xy 432.504354 -133.03328)
			(xy 432.444386 -133.03328) (xy 432.38493 -133.025452) (xy 432.327005 -133.009931) (xy 432.271601 -132.986982)
			(xy 432.219667 -132.956998) (xy 432.172091 -132.920492) (xy 432.129686 -132.878087) (xy 432.09318 -132.830511)
			(xy 432.063196 -132.778577) (xy 432.040247 -132.723173) (xy 432.024726 -132.665248) (xy 432.016898 -132.605792)
			(xy 432.016408 -132.575808) (xy 413.961072 -132.575808) (xy 413.961072 -132.577332) (xy 413.960582 -132.607316)
			(xy 413.952754 -132.666772) (xy 413.937233 -132.724697) (xy 413.914284 -132.780101) (xy 413.8843 -132.832035)
			(xy 413.847794 -132.879611) (xy 413.805389 -132.922016) (xy 413.757813 -132.958522) (xy 413.705879 -132.988506)
			(xy 413.650475 -133.011455) (xy 413.59255 -133.026976) (xy 413.533094 -133.034804) (xy 413.473126 -133.034804)
			(xy 413.41367 -133.026976) (xy 413.355745 -133.011455) (xy 413.300341 -132.988506) (xy 413.248407 -132.958522)
			(xy 413.200831 -132.922016) (xy 413.158426 -132.879611) (xy 413.12192 -132.832035) (xy 413.091936 -132.780101)
			(xy 413.068987 -132.724697) (xy 413.053466 -132.666772) (xy 413.045638 -132.607316) (xy 413.045148 -132.577332)
			(xy 401.000468 -132.577332) (xy 401.000468 -133.096508) (xy 400.999978 -133.126476) (xy 400.992155 -133.185898)
			(xy 400.976642 -133.243791) (xy 400.953706 -133.299164) (xy 400.923739 -133.35107) (xy 400.887252 -133.39862)
			(xy 400.844872 -133.441) (xy 400.797322 -133.477487) (xy 400.745416 -133.507454) (xy 400.690043 -133.53039)
			(xy 400.63215 -133.545903) (xy 400.572728 -133.553726) (xy 400.512792 -133.553726) (xy 400.45337 -133.545903)
			(xy 400.395477 -133.53039) (xy 400.340104 -133.507454) (xy 400.288198 -133.477487) (xy 400.240648 -133.441)
			(xy 400.198268 -133.39862) (xy 400.161781 -133.35107) (xy 400.131814 -133.299164) (xy 400.108878 -133.243791)
			(xy 400.093365 -133.185898) (xy 400.085542 -133.126476) (xy 400.085052 -133.096508) (xy 386.525516 -133.096508)
			(xy 386.525516 -133.104382) (xy 386.525026 -133.13435) (xy 386.517203 -133.193772) (xy 386.50169 -133.251665)
			(xy 386.478754 -133.307038) (xy 386.448787 -133.358944) (xy 386.4123 -133.406494) (xy 386.36992 -133.448874)
			(xy 386.32237 -133.485361) (xy 386.270464 -133.515328) (xy 386.215091 -133.538264) (xy 386.157198 -133.553777)
			(xy 386.097776 -133.5616) (xy 386.03784 -133.5616) (xy 385.978418 -133.553777) (xy 385.920525 -133.538264)
			(xy 385.865152 -133.515328) (xy 385.813246 -133.485361) (xy 385.765696 -133.448874) (xy 385.723316 -133.406494)
			(xy 385.686829 -133.358944) (xy 385.656862 -133.307038) (xy 385.633926 -133.251665) (xy 385.618413 -133.193772)
			(xy 385.61059 -133.13435) (xy 385.6101 -133.104382) (xy 313.951493 -133.104382) (xy 313.986726 -133.124723)
			(xy 314.034276 -133.16121) (xy 314.076656 -133.20359) (xy 314.113143 -133.25114) (xy 314.14311 -133.303046)
			(xy 314.166046 -133.358419) (xy 314.181559 -133.416312) (xy 314.189382 -133.475734) (xy 314.189872 -133.505702)
			(xy 314.189872 -134.369302) (xy 314.189382 -134.39927) (xy 314.181559 -134.458692) (xy 314.166046 -134.516585)
			(xy 314.14311 -134.571958) (xy 314.113143 -134.623864) (xy 314.076656 -134.671414) (xy 314.034276 -134.713794)
			(xy 313.986726 -134.750281) (xy 313.93482 -134.780248) (xy 313.879447 -134.803184) (xy 313.821554 -134.818697)
			(xy 313.762132 -134.82652) (xy 313.702196 -134.82652) (xy 313.642774 -134.818697) (xy 313.584881 -134.803184)
			(xy 313.529508 -134.780248) (xy 313.477602 -134.750281) (xy 313.430052 -134.713794) (xy 313.387672 -134.671414)
			(xy 313.351185 -134.623864) (xy 313.321218 -134.571958) (xy 313.298282 -134.516585) (xy 313.282769 -134.458692)
			(xy 313.274946 -134.39927) (xy 313.274456 -134.369302) (xy 299.71492 -134.369302) (xy 299.71492 -134.377176)
			(xy 299.71443 -134.407144) (xy 299.706607 -134.466566) (xy 299.691094 -134.524459) (xy 299.668158 -134.579832)
			(xy 299.638191 -134.631738) (xy 299.601704 -134.679288) (xy 299.559324 -134.721668) (xy 299.511774 -134.758155)
			(xy 299.459868 -134.788122) (xy 299.404495 -134.811058) (xy 299.346602 -134.826571) (xy 299.28718 -134.834394)
			(xy 299.227244 -134.834394) (xy 299.167822 -134.826571) (xy 299.109929 -134.811058) (xy 299.054556 -134.788122)
			(xy 299.00265 -134.758155) (xy 298.9551 -134.721668) (xy 298.91272 -134.679288) (xy 298.876233 -134.631738)
			(xy 298.846266 -134.579832) (xy 298.82333 -134.524459) (xy 298.807817 -134.466566) (xy 298.799994 -134.407144)
			(xy 298.799504 -134.377176) (xy 286.754824 -134.377176) (xy 286.754824 -134.896352) (xy 286.754334 -134.926336)
			(xy 286.746506 -134.985792) (xy 286.730985 -135.043717) (xy 286.708036 -135.099121) (xy 286.678052 -135.151055)
			(xy 286.641546 -135.198631) (xy 286.599141 -135.241036) (xy 286.551565 -135.277542) (xy 286.499631 -135.307526)
			(xy 286.444227 -135.330475) (xy 286.386302 -135.345996) (xy 286.326846 -135.353824) (xy 286.266878 -135.353824)
			(xy 286.207422 -135.345996) (xy 286.149497 -135.330475) (xy 286.094093 -135.307526) (xy 286.042159 -135.277542)
			(xy 285.994583 -135.241036) (xy 285.952178 -135.198631) (xy 285.915672 -135.151055) (xy 285.885688 -135.099121)
			(xy 285.862739 -135.043717) (xy 285.847218 -134.985792) (xy 285.83939 -134.926336) (xy 285.8389 -134.896352)
			(xy 267.783564 -134.896352) (xy 267.783564 -134.897876) (xy 267.783074 -134.92786) (xy 267.775246 -134.987316)
			(xy 267.759725 -135.045241) (xy 267.736776 -135.100645) (xy 267.706792 -135.152579) (xy 267.670286 -135.200155)
			(xy 267.627881 -135.24256) (xy 267.580305 -135.279066) (xy 267.528371 -135.30905) (xy 267.472967 -135.331999)
			(xy 267.415042 -135.34752) (xy 267.355586 -135.355348) (xy 267.295618 -135.355348) (xy 267.236162 -135.34752)
			(xy 267.178237 -135.331999) (xy 267.122833 -135.30905) (xy 267.070899 -135.279066) (xy 267.023323 -135.24256)
			(xy 266.980918 -135.200155) (xy 266.944412 -135.152579) (xy 266.914428 -135.100645) (xy 266.891479 -135.045241)
			(xy 266.875958 -134.987316) (xy 266.86813 -134.92786) (xy 266.86764 -134.897876) (xy 200.469049 -134.897876)
			(xy 200.477084 -134.901204) (xy 200.52899 -134.931171) (xy 200.57654 -134.967658) (xy 200.61892 -135.010038)
			(xy 200.655407 -135.057588) (xy 200.685374 -135.109494) (xy 200.70831 -135.164867) (xy 200.723823 -135.22276)
			(xy 200.731646 -135.282182) (xy 200.732136 -135.31215) (xy 200.732136 -136.17575) (xy 200.731646 -136.205718)
			(xy 200.723823 -136.26514) (xy 200.70831 -136.323033) (xy 200.685374 -136.378406) (xy 200.655407 -136.430312)
			(xy 200.61892 -136.477862) (xy 200.57654 -136.520242) (xy 200.52899 -136.556729) (xy 200.477084 -136.586696)
			(xy 200.421711 -136.609632) (xy 200.363818 -136.625145) (xy 200.304396 -136.632968) (xy 200.24446 -136.632968)
			(xy 200.185038 -136.625145) (xy 200.127145 -136.609632) (xy 200.071772 -136.586696) (xy 200.019866 -136.556729)
			(xy 199.972316 -136.520242) (xy 199.929936 -136.477862) (xy 199.893449 -136.430312) (xy 199.863482 -136.378406)
			(xy 199.840546 -136.323033) (xy 199.825033 -136.26514) (xy 199.81721 -136.205718) (xy 199.81672 -136.17575)
			(xy 181.760876 -136.17575) (xy 181.760876 -136.177274) (xy 181.760386 -136.207242) (xy 181.752563 -136.266664)
			(xy 181.73705 -136.324557) (xy 181.714114 -136.37993) (xy 181.684147 -136.431836) (xy 181.64766 -136.479386)
			(xy 181.60528 -136.521766) (xy 181.55773 -136.558253) (xy 181.505824 -136.58822) (xy 181.450451 -136.611156)
			(xy 181.392558 -136.626669) (xy 181.333136 -136.634492) (xy 181.2732 -136.634492) (xy 181.213778 -136.626669)
			(xy 181.155885 -136.611156) (xy 181.100512 -136.58822) (xy 181.048606 -136.558253) (xy 181.001056 -136.521766)
			(xy 180.958676 -136.479386) (xy 180.922189 -136.431836) (xy 180.892222 -136.37993) (xy 180.869286 -136.324557)
			(xy 180.853773 -136.266664) (xy 180.84595 -136.207242) (xy 180.84546 -136.177274) (xy 168.80078 -136.177274)
			(xy 168.80078 -136.69645) (xy 168.800651 -136.704324) (xy 269.509748 -136.704324) (xy 269.509748 -135.840724)
			(xy 269.510238 -135.81074) (xy 269.518066 -135.751284) (xy 269.533587 -135.693359) (xy 269.556536 -135.637955)
			(xy 269.58652 -135.586021) (xy 269.623026 -135.538445) (xy 269.665431 -135.49604) (xy 269.713007 -135.459534)
			(xy 269.764941 -135.42955) (xy 269.820345 -135.406601) (xy 269.87827 -135.39108) (xy 269.937726 -135.383252)
			(xy 269.997694 -135.383252) (xy 270.05715 -135.39108) (xy 270.115075 -135.406601) (xy 270.170479 -135.42955)
			(xy 270.222413 -135.459534) (xy 270.269989 -135.49604) (xy 270.312394 -135.538445) (xy 270.3489 -135.586021)
			(xy 270.378884 -135.637955) (xy 270.401833 -135.693359) (xy 270.417354 -135.751284) (xy 270.425182 -135.81074)
			(xy 270.425672 -135.840724) (xy 270.425672 -136.69645) (xy 283.9847 -136.69645) (xy 283.9847 -135.83285)
			(xy 283.98519 -135.802866) (xy 283.993018 -135.74341) (xy 284.008539 -135.685485) (xy 284.031488 -135.630081)
			(xy 284.061472 -135.578147) (xy 284.097978 -135.530571) (xy 284.140383 -135.488166) (xy 284.187959 -135.45166)
			(xy 284.239893 -135.421676) (xy 284.295297 -135.398727) (xy 284.353222 -135.383206) (xy 284.412678 -135.375378)
			(xy 284.472646 -135.375378) (xy 284.532102 -135.383206) (xy 284.590027 -135.398727) (xy 284.645431 -135.421676)
			(xy 284.697365 -135.45166) (xy 284.744941 -135.488166) (xy 284.787346 -135.530571) (xy 284.823852 -135.578147)
			(xy 284.853836 -135.630081) (xy 284.876785 -135.685485) (xy 284.892306 -135.74341) (xy 284.900134 -135.802866)
			(xy 284.900624 -135.83285) (xy 284.900624 -136.177274) (xy 296.945304 -136.177274) (xy 296.945304 -135.313674)
			(xy 296.945794 -135.283706) (xy 296.953617 -135.224284) (xy 296.96913 -135.166391) (xy 296.992066 -135.111018)
			(xy 297.022033 -135.059112) (xy 297.05852 -135.011562) (xy 297.1009 -134.969182) (xy 297.14845 -134.932695)
			(xy 297.200356 -134.902728) (xy 297.255729 -134.879792) (xy 297.313622 -134.864279) (xy 297.373044 -134.856456)
			(xy 297.43298 -134.856456) (xy 297.492402 -134.864279) (xy 297.550295 -134.879792) (xy 297.605668 -134.902728)
			(xy 297.657574 -134.932695) (xy 297.705124 -134.969182) (xy 297.747504 -135.011562) (xy 297.783991 -135.059112)
			(xy 297.813958 -135.111018) (xy 297.836894 -135.166391) (xy 297.852407 -135.224284) (xy 297.86023 -135.283706)
			(xy 297.86072 -135.313674) (xy 297.86072 -136.17575) (xy 315.916564 -136.17575) (xy 315.916564 -135.31215)
			(xy 315.917054 -135.282182) (xy 315.924877 -135.22276) (xy 315.94039 -135.164867) (xy 315.963326 -135.109494)
			(xy 315.993293 -135.057588) (xy 316.02978 -135.010038) (xy 316.07216 -134.967658) (xy 316.11971 -134.931171)
			(xy 316.171616 -134.901204) (xy 316.226989 -134.878268) (xy 316.284882 -134.862755) (xy 316.344304 -134.854932)
			(xy 316.40424 -134.854932) (xy 316.463662 -134.862755) (xy 316.521555 -134.878268) (xy 316.568893 -134.897876)
			(xy 382.967992 -134.897876) (xy 382.967992 -134.034276) (xy 382.968482 -134.004308) (xy 382.976305 -133.944886)
			(xy 382.991818 -133.886993) (xy 383.014754 -133.83162) (xy 383.044721 -133.779714) (xy 383.081208 -133.732164)
			(xy 383.123588 -133.689784) (xy 383.171138 -133.653297) (xy 383.223044 -133.62333) (xy 383.278417 -133.600394)
			(xy 383.33631 -133.584881) (xy 383.395732 -133.577058) (xy 383.455668 -133.577058) (xy 383.51509 -133.584881)
			(xy 383.572983 -133.600394) (xy 383.628356 -133.62333) (xy 383.680262 -133.653297) (xy 383.727812 -133.689784)
			(xy 383.770192 -133.732164) (xy 383.806679 -133.779714) (xy 383.836646 -133.83162) (xy 383.859582 -133.886993)
			(xy 383.875095 -133.944886) (xy 383.882918 -134.004308) (xy 383.883408 -134.034276) (xy 383.883408 -134.896352)
			(xy 401.939252 -134.896352) (xy 401.939252 -134.032752) (xy 401.939742 -134.002784) (xy 401.947565 -133.943362)
			(xy 401.963078 -133.885469) (xy 401.986014 -133.830096) (xy 402.015981 -133.77819) (xy 402.052468 -133.73064)
			(xy 402.094848 -133.68826) (xy 402.142398 -133.651773) (xy 402.194304 -133.621806) (xy 402.249677 -133.59887)
			(xy 402.30757 -133.583357) (xy 402.366992 -133.575534) (xy 402.426928 -133.575534) (xy 402.48635 -133.583357)
			(xy 402.544243 -133.59887) (xy 402.599616 -133.621806) (xy 402.651522 -133.651773) (xy 402.699072 -133.68826)
			(xy 402.741452 -133.73064) (xy 402.777939 -133.77819) (xy 402.807906 -133.830096) (xy 402.830842 -133.885469)
			(xy 402.846355 -133.943362) (xy 402.854178 -134.002784) (xy 402.854668 -134.032752) (xy 402.854668 -134.377176)
			(xy 414.899348 -134.377176) (xy 414.899348 -133.513576) (xy 414.899838 -133.483592) (xy 414.907666 -133.424136)
			(xy 414.923187 -133.366211) (xy 414.946136 -133.310807) (xy 414.97612 -133.258873) (xy 415.012626 -133.211297)
			(xy 415.055031 -133.168892) (xy 415.102607 -133.132386) (xy 415.154541 -133.102402) (xy 415.209945 -133.079453)
			(xy 415.26787 -133.063932) (xy 415.327326 -133.056104) (xy 415.387294 -133.056104) (xy 415.44675 -133.063932)
			(xy 415.504675 -133.079453) (xy 415.560079 -133.102402) (xy 415.612013 -133.132386) (xy 415.659589 -133.168892)
			(xy 415.701994 -133.211297) (xy 415.7385 -133.258873) (xy 415.768484 -133.310807) (xy 415.791433 -133.366211)
			(xy 415.806954 -133.424136) (xy 415.814782 -133.483592) (xy 415.815272 -133.513576) (xy 415.815272 -134.369302)
			(xy 429.3743 -134.369302) (xy 429.3743 -133.505702) (xy 429.37479 -133.475718) (xy 429.382618 -133.416262)
			(xy 429.398139 -133.358337) (xy 429.421088 -133.302933) (xy 429.451072 -133.250999) (xy 429.487578 -133.203423)
			(xy 429.529983 -133.161018) (xy 429.577559 -133.124512) (xy 429.629493 -133.094528) (xy 429.684897 -133.071579)
			(xy 429.742822 -133.056058) (xy 429.802278 -133.04823) (xy 429.862246 -133.04823) (xy 429.921702 -133.056058)
			(xy 429.979627 -133.071579) (xy 430.035031 -133.094528) (xy 430.086965 -133.124512) (xy 430.134541 -133.161018)
			(xy 430.176946 -133.203423) (xy 430.213452 -133.250999) (xy 430.243436 -133.302933) (xy 430.266385 -133.358337)
			(xy 430.281906 -133.416262) (xy 430.289734 -133.475718) (xy 430.290224 -133.505702) (xy 430.290224 -134.369302)
			(xy 430.289734 -134.399286) (xy 430.281906 -134.458742) (xy 430.266385 -134.516667) (xy 430.243436 -134.572071)
			(xy 430.213452 -134.624005) (xy 430.176946 -134.671581) (xy 430.134541 -134.713986) (xy 430.086965 -134.750492)
			(xy 430.035031 -134.780476) (xy 429.979627 -134.803425) (xy 429.921702 -134.818946) (xy 429.862246 -134.826774)
			(xy 429.802278 -134.826774) (xy 429.742822 -134.818946) (xy 429.684897 -134.803425) (xy 429.629493 -134.780476)
			(xy 429.577559 -134.750492) (xy 429.529983 -134.713986) (xy 429.487578 -134.671581) (xy 429.451072 -134.624005)
			(xy 429.421088 -134.572071) (xy 429.398139 -134.516667) (xy 429.382618 -134.458742) (xy 429.37479 -134.399286)
			(xy 429.3743 -134.369302) (xy 415.815272 -134.369302) (xy 415.815272 -134.377176) (xy 415.814782 -134.40716)
			(xy 415.806954 -134.466616) (xy 415.791433 -134.524541) (xy 415.768484 -134.579945) (xy 415.7385 -134.631879)
			(xy 415.701994 -134.679455) (xy 415.659589 -134.72186) (xy 415.612013 -134.758366) (xy 415.560079 -134.78835)
			(xy 415.504675 -134.811299) (xy 415.44675 -134.82682) (xy 415.387294 -134.834648) (xy 415.327326 -134.834648)
			(xy 415.26787 -134.82682) (xy 415.209945 -134.811299) (xy 415.154541 -134.78835) (xy 415.102607 -134.758366)
			(xy 415.055031 -134.72186) (xy 415.012626 -134.679455) (xy 414.97612 -134.631879) (xy 414.946136 -134.579945)
			(xy 414.923187 -134.524541) (xy 414.907666 -134.466616) (xy 414.899838 -134.40716) (xy 414.899348 -134.377176)
			(xy 402.854668 -134.377176) (xy 402.854668 -134.896352) (xy 402.854178 -134.92632) (xy 402.846355 -134.985742)
			(xy 402.830842 -135.043635) (xy 402.807906 -135.099008) (xy 402.777939 -135.150914) (xy 402.741452 -135.198464)
			(xy 402.699072 -135.240844) (xy 402.651522 -135.277331) (xy 402.599616 -135.307298) (xy 402.544243 -135.330234)
			(xy 402.48635 -135.345747) (xy 402.426928 -135.35357) (xy 402.366992 -135.35357) (xy 402.30757 -135.345747)
			(xy 402.249677 -135.330234) (xy 402.194304 -135.307298) (xy 402.142398 -135.277331) (xy 402.094848 -135.240844)
			(xy 402.052468 -135.198464) (xy 402.015981 -135.150914) (xy 401.986014 -135.099008) (xy 401.963078 -135.043635)
			(xy 401.947565 -134.985742) (xy 401.939742 -134.92632) (xy 401.939252 -134.896352) (xy 383.883408 -134.896352)
			(xy 383.883408 -134.897876) (xy 383.882918 -134.927844) (xy 383.875095 -134.987266) (xy 383.859582 -135.045159)
			(xy 383.836646 -135.100532) (xy 383.806679 -135.152438) (xy 383.770192 -135.199988) (xy 383.727812 -135.242368)
			(xy 383.680262 -135.278855) (xy 383.628356 -135.308822) (xy 383.572983 -135.331758) (xy 383.51509 -135.347271)
			(xy 383.455668 -135.355094) (xy 383.395732 -135.355094) (xy 383.33631 -135.347271) (xy 383.278417 -135.331758)
			(xy 383.223044 -135.308822) (xy 383.171138 -135.278855) (xy 383.123588 -135.242368) (xy 383.081208 -135.199988)
			(xy 383.044721 -135.152438) (xy 383.014754 -135.100532) (xy 382.991818 -135.045159) (xy 382.976305 -134.987266)
			(xy 382.968482 -134.927844) (xy 382.967992 -134.897876) (xy 316.568893 -134.897876) (xy 316.576928 -134.901204)
			(xy 316.628834 -134.931171) (xy 316.676384 -134.967658) (xy 316.718764 -135.010038) (xy 316.755251 -135.057588)
			(xy 316.785218 -135.109494) (xy 316.808154 -135.164867) (xy 316.823667 -135.22276) (xy 316.83149 -135.282182)
			(xy 316.83198 -135.31215) (xy 316.83198 -136.17575) (xy 316.83149 -136.205718) (xy 316.823667 -136.26514)
			(xy 316.808154 -136.323033) (xy 316.785218 -136.378406) (xy 316.755251 -136.430312) (xy 316.718764 -136.477862)
			(xy 316.676384 -136.520242) (xy 316.628834 -136.556729) (xy 316.576928 -136.586696) (xy 316.521555 -136.609632)
			(xy 316.463662 -136.625145) (xy 316.40424 -136.632968) (xy 316.344304 -136.632968) (xy 316.284882 -136.625145)
			(xy 316.226989 -136.609632) (xy 316.171616 -136.586696) (xy 316.11971 -136.556729) (xy 316.07216 -136.520242)
			(xy 316.02978 -136.477862) (xy 315.993293 -136.430312) (xy 315.963326 -136.378406) (xy 315.94039 -136.323033)
			(xy 315.924877 -136.26514) (xy 315.917054 -136.205718) (xy 315.916564 -136.17575) (xy 297.86072 -136.17575)
			(xy 297.86072 -136.177274) (xy 297.86023 -136.207242) (xy 297.852407 -136.266664) (xy 297.836894 -136.324557)
			(xy 297.813958 -136.37993) (xy 297.783991 -136.431836) (xy 297.747504 -136.479386) (xy 297.705124 -136.521766)
			(xy 297.657574 -136.558253) (xy 297.605668 -136.58822) (xy 297.550295 -136.611156) (xy 297.492402 -136.626669)
			(xy 297.43298 -136.634492) (xy 297.373044 -136.634492) (xy 297.313622 -136.626669) (xy 297.255729 -136.611156)
			(xy 297.200356 -136.58822) (xy 297.14845 -136.558253) (xy 297.1009 -136.521766) (xy 297.05852 -136.479386)
			(xy 297.022033 -136.431836) (xy 296.992066 -136.37993) (xy 296.96913 -136.324557) (xy 296.953617 -136.266664)
			(xy 296.945794 -136.207242) (xy 296.945304 -136.177274) (xy 284.900624 -136.177274) (xy 284.900624 -136.69645)
			(xy 284.900495 -136.704324) (xy 385.6101 -136.704324) (xy 385.6101 -135.840724) (xy 385.61059 -135.810756)
			(xy 385.618413 -135.751334) (xy 385.633926 -135.693441) (xy 385.656862 -135.638068) (xy 385.686829 -135.586162)
			(xy 385.723316 -135.538612) (xy 385.765696 -135.496232) (xy 385.813246 -135.459745) (xy 385.865152 -135.429778)
			(xy 385.920525 -135.406842) (xy 385.978418 -135.391329) (xy 386.03784 -135.383506) (xy 386.097776 -135.383506)
			(xy 386.157198 -135.391329) (xy 386.215091 -135.406842) (xy 386.270464 -135.429778) (xy 386.32237 -135.459745)
			(xy 386.36992 -135.496232) (xy 386.4123 -135.538612) (xy 386.448787 -135.586162) (xy 386.478754 -135.638068)
			(xy 386.50169 -135.693441) (xy 386.517203 -135.751334) (xy 386.525026 -135.810756) (xy 386.525516 -135.840724)
			(xy 386.525516 -136.69645) (xy 400.085052 -136.69645) (xy 400.085052 -135.83285) (xy 400.085542 -135.802882)
			(xy 400.093365 -135.74346) (xy 400.108878 -135.685567) (xy 400.131814 -135.630194) (xy 400.161781 -135.578288)
			(xy 400.198268 -135.530738) (xy 400.240648 -135.488358) (xy 400.288198 -135.451871) (xy 400.340104 -135.421904)
			(xy 400.395477 -135.398968) (xy 400.45337 -135.383455) (xy 400.512792 -135.375632) (xy 400.572728 -135.375632)
			(xy 400.63215 -135.383455) (xy 400.690043 -135.398968) (xy 400.745416 -135.421904) (xy 400.797322 -135.451871)
			(xy 400.844872 -135.488358) (xy 400.887252 -135.530738) (xy 400.923739 -135.578288) (xy 400.953706 -135.630194)
			(xy 400.976642 -135.685567) (xy 400.992155 -135.74346) (xy 400.999978 -135.802882) (xy 401.000468 -135.83285)
			(xy 401.000468 -136.177274) (xy 413.045148 -136.177274) (xy 413.045148 -135.313674) (xy 413.045638 -135.28369)
			(xy 413.053466 -135.224234) (xy 413.068987 -135.166309) (xy 413.091936 -135.110905) (xy 413.12192 -135.058971)
			(xy 413.158426 -135.011395) (xy 413.200831 -134.96899) (xy 413.248407 -134.932484) (xy 413.300341 -134.9025)
			(xy 413.355745 -134.879551) (xy 413.41367 -134.86403) (xy 413.473126 -134.856202) (xy 413.533094 -134.856202)
			(xy 413.59255 -134.86403) (xy 413.650475 -134.879551) (xy 413.705879 -134.9025) (xy 413.757813 -134.932484)
			(xy 413.805389 -134.96899) (xy 413.847794 -135.011395) (xy 413.8843 -135.058971) (xy 413.914284 -135.110905)
			(xy 413.937233 -135.166309) (xy 413.952754 -135.224234) (xy 413.960582 -135.28369) (xy 413.961072 -135.313674)
			(xy 413.961072 -136.17575) (xy 432.016408 -136.17575) (xy 432.016408 -135.31215) (xy 432.016898 -135.282166)
			(xy 432.024726 -135.22271) (xy 432.040247 -135.164785) (xy 432.063196 -135.109381) (xy 432.09318 -135.057447)
			(xy 432.129686 -135.009871) (xy 432.172091 -134.967466) (xy 432.219667 -134.93096) (xy 432.271601 -134.900976)
			(xy 432.327005 -134.878027) (xy 432.38493 -134.862506) (xy 432.444386 -134.854678) (xy 432.504354 -134.854678)
			(xy 432.56381 -134.862506) (xy 432.621735 -134.878027) (xy 432.677139 -134.900976) (xy 432.729073 -134.93096)
			(xy 432.776649 -134.967466) (xy 432.819054 -135.009871) (xy 432.85556 -135.057447) (xy 432.885544 -135.109381)
			(xy 432.908493 -135.164785) (xy 432.924014 -135.22271) (xy 432.931842 -135.282166) (xy 432.932332 -135.31215)
			(xy 432.932332 -136.17575) (xy 432.931842 -136.205734) (xy 432.924014 -136.26519) (xy 432.908493 -136.323115)
			(xy 432.885544 -136.378519) (xy 432.85556 -136.430453) (xy 432.819054 -136.478029) (xy 432.776649 -136.520434)
			(xy 432.729073 -136.55694) (xy 432.677139 -136.586924) (xy 432.621735 -136.609873) (xy 432.56381 -136.625394)
			(xy 432.504354 -136.633222) (xy 432.444386 -136.633222) (xy 432.38493 -136.625394) (xy 432.327005 -136.609873)
			(xy 432.271601 -136.586924) (xy 432.219667 -136.55694) (xy 432.172091 -136.520434) (xy 432.129686 -136.478029)
			(xy 432.09318 -136.430453) (xy 432.063196 -136.378519) (xy 432.040247 -136.323115) (xy 432.024726 -136.26519)
			(xy 432.016898 -136.205734) (xy 432.016408 -136.17575) (xy 413.961072 -136.17575) (xy 413.961072 -136.177274)
			(xy 413.960582 -136.207258) (xy 413.952754 -136.266714) (xy 413.937233 -136.324639) (xy 413.914284 -136.380043)
			(xy 413.8843 -136.431977) (xy 413.847794 -136.479553) (xy 413.805389 -136.521958) (xy 413.757813 -136.558464)
			(xy 413.705879 -136.588448) (xy 413.650475 -136.611397) (xy 413.59255 -136.626918) (xy 413.533094 -136.634746)
			(xy 413.473126 -136.634746) (xy 413.41367 -136.626918) (xy 413.355745 -136.611397) (xy 413.300341 -136.588448)
			(xy 413.248407 -136.558464) (xy 413.200831 -136.521958) (xy 413.158426 -136.479553) (xy 413.12192 -136.431977)
			(xy 413.091936 -136.380043) (xy 413.068987 -136.324639) (xy 413.053466 -136.266714) (xy 413.045638 -136.207258)
			(xy 413.045148 -136.177274) (xy 401.000468 -136.177274) (xy 401.000468 -136.69645) (xy 400.999978 -136.726418)
			(xy 400.992155 -136.78584) (xy 400.976642 -136.843733) (xy 400.953706 -136.899106) (xy 400.923739 -136.951012)
			(xy 400.887252 -136.998562) (xy 400.844872 -137.040942) (xy 400.797322 -137.077429) (xy 400.745416 -137.107396)
			(xy 400.690043 -137.130332) (xy 400.63215 -137.145845) (xy 400.572728 -137.153668) (xy 400.512792 -137.153668)
			(xy 400.45337 -137.145845) (xy 400.395477 -137.130332) (xy 400.340104 -137.107396) (xy 400.288198 -137.077429)
			(xy 400.240648 -137.040942) (xy 400.198268 -136.998562) (xy 400.161781 -136.951012) (xy 400.131814 -136.899106)
			(xy 400.108878 -136.843733) (xy 400.093365 -136.78584) (xy 400.085542 -136.726418) (xy 400.085052 -136.69645)
			(xy 386.525516 -136.69645) (xy 386.525516 -136.704324) (xy 386.525026 -136.734292) (xy 386.517203 -136.793714)
			(xy 386.50169 -136.851607) (xy 386.478754 -136.90698) (xy 386.448787 -136.958886) (xy 386.4123 -137.006436)
			(xy 386.36992 -137.048816) (xy 386.32237 -137.085303) (xy 386.270464 -137.11527) (xy 386.215091 -137.138206)
			(xy 386.157198 -137.153719) (xy 386.097776 -137.161542) (xy 386.03784 -137.161542) (xy 385.978418 -137.153719)
			(xy 385.920525 -137.138206) (xy 385.865152 -137.11527) (xy 385.813246 -137.085303) (xy 385.765696 -137.048816)
			(xy 385.723316 -137.006436) (xy 385.686829 -136.958886) (xy 385.656862 -136.90698) (xy 385.633926 -136.851607)
			(xy 385.618413 -136.793714) (xy 385.61059 -136.734292) (xy 385.6101 -136.704324) (xy 284.900495 -136.704324)
			(xy 284.900134 -136.726434) (xy 284.892306 -136.78589) (xy 284.876785 -136.843815) (xy 284.853836 -136.899219)
			(xy 284.823852 -136.951153) (xy 284.787346 -136.998729) (xy 284.744941 -137.041134) (xy 284.697365 -137.07764)
			(xy 284.645431 -137.107624) (xy 284.590027 -137.130573) (xy 284.532102 -137.146094) (xy 284.472646 -137.153922)
			(xy 284.412678 -137.153922) (xy 284.353222 -137.146094) (xy 284.295297 -137.130573) (xy 284.239893 -137.107624)
			(xy 284.187959 -137.07764) (xy 284.140383 -137.041134) (xy 284.097978 -136.998729) (xy 284.061472 -136.951153)
			(xy 284.031488 -136.899219) (xy 284.008539 -136.843815) (xy 283.993018 -136.78589) (xy 283.98519 -136.726434)
			(xy 283.9847 -136.69645) (xy 270.425672 -136.69645) (xy 270.425672 -136.704324) (xy 270.425182 -136.734308)
			(xy 270.417354 -136.793764) (xy 270.401833 -136.851689) (xy 270.378884 -136.907093) (xy 270.3489 -136.959027)
			(xy 270.312394 -137.006603) (xy 270.269989 -137.049008) (xy 270.222413 -137.085514) (xy 270.170479 -137.115498)
			(xy 270.115075 -137.138447) (xy 270.05715 -137.153968) (xy 269.997694 -137.161796) (xy 269.937726 -137.161796)
			(xy 269.87827 -137.153968) (xy 269.820345 -137.138447) (xy 269.764941 -137.115498) (xy 269.713007 -137.085514)
			(xy 269.665431 -137.049008) (xy 269.623026 -137.006603) (xy 269.58652 -136.959027) (xy 269.556536 -136.907093)
			(xy 269.533587 -136.851689) (xy 269.518066 -136.793764) (xy 269.510238 -136.734308) (xy 269.509748 -136.704324)
			(xy 168.800651 -136.704324) (xy 168.80029 -136.726434) (xy 168.792462 -136.78589) (xy 168.776941 -136.843815)
			(xy 168.753992 -136.899219) (xy 168.724008 -136.951153) (xy 168.687502 -136.998729) (xy 168.645097 -137.041134)
			(xy 168.597521 -137.07764) (xy 168.545587 -137.107624) (xy 168.490183 -137.130573) (xy 168.432258 -137.146094)
			(xy 168.372802 -137.153922) (xy 168.312834 -137.153922) (xy 168.253378 -137.146094) (xy 168.195453 -137.130573)
			(xy 168.140049 -137.107624) (xy 168.088115 -137.07764) (xy 168.040539 -137.041134) (xy 167.998134 -136.998729)
			(xy 167.961628 -136.951153) (xy 167.931644 -136.899219) (xy 167.908695 -136.843815) (xy 167.893174 -136.78589)
			(xy 167.885346 -136.726434) (xy 167.884856 -136.69645) (xy 154.325828 -136.69645) (xy 154.325828 -136.704324)
			(xy 154.325338 -136.734308) (xy 154.31751 -136.793764) (xy 154.301989 -136.851689) (xy 154.27904 -136.907093)
			(xy 154.249056 -136.959027) (xy 154.21255 -137.006603) (xy 154.170145 -137.049008) (xy 154.122569 -137.085514)
			(xy 154.070635 -137.115498) (xy 154.015231 -137.138447) (xy 153.957306 -137.153968) (xy 153.89785 -137.161796)
			(xy 153.837882 -137.161796) (xy 153.778426 -137.153968) (xy 153.720501 -137.138447) (xy 153.665097 -137.115498)
			(xy 153.613163 -137.085514) (xy 153.565587 -137.049008) (xy 153.523182 -137.006603) (xy 153.486676 -136.959027)
			(xy 153.456692 -136.907093) (xy 153.433743 -136.851689) (xy 153.418222 -136.793764) (xy 153.410394 -136.734308)
			(xy 153.409904 -136.704324) (xy 52.700299 -136.704324) (xy 52.699938 -136.726418) (xy 52.692115 -136.78584)
			(xy 52.676602 -136.843733) (xy 52.653666 -136.899106) (xy 52.623699 -136.951012) (xy 52.587212 -136.998562)
			(xy 52.544832 -137.040942) (xy 52.497282 -137.077429) (xy 52.445376 -137.107396) (xy 52.390003 -137.130332)
			(xy 52.33211 -137.145845) (xy 52.272688 -137.153668) (xy 52.212752 -137.153668) (xy 52.15333 -137.145845)
			(xy 52.095437 -137.130332) (xy 52.040064 -137.107396) (xy 51.988158 -137.077429) (xy 51.940608 -137.040942)
			(xy 51.898228 -136.998562) (xy 51.861741 -136.951012) (xy 51.831774 -136.899106) (xy 51.808838 -136.843733)
			(xy 51.793325 -136.78584) (xy 51.785502 -136.726418) (xy 51.785012 -136.69645) (xy 38.225476 -136.69645)
			(xy 38.225476 -136.704324) (xy 38.224986 -136.734292) (xy 38.217163 -136.793714) (xy 38.20165 -136.851607)
			(xy 38.178714 -136.90698) (xy 38.148747 -136.958886) (xy 38.11226 -137.006436) (xy 38.06988 -137.048816)
			(xy 38.02233 -137.085303) (xy 37.970424 -137.11527) (xy 37.915051 -137.138206) (xy 37.857158 -137.153719)
			(xy 37.797736 -137.161542) (xy 37.7378 -137.161542) (xy 37.678378 -137.153719) (xy 37.620485 -137.138206)
			(xy 37.565112 -137.11527) (xy 37.513206 -137.085303) (xy 37.465656 -137.048816) (xy 37.423276 -137.006436)
			(xy 37.386789 -136.958886) (xy 37.356822 -136.90698) (xy 37.333886 -136.851607) (xy 37.318373 -136.793714)
			(xy 37.31055 -136.734292) (xy 37.31006 -136.704324) (xy 5.324094 -136.704324) (xy 5.324094 -138.496548)
			(xy 43.97248 -138.496548) (xy 43.97248 -137.632948) (xy 43.97297 -137.602964) (xy 43.980798 -137.543508)
			(xy 43.996319 -137.485583) (xy 44.019268 -137.430179) (xy 44.049252 -137.378245) (xy 44.085758 -137.330669)
			(xy 44.128163 -137.288264) (xy 44.175739 -137.251758) (xy 44.227673 -137.221774) (xy 44.283077 -137.198825)
			(xy 44.341002 -137.183304) (xy 44.400458 -137.175476) (xy 44.460426 -137.175476) (xy 44.519882 -137.183304)
			(xy 44.577807 -137.198825) (xy 44.633211 -137.221774) (xy 44.685145 -137.251758) (xy 44.732721 -137.288264)
			(xy 44.775126 -137.330669) (xy 44.811632 -137.378245) (xy 44.841616 -137.430179) (xy 44.864565 -137.485583)
			(xy 44.880086 -137.543508) (xy 44.887914 -137.602964) (xy 44.888404 -137.632948) (xy 44.888404 -138.496548)
			(xy 160.072324 -138.496548) (xy 160.072324 -137.632948) (xy 160.072814 -137.602964) (xy 160.080642 -137.543508)
			(xy 160.096163 -137.485583) (xy 160.119112 -137.430179) (xy 160.149096 -137.378245) (xy 160.185602 -137.330669)
			(xy 160.228007 -137.288264) (xy 160.275583 -137.251758) (xy 160.327517 -137.221774) (xy 160.382921 -137.198825)
			(xy 160.440846 -137.183304) (xy 160.500302 -137.175476) (xy 160.56027 -137.175476) (xy 160.619726 -137.183304)
			(xy 160.677651 -137.198825) (xy 160.733055 -137.221774) (xy 160.784989 -137.251758) (xy 160.832565 -137.288264)
			(xy 160.87497 -137.330669) (xy 160.911476 -137.378245) (xy 160.94146 -137.430179) (xy 160.964409 -137.485583)
			(xy 160.97993 -137.543508) (xy 160.987758 -137.602964) (xy 160.988248 -137.632948) (xy 160.988248 -138.496548)
			(xy 276.172676 -138.496548) (xy 276.172676 -137.632948) (xy 276.173166 -137.60298) (xy 276.180989 -137.543558)
			(xy 276.196502 -137.485665) (xy 276.219438 -137.430292) (xy 276.249405 -137.378386) (xy 276.285892 -137.330836)
			(xy 276.328272 -137.288456) (xy 276.375822 -137.251969) (xy 276.427728 -137.222002) (xy 276.483101 -137.199066)
			(xy 276.540994 -137.183553) (xy 276.600416 -137.17573) (xy 276.660352 -137.17573) (xy 276.719774 -137.183553)
			(xy 276.777667 -137.199066) (xy 276.83304 -137.222002) (xy 276.884946 -137.251969) (xy 276.932496 -137.288456)
			(xy 276.974876 -137.330836) (xy 277.011363 -137.378386) (xy 277.04133 -137.430292) (xy 277.064266 -137.485665)
			(xy 277.079779 -137.543558) (xy 277.087602 -137.60298) (xy 277.088092 -137.632948) (xy 277.088092 -138.496548)
			(xy 277.088084 -138.497056) (xy 392.27252 -138.497056) (xy 392.27252 -137.633456) (xy 392.27301 -137.603472)
			(xy 392.280838 -137.544016) (xy 392.296359 -137.486091) (xy 392.319308 -137.430687) (xy 392.349292 -137.378753)
			(xy 392.385798 -137.331177) (xy 392.428203 -137.288772) (xy 392.475779 -137.252266) (xy 392.527713 -137.222282)
			(xy 392.583117 -137.199333) (xy 392.641042 -137.183812) (xy 392.700498 -137.175984) (xy 392.760466 -137.175984)
			(xy 392.819922 -137.183812) (xy 392.877847 -137.199333) (xy 392.933251 -137.222282) (xy 392.985185 -137.252266)
			(xy 393.032761 -137.288772) (xy 393.075166 -137.331177) (xy 393.111672 -137.378753) (xy 393.141656 -137.430687)
			(xy 393.164605 -137.486091) (xy 393.180126 -137.544016) (xy 393.187954 -137.603472) (xy 393.188444 -137.633456)
			(xy 393.188444 -138.497056) (xy 393.187954 -138.52704) (xy 393.180126 -138.586496) (xy 393.164605 -138.644421)
			(xy 393.141656 -138.699825) (xy 393.111672 -138.751759) (xy 393.075166 -138.799335) (xy 393.032761 -138.84174)
			(xy 392.985185 -138.878246) (xy 392.933251 -138.90823) (xy 392.877847 -138.931179) (xy 392.819922 -138.9467)
			(xy 392.760466 -138.954528) (xy 392.700498 -138.954528) (xy 392.641042 -138.9467) (xy 392.583117 -138.931179)
			(xy 392.527713 -138.90823) (xy 392.475779 -138.878246) (xy 392.428203 -138.84174) (xy 392.385798 -138.799335)
			(xy 392.349292 -138.751759) (xy 392.319308 -138.699825) (xy 392.296359 -138.644421) (xy 392.280838 -138.586496)
			(xy 392.27301 -138.52704) (xy 392.27252 -138.497056) (xy 277.088084 -138.497056) (xy 277.087602 -138.526516)
			(xy 277.079779 -138.585938) (xy 277.064266 -138.643831) (xy 277.04133 -138.699204) (xy 277.011363 -138.75111)
			(xy 276.974876 -138.79866) (xy 276.932496 -138.84104) (xy 276.884946 -138.877527) (xy 276.83304 -138.907494)
			(xy 276.777667 -138.93043) (xy 276.719774 -138.945943) (xy 276.660352 -138.953766) (xy 276.600416 -138.953766)
			(xy 276.540994 -138.945943) (xy 276.483101 -138.93043) (xy 276.427728 -138.907494) (xy 276.375822 -138.877527)
			(xy 276.328272 -138.84104) (xy 276.285892 -138.79866) (xy 276.249405 -138.75111) (xy 276.219438 -138.699204)
			(xy 276.196502 -138.643831) (xy 276.180989 -138.585938) (xy 276.173166 -138.526516) (xy 276.172676 -138.496548)
			(xy 160.988248 -138.496548) (xy 160.987758 -138.526532) (xy 160.97993 -138.585988) (xy 160.964409 -138.643913)
			(xy 160.94146 -138.699317) (xy 160.911476 -138.751251) (xy 160.87497 -138.798827) (xy 160.832565 -138.841232)
			(xy 160.784989 -138.877738) (xy 160.733055 -138.907722) (xy 160.677651 -138.930671) (xy 160.619726 -138.946192)
			(xy 160.56027 -138.95402) (xy 160.500302 -138.95402) (xy 160.440846 -138.946192) (xy 160.382921 -138.930671)
			(xy 160.327517 -138.907722) (xy 160.275583 -138.877738) (xy 160.228007 -138.841232) (xy 160.185602 -138.798827)
			(xy 160.149096 -138.751251) (xy 160.119112 -138.699317) (xy 160.096163 -138.643913) (xy 160.080642 -138.585988)
			(xy 160.072814 -138.526532) (xy 160.072324 -138.496548) (xy 44.888404 -138.496548) (xy 44.887914 -138.526532)
			(xy 44.880086 -138.585988) (xy 44.864565 -138.643913) (xy 44.841616 -138.699317) (xy 44.811632 -138.751251)
			(xy 44.775126 -138.798827) (xy 44.732721 -138.841232) (xy 44.685145 -138.877738) (xy 44.633211 -138.907722)
			(xy 44.577807 -138.930671) (xy 44.519882 -138.946192) (xy 44.460426 -138.95402) (xy 44.400458 -138.95402)
			(xy 44.341002 -138.946192) (xy 44.283077 -138.930671) (xy 44.227673 -138.907722) (xy 44.175739 -138.877738)
			(xy 44.128163 -138.841232) (xy 44.085758 -138.798827) (xy 44.049252 -138.751251) (xy 44.019268 -138.699317)
			(xy 43.996319 -138.643913) (xy 43.980798 -138.585988) (xy 43.97297 -138.526532) (xy 43.97248 -138.496548)
			(xy 5.324094 -138.496548) (xy 5.324094 -143.48714) (xy 66.599308 -143.48714) (xy 66.599308 -142.62354)
			(xy 66.599798 -142.593556) (xy 66.607626 -142.5341) (xy 66.623147 -142.476175) (xy 66.646096 -142.420771)
			(xy 66.67608 -142.368837) (xy 66.712586 -142.321261) (xy 66.754991 -142.278856) (xy 66.802567 -142.24235)
			(xy 66.854501 -142.212366) (xy 66.909905 -142.189417) (xy 66.96783 -142.173896) (xy 67.027286 -142.166068)
			(xy 67.087254 -142.166068) (xy 67.14671 -142.173896) (xy 67.204635 -142.189417) (xy 67.260039 -142.212366)
			(xy 67.311973 -142.24235) (xy 67.359549 -142.278856) (xy 67.401954 -142.321261) (xy 67.43846 -142.368837)
			(xy 67.468444 -142.420771) (xy 67.491393 -142.476175) (xy 67.506914 -142.5341) (xy 67.514742 -142.593556)
			(xy 67.515232 -142.62354) (xy 67.515232 -143.479266) (xy 81.07426 -143.479266) (xy 81.07426 -142.615666)
			(xy 81.07475 -142.585682) (xy 81.082578 -142.526226) (xy 81.098099 -142.468301) (xy 81.121048 -142.412897)
			(xy 81.151032 -142.360963) (xy 81.187538 -142.313387) (xy 81.229943 -142.270982) (xy 81.277519 -142.234476)
			(xy 81.329453 -142.204492) (xy 81.384857 -142.181543) (xy 81.442782 -142.166022) (xy 81.502238 -142.158194)
			(xy 81.562206 -142.158194) (xy 81.621662 -142.166022) (xy 81.679587 -142.181543) (xy 81.734991 -142.204492)
			(xy 81.786925 -142.234476) (xy 81.834501 -142.270982) (xy 81.876906 -142.313387) (xy 81.913412 -142.360963)
			(xy 81.943396 -142.412897) (xy 81.966345 -142.468301) (xy 81.981866 -142.526226) (xy 81.989694 -142.585682)
			(xy 81.990184 -142.615666) (xy 81.990184 -143.479266) (xy 81.990055 -143.48714) (xy 182.69966 -143.48714)
			(xy 182.69966 -142.62354) (xy 182.70015 -142.593572) (xy 182.707973 -142.53415) (xy 182.723486 -142.476257)
			(xy 182.746422 -142.420884) (xy 182.776389 -142.368978) (xy 182.812876 -142.321428) (xy 182.855256 -142.279048)
			(xy 182.902806 -142.242561) (xy 182.954712 -142.212594) (xy 183.010085 -142.189658) (xy 183.067978 -142.174145)
			(xy 183.1274 -142.166322) (xy 183.187336 -142.166322) (xy 183.246758 -142.174145) (xy 183.304651 -142.189658)
			(xy 183.360024 -142.212594) (xy 183.41193 -142.242561) (xy 183.45948 -142.279048) (xy 183.50186 -142.321428)
			(xy 183.538347 -142.368978) (xy 183.568314 -142.420884) (xy 183.59125 -142.476257) (xy 183.606763 -142.53415)
			(xy 183.614586 -142.593572) (xy 183.615076 -142.62354) (xy 183.615076 -143.479266) (xy 197.174612 -143.479266)
			(xy 197.174612 -142.615666) (xy 197.175102 -142.585698) (xy 197.182925 -142.526276) (xy 197.198438 -142.468383)
			(xy 197.221374 -142.41301) (xy 197.251341 -142.361104) (xy 197.287828 -142.313554) (xy 197.330208 -142.271174)
			(xy 197.377758 -142.234687) (xy 197.429664 -142.20472) (xy 197.485037 -142.181784) (xy 197.54293 -142.166271)
			(xy 197.602352 -142.158448) (xy 197.662288 -142.158448) (xy 197.72171 -142.166271) (xy 197.779603 -142.181784)
			(xy 197.834976 -142.20472) (xy 197.886882 -142.234687) (xy 197.934432 -142.271174) (xy 197.976812 -142.313554)
			(xy 198.013299 -142.361104) (xy 198.043266 -142.41301) (xy 198.066202 -142.468383) (xy 198.081715 -142.526276)
			(xy 198.089538 -142.585698) (xy 198.090028 -142.615666) (xy 198.090028 -143.479266) (xy 198.089899 -143.48714)
			(xy 298.799504 -143.48714) (xy 298.799504 -142.62354) (xy 298.799994 -142.593572) (xy 298.807817 -142.53415)
			(xy 298.82333 -142.476257) (xy 298.846266 -142.420884) (xy 298.876233 -142.368978) (xy 298.91272 -142.321428)
			(xy 298.9551 -142.279048) (xy 299.00265 -142.242561) (xy 299.054556 -142.212594) (xy 299.109929 -142.189658)
			(xy 299.167822 -142.174145) (xy 299.227244 -142.166322) (xy 299.28718 -142.166322) (xy 299.346602 -142.174145)
			(xy 299.404495 -142.189658) (xy 299.459868 -142.212594) (xy 299.511774 -142.242561) (xy 299.559324 -142.279048)
			(xy 299.601704 -142.321428) (xy 299.638191 -142.368978) (xy 299.668158 -142.420884) (xy 299.691094 -142.476257)
			(xy 299.706607 -142.53415) (xy 299.71443 -142.593572) (xy 299.71492 -142.62354) (xy 299.71492 -143.479266)
			(xy 313.274456 -143.479266) (xy 313.274456 -142.615666) (xy 313.274946 -142.585698) (xy 313.282769 -142.526276)
			(xy 313.298282 -142.468383) (xy 313.321218 -142.41301) (xy 313.351185 -142.361104) (xy 313.387672 -142.313554)
			(xy 313.430052 -142.271174) (xy 313.477602 -142.234687) (xy 313.529508 -142.20472) (xy 313.584881 -142.181784)
			(xy 313.642774 -142.166271) (xy 313.702196 -142.158448) (xy 313.762132 -142.158448) (xy 313.821554 -142.166271)
			(xy 313.879447 -142.181784) (xy 313.93482 -142.20472) (xy 313.986726 -142.234687) (xy 314.034276 -142.271174)
			(xy 314.076656 -142.313554) (xy 314.113143 -142.361104) (xy 314.14311 -142.41301) (xy 314.166046 -142.468383)
			(xy 314.181559 -142.526276) (xy 314.189382 -142.585698) (xy 314.189872 -142.615666) (xy 314.189872 -143.479266)
			(xy 314.189743 -143.48714) (xy 414.899348 -143.48714) (xy 414.899348 -142.62354) (xy 414.899838 -142.593556)
			(xy 414.907666 -142.5341) (xy 414.923187 -142.476175) (xy 414.946136 -142.420771) (xy 414.97612 -142.368837)
			(xy 415.012626 -142.321261) (xy 415.055031 -142.278856) (xy 415.102607 -142.24235) (xy 415.154541 -142.212366)
			(xy 415.209945 -142.189417) (xy 415.26787 -142.173896) (xy 415.327326 -142.166068) (xy 415.387294 -142.166068)
			(xy 415.44675 -142.173896) (xy 415.504675 -142.189417) (xy 415.560079 -142.212366) (xy 415.612013 -142.24235)
			(xy 415.659589 -142.278856) (xy 415.701994 -142.321261) (xy 415.7385 -142.368837) (xy 415.768484 -142.420771)
			(xy 415.791433 -142.476175) (xy 415.806954 -142.5341) (xy 415.814782 -142.593556) (xy 415.815272 -142.62354)
			(xy 415.815272 -143.479266) (xy 429.3743 -143.479266) (xy 429.3743 -142.615666) (xy 429.37479 -142.585682)
			(xy 429.382618 -142.526226) (xy 429.398139 -142.468301) (xy 429.421088 -142.412897) (xy 429.451072 -142.360963)
			(xy 429.487578 -142.313387) (xy 429.529983 -142.270982) (xy 429.577559 -142.234476) (xy 429.629493 -142.204492)
			(xy 429.684897 -142.181543) (xy 429.742822 -142.166022) (xy 429.802278 -142.158194) (xy 429.862246 -142.158194)
			(xy 429.921702 -142.166022) (xy 429.979627 -142.181543) (xy 430.035031 -142.204492) (xy 430.086965 -142.234476)
			(xy 430.134541 -142.270982) (xy 430.176946 -142.313387) (xy 430.213452 -142.360963) (xy 430.243436 -142.412897)
			(xy 430.266385 -142.468301) (xy 430.281906 -142.526226) (xy 430.289734 -142.585682) (xy 430.290224 -142.615666)
			(xy 430.290224 -143.479266) (xy 430.289734 -143.50925) (xy 430.281906 -143.568706) (xy 430.266385 -143.626631)
			(xy 430.243436 -143.682035) (xy 430.213452 -143.733969) (xy 430.176946 -143.781545) (xy 430.134541 -143.82395)
			(xy 430.086965 -143.860456) (xy 430.035031 -143.89044) (xy 429.979627 -143.913389) (xy 429.921702 -143.92891)
			(xy 429.862246 -143.936738) (xy 429.802278 -143.936738) (xy 429.742822 -143.92891) (xy 429.684897 -143.913389)
			(xy 429.629493 -143.89044) (xy 429.577559 -143.860456) (xy 429.529983 -143.82395) (xy 429.487578 -143.781545)
			(xy 429.451072 -143.733969) (xy 429.421088 -143.682035) (xy 429.398139 -143.626631) (xy 429.382618 -143.568706)
			(xy 429.37479 -143.50925) (xy 429.3743 -143.479266) (xy 415.815272 -143.479266) (xy 415.815272 -143.48714)
			(xy 415.814782 -143.517124) (xy 415.806954 -143.57658) (xy 415.791433 -143.634505) (xy 415.768484 -143.689909)
			(xy 415.7385 -143.741843) (xy 415.701994 -143.789419) (xy 415.659589 -143.831824) (xy 415.612013 -143.86833)
			(xy 415.560079 -143.898314) (xy 415.504675 -143.921263) (xy 415.44675 -143.936784) (xy 415.387294 -143.944612)
			(xy 415.327326 -143.944612) (xy 415.26787 -143.936784) (xy 415.209945 -143.921263) (xy 415.154541 -143.898314)
			(xy 415.102607 -143.86833) (xy 415.055031 -143.831824) (xy 415.012626 -143.789419) (xy 414.97612 -143.741843)
			(xy 414.946136 -143.689909) (xy 414.923187 -143.634505) (xy 414.907666 -143.57658) (xy 414.899838 -143.517124)
			(xy 414.899348 -143.48714) (xy 314.189743 -143.48714) (xy 314.189382 -143.509234) (xy 314.181559 -143.568656)
			(xy 314.166046 -143.626549) (xy 314.14311 -143.681922) (xy 314.113143 -143.733828) (xy 314.076656 -143.781378)
			(xy 314.034276 -143.823758) (xy 313.986726 -143.860245) (xy 313.93482 -143.890212) (xy 313.879447 -143.913148)
			(xy 313.821554 -143.928661) (xy 313.762132 -143.936484) (xy 313.702196 -143.936484) (xy 313.642774 -143.928661)
			(xy 313.584881 -143.913148) (xy 313.529508 -143.890212) (xy 313.477602 -143.860245) (xy 313.430052 -143.823758)
			(xy 313.387672 -143.781378) (xy 313.351185 -143.733828) (xy 313.321218 -143.681922) (xy 313.298282 -143.626549)
			(xy 313.282769 -143.568656) (xy 313.274946 -143.509234) (xy 313.274456 -143.479266) (xy 299.71492 -143.479266)
			(xy 299.71492 -143.48714) (xy 299.71443 -143.517108) (xy 299.706607 -143.57653) (xy 299.691094 -143.634423)
			(xy 299.668158 -143.689796) (xy 299.638191 -143.741702) (xy 299.601704 -143.789252) (xy 299.559324 -143.831632)
			(xy 299.511774 -143.868119) (xy 299.459868 -143.898086) (xy 299.404495 -143.921022) (xy 299.346602 -143.936535)
			(xy 299.28718 -143.944358) (xy 299.227244 -143.944358) (xy 299.167822 -143.936535) (xy 299.109929 -143.921022)
			(xy 299.054556 -143.898086) (xy 299.00265 -143.868119) (xy 298.9551 -143.831632) (xy 298.91272 -143.789252)
			(xy 298.876233 -143.741702) (xy 298.846266 -143.689796) (xy 298.82333 -143.634423) (xy 298.807817 -143.57653)
			(xy 298.799994 -143.517108) (xy 298.799504 -143.48714) (xy 198.089899 -143.48714) (xy 198.089538 -143.509234)
			(xy 198.081715 -143.568656) (xy 198.066202 -143.626549) (xy 198.043266 -143.681922) (xy 198.013299 -143.733828)
			(xy 197.976812 -143.781378) (xy 197.934432 -143.823758) (xy 197.886882 -143.860245) (xy 197.834976 -143.890212)
			(xy 197.779603 -143.913148) (xy 197.72171 -143.928661) (xy 197.662288 -143.936484) (xy 197.602352 -143.936484)
			(xy 197.54293 -143.928661) (xy 197.485037 -143.913148) (xy 197.429664 -143.890212) (xy 197.377758 -143.860245)
			(xy 197.330208 -143.823758) (xy 197.287828 -143.781378) (xy 197.251341 -143.733828) (xy 197.221374 -143.681922)
			(xy 197.198438 -143.626549) (xy 197.182925 -143.568656) (xy 197.175102 -143.509234) (xy 197.174612 -143.479266)
			(xy 183.615076 -143.479266) (xy 183.615076 -143.48714) (xy 183.614586 -143.517108) (xy 183.606763 -143.57653)
			(xy 183.59125 -143.634423) (xy 183.568314 -143.689796) (xy 183.538347 -143.741702) (xy 183.50186 -143.789252)
			(xy 183.45948 -143.831632) (xy 183.41193 -143.868119) (xy 183.360024 -143.898086) (xy 183.304651 -143.921022)
			(xy 183.246758 -143.936535) (xy 183.187336 -143.944358) (xy 183.1274 -143.944358) (xy 183.067978 -143.936535)
			(xy 183.010085 -143.921022) (xy 182.954712 -143.898086) (xy 182.902806 -143.868119) (xy 182.855256 -143.831632)
			(xy 182.812876 -143.789252) (xy 182.776389 -143.741702) (xy 182.746422 -143.689796) (xy 182.723486 -143.634423)
			(xy 182.707973 -143.57653) (xy 182.70015 -143.517108) (xy 182.69966 -143.48714) (xy 81.990055 -143.48714)
			(xy 81.989694 -143.50925) (xy 81.981866 -143.568706) (xy 81.966345 -143.626631) (xy 81.943396 -143.682035)
			(xy 81.913412 -143.733969) (xy 81.876906 -143.781545) (xy 81.834501 -143.82395) (xy 81.786925 -143.860456)
			(xy 81.734991 -143.89044) (xy 81.679587 -143.913389) (xy 81.621662 -143.92891) (xy 81.562206 -143.936738)
			(xy 81.502238 -143.936738) (xy 81.442782 -143.92891) (xy 81.384857 -143.913389) (xy 81.329453 -143.89044)
			(xy 81.277519 -143.860456) (xy 81.229943 -143.82395) (xy 81.187538 -143.781545) (xy 81.151032 -143.733969)
			(xy 81.121048 -143.682035) (xy 81.098099 -143.626631) (xy 81.082578 -143.568706) (xy 81.07475 -143.50925)
			(xy 81.07426 -143.479266) (xy 67.515232 -143.479266) (xy 67.515232 -143.48714) (xy 67.514742 -143.517124)
			(xy 67.506914 -143.57658) (xy 67.491393 -143.634505) (xy 67.468444 -143.689909) (xy 67.43846 -143.741843)
			(xy 67.401954 -143.789419) (xy 67.359549 -143.831824) (xy 67.311973 -143.86833) (xy 67.260039 -143.898314)
			(xy 67.204635 -143.921263) (xy 67.14671 -143.936784) (xy 67.087254 -143.944612) (xy 67.027286 -143.944612)
			(xy 66.96783 -143.936784) (xy 66.909905 -143.921263) (xy 66.854501 -143.898314) (xy 66.802567 -143.86833)
			(xy 66.754991 -143.831824) (xy 66.712586 -143.789419) (xy 66.67608 -143.741843) (xy 66.646096 -143.689909)
			(xy 66.623147 -143.634505) (xy 66.607626 -143.57658) (xy 66.599798 -143.517124) (xy 66.599308 -143.48714)
			(xy 5.324094 -143.48714) (xy 5.324094 -145.287238) (xy 64.745108 -145.287238) (xy 64.745108 -144.423638)
			(xy 64.745598 -144.393654) (xy 64.753426 -144.334198) (xy 64.768947 -144.276273) (xy 64.791896 -144.220869)
			(xy 64.82188 -144.168935) (xy 64.858386 -144.121359) (xy 64.900791 -144.078954) (xy 64.948367 -144.042448)
			(xy 65.000301 -144.012464) (xy 65.055705 -143.989515) (xy 65.11363 -143.973994) (xy 65.173086 -143.966166)
			(xy 65.233054 -143.966166) (xy 65.29251 -143.973994) (xy 65.350435 -143.989515) (xy 65.405839 -144.012464)
			(xy 65.457773 -144.042448) (xy 65.505349 -144.078954) (xy 65.547754 -144.121359) (xy 65.58426 -144.168935)
			(xy 65.614244 -144.220869) (xy 65.637193 -144.276273) (xy 65.652714 -144.334198) (xy 65.660542 -144.393654)
			(xy 65.661032 -144.423638) (xy 65.661032 -145.285714) (xy 83.716368 -145.285714) (xy 83.716368 -144.422114)
			(xy 83.716858 -144.39213) (xy 83.724686 -144.332674) (xy 83.740207 -144.274749) (xy 83.763156 -144.219345)
			(xy 83.79314 -144.167411) (xy 83.829646 -144.119835) (xy 83.872051 -144.07743) (xy 83.919627 -144.040924)
			(xy 83.971561 -144.01094) (xy 84.026965 -143.987991) (xy 84.08489 -143.97247) (xy 84.144346 -143.964642)
			(xy 84.204314 -143.964642) (xy 84.26377 -143.97247) (xy 84.321695 -143.987991) (xy 84.377099 -144.01094)
			(xy 84.429033 -144.040924) (xy 84.476609 -144.07743) (xy 84.519014 -144.119835) (xy 84.55552 -144.167411)
			(xy 84.585504 -144.219345) (xy 84.608453 -144.274749) (xy 84.623974 -144.332674) (xy 84.631802 -144.39213)
			(xy 84.632292 -144.422114) (xy 84.632292 -145.285714) (xy 84.632267 -145.287238) (xy 180.84546 -145.287238)
			(xy 180.84546 -144.423638) (xy 180.84595 -144.39367) (xy 180.853773 -144.334248) (xy 180.869286 -144.276355)
			(xy 180.892222 -144.220982) (xy 180.922189 -144.169076) (xy 180.958676 -144.121526) (xy 181.001056 -144.079146)
			(xy 181.048606 -144.042659) (xy 181.100512 -144.012692) (xy 181.155885 -143.989756) (xy 181.213778 -143.974243)
			(xy 181.2732 -143.96642) (xy 181.333136 -143.96642) (xy 181.392558 -143.974243) (xy 181.450451 -143.989756)
			(xy 181.505824 -144.012692) (xy 181.55773 -144.042659) (xy 181.60528 -144.079146) (xy 181.64766 -144.121526)
			(xy 181.684147 -144.169076) (xy 181.714114 -144.220982) (xy 181.73705 -144.276355) (xy 181.752563 -144.334248)
			(xy 181.760386 -144.39367) (xy 181.760876 -144.423638) (xy 181.760876 -145.285714) (xy 199.81672 -145.285714)
			(xy 199.81672 -144.422114) (xy 199.81721 -144.392146) (xy 199.825033 -144.332724) (xy 199.840546 -144.274831)
			(xy 199.863482 -144.219458) (xy 199.893449 -144.167552) (xy 199.929936 -144.120002) (xy 199.972316 -144.077622)
			(xy 200.019866 -144.041135) (xy 200.071772 -144.011168) (xy 200.127145 -143.988232) (xy 200.185038 -143.972719)
			(xy 200.24446 -143.964896) (xy 200.304396 -143.964896) (xy 200.363818 -143.972719) (xy 200.421711 -143.988232)
			(xy 200.477084 -144.011168) (xy 200.52899 -144.041135) (xy 200.57654 -144.077622) (xy 200.61892 -144.120002)
			(xy 200.655407 -144.167552) (xy 200.685374 -144.219458) (xy 200.70831 -144.274831) (xy 200.723823 -144.332724)
			(xy 200.731646 -144.392146) (xy 200.732136 -144.422114) (xy 200.732136 -145.285714) (xy 200.732111 -145.287238)
			(xy 296.945304 -145.287238) (xy 296.945304 -144.423638) (xy 296.945794 -144.39367) (xy 296.953617 -144.334248)
			(xy 296.96913 -144.276355) (xy 296.992066 -144.220982) (xy 297.022033 -144.169076) (xy 297.05852 -144.121526)
			(xy 297.1009 -144.079146) (xy 297.14845 -144.042659) (xy 297.200356 -144.012692) (xy 297.255729 -143.989756)
			(xy 297.313622 -143.974243) (xy 297.373044 -143.96642) (xy 297.43298 -143.96642) (xy 297.492402 -143.974243)
			(xy 297.550295 -143.989756) (xy 297.605668 -144.012692) (xy 297.657574 -144.042659) (xy 297.705124 -144.079146)
			(xy 297.747504 -144.121526) (xy 297.783991 -144.169076) (xy 297.813958 -144.220982) (xy 297.836894 -144.276355)
			(xy 297.852407 -144.334248) (xy 297.86023 -144.39367) (xy 297.86072 -144.423638) (xy 297.86072 -145.285714)
			(xy 315.916564 -145.285714) (xy 315.916564 -144.422114) (xy 315.917054 -144.392146) (xy 315.924877 -144.332724)
			(xy 315.94039 -144.274831) (xy 315.963326 -144.219458) (xy 315.993293 -144.167552) (xy 316.02978 -144.120002)
			(xy 316.07216 -144.077622) (xy 316.11971 -144.041135) (xy 316.171616 -144.011168) (xy 316.226989 -143.988232)
			(xy 316.284882 -143.972719) (xy 316.344304 -143.964896) (xy 316.40424 -143.964896) (xy 316.463662 -143.972719)
			(xy 316.521555 -143.988232) (xy 316.576928 -144.011168) (xy 316.628834 -144.041135) (xy 316.676384 -144.077622)
			(xy 316.718764 -144.120002) (xy 316.755251 -144.167552) (xy 316.785218 -144.219458) (xy 316.808154 -144.274831)
			(xy 316.823667 -144.332724) (xy 316.83149 -144.392146) (xy 316.83198 -144.422114) (xy 316.83198 -145.285714)
			(xy 316.831955 -145.287238) (xy 413.045148 -145.287238) (xy 413.045148 -144.423638) (xy 413.045638 -144.393654)
			(xy 413.053466 -144.334198) (xy 413.068987 -144.276273) (xy 413.091936 -144.220869) (xy 413.12192 -144.168935)
			(xy 413.158426 -144.121359) (xy 413.200831 -144.078954) (xy 413.248407 -144.042448) (xy 413.300341 -144.012464)
			(xy 413.355745 -143.989515) (xy 413.41367 -143.973994) (xy 413.473126 -143.966166) (xy 413.533094 -143.966166)
			(xy 413.59255 -143.973994) (xy 413.650475 -143.989515) (xy 413.705879 -144.012464) (xy 413.757813 -144.042448)
			(xy 413.805389 -144.078954) (xy 413.847794 -144.121359) (xy 413.8843 -144.168935) (xy 413.914284 -144.220869)
			(xy 413.937233 -144.276273) (xy 413.952754 -144.334198) (xy 413.960582 -144.393654) (xy 413.961072 -144.423638)
			(xy 413.961072 -145.285714) (xy 432.016408 -145.285714) (xy 432.016408 -144.422114) (xy 432.016898 -144.39213)
			(xy 432.024726 -144.332674) (xy 432.040247 -144.274749) (xy 432.063196 -144.219345) (xy 432.09318 -144.167411)
			(xy 432.129686 -144.119835) (xy 432.172091 -144.07743) (xy 432.219667 -144.040924) (xy 432.271601 -144.01094)
			(xy 432.327005 -143.987991) (xy 432.38493 -143.97247) (xy 432.444386 -143.964642) (xy 432.504354 -143.964642)
			(xy 432.56381 -143.97247) (xy 432.621735 -143.987991) (xy 432.677139 -144.01094) (xy 432.729073 -144.040924)
			(xy 432.776649 -144.07743) (xy 432.819054 -144.119835) (xy 432.85556 -144.167411) (xy 432.885544 -144.219345)
			(xy 432.908493 -144.274749) (xy 432.924014 -144.332674) (xy 432.931842 -144.39213) (xy 432.932332 -144.422114)
			(xy 432.932332 -145.285714) (xy 432.931842 -145.315698) (xy 432.924014 -145.375154) (xy 432.908493 -145.433079)
			(xy 432.885544 -145.488483) (xy 432.85556 -145.540417) (xy 432.819054 -145.587993) (xy 432.776649 -145.630398)
			(xy 432.729073 -145.666904) (xy 432.677139 -145.696888) (xy 432.621735 -145.719837) (xy 432.56381 -145.735358)
			(xy 432.504354 -145.743186) (xy 432.444386 -145.743186) (xy 432.38493 -145.735358) (xy 432.327005 -145.719837)
			(xy 432.271601 -145.696888) (xy 432.219667 -145.666904) (xy 432.172091 -145.630398) (xy 432.129686 -145.587993)
			(xy 432.09318 -145.540417) (xy 432.063196 -145.488483) (xy 432.040247 -145.433079) (xy 432.024726 -145.375154)
			(xy 432.016898 -145.315698) (xy 432.016408 -145.285714) (xy 413.961072 -145.285714) (xy 413.961072 -145.287238)
			(xy 413.960582 -145.317222) (xy 413.952754 -145.376678) (xy 413.937233 -145.434603) (xy 413.914284 -145.490007)
			(xy 413.8843 -145.541941) (xy 413.847794 -145.589517) (xy 413.805389 -145.631922) (xy 413.757813 -145.668428)
			(xy 413.705879 -145.698412) (xy 413.650475 -145.721361) (xy 413.59255 -145.736882) (xy 413.533094 -145.74471)
			(xy 413.473126 -145.74471) (xy 413.41367 -145.736882) (xy 413.355745 -145.721361) (xy 413.300341 -145.698412)
			(xy 413.248407 -145.668428) (xy 413.200831 -145.631922) (xy 413.158426 -145.589517) (xy 413.12192 -145.541941)
			(xy 413.091936 -145.490007) (xy 413.068987 -145.434603) (xy 413.053466 -145.376678) (xy 413.045638 -145.317222)
			(xy 413.045148 -145.287238) (xy 316.831955 -145.287238) (xy 316.83149 -145.315682) (xy 316.823667 -145.375104)
			(xy 316.808154 -145.432997) (xy 316.785218 -145.48837) (xy 316.755251 -145.540276) (xy 316.718764 -145.587826)
			(xy 316.676384 -145.630206) (xy 316.628834 -145.666693) (xy 316.576928 -145.69666) (xy 316.521555 -145.719596)
			(xy 316.463662 -145.735109) (xy 316.40424 -145.742932) (xy 316.344304 -145.742932) (xy 316.284882 -145.735109)
			(xy 316.226989 -145.719596) (xy 316.171616 -145.69666) (xy 316.11971 -145.666693) (xy 316.07216 -145.630206)
			(xy 316.02978 -145.587826) (xy 315.993293 -145.540276) (xy 315.963326 -145.48837) (xy 315.94039 -145.432997)
			(xy 315.924877 -145.375104) (xy 315.917054 -145.315682) (xy 315.916564 -145.285714) (xy 297.86072 -145.285714)
			(xy 297.86072 -145.287238) (xy 297.86023 -145.317206) (xy 297.852407 -145.376628) (xy 297.836894 -145.434521)
			(xy 297.813958 -145.489894) (xy 297.783991 -145.5418) (xy 297.747504 -145.58935) (xy 297.705124 -145.63173)
			(xy 297.657574 -145.668217) (xy 297.605668 -145.698184) (xy 297.550295 -145.72112) (xy 297.492402 -145.736633)
			(xy 297.43298 -145.744456) (xy 297.373044 -145.744456) (xy 297.313622 -145.736633) (xy 297.255729 -145.72112)
			(xy 297.200356 -145.698184) (xy 297.14845 -145.668217) (xy 297.1009 -145.63173) (xy 297.05852 -145.58935)
			(xy 297.022033 -145.5418) (xy 296.992066 -145.489894) (xy 296.96913 -145.434521) (xy 296.953617 -145.376628)
			(xy 296.945794 -145.317206) (xy 296.945304 -145.287238) (xy 200.732111 -145.287238) (xy 200.731646 -145.315682)
			(xy 200.723823 -145.375104) (xy 200.70831 -145.432997) (xy 200.685374 -145.48837) (xy 200.655407 -145.540276)
			(xy 200.61892 -145.587826) (xy 200.57654 -145.630206) (xy 200.52899 -145.666693) (xy 200.477084 -145.69666)
			(xy 200.421711 -145.719596) (xy 200.363818 -145.735109) (xy 200.304396 -145.742932) (xy 200.24446 -145.742932)
			(xy 200.185038 -145.735109) (xy 200.127145 -145.719596) (xy 200.071772 -145.69666) (xy 200.019866 -145.666693)
			(xy 199.972316 -145.630206) (xy 199.929936 -145.587826) (xy 199.893449 -145.540276) (xy 199.863482 -145.48837)
			(xy 199.840546 -145.432997) (xy 199.825033 -145.375104) (xy 199.81721 -145.315682) (xy 199.81672 -145.285714)
			(xy 181.760876 -145.285714) (xy 181.760876 -145.287238) (xy 181.760386 -145.317206) (xy 181.752563 -145.376628)
			(xy 181.73705 -145.434521) (xy 181.714114 -145.489894) (xy 181.684147 -145.5418) (xy 181.64766 -145.58935)
			(xy 181.60528 -145.63173) (xy 181.55773 -145.668217) (xy 181.505824 -145.698184) (xy 181.450451 -145.72112)
			(xy 181.392558 -145.736633) (xy 181.333136 -145.744456) (xy 181.2732 -145.744456) (xy 181.213778 -145.736633)
			(xy 181.155885 -145.72112) (xy 181.100512 -145.698184) (xy 181.048606 -145.668217) (xy 181.001056 -145.63173)
			(xy 180.958676 -145.58935) (xy 180.922189 -145.5418) (xy 180.892222 -145.489894) (xy 180.869286 -145.434521)
			(xy 180.853773 -145.376628) (xy 180.84595 -145.317206) (xy 180.84546 -145.287238) (xy 84.632267 -145.287238)
			(xy 84.631802 -145.315698) (xy 84.623974 -145.375154) (xy 84.608453 -145.433079) (xy 84.585504 -145.488483)
			(xy 84.55552 -145.540417) (xy 84.519014 -145.587993) (xy 84.476609 -145.630398) (xy 84.429033 -145.666904)
			(xy 84.377099 -145.696888) (xy 84.321695 -145.719837) (xy 84.26377 -145.735358) (xy 84.204314 -145.743186)
			(xy 84.144346 -145.743186) (xy 84.08489 -145.735358) (xy 84.026965 -145.719837) (xy 83.971561 -145.696888)
			(xy 83.919627 -145.666904) (xy 83.872051 -145.630398) (xy 83.829646 -145.587993) (xy 83.79314 -145.540417)
			(xy 83.763156 -145.488483) (xy 83.740207 -145.433079) (xy 83.724686 -145.375154) (xy 83.716858 -145.315698)
			(xy 83.716368 -145.285714) (xy 65.661032 -145.285714) (xy 65.661032 -145.287238) (xy 65.660542 -145.317222)
			(xy 65.652714 -145.376678) (xy 65.637193 -145.434603) (xy 65.614244 -145.490007) (xy 65.58426 -145.541941)
			(xy 65.547754 -145.589517) (xy 65.505349 -145.631922) (xy 65.457773 -145.668428) (xy 65.405839 -145.698412)
			(xy 65.350435 -145.721361) (xy 65.29251 -145.736882) (xy 65.233054 -145.74471) (xy 65.173086 -145.74471)
			(xy 65.11363 -145.736882) (xy 65.055705 -145.721361) (xy 65.000301 -145.698412) (xy 64.948367 -145.668428)
			(xy 64.900791 -145.631922) (xy 64.858386 -145.589517) (xy 64.82188 -145.541941) (xy 64.791896 -145.490007)
			(xy 64.768947 -145.434603) (xy 64.753426 -145.376678) (xy 64.745598 -145.317222) (xy 64.745108 -145.287238)
			(xy 5.324094 -145.287238) (xy 5.324094 -147.087336) (xy 66.599308 -147.087336) (xy 66.599308 -146.223736)
			(xy 66.599798 -146.193752) (xy 66.607626 -146.134296) (xy 66.623147 -146.076371) (xy 66.646096 -146.020967)
			(xy 66.67608 -145.969033) (xy 66.712586 -145.921457) (xy 66.754991 -145.879052) (xy 66.802567 -145.842546)
			(xy 66.854501 -145.812562) (xy 66.909905 -145.789613) (xy 66.96783 -145.774092) (xy 67.027286 -145.766264)
			(xy 67.087254 -145.766264) (xy 67.14671 -145.774092) (xy 67.204635 -145.789613) (xy 67.260039 -145.812562)
			(xy 67.311973 -145.842546) (xy 67.359549 -145.879052) (xy 67.401954 -145.921457) (xy 67.43846 -145.969033)
			(xy 67.468444 -146.020967) (xy 67.491393 -146.076371) (xy 67.506914 -146.134296) (xy 67.514742 -146.193752)
			(xy 67.515232 -146.223736) (xy 67.515232 -147.079208) (xy 81.07426 -147.079208) (xy 81.07426 -146.215608)
			(xy 81.07475 -146.185624) (xy 81.082578 -146.126168) (xy 81.098099 -146.068243) (xy 81.121048 -146.012839)
			(xy 81.151032 -145.960905) (xy 81.187538 -145.913329) (xy 81.229943 -145.870924) (xy 81.277519 -145.834418)
			(xy 81.329453 -145.804434) (xy 81.384857 -145.781485) (xy 81.442782 -145.765964) (xy 81.502238 -145.758136)
			(xy 81.562206 -145.758136) (xy 81.621662 -145.765964) (xy 81.679587 -145.781485) (xy 81.734991 -145.804434)
			(xy 81.786925 -145.834418) (xy 81.834501 -145.870924) (xy 81.876906 -145.913329) (xy 81.913412 -145.960905)
			(xy 81.943396 -146.012839) (xy 81.966345 -146.068243) (xy 81.981866 -146.126168) (xy 81.989694 -146.185624)
			(xy 81.990184 -146.215608) (xy 81.990184 -147.079208) (xy 81.990051 -147.087336) (xy 182.69966 -147.087336)
			(xy 182.69966 -146.223736) (xy 182.70015 -146.193768) (xy 182.707973 -146.134346) (xy 182.723486 -146.076453)
			(xy 182.746422 -146.02108) (xy 182.776389 -145.969174) (xy 182.812876 -145.921624) (xy 182.855256 -145.879244)
			(xy 182.902806 -145.842757) (xy 182.954712 -145.81279) (xy 183.010085 -145.789854) (xy 183.067978 -145.774341)
			(xy 183.1274 -145.766518) (xy 183.187336 -145.766518) (xy 183.246758 -145.774341) (xy 183.304651 -145.789854)
			(xy 183.360024 -145.81279) (xy 183.41193 -145.842757) (xy 183.45948 -145.879244) (xy 183.50186 -145.921624)
			(xy 183.538347 -145.969174) (xy 183.568314 -146.02108) (xy 183.59125 -146.076453) (xy 183.606763 -146.134346)
			(xy 183.614586 -146.193768) (xy 183.615076 -146.223736) (xy 183.615076 -147.079208) (xy 197.174612 -147.079208)
			(xy 197.174612 -146.215608) (xy 197.175102 -146.18564) (xy 197.182925 -146.126218) (xy 197.198438 -146.068325)
			(xy 197.221374 -146.012952) (xy 197.251341 -145.961046) (xy 197.287828 -145.913496) (xy 197.330208 -145.871116)
			(xy 197.377758 -145.834629) (xy 197.429664 -145.804662) (xy 197.485037 -145.781726) (xy 197.54293 -145.766213)
			(xy 197.602352 -145.75839) (xy 197.662288 -145.75839) (xy 197.72171 -145.766213) (xy 197.779603 -145.781726)
			(xy 197.834976 -145.804662) (xy 197.886882 -145.834629) (xy 197.934432 -145.871116) (xy 197.976812 -145.913496)
			(xy 198.013299 -145.961046) (xy 198.043266 -146.012952) (xy 198.066202 -146.068325) (xy 198.081715 -146.126218)
			(xy 198.089538 -146.18564) (xy 198.090028 -146.215608) (xy 198.090028 -147.079208) (xy 198.089895 -147.087336)
			(xy 298.799504 -147.087336) (xy 298.799504 -146.223736) (xy 298.799994 -146.193768) (xy 298.807817 -146.134346)
			(xy 298.82333 -146.076453) (xy 298.846266 -146.02108) (xy 298.876233 -145.969174) (xy 298.91272 -145.921624)
			(xy 298.9551 -145.879244) (xy 299.00265 -145.842757) (xy 299.054556 -145.81279) (xy 299.109929 -145.789854)
			(xy 299.167822 -145.774341) (xy 299.227244 -145.766518) (xy 299.28718 -145.766518) (xy 299.346602 -145.774341)
			(xy 299.404495 -145.789854) (xy 299.459868 -145.81279) (xy 299.511774 -145.842757) (xy 299.559324 -145.879244)
			(xy 299.601704 -145.921624) (xy 299.638191 -145.969174) (xy 299.668158 -146.02108) (xy 299.691094 -146.076453)
			(xy 299.706607 -146.134346) (xy 299.71443 -146.193768) (xy 299.71492 -146.223736) (xy 299.71492 -147.079208)
			(xy 313.274456 -147.079208) (xy 313.274456 -146.215608) (xy 313.274946 -146.18564) (xy 313.282769 -146.126218)
			(xy 313.298282 -146.068325) (xy 313.321218 -146.012952) (xy 313.351185 -145.961046) (xy 313.387672 -145.913496)
			(xy 313.430052 -145.871116) (xy 313.477602 -145.834629) (xy 313.529508 -145.804662) (xy 313.584881 -145.781726)
			(xy 313.642774 -145.766213) (xy 313.702196 -145.75839) (xy 313.762132 -145.75839) (xy 313.821554 -145.766213)
			(xy 313.879447 -145.781726) (xy 313.93482 -145.804662) (xy 313.986726 -145.834629) (xy 314.034276 -145.871116)
			(xy 314.076656 -145.913496) (xy 314.113143 -145.961046) (xy 314.14311 -146.012952) (xy 314.166046 -146.068325)
			(xy 314.181559 -146.126218) (xy 314.189382 -146.18564) (xy 314.189872 -146.215608) (xy 314.189872 -147.079208)
			(xy 314.189739 -147.087336) (xy 414.899348 -147.087336) (xy 414.899348 -146.223736) (xy 414.899838 -146.193752)
			(xy 414.907666 -146.134296) (xy 414.923187 -146.076371) (xy 414.946136 -146.020967) (xy 414.97612 -145.969033)
			(xy 415.012626 -145.921457) (xy 415.055031 -145.879052) (xy 415.102607 -145.842546) (xy 415.154541 -145.812562)
			(xy 415.209945 -145.789613) (xy 415.26787 -145.774092) (xy 415.327326 -145.766264) (xy 415.387294 -145.766264)
			(xy 415.44675 -145.774092) (xy 415.504675 -145.789613) (xy 415.560079 -145.812562) (xy 415.612013 -145.842546)
			(xy 415.659589 -145.879052) (xy 415.701994 -145.921457) (xy 415.7385 -145.969033) (xy 415.768484 -146.020967)
			(xy 415.791433 -146.076371) (xy 415.806954 -146.134296) (xy 415.814782 -146.193752) (xy 415.815272 -146.223736)
			(xy 415.815272 -147.079208) (xy 429.3743 -147.079208) (xy 429.3743 -146.215608) (xy 429.37479 -146.185624)
			(xy 429.382618 -146.126168) (xy 429.398139 -146.068243) (xy 429.421088 -146.012839) (xy 429.451072 -145.960905)
			(xy 429.487578 -145.913329) (xy 429.529983 -145.870924) (xy 429.577559 -145.834418) (xy 429.629493 -145.804434)
			(xy 429.684897 -145.781485) (xy 429.742822 -145.765964) (xy 429.802278 -145.758136) (xy 429.862246 -145.758136)
			(xy 429.921702 -145.765964) (xy 429.979627 -145.781485) (xy 430.035031 -145.804434) (xy 430.086965 -145.834418)
			(xy 430.134541 -145.870924) (xy 430.176946 -145.913329) (xy 430.213452 -145.960905) (xy 430.243436 -146.012839)
			(xy 430.266385 -146.068243) (xy 430.281906 -146.126168) (xy 430.289734 -146.185624) (xy 430.290224 -146.215608)
			(xy 430.290224 -147.079208) (xy 430.289734 -147.109192) (xy 430.281906 -147.168648) (xy 430.266385 -147.226573)
			(xy 430.243436 -147.281977) (xy 430.213452 -147.333911) (xy 430.176946 -147.381487) (xy 430.134541 -147.423892)
			(xy 430.086965 -147.460398) (xy 430.035031 -147.490382) (xy 429.979627 -147.513331) (xy 429.921702 -147.528852)
			(xy 429.862246 -147.53668) (xy 429.802278 -147.53668) (xy 429.742822 -147.528852) (xy 429.684897 -147.513331)
			(xy 429.629493 -147.490382) (xy 429.577559 -147.460398) (xy 429.529983 -147.423892) (xy 429.487578 -147.381487)
			(xy 429.451072 -147.333911) (xy 429.421088 -147.281977) (xy 429.398139 -147.226573) (xy 429.382618 -147.168648)
			(xy 429.37479 -147.109192) (xy 429.3743 -147.079208) (xy 415.815272 -147.079208) (xy 415.815272 -147.087336)
			(xy 415.814782 -147.11732) (xy 415.806954 -147.176776) (xy 415.791433 -147.234701) (xy 415.768484 -147.290105)
			(xy 415.7385 -147.342039) (xy 415.701994 -147.389615) (xy 415.659589 -147.43202) (xy 415.612013 -147.468526)
			(xy 415.560079 -147.49851) (xy 415.504675 -147.521459) (xy 415.44675 -147.53698) (xy 415.387294 -147.544808)
			(xy 415.327326 -147.544808) (xy 415.26787 -147.53698) (xy 415.209945 -147.521459) (xy 415.154541 -147.49851)
			(xy 415.102607 -147.468526) (xy 415.055031 -147.43202) (xy 415.012626 -147.389615) (xy 414.97612 -147.342039)
			(xy 414.946136 -147.290105) (xy 414.923187 -147.234701) (xy 414.907666 -147.176776) (xy 414.899838 -147.11732)
			(xy 414.899348 -147.087336) (xy 314.189739 -147.087336) (xy 314.189382 -147.109176) (xy 314.181559 -147.168598)
			(xy 314.166046 -147.226491) (xy 314.14311 -147.281864) (xy 314.113143 -147.33377) (xy 314.076656 -147.38132)
			(xy 314.034276 -147.4237) (xy 313.986726 -147.460187) (xy 313.93482 -147.490154) (xy 313.879447 -147.51309)
			(xy 313.821554 -147.528603) (xy 313.762132 -147.536426) (xy 313.702196 -147.536426) (xy 313.642774 -147.528603)
			(xy 313.584881 -147.51309) (xy 313.529508 -147.490154) (xy 313.477602 -147.460187) (xy 313.430052 -147.4237)
			(xy 313.387672 -147.38132) (xy 313.351185 -147.33377) (xy 313.321218 -147.281864) (xy 313.298282 -147.226491)
			(xy 313.282769 -147.168598) (xy 313.274946 -147.109176) (xy 313.274456 -147.079208) (xy 299.71492 -147.079208)
			(xy 299.71492 -147.087336) (xy 299.71443 -147.117304) (xy 299.706607 -147.176726) (xy 299.691094 -147.234619)
			(xy 299.668158 -147.289992) (xy 299.638191 -147.341898) (xy 299.601704 -147.389448) (xy 299.559324 -147.431828)
			(xy 299.511774 -147.468315) (xy 299.459868 -147.498282) (xy 299.404495 -147.521218) (xy 299.346602 -147.536731)
			(xy 299.28718 -147.544554) (xy 299.227244 -147.544554) (xy 299.167822 -147.536731) (xy 299.109929 -147.521218)
			(xy 299.054556 -147.498282) (xy 299.00265 -147.468315) (xy 298.9551 -147.431828) (xy 298.91272 -147.389448)
			(xy 298.876233 -147.341898) (xy 298.846266 -147.289992) (xy 298.82333 -147.234619) (xy 298.807817 -147.176726)
			(xy 298.799994 -147.117304) (xy 298.799504 -147.087336) (xy 198.089895 -147.087336) (xy 198.089538 -147.109176)
			(xy 198.081715 -147.168598) (xy 198.066202 -147.226491) (xy 198.043266 -147.281864) (xy 198.013299 -147.33377)
			(xy 197.976812 -147.38132) (xy 197.934432 -147.4237) (xy 197.886882 -147.460187) (xy 197.834976 -147.490154)
			(xy 197.779603 -147.51309) (xy 197.72171 -147.528603) (xy 197.662288 -147.536426) (xy 197.602352 -147.536426)
			(xy 197.54293 -147.528603) (xy 197.485037 -147.51309) (xy 197.429664 -147.490154) (xy 197.377758 -147.460187)
			(xy 197.330208 -147.4237) (xy 197.287828 -147.38132) (xy 197.251341 -147.33377) (xy 197.221374 -147.281864)
			(xy 197.198438 -147.226491) (xy 197.182925 -147.168598) (xy 197.175102 -147.109176) (xy 197.174612 -147.079208)
			(xy 183.615076 -147.079208) (xy 183.615076 -147.087336) (xy 183.614586 -147.117304) (xy 183.606763 -147.176726)
			(xy 183.59125 -147.234619) (xy 183.568314 -147.289992) (xy 183.538347 -147.341898) (xy 183.50186 -147.389448)
			(xy 183.45948 -147.431828) (xy 183.41193 -147.468315) (xy 183.360024 -147.498282) (xy 183.304651 -147.521218)
			(xy 183.246758 -147.536731) (xy 183.187336 -147.544554) (xy 183.1274 -147.544554) (xy 183.067978 -147.536731)
			(xy 183.010085 -147.521218) (xy 182.954712 -147.498282) (xy 182.902806 -147.468315) (xy 182.855256 -147.431828)
			(xy 182.812876 -147.389448) (xy 182.776389 -147.341898) (xy 182.746422 -147.289992) (xy 182.723486 -147.234619)
			(xy 182.707973 -147.176726) (xy 182.70015 -147.117304) (xy 182.69966 -147.087336) (xy 81.990051 -147.087336)
			(xy 81.989694 -147.109192) (xy 81.981866 -147.168648) (xy 81.966345 -147.226573) (xy 81.943396 -147.281977)
			(xy 81.913412 -147.333911) (xy 81.876906 -147.381487) (xy 81.834501 -147.423892) (xy 81.786925 -147.460398)
			(xy 81.734991 -147.490382) (xy 81.679587 -147.513331) (xy 81.621662 -147.528852) (xy 81.562206 -147.53668)
			(xy 81.502238 -147.53668) (xy 81.442782 -147.528852) (xy 81.384857 -147.513331) (xy 81.329453 -147.490382)
			(xy 81.277519 -147.460398) (xy 81.229943 -147.423892) (xy 81.187538 -147.381487) (xy 81.151032 -147.333911)
			(xy 81.121048 -147.281977) (xy 81.098099 -147.226573) (xy 81.082578 -147.168648) (xy 81.07475 -147.109192)
			(xy 81.07426 -147.079208) (xy 67.515232 -147.079208) (xy 67.515232 -147.087336) (xy 67.514742 -147.11732)
			(xy 67.506914 -147.176776) (xy 67.491393 -147.234701) (xy 67.468444 -147.290105) (xy 67.43846 -147.342039)
			(xy 67.401954 -147.389615) (xy 67.359549 -147.43202) (xy 67.311973 -147.468526) (xy 67.260039 -147.49851)
			(xy 67.204635 -147.521459) (xy 67.14671 -147.53698) (xy 67.087254 -147.544808) (xy 67.027286 -147.544808)
			(xy 66.96783 -147.53698) (xy 66.909905 -147.521459) (xy 66.854501 -147.49851) (xy 66.802567 -147.468526)
			(xy 66.754991 -147.43202) (xy 66.712586 -147.389615) (xy 66.67608 -147.342039) (xy 66.646096 -147.290105)
			(xy 66.623147 -147.234701) (xy 66.607626 -147.176776) (xy 66.599798 -147.11732) (xy 66.599308 -147.087336)
			(xy 5.324094 -147.087336) (xy 5.324094 -148.887434) (xy 64.745108 -148.887434) (xy 64.745108 -148.023834)
			(xy 64.745598 -147.99385) (xy 64.753426 -147.934394) (xy 64.768947 -147.876469) (xy 64.791896 -147.821065)
			(xy 64.82188 -147.769131) (xy 64.858386 -147.721555) (xy 64.900791 -147.67915) (xy 64.948367 -147.642644)
			(xy 65.000301 -147.61266) (xy 65.055705 -147.589711) (xy 65.11363 -147.57419) (xy 65.173086 -147.566362)
			(xy 65.233054 -147.566362) (xy 65.29251 -147.57419) (xy 65.350435 -147.589711) (xy 65.405839 -147.61266)
			(xy 65.457773 -147.642644) (xy 65.505349 -147.67915) (xy 65.547754 -147.721555) (xy 65.58426 -147.769131)
			(xy 65.614244 -147.821065) (xy 65.637193 -147.876469) (xy 65.652714 -147.934394) (xy 65.660542 -147.99385)
			(xy 65.661032 -148.023834) (xy 65.661032 -148.88591) (xy 83.716368 -148.88591) (xy 83.716368 -148.02231)
			(xy 83.716858 -147.992326) (xy 83.724686 -147.93287) (xy 83.740207 -147.874945) (xy 83.763156 -147.819541)
			(xy 83.79314 -147.767607) (xy 83.829646 -147.720031) (xy 83.872051 -147.677626) (xy 83.919627 -147.64112)
			(xy 83.971561 -147.611136) (xy 84.026965 -147.588187) (xy 84.08489 -147.572666) (xy 84.144346 -147.564838)
			(xy 84.204314 -147.564838) (xy 84.26377 -147.572666) (xy 84.321695 -147.588187) (xy 84.377099 -147.611136)
			(xy 84.429033 -147.64112) (xy 84.476609 -147.677626) (xy 84.519014 -147.720031) (xy 84.55552 -147.767607)
			(xy 84.585504 -147.819541) (xy 84.608453 -147.874945) (xy 84.623974 -147.93287) (xy 84.631802 -147.992326)
			(xy 84.632292 -148.02231) (xy 84.632292 -148.88591) (xy 84.632267 -148.887434) (xy 180.84546 -148.887434)
			(xy 180.84546 -148.023834) (xy 180.84595 -147.993866) (xy 180.853773 -147.934444) (xy 180.869286 -147.876551)
			(xy 180.892222 -147.821178) (xy 180.922189 -147.769272) (xy 180.958676 -147.721722) (xy 181.001056 -147.679342)
			(xy 181.048606 -147.642855) (xy 181.100512 -147.612888) (xy 181.155885 -147.589952) (xy 181.213778 -147.574439)
			(xy 181.2732 -147.566616) (xy 181.333136 -147.566616) (xy 181.392558 -147.574439) (xy 181.450451 -147.589952)
			(xy 181.505824 -147.612888) (xy 181.55773 -147.642855) (xy 181.60528 -147.679342) (xy 181.64766 -147.721722)
			(xy 181.684147 -147.769272) (xy 181.714114 -147.821178) (xy 181.73705 -147.876551) (xy 181.752563 -147.934444)
			(xy 181.760386 -147.993866) (xy 181.760876 -148.023834) (xy 181.760876 -148.88591) (xy 199.81672 -148.88591)
			(xy 199.81672 -148.02231) (xy 199.81721 -147.992342) (xy 199.825033 -147.93292) (xy 199.840546 -147.875027)
			(xy 199.863482 -147.819654) (xy 199.893449 -147.767748) (xy 199.929936 -147.720198) (xy 199.972316 -147.677818)
			(xy 200.019866 -147.641331) (xy 200.071772 -147.611364) (xy 200.127145 -147.588428) (xy 200.185038 -147.572915)
			(xy 200.24446 -147.565092) (xy 200.304396 -147.565092) (xy 200.363818 -147.572915) (xy 200.421711 -147.588428)
			(xy 200.477084 -147.611364) (xy 200.52899 -147.641331) (xy 200.57654 -147.677818) (xy 200.61892 -147.720198)
			(xy 200.655407 -147.767748) (xy 200.685374 -147.819654) (xy 200.70831 -147.875027) (xy 200.723823 -147.93292)
			(xy 200.731646 -147.992342) (xy 200.732136 -148.02231) (xy 200.732136 -148.88591) (xy 200.731646 -148.915878)
			(xy 200.723823 -148.9753) (xy 200.70831 -149.033193) (xy 200.685374 -149.088566) (xy 200.655407 -149.140472)
			(xy 200.61892 -149.188022) (xy 200.57654 -149.230402) (xy 200.52899 -149.266889) (xy 200.477084 -149.296856)
			(xy 200.421711 -149.319792) (xy 200.363818 -149.335305) (xy 200.304396 -149.343128) (xy 200.24446 -149.343128)
			(xy 200.185038 -149.335305) (xy 200.127145 -149.319792) (xy 200.071772 -149.296856) (xy 200.019866 -149.266889)
			(xy 199.972316 -149.230402) (xy 199.929936 -149.188022) (xy 199.893449 -149.140472) (xy 199.863482 -149.088566)
			(xy 199.840546 -149.033193) (xy 199.825033 -148.9753) (xy 199.81721 -148.915878) (xy 199.81672 -148.88591)
			(xy 181.760876 -148.88591) (xy 181.760876 -148.887434) (xy 181.760386 -148.917402) (xy 181.752563 -148.976824)
			(xy 181.73705 -149.034717) (xy 181.714114 -149.09009) (xy 181.684147 -149.141996) (xy 181.64766 -149.189546)
			(xy 181.60528 -149.231926) (xy 181.55773 -149.268413) (xy 181.505824 -149.29838) (xy 181.450451 -149.321316)
			(xy 181.392558 -149.336829) (xy 181.333136 -149.344652) (xy 181.2732 -149.344652) (xy 181.213778 -149.336829)
			(xy 181.155885 -149.321316) (xy 181.100512 -149.29838) (xy 181.048606 -149.268413) (xy 181.001056 -149.231926)
			(xy 180.958676 -149.189546) (xy 180.922189 -149.141996) (xy 180.892222 -149.09009) (xy 180.869286 -149.034717)
			(xy 180.853773 -148.976824) (xy 180.84595 -148.917402) (xy 180.84546 -148.887434) (xy 84.632267 -148.887434)
			(xy 84.631802 -148.915894) (xy 84.623974 -148.97535) (xy 84.608453 -149.033275) (xy 84.585504 -149.088679)
			(xy 84.55552 -149.140613) (xy 84.519014 -149.188189) (xy 84.476609 -149.230594) (xy 84.429033 -149.2671)
			(xy 84.377099 -149.297084) (xy 84.321695 -149.320033) (xy 84.26377 -149.335554) (xy 84.204314 -149.343382)
			(xy 84.144346 -149.343382) (xy 84.08489 -149.335554) (xy 84.026965 -149.320033) (xy 83.971561 -149.297084)
			(xy 83.919627 -149.2671) (xy 83.872051 -149.230594) (xy 83.829646 -149.188189) (xy 83.79314 -149.140613)
			(xy 83.763156 -149.088679) (xy 83.740207 -149.033275) (xy 83.724686 -148.97535) (xy 83.716858 -148.915894)
			(xy 83.716368 -148.88591) (xy 65.661032 -148.88591) (xy 65.661032 -148.887434) (xy 65.660542 -148.917418)
			(xy 65.652714 -148.976874) (xy 65.637193 -149.034799) (xy 65.614244 -149.090203) (xy 65.58426 -149.142137)
			(xy 65.547754 -149.189713) (xy 65.505349 -149.232118) (xy 65.457773 -149.268624) (xy 65.405839 -149.298608)
			(xy 65.350435 -149.321557) (xy 65.29251 -149.337078) (xy 65.233054 -149.344906) (xy 65.173086 -149.344906)
			(xy 65.11363 -149.337078) (xy 65.055705 -149.321557) (xy 65.000301 -149.298608) (xy 64.948367 -149.268624)
			(xy 64.900791 -149.232118) (xy 64.858386 -149.189713) (xy 64.82188 -149.142137) (xy 64.791896 -149.090203)
			(xy 64.768947 -149.034799) (xy 64.753426 -148.976874) (xy 64.745598 -148.917418) (xy 64.745108 -148.887434)
			(xy 5.324094 -148.887434) (xy 5.324094 -150.687278) (xy 66.599308 -150.687278) (xy 66.599308 -149.823678)
			(xy 66.599798 -149.793694) (xy 66.607626 -149.734238) (xy 66.623147 -149.676313) (xy 66.646096 -149.620909)
			(xy 66.67608 -149.568975) (xy 66.712586 -149.521399) (xy 66.754991 -149.478994) (xy 66.802567 -149.442488)
			(xy 66.854501 -149.412504) (xy 66.909905 -149.389555) (xy 66.96783 -149.374034) (xy 67.027286 -149.366206)
			(xy 67.087254 -149.366206) (xy 67.14671 -149.374034) (xy 67.204635 -149.389555) (xy 67.260039 -149.412504)
			(xy 67.311973 -149.442488) (xy 67.359549 -149.478994) (xy 67.401954 -149.521399) (xy 67.43846 -149.568975)
			(xy 67.468444 -149.620909) (xy 67.491393 -149.676313) (xy 67.506914 -149.734238) (xy 67.514742 -149.793694)
			(xy 67.515232 -149.823678) (xy 67.515232 -150.67915) (xy 81.07426 -150.67915) (xy 81.07426 -149.81555)
			(xy 81.07475 -149.785566) (xy 81.082578 -149.72611) (xy 81.098099 -149.668185) (xy 81.121048 -149.612781)
			(xy 81.151032 -149.560847) (xy 81.187538 -149.513271) (xy 81.229943 -149.470866) (xy 81.277519 -149.43436)
			(xy 81.329453 -149.404376) (xy 81.384857 -149.381427) (xy 81.442782 -149.365906) (xy 81.502238 -149.358078)
			(xy 81.562206 -149.358078) (xy 81.621662 -149.365906) (xy 81.679587 -149.381427) (xy 81.734991 -149.404376)
			(xy 81.786925 -149.43436) (xy 81.834501 -149.470866) (xy 81.876906 -149.513271) (xy 81.913412 -149.560847)
			(xy 81.943396 -149.612781) (xy 81.966345 -149.668185) (xy 81.981866 -149.72611) (xy 81.989694 -149.785566)
			(xy 81.990184 -149.81555) (xy 81.990184 -150.67915) (xy 81.990051 -150.687278) (xy 182.69966 -150.687278)
			(xy 182.69966 -149.823678) (xy 182.70015 -149.79371) (xy 182.707973 -149.734288) (xy 182.723486 -149.676395)
			(xy 182.746422 -149.621022) (xy 182.776389 -149.569116) (xy 182.812876 -149.521566) (xy 182.855256 -149.479186)
			(xy 182.902806 -149.442699) (xy 182.954712 -149.412732) (xy 183.010085 -149.389796) (xy 183.067978 -149.374283)
			(xy 183.1274 -149.36646) (xy 183.187336 -149.36646) (xy 183.246758 -149.374283) (xy 183.304651 -149.389796)
			(xy 183.360024 -149.412732) (xy 183.41193 -149.442699) (xy 183.45948 -149.479186) (xy 183.50186 -149.521566)
			(xy 183.538347 -149.569116) (xy 183.568314 -149.621022) (xy 183.59125 -149.676395) (xy 183.606763 -149.734288)
			(xy 183.614586 -149.79371) (xy 183.615076 -149.823678) (xy 183.615076 -150.67915) (xy 197.174612 -150.67915)
			(xy 197.174612 -149.81555) (xy 197.175102 -149.785582) (xy 197.182925 -149.72616) (xy 197.198438 -149.668267)
			(xy 197.221374 -149.612894) (xy 197.251341 -149.560988) (xy 197.287828 -149.513438) (xy 197.330208 -149.471058)
			(xy 197.377758 -149.434571) (xy 197.429664 -149.404604) (xy 197.485037 -149.381668) (xy 197.54293 -149.366155)
			(xy 197.602352 -149.358332) (xy 197.662288 -149.358332) (xy 197.72171 -149.366155) (xy 197.779603 -149.381668)
			(xy 197.834976 -149.404604) (xy 197.886882 -149.434571) (xy 197.934432 -149.471058) (xy 197.976812 -149.513438)
			(xy 198.013299 -149.560988) (xy 198.043266 -149.612894) (xy 198.066202 -149.668267) (xy 198.072386 -149.691344)
			(xy 236.708188 -149.691344) (xy 236.708188 -148.827744) (xy 236.708678 -148.79776) (xy 236.716506 -148.738304)
			(xy 236.732027 -148.680379) (xy 236.754976 -148.624975) (xy 236.78496 -148.573041) (xy 236.821466 -148.525465)
			(xy 236.863871 -148.48306) (xy 236.911447 -148.446554) (xy 236.963381 -148.41657) (xy 237.018785 -148.393621)
			(xy 237.07671 -148.3781) (xy 237.136166 -148.370272) (xy 237.196134 -148.370272) (xy 237.25559 -148.3781)
			(xy 237.313515 -148.393621) (xy 237.368919 -148.41657) (xy 237.420853 -148.446554) (xy 237.468429 -148.48306)
			(xy 237.510834 -148.525465) (xy 237.54734 -148.573041) (xy 237.577324 -148.624975) (xy 237.600273 -148.680379)
			(xy 237.615794 -148.738304) (xy 237.623622 -148.79776) (xy 237.624112 -148.827744) (xy 237.624112 -148.887434)
			(xy 296.945304 -148.887434) (xy 296.945304 -148.023834) (xy 296.945794 -147.993866) (xy 296.953617 -147.934444)
			(xy 296.96913 -147.876551) (xy 296.992066 -147.821178) (xy 297.022033 -147.769272) (xy 297.05852 -147.721722)
			(xy 297.1009 -147.679342) (xy 297.14845 -147.642855) (xy 297.200356 -147.612888) (xy 297.255729 -147.589952)
			(xy 297.313622 -147.574439) (xy 297.373044 -147.566616) (xy 297.43298 -147.566616) (xy 297.492402 -147.574439)
			(xy 297.550295 -147.589952) (xy 297.605668 -147.612888) (xy 297.657574 -147.642855) (xy 297.705124 -147.679342)
			(xy 297.747504 -147.721722) (xy 297.783991 -147.769272) (xy 297.813958 -147.821178) (xy 297.836894 -147.876551)
			(xy 297.852407 -147.934444) (xy 297.86023 -147.993866) (xy 297.86072 -148.023834) (xy 297.86072 -148.88591)
			(xy 315.916564 -148.88591) (xy 315.916564 -148.02231) (xy 315.917054 -147.992342) (xy 315.924877 -147.93292)
			(xy 315.94039 -147.875027) (xy 315.963326 -147.819654) (xy 315.993293 -147.767748) (xy 316.02978 -147.720198)
			(xy 316.07216 -147.677818) (xy 316.11971 -147.641331) (xy 316.171616 -147.611364) (xy 316.226989 -147.588428)
			(xy 316.284882 -147.572915) (xy 316.344304 -147.565092) (xy 316.40424 -147.565092) (xy 316.463662 -147.572915)
			(xy 316.521555 -147.588428) (xy 316.576928 -147.611364) (xy 316.628834 -147.641331) (xy 316.676384 -147.677818)
			(xy 316.718764 -147.720198) (xy 316.755251 -147.767748) (xy 316.785218 -147.819654) (xy 316.808154 -147.875027)
			(xy 316.823667 -147.93292) (xy 316.83149 -147.992342) (xy 316.83198 -148.02231) (xy 316.83198 -148.88591)
			(xy 316.831955 -148.887434) (xy 413.045148 -148.887434) (xy 413.045148 -148.023834) (xy 413.045638 -147.99385)
			(xy 413.053466 -147.934394) (xy 413.068987 -147.876469) (xy 413.091936 -147.821065) (xy 413.12192 -147.769131)
			(xy 413.158426 -147.721555) (xy 413.200831 -147.67915) (xy 413.248407 -147.642644) (xy 413.300341 -147.61266)
			(xy 413.355745 -147.589711) (xy 413.41367 -147.57419) (xy 413.473126 -147.566362) (xy 413.533094 -147.566362)
			(xy 413.59255 -147.57419) (xy 413.650475 -147.589711) (xy 413.705879 -147.61266) (xy 413.757813 -147.642644)
			(xy 413.805389 -147.67915) (xy 413.847794 -147.721555) (xy 413.8843 -147.769131) (xy 413.914284 -147.821065)
			(xy 413.937233 -147.876469) (xy 413.952754 -147.934394) (xy 413.960582 -147.99385) (xy 413.961072 -148.023834)
			(xy 413.961072 -148.88591) (xy 432.016408 -148.88591) (xy 432.016408 -148.02231) (xy 432.016898 -147.992326)
			(xy 432.024726 -147.93287) (xy 432.040247 -147.874945) (xy 432.063196 -147.819541) (xy 432.09318 -147.767607)
			(xy 432.129686 -147.720031) (xy 432.172091 -147.677626) (xy 432.219667 -147.64112) (xy 432.271601 -147.611136)
			(xy 432.327005 -147.588187) (xy 432.38493 -147.572666) (xy 432.444386 -147.564838) (xy 432.504354 -147.564838)
			(xy 432.56381 -147.572666) (xy 432.621735 -147.588187) (xy 432.677139 -147.611136) (xy 432.729073 -147.64112)
			(xy 432.776649 -147.677626) (xy 432.819054 -147.720031) (xy 432.85556 -147.767607) (xy 432.885544 -147.819541)
			(xy 432.908493 -147.874945) (xy 432.924014 -147.93287) (xy 432.931842 -147.992326) (xy 432.932332 -148.02231)
			(xy 432.932332 -148.88591) (xy 432.931842 -148.915894) (xy 432.924014 -148.97535) (xy 432.908493 -149.033275)
			(xy 432.885544 -149.088679) (xy 432.85556 -149.140613) (xy 432.819054 -149.188189) (xy 432.776649 -149.230594)
			(xy 432.729073 -149.2671) (xy 432.677139 -149.297084) (xy 432.621735 -149.320033) (xy 432.56381 -149.335554)
			(xy 432.504354 -149.343382) (xy 432.444386 -149.343382) (xy 432.38493 -149.335554) (xy 432.327005 -149.320033)
			(xy 432.271601 -149.297084) (xy 432.219667 -149.2671) (xy 432.172091 -149.230594) (xy 432.129686 -149.188189)
			(xy 432.09318 -149.140613) (xy 432.063196 -149.088679) (xy 432.040247 -149.033275) (xy 432.024726 -148.97535)
			(xy 432.016898 -148.915894) (xy 432.016408 -148.88591) (xy 413.961072 -148.88591) (xy 413.961072 -148.887434)
			(xy 413.960582 -148.917418) (xy 413.952754 -148.976874) (xy 413.937233 -149.034799) (xy 413.914284 -149.090203)
			(xy 413.8843 -149.142137) (xy 413.847794 -149.189713) (xy 413.805389 -149.232118) (xy 413.757813 -149.268624)
			(xy 413.705879 -149.298608) (xy 413.650475 -149.321557) (xy 413.59255 -149.337078) (xy 413.533094 -149.344906)
			(xy 413.473126 -149.344906) (xy 413.41367 -149.337078) (xy 413.355745 -149.321557) (xy 413.300341 -149.298608)
			(xy 413.248407 -149.268624) (xy 413.200831 -149.232118) (xy 413.158426 -149.189713) (xy 413.12192 -149.142137)
			(xy 413.091936 -149.090203) (xy 413.068987 -149.034799) (xy 413.053466 -148.976874) (xy 413.045638 -148.917418)
			(xy 413.045148 -148.887434) (xy 316.831955 -148.887434) (xy 316.83149 -148.915878) (xy 316.823667 -148.9753)
			(xy 316.808154 -149.033193) (xy 316.785218 -149.088566) (xy 316.755251 -149.140472) (xy 316.718764 -149.188022)
			(xy 316.676384 -149.230402) (xy 316.628834 -149.266889) (xy 316.576928 -149.296856) (xy 316.521555 -149.319792)
			(xy 316.463662 -149.335305) (xy 316.40424 -149.343128) (xy 316.344304 -149.343128) (xy 316.284882 -149.335305)
			(xy 316.226989 -149.319792) (xy 316.171616 -149.296856) (xy 316.11971 -149.266889) (xy 316.07216 -149.230402)
			(xy 316.02978 -149.188022) (xy 315.993293 -149.140472) (xy 315.963326 -149.088566) (xy 315.94039 -149.033193)
			(xy 315.924877 -148.9753) (xy 315.917054 -148.915878) (xy 315.916564 -148.88591) (xy 297.86072 -148.88591)
			(xy 297.86072 -148.887434) (xy 297.86023 -148.917402) (xy 297.852407 -148.976824) (xy 297.836894 -149.034717)
			(xy 297.813958 -149.09009) (xy 297.783991 -149.141996) (xy 297.747504 -149.189546) (xy 297.705124 -149.231926)
			(xy 297.657574 -149.268413) (xy 297.605668 -149.29838) (xy 297.550295 -149.321316) (xy 297.492402 -149.336829)
			(xy 297.43298 -149.344652) (xy 297.373044 -149.344652) (xy 297.313622 -149.336829) (xy 297.255729 -149.321316)
			(xy 297.200356 -149.29838) (xy 297.14845 -149.268413) (xy 297.1009 -149.231926) (xy 297.05852 -149.189546)
			(xy 297.022033 -149.141996) (xy 296.992066 -149.09009) (xy 296.96913 -149.034717) (xy 296.953617 -148.976824)
			(xy 296.945794 -148.917402) (xy 296.945304 -148.887434) (xy 237.624112 -148.887434) (xy 237.624112 -149.691344)
			(xy 237.623622 -149.721328) (xy 237.615794 -149.780784) (xy 237.600273 -149.838709) (xy 237.577324 -149.894113)
			(xy 237.54734 -149.946047) (xy 237.510834 -149.993623) (xy 237.468429 -150.036028) (xy 237.420853 -150.072534)
			(xy 237.368919 -150.102518) (xy 237.313515 -150.125467) (xy 237.25559 -150.140988) (xy 237.196134 -150.148816)
			(xy 237.136166 -150.148816) (xy 237.07671 -150.140988) (xy 237.018785 -150.125467) (xy 236.963381 -150.102518)
			(xy 236.911447 -150.072534) (xy 236.863871 -150.036028) (xy 236.821466 -149.993623) (xy 236.78496 -149.946047)
			(xy 236.754976 -149.894113) (xy 236.732027 -149.838709) (xy 236.716506 -149.780784) (xy 236.708678 -149.721328)
			(xy 236.708188 -149.691344) (xy 198.072386 -149.691344) (xy 198.081715 -149.72616) (xy 198.089538 -149.785582)
			(xy 198.090028 -149.81555) (xy 198.090028 -150.67915) (xy 198.089538 -150.709118) (xy 198.081715 -150.76854)
			(xy 198.066202 -150.826433) (xy 198.043266 -150.881806) (xy 198.013299 -150.933712) (xy 197.976812 -150.981262)
			(xy 197.934432 -151.023642) (xy 197.886882 -151.060129) (xy 197.834976 -151.090096) (xy 197.779603 -151.113032)
			(xy 197.72171 -151.128545) (xy 197.662288 -151.136368) (xy 197.602352 -151.136368) (xy 197.54293 -151.128545)
			(xy 197.485037 -151.113032) (xy 197.429664 -151.090096) (xy 197.377758 -151.060129) (xy 197.330208 -151.023642)
			(xy 197.287828 -150.981262) (xy 197.251341 -150.933712) (xy 197.221374 -150.881806) (xy 197.198438 -150.826433)
			(xy 197.182925 -150.76854) (xy 197.175102 -150.709118) (xy 197.174612 -150.67915) (xy 183.615076 -150.67915)
			(xy 183.615076 -150.687278) (xy 183.614586 -150.717246) (xy 183.606763 -150.776668) (xy 183.59125 -150.834561)
			(xy 183.568314 -150.889934) (xy 183.538347 -150.94184) (xy 183.50186 -150.98939) (xy 183.45948 -151.03177)
			(xy 183.41193 -151.068257) (xy 183.360024 -151.098224) (xy 183.304651 -151.12116) (xy 183.246758 -151.136673)
			(xy 183.187336 -151.144496) (xy 183.1274 -151.144496) (xy 183.067978 -151.136673) (xy 183.010085 -151.12116)
			(xy 182.954712 -151.098224) (xy 182.902806 -151.068257) (xy 182.855256 -151.03177) (xy 182.812876 -150.98939)
			(xy 182.776389 -150.94184) (xy 182.746422 -150.889934) (xy 182.723486 -150.834561) (xy 182.707973 -150.776668)
			(xy 182.70015 -150.717246) (xy 182.69966 -150.687278) (xy 81.990051 -150.687278) (xy 81.989694 -150.709134)
			(xy 81.981866 -150.76859) (xy 81.966345 -150.826515) (xy 81.943396 -150.881919) (xy 81.913412 -150.933853)
			(xy 81.876906 -150.981429) (xy 81.834501 -151.023834) (xy 81.786925 -151.06034) (xy 81.734991 -151.090324)
			(xy 81.679587 -151.113273) (xy 81.621662 -151.128794) (xy 81.562206 -151.136622) (xy 81.502238 -151.136622)
			(xy 81.442782 -151.128794) (xy 81.384857 -151.113273) (xy 81.329453 -151.090324) (xy 81.277519 -151.06034)
			(xy 81.229943 -151.023834) (xy 81.187538 -150.981429) (xy 81.151032 -150.933853) (xy 81.121048 -150.881919)
			(xy 81.098099 -150.826515) (xy 81.082578 -150.76859) (xy 81.07475 -150.709134) (xy 81.07426 -150.67915)
			(xy 67.515232 -150.67915) (xy 67.515232 -150.687278) (xy 67.514742 -150.717262) (xy 67.506914 -150.776718)
			(xy 67.491393 -150.834643) (xy 67.468444 -150.890047) (xy 67.43846 -150.941981) (xy 67.401954 -150.989557)
			(xy 67.359549 -151.031962) (xy 67.311973 -151.068468) (xy 67.260039 -151.098452) (xy 67.204635 -151.121401)
			(xy 67.14671 -151.136922) (xy 67.087254 -151.14475) (xy 67.027286 -151.14475) (xy 66.96783 -151.136922)
			(xy 66.909905 -151.121401) (xy 66.854501 -151.098452) (xy 66.802567 -151.068468) (xy 66.754991 -151.031962)
			(xy 66.712586 -150.989557) (xy 66.67608 -150.941981) (xy 66.646096 -150.890047) (xy 66.623147 -150.834643)
			(xy 66.607626 -150.776718) (xy 66.599798 -150.717262) (xy 66.599308 -150.687278) (xy 5.324094 -150.687278)
			(xy 5.324094 -152.487376) (xy 64.745108 -152.487376) (xy 64.745108 -151.623776) (xy 64.745598 -151.593792)
			(xy 64.753426 -151.534336) (xy 64.768947 -151.476411) (xy 64.791896 -151.421007) (xy 64.82188 -151.369073)
			(xy 64.858386 -151.321497) (xy 64.900791 -151.279092) (xy 64.948367 -151.242586) (xy 65.000301 -151.212602)
			(xy 65.055705 -151.189653) (xy 65.11363 -151.174132) (xy 65.173086 -151.166304) (xy 65.233054 -151.166304)
			(xy 65.29251 -151.174132) (xy 65.350435 -151.189653) (xy 65.405839 -151.212602) (xy 65.457773 -151.242586)
			(xy 65.505349 -151.279092) (xy 65.547754 -151.321497) (xy 65.58426 -151.369073) (xy 65.614244 -151.421007)
			(xy 65.637193 -151.476411) (xy 65.652714 -151.534336) (xy 65.660542 -151.593792) (xy 65.661032 -151.623776)
			(xy 65.661032 -152.485852) (xy 83.716368 -152.485852) (xy 83.716368 -151.622252) (xy 83.716858 -151.592268)
			(xy 83.724686 -151.532812) (xy 83.740207 -151.474887) (xy 83.763156 -151.419483) (xy 83.79314 -151.367549)
			(xy 83.829646 -151.319973) (xy 83.872051 -151.277568) (xy 83.919627 -151.241062) (xy 83.971561 -151.211078)
			(xy 84.026965 -151.188129) (xy 84.08489 -151.172608) (xy 84.144346 -151.16478) (xy 84.204314 -151.16478)
			(xy 84.26377 -151.172608) (xy 84.321695 -151.188129) (xy 84.377099 -151.211078) (xy 84.429033 -151.241062)
			(xy 84.476609 -151.277568) (xy 84.519014 -151.319973) (xy 84.55552 -151.367549) (xy 84.585504 -151.419483)
			(xy 84.608453 -151.474887) (xy 84.623974 -151.532812) (xy 84.631802 -151.592268) (xy 84.632292 -151.622252)
			(xy 84.632292 -152.485852) (xy 84.632267 -152.487376) (xy 180.84546 -152.487376) (xy 180.84546 -151.623776)
			(xy 180.84595 -151.593808) (xy 180.853773 -151.534386) (xy 180.869286 -151.476493) (xy 180.892222 -151.42112)
			(xy 180.922189 -151.369214) (xy 180.958676 -151.321664) (xy 181.001056 -151.279284) (xy 181.048606 -151.242797)
			(xy 181.100512 -151.21283) (xy 181.155885 -151.189894) (xy 181.213778 -151.174381) (xy 181.2732 -151.166558)
			(xy 181.333136 -151.166558) (xy 181.392558 -151.174381) (xy 181.450451 -151.189894) (xy 181.505824 -151.21283)
			(xy 181.55773 -151.242797) (xy 181.60528 -151.279284) (xy 181.64766 -151.321664) (xy 181.684147 -151.369214)
			(xy 181.714114 -151.42112) (xy 181.73705 -151.476493) (xy 181.752563 -151.534386) (xy 181.760386 -151.593808)
			(xy 181.760876 -151.623776) (xy 181.760876 -152.485852) (xy 199.81672 -152.485852) (xy 199.81672 -151.622252)
			(xy 199.81721 -151.592284) (xy 199.825033 -151.532862) (xy 199.840546 -151.474969) (xy 199.863482 -151.419596)
			(xy 199.893449 -151.36769) (xy 199.929936 -151.32014) (xy 199.972316 -151.27776) (xy 200.019866 -151.241273)
			(xy 200.071772 -151.211306) (xy 200.127145 -151.18837) (xy 200.185038 -151.172857) (xy 200.24446 -151.165034)
			(xy 200.304396 -151.165034) (xy 200.363818 -151.172857) (xy 200.421711 -151.18837) (xy 200.477084 -151.211306)
			(xy 200.52899 -151.241273) (xy 200.57654 -151.27776) (xy 200.61892 -151.32014) (xy 200.655407 -151.36769)
			(xy 200.685374 -151.419596) (xy 200.70831 -151.474969) (xy 200.723823 -151.532862) (xy 200.731646 -151.592284)
			(xy 200.732136 -151.622252) (xy 200.732136 -151.914098) (xy 236.712252 -151.914098) (xy 236.712252 -151.050498)
			(xy 236.712742 -151.020514) (xy 236.72057 -150.961058) (xy 236.736091 -150.903133) (xy 236.75904 -150.847729)
			(xy 236.789024 -150.795795) (xy 236.82553 -150.748219) (xy 236.867935 -150.705814) (xy 236.915511 -150.669308)
			(xy 236.967445 -150.639324) (xy 237.022849 -150.616375) (xy 237.080774 -150.600854) (xy 237.14023 -150.593026)
			(xy 237.200198 -150.593026) (xy 237.259654 -150.600854) (xy 237.317579 -150.616375) (xy 237.372983 -150.639324)
			(xy 237.424917 -150.669308) (xy 237.448336 -150.687278) (xy 298.799504 -150.687278) (xy 298.799504 -149.823678)
			(xy 298.799994 -149.79371) (xy 298.807817 -149.734288) (xy 298.82333 -149.676395) (xy 298.846266 -149.621022)
			(xy 298.876233 -149.569116) (xy 298.91272 -149.521566) (xy 298.9551 -149.479186) (xy 299.00265 -149.442699)
			(xy 299.054556 -149.412732) (xy 299.109929 -149.389796) (xy 299.167822 -149.374283) (xy 299.227244 -149.36646)
			(xy 299.28718 -149.36646) (xy 299.346602 -149.374283) (xy 299.404495 -149.389796) (xy 299.459868 -149.412732)
			(xy 299.511774 -149.442699) (xy 299.559324 -149.479186) (xy 299.601704 -149.521566) (xy 299.638191 -149.569116)
			(xy 299.668158 -149.621022) (xy 299.691094 -149.676395) (xy 299.706607 -149.734288) (xy 299.71443 -149.79371)
			(xy 299.71492 -149.823678) (xy 299.71492 -150.67915) (xy 313.274456 -150.67915) (xy 313.274456 -149.81555)
			(xy 313.274946 -149.785582) (xy 313.282769 -149.72616) (xy 313.298282 -149.668267) (xy 313.321218 -149.612894)
			(xy 313.351185 -149.560988) (xy 313.387672 -149.513438) (xy 313.430052 -149.471058) (xy 313.477602 -149.434571)
			(xy 313.529508 -149.404604) (xy 313.584881 -149.381668) (xy 313.642774 -149.366155) (xy 313.702196 -149.358332)
			(xy 313.762132 -149.358332) (xy 313.821554 -149.366155) (xy 313.879447 -149.381668) (xy 313.93482 -149.404604)
			(xy 313.986726 -149.434571) (xy 314.034276 -149.471058) (xy 314.076656 -149.513438) (xy 314.113143 -149.560988)
			(xy 314.14311 -149.612894) (xy 314.166046 -149.668267) (xy 314.181559 -149.72616) (xy 314.189382 -149.785582)
			(xy 314.189872 -149.81555) (xy 314.189872 -150.67915) (xy 314.189739 -150.687278) (xy 414.899348 -150.687278)
			(xy 414.899348 -149.823678) (xy 414.899838 -149.793694) (xy 414.907666 -149.734238) (xy 414.923187 -149.676313)
			(xy 414.946136 -149.620909) (xy 414.97612 -149.568975) (xy 415.012626 -149.521399) (xy 415.055031 -149.478994)
			(xy 415.102607 -149.442488) (xy 415.154541 -149.412504) (xy 415.209945 -149.389555) (xy 415.26787 -149.374034)
			(xy 415.327326 -149.366206) (xy 415.387294 -149.366206) (xy 415.44675 -149.374034) (xy 415.504675 -149.389555)
			(xy 415.560079 -149.412504) (xy 415.612013 -149.442488) (xy 415.659589 -149.478994) (xy 415.701994 -149.521399)
			(xy 415.7385 -149.568975) (xy 415.768484 -149.620909) (xy 415.791433 -149.676313) (xy 415.806954 -149.734238)
			(xy 415.814782 -149.793694) (xy 415.815272 -149.823678) (xy 415.815272 -150.67915) (xy 429.3743 -150.67915)
			(xy 429.3743 -149.81555) (xy 429.37479 -149.785566) (xy 429.382618 -149.72611) (xy 429.398139 -149.668185)
			(xy 429.421088 -149.612781) (xy 429.451072 -149.560847) (xy 429.487578 -149.513271) (xy 429.529983 -149.470866)
			(xy 429.577559 -149.43436) (xy 429.629493 -149.404376) (xy 429.684897 -149.381427) (xy 429.742822 -149.365906)
			(xy 429.802278 -149.358078) (xy 429.862246 -149.358078) (xy 429.921702 -149.365906) (xy 429.979627 -149.381427)
			(xy 430.035031 -149.404376) (xy 430.086965 -149.43436) (xy 430.134541 -149.470866) (xy 430.176946 -149.513271)
			(xy 430.213452 -149.560847) (xy 430.243436 -149.612781) (xy 430.266385 -149.668185) (xy 430.281906 -149.72611)
			(xy 430.289734 -149.785566) (xy 430.290224 -149.81555) (xy 430.290224 -150.67915) (xy 430.289734 -150.709134)
			(xy 430.281906 -150.76859) (xy 430.266385 -150.826515) (xy 430.243436 -150.881919) (xy 430.213452 -150.933853)
			(xy 430.176946 -150.981429) (xy 430.134541 -151.023834) (xy 430.086965 -151.06034) (xy 430.035031 -151.090324)
			(xy 429.979627 -151.113273) (xy 429.921702 -151.128794) (xy 429.862246 -151.136622) (xy 429.802278 -151.136622)
			(xy 429.742822 -151.128794) (xy 429.684897 -151.113273) (xy 429.629493 -151.090324) (xy 429.577559 -151.06034)
			(xy 429.529983 -151.023834) (xy 429.487578 -150.981429) (xy 429.451072 -150.933853) (xy 429.421088 -150.881919)
			(xy 429.398139 -150.826515) (xy 429.382618 -150.76859) (xy 429.37479 -150.709134) (xy 429.3743 -150.67915)
			(xy 415.815272 -150.67915) (xy 415.815272 -150.687278) (xy 415.814782 -150.717262) (xy 415.806954 -150.776718)
			(xy 415.791433 -150.834643) (xy 415.768484 -150.890047) (xy 415.7385 -150.941981) (xy 415.701994 -150.989557)
			(xy 415.659589 -151.031962) (xy 415.612013 -151.068468) (xy 415.560079 -151.098452) (xy 415.504675 -151.121401)
			(xy 415.44675 -151.136922) (xy 415.387294 -151.14475) (xy 415.327326 -151.14475) (xy 415.26787 -151.136922)
			(xy 415.209945 -151.121401) (xy 415.154541 -151.098452) (xy 415.102607 -151.068468) (xy 415.055031 -151.031962)
			(xy 415.012626 -150.989557) (xy 414.97612 -150.941981) (xy 414.946136 -150.890047) (xy 414.923187 -150.834643)
			(xy 414.907666 -150.776718) (xy 414.899838 -150.717262) (xy 414.899348 -150.687278) (xy 314.189739 -150.687278)
			(xy 314.189382 -150.709118) (xy 314.181559 -150.76854) (xy 314.166046 -150.826433) (xy 314.14311 -150.881806)
			(xy 314.113143 -150.933712) (xy 314.076656 -150.981262) (xy 314.034276 -151.023642) (xy 313.986726 -151.060129)
			(xy 313.93482 -151.090096) (xy 313.879447 -151.113032) (xy 313.821554 -151.128545) (xy 313.762132 -151.136368)
			(xy 313.702196 -151.136368) (xy 313.642774 -151.128545) (xy 313.584881 -151.113032) (xy 313.529508 -151.090096)
			(xy 313.477602 -151.060129) (xy 313.430052 -151.023642) (xy 313.387672 -150.981262) (xy 313.351185 -150.933712)
			(xy 313.321218 -150.881806) (xy 313.298282 -150.826433) (xy 313.282769 -150.76854) (xy 313.274946 -150.709118)
			(xy 313.274456 -150.67915) (xy 299.71492 -150.67915) (xy 299.71492 -150.687278) (xy 299.71443 -150.717246)
			(xy 299.706607 -150.776668) (xy 299.691094 -150.834561) (xy 299.668158 -150.889934) (xy 299.638191 -150.94184)
			(xy 299.601704 -150.98939) (xy 299.559324 -151.03177) (xy 299.511774 -151.068257) (xy 299.459868 -151.098224)
			(xy 299.404495 -151.12116) (xy 299.346602 -151.136673) (xy 299.28718 -151.144496) (xy 299.227244 -151.144496)
			(xy 299.167822 -151.136673) (xy 299.109929 -151.12116) (xy 299.054556 -151.098224) (xy 299.00265 -151.068257)
			(xy 298.9551 -151.03177) (xy 298.91272 -150.98939) (xy 298.876233 -150.94184) (xy 298.846266 -150.889934)
			(xy 298.82333 -150.834561) (xy 298.807817 -150.776668) (xy 298.799994 -150.717246) (xy 298.799504 -150.687278)
			(xy 237.448336 -150.687278) (xy 237.472493 -150.705814) (xy 237.514898 -150.748219) (xy 237.551404 -150.795795)
			(xy 237.581388 -150.847729) (xy 237.604337 -150.903133) (xy 237.619858 -150.961058) (xy 237.627686 -151.020514)
			(xy 237.628176 -151.050498) (xy 237.628176 -151.914098) (xy 237.627686 -151.944082) (xy 237.619858 -152.003538)
			(xy 237.604337 -152.061463) (xy 237.581388 -152.116867) (xy 237.551404 -152.168801) (xy 237.514898 -152.216377)
			(xy 237.472493 -152.258782) (xy 237.424917 -152.295288) (xy 237.372983 -152.325272) (xy 237.317579 -152.348221)
			(xy 237.259654 -152.363742) (xy 237.200198 -152.37157) (xy 237.14023 -152.37157) (xy 237.080774 -152.363742)
			(xy 237.022849 -152.348221) (xy 236.967445 -152.325272) (xy 236.915511 -152.295288) (xy 236.867935 -152.258782)
			(xy 236.82553 -152.216377) (xy 236.789024 -152.168801) (xy 236.75904 -152.116867) (xy 236.736091 -152.061463)
			(xy 236.72057 -152.003538) (xy 236.712742 -151.944082) (xy 236.712252 -151.914098) (xy 200.732136 -151.914098)
			(xy 200.732136 -152.485852) (xy 200.732111 -152.487376) (xy 296.945304 -152.487376) (xy 296.945304 -151.623776)
			(xy 296.945794 -151.593808) (xy 296.953617 -151.534386) (xy 296.96913 -151.476493) (xy 296.992066 -151.42112)
			(xy 297.022033 -151.369214) (xy 297.05852 -151.321664) (xy 297.1009 -151.279284) (xy 297.14845 -151.242797)
			(xy 297.200356 -151.21283) (xy 297.255729 -151.189894) (xy 297.313622 -151.174381) (xy 297.373044 -151.166558)
			(xy 297.43298 -151.166558) (xy 297.492402 -151.174381) (xy 297.550295 -151.189894) (xy 297.605668 -151.21283)
			(xy 297.657574 -151.242797) (xy 297.705124 -151.279284) (xy 297.747504 -151.321664) (xy 297.783991 -151.369214)
			(xy 297.813958 -151.42112) (xy 297.836894 -151.476493) (xy 297.852407 -151.534386) (xy 297.86023 -151.593808)
			(xy 297.86072 -151.623776) (xy 297.86072 -152.485852) (xy 315.916564 -152.485852) (xy 315.916564 -151.622252)
			(xy 315.917054 -151.592284) (xy 315.924877 -151.532862) (xy 315.94039 -151.474969) (xy 315.963326 -151.419596)
			(xy 315.993293 -151.36769) (xy 316.02978 -151.32014) (xy 316.07216 -151.27776) (xy 316.11971 -151.241273)
			(xy 316.171616 -151.211306) (xy 316.226989 -151.18837) (xy 316.284882 -151.172857) (xy 316.344304 -151.165034)
			(xy 316.40424 -151.165034) (xy 316.463662 -151.172857) (xy 316.521555 -151.18837) (xy 316.576928 -151.211306)
			(xy 316.628834 -151.241273) (xy 316.676384 -151.27776) (xy 316.718764 -151.32014) (xy 316.755251 -151.36769)
			(xy 316.785218 -151.419596) (xy 316.808154 -151.474969) (xy 316.823667 -151.532862) (xy 316.83149 -151.592284)
			(xy 316.83198 -151.622252) (xy 316.83198 -152.485852) (xy 316.831955 -152.487376) (xy 413.045148 -152.487376)
			(xy 413.045148 -151.623776) (xy 413.045638 -151.593792) (xy 413.053466 -151.534336) (xy 413.068987 -151.476411)
			(xy 413.091936 -151.421007) (xy 413.12192 -151.369073) (xy 413.158426 -151.321497) (xy 413.200831 -151.279092)
			(xy 413.248407 -151.242586) (xy 413.300341 -151.212602) (xy 413.355745 -151.189653) (xy 413.41367 -151.174132)
			(xy 413.473126 -151.166304) (xy 413.533094 -151.166304) (xy 413.59255 -151.174132) (xy 413.650475 -151.189653)
			(xy 413.705879 -151.212602) (xy 413.757813 -151.242586) (xy 413.805389 -151.279092) (xy 413.847794 -151.321497)
			(xy 413.8843 -151.369073) (xy 413.914284 -151.421007) (xy 413.937233 -151.476411) (xy 413.952754 -151.534336)
			(xy 413.960582 -151.593792) (xy 413.961072 -151.623776) (xy 413.961072 -152.485852) (xy 432.016408 -152.485852)
			(xy 432.016408 -151.622252) (xy 432.016898 -151.592268) (xy 432.024726 -151.532812) (xy 432.040247 -151.474887)
			(xy 432.063196 -151.419483) (xy 432.09318 -151.367549) (xy 432.129686 -151.319973) (xy 432.172091 -151.277568)
			(xy 432.219667 -151.241062) (xy 432.271601 -151.211078) (xy 432.327005 -151.188129) (xy 432.38493 -151.172608)
			(xy 432.444386 -151.16478) (xy 432.504354 -151.16478) (xy 432.56381 -151.172608) (xy 432.621735 -151.188129)
			(xy 432.677139 -151.211078) (xy 432.729073 -151.241062) (xy 432.776649 -151.277568) (xy 432.819054 -151.319973)
			(xy 432.85556 -151.367549) (xy 432.885544 -151.419483) (xy 432.908493 -151.474887) (xy 432.924014 -151.532812)
			(xy 432.931842 -151.592268) (xy 432.932332 -151.622252) (xy 432.932332 -152.485852) (xy 432.931842 -152.515836)
			(xy 432.924014 -152.575292) (xy 432.908493 -152.633217) (xy 432.885544 -152.688621) (xy 432.85556 -152.740555)
			(xy 432.819054 -152.788131) (xy 432.776649 -152.830536) (xy 432.729073 -152.867042) (xy 432.677139 -152.897026)
			(xy 432.621735 -152.919975) (xy 432.56381 -152.935496) (xy 432.504354 -152.943324) (xy 432.444386 -152.943324)
			(xy 432.38493 -152.935496) (xy 432.327005 -152.919975) (xy 432.271601 -152.897026) (xy 432.219667 -152.867042)
			(xy 432.172091 -152.830536) (xy 432.129686 -152.788131) (xy 432.09318 -152.740555) (xy 432.063196 -152.688621)
			(xy 432.040247 -152.633217) (xy 432.024726 -152.575292) (xy 432.016898 -152.515836) (xy 432.016408 -152.485852)
			(xy 413.961072 -152.485852) (xy 413.961072 -152.487376) (xy 413.960582 -152.51736) (xy 413.952754 -152.576816)
			(xy 413.937233 -152.634741) (xy 413.914284 -152.690145) (xy 413.8843 -152.742079) (xy 413.847794 -152.789655)
			(xy 413.805389 -152.83206) (xy 413.757813 -152.868566) (xy 413.705879 -152.89855) (xy 413.650475 -152.921499)
			(xy 413.59255 -152.93702) (xy 413.533094 -152.944848) (xy 413.473126 -152.944848) (xy 413.41367 -152.93702)
			(xy 413.355745 -152.921499) (xy 413.300341 -152.89855) (xy 413.248407 -152.868566) (xy 413.200831 -152.83206)
			(xy 413.158426 -152.789655) (xy 413.12192 -152.742079) (xy 413.091936 -152.690145) (xy 413.068987 -152.634741)
			(xy 413.053466 -152.576816) (xy 413.045638 -152.51736) (xy 413.045148 -152.487376) (xy 316.831955 -152.487376)
			(xy 316.83149 -152.51582) (xy 316.823667 -152.575242) (xy 316.808154 -152.633135) (xy 316.785218 -152.688508)
			(xy 316.755251 -152.740414) (xy 316.718764 -152.787964) (xy 316.676384 -152.830344) (xy 316.628834 -152.866831)
			(xy 316.576928 -152.896798) (xy 316.521555 -152.919734) (xy 316.463662 -152.935247) (xy 316.40424 -152.94307)
			(xy 316.344304 -152.94307) (xy 316.284882 -152.935247) (xy 316.226989 -152.919734) (xy 316.171616 -152.896798)
			(xy 316.11971 -152.866831) (xy 316.07216 -152.830344) (xy 316.02978 -152.787964) (xy 315.993293 -152.740414)
			(xy 315.963326 -152.688508) (xy 315.94039 -152.633135) (xy 315.924877 -152.575242) (xy 315.917054 -152.51582)
			(xy 315.916564 -152.485852) (xy 297.86072 -152.485852) (xy 297.86072 -152.487376) (xy 297.86023 -152.517344)
			(xy 297.852407 -152.576766) (xy 297.836894 -152.634659) (xy 297.813958 -152.690032) (xy 297.783991 -152.741938)
			(xy 297.747504 -152.789488) (xy 297.705124 -152.831868) (xy 297.657574 -152.868355) (xy 297.605668 -152.898322)
			(xy 297.550295 -152.921258) (xy 297.492402 -152.936771) (xy 297.43298 -152.944594) (xy 297.373044 -152.944594)
			(xy 297.313622 -152.936771) (xy 297.255729 -152.921258) (xy 297.200356 -152.898322) (xy 297.14845 -152.868355)
			(xy 297.1009 -152.831868) (xy 297.05852 -152.789488) (xy 297.022033 -152.741938) (xy 296.992066 -152.690032)
			(xy 296.96913 -152.634659) (xy 296.953617 -152.576766) (xy 296.945794 -152.517344) (xy 296.945304 -152.487376)
			(xy 200.732111 -152.487376) (xy 200.731646 -152.51582) (xy 200.723823 -152.575242) (xy 200.70831 -152.633135)
			(xy 200.685374 -152.688508) (xy 200.655407 -152.740414) (xy 200.61892 -152.787964) (xy 200.57654 -152.830344)
			(xy 200.52899 -152.866831) (xy 200.477084 -152.896798) (xy 200.421711 -152.919734) (xy 200.363818 -152.935247)
			(xy 200.304396 -152.94307) (xy 200.24446 -152.94307) (xy 200.185038 -152.935247) (xy 200.127145 -152.919734)
			(xy 200.071772 -152.896798) (xy 200.019866 -152.866831) (xy 199.972316 -152.830344) (xy 199.929936 -152.787964)
			(xy 199.893449 -152.740414) (xy 199.863482 -152.688508) (xy 199.840546 -152.633135) (xy 199.825033 -152.575242)
			(xy 199.81721 -152.51582) (xy 199.81672 -152.485852) (xy 181.760876 -152.485852) (xy 181.760876 -152.487376)
			(xy 181.760386 -152.517344) (xy 181.752563 -152.576766) (xy 181.73705 -152.634659) (xy 181.714114 -152.690032)
			(xy 181.684147 -152.741938) (xy 181.64766 -152.789488) (xy 181.60528 -152.831868) (xy 181.55773 -152.868355)
			(xy 181.505824 -152.898322) (xy 181.450451 -152.921258) (xy 181.392558 -152.936771) (xy 181.333136 -152.944594)
			(xy 181.2732 -152.944594) (xy 181.213778 -152.936771) (xy 181.155885 -152.921258) (xy 181.100512 -152.898322)
			(xy 181.048606 -152.868355) (xy 181.001056 -152.831868) (xy 180.958676 -152.789488) (xy 180.922189 -152.741938)
			(xy 180.892222 -152.690032) (xy 180.869286 -152.634659) (xy 180.853773 -152.576766) (xy 180.84595 -152.517344)
			(xy 180.84546 -152.487376) (xy 84.632267 -152.487376) (xy 84.631802 -152.515836) (xy 84.623974 -152.575292)
			(xy 84.608453 -152.633217) (xy 84.585504 -152.688621) (xy 84.55552 -152.740555) (xy 84.519014 -152.788131)
			(xy 84.476609 -152.830536) (xy 84.429033 -152.867042) (xy 84.377099 -152.897026) (xy 84.321695 -152.919975)
			(xy 84.26377 -152.935496) (xy 84.204314 -152.943324) (xy 84.144346 -152.943324) (xy 84.08489 -152.935496)
			(xy 84.026965 -152.919975) (xy 83.971561 -152.897026) (xy 83.919627 -152.867042) (xy 83.872051 -152.830536)
			(xy 83.829646 -152.788131) (xy 83.79314 -152.740555) (xy 83.763156 -152.688621) (xy 83.740207 -152.633217)
			(xy 83.724686 -152.575292) (xy 83.716858 -152.515836) (xy 83.716368 -152.485852) (xy 65.661032 -152.485852)
			(xy 65.661032 -152.487376) (xy 65.660542 -152.51736) (xy 65.652714 -152.576816) (xy 65.637193 -152.634741)
			(xy 65.614244 -152.690145) (xy 65.58426 -152.742079) (xy 65.547754 -152.789655) (xy 65.505349 -152.83206)
			(xy 65.457773 -152.868566) (xy 65.405839 -152.89855) (xy 65.350435 -152.921499) (xy 65.29251 -152.93702)
			(xy 65.233054 -152.944848) (xy 65.173086 -152.944848) (xy 65.11363 -152.93702) (xy 65.055705 -152.921499)
			(xy 65.000301 -152.89855) (xy 64.948367 -152.868566) (xy 64.900791 -152.83206) (xy 64.858386 -152.789655)
			(xy 64.82188 -152.742079) (xy 64.791896 -152.690145) (xy 64.768947 -152.634741) (xy 64.753426 -152.576816)
			(xy 64.745598 -152.51736) (xy 64.745108 -152.487376) (xy 5.324094 -152.487376) (xy 5.324094 -154.28722)
			(xy 66.599308 -154.28722) (xy 66.599308 -153.42362) (xy 66.599798 -153.393636) (xy 66.607626 -153.33418)
			(xy 66.623147 -153.276255) (xy 66.646096 -153.220851) (xy 66.67608 -153.168917) (xy 66.712586 -153.121341)
			(xy 66.754991 -153.078936) (xy 66.802567 -153.04243) (xy 66.854501 -153.012446) (xy 66.909905 -152.989497)
			(xy 66.96783 -152.973976) (xy 67.027286 -152.966148) (xy 67.087254 -152.966148) (xy 67.14671 -152.973976)
			(xy 67.204635 -152.989497) (xy 67.260039 -153.012446) (xy 67.311973 -153.04243) (xy 67.359549 -153.078936)
			(xy 67.401954 -153.121341) (xy 67.43846 -153.168917) (xy 67.468444 -153.220851) (xy 67.491393 -153.276255)
			(xy 67.506914 -153.33418) (xy 67.514742 -153.393636) (xy 67.515232 -153.42362) (xy 67.515232 -154.279346)
			(xy 81.07426 -154.279346) (xy 81.07426 -153.415746) (xy 81.07475 -153.385762) (xy 81.082578 -153.326306)
			(xy 81.098099 -153.268381) (xy 81.121048 -153.212977) (xy 81.151032 -153.161043) (xy 81.187538 -153.113467)
			(xy 81.229943 -153.071062) (xy 81.277519 -153.034556) (xy 81.329453 -153.004572) (xy 81.384857 -152.981623)
			(xy 81.442782 -152.966102) (xy 81.502238 -152.958274) (xy 81.562206 -152.958274) (xy 81.621662 -152.966102)
			(xy 81.679587 -152.981623) (xy 81.734991 -153.004572) (xy 81.786925 -153.034556) (xy 81.834501 -153.071062)
			(xy 81.876906 -153.113467) (xy 81.913412 -153.161043) (xy 81.943396 -153.212977) (xy 81.966345 -153.268381)
			(xy 81.981866 -153.326306) (xy 81.989694 -153.385762) (xy 81.990184 -153.415746) (xy 81.990184 -154.279346)
			(xy 81.990055 -154.28722) (xy 182.69966 -154.28722) (xy 182.69966 -153.42362) (xy 182.70015 -153.393652)
			(xy 182.707973 -153.33423) (xy 182.723486 -153.276337) (xy 182.746422 -153.220964) (xy 182.776389 -153.169058)
			(xy 182.812876 -153.121508) (xy 182.855256 -153.079128) (xy 182.902806 -153.042641) (xy 182.954712 -153.012674)
			(xy 183.010085 -152.989738) (xy 183.067978 -152.974225) (xy 183.1274 -152.966402) (xy 183.187336 -152.966402)
			(xy 183.246758 -152.974225) (xy 183.304651 -152.989738) (xy 183.360024 -153.012674) (xy 183.41193 -153.042641)
			(xy 183.45948 -153.079128) (xy 183.50186 -153.121508) (xy 183.538347 -153.169058) (xy 183.568314 -153.220964)
			(xy 183.59125 -153.276337) (xy 183.606763 -153.33423) (xy 183.614586 -153.393652) (xy 183.615076 -153.42362)
			(xy 183.615076 -154.279346) (xy 197.174612 -154.279346) (xy 197.174612 -153.415746) (xy 197.175102 -153.385778)
			(xy 197.182925 -153.326356) (xy 197.198438 -153.268463) (xy 197.221374 -153.21309) (xy 197.251341 -153.161184)
			(xy 197.287828 -153.113634) (xy 197.330208 -153.071254) (xy 197.377758 -153.034767) (xy 197.429664 -153.0048)
			(xy 197.485037 -152.981864) (xy 197.54293 -152.966351) (xy 197.602352 -152.958528) (xy 197.662288 -152.958528)
			(xy 197.72171 -152.966351) (xy 197.779603 -152.981864) (xy 197.834976 -153.0048) (xy 197.886882 -153.034767)
			(xy 197.934432 -153.071254) (xy 197.976812 -153.113634) (xy 198.013299 -153.161184) (xy 198.043266 -153.21309)
			(xy 198.066202 -153.268463) (xy 198.081715 -153.326356) (xy 198.089538 -153.385778) (xy 198.090028 -153.415746)
			(xy 198.090028 -154.279346) (xy 198.089899 -154.28722) (xy 298.799504 -154.28722) (xy 298.799504 -153.42362)
			(xy 298.799994 -153.393652) (xy 298.807817 -153.33423) (xy 298.82333 -153.276337) (xy 298.846266 -153.220964)
			(xy 298.876233 -153.169058) (xy 298.91272 -153.121508) (xy 298.9551 -153.079128) (xy 299.00265 -153.042641)
			(xy 299.054556 -153.012674) (xy 299.109929 -152.989738) (xy 299.167822 -152.974225) (xy 299.227244 -152.966402)
			(xy 299.28718 -152.966402) (xy 299.346602 -152.974225) (xy 299.404495 -152.989738) (xy 299.459868 -153.012674)
			(xy 299.511774 -153.042641) (xy 299.559324 -153.079128) (xy 299.601704 -153.121508) (xy 299.638191 -153.169058)
			(xy 299.668158 -153.220964) (xy 299.691094 -153.276337) (xy 299.706607 -153.33423) (xy 299.71443 -153.393652)
			(xy 299.71492 -153.42362) (xy 299.71492 -154.279346) (xy 313.274456 -154.279346) (xy 313.274456 -153.415746)
			(xy 313.274946 -153.385778) (xy 313.282769 -153.326356) (xy 313.298282 -153.268463) (xy 313.321218 -153.21309)
			(xy 313.351185 -153.161184) (xy 313.387672 -153.113634) (xy 313.430052 -153.071254) (xy 313.477602 -153.034767)
			(xy 313.529508 -153.0048) (xy 313.584881 -152.981864) (xy 313.642774 -152.966351) (xy 313.702196 -152.958528)
			(xy 313.762132 -152.958528) (xy 313.821554 -152.966351) (xy 313.879447 -152.981864) (xy 313.93482 -153.0048)
			(xy 313.986726 -153.034767) (xy 314.034276 -153.071254) (xy 314.076656 -153.113634) (xy 314.113143 -153.161184)
			(xy 314.14311 -153.21309) (xy 314.166046 -153.268463) (xy 314.181559 -153.326356) (xy 314.189382 -153.385778)
			(xy 314.189872 -153.415746) (xy 314.189872 -154.279346) (xy 314.189743 -154.28722) (xy 414.899348 -154.28722)
			(xy 414.899348 -153.42362) (xy 414.899838 -153.393636) (xy 414.907666 -153.33418) (xy 414.923187 -153.276255)
			(xy 414.946136 -153.220851) (xy 414.97612 -153.168917) (xy 415.012626 -153.121341) (xy 415.055031 -153.078936)
			(xy 415.102607 -153.04243) (xy 415.154541 -153.012446) (xy 415.209945 -152.989497) (xy 415.26787 -152.973976)
			(xy 415.327326 -152.966148) (xy 415.387294 -152.966148) (xy 415.44675 -152.973976) (xy 415.504675 -152.989497)
			(xy 415.560079 -153.012446) (xy 415.612013 -153.04243) (xy 415.659589 -153.078936) (xy 415.701994 -153.121341)
			(xy 415.7385 -153.168917) (xy 415.768484 -153.220851) (xy 415.791433 -153.276255) (xy 415.806954 -153.33418)
			(xy 415.814782 -153.393636) (xy 415.815272 -153.42362) (xy 415.815272 -154.279346) (xy 429.3743 -154.279346)
			(xy 429.3743 -153.415746) (xy 429.37479 -153.385762) (xy 429.382618 -153.326306) (xy 429.398139 -153.268381)
			(xy 429.421088 -153.212977) (xy 429.451072 -153.161043) (xy 429.487578 -153.113467) (xy 429.529983 -153.071062)
			(xy 429.577559 -153.034556) (xy 429.629493 -153.004572) (xy 429.684897 -152.981623) (xy 429.742822 -152.966102)
			(xy 429.802278 -152.958274) (xy 429.862246 -152.958274) (xy 429.921702 -152.966102) (xy 429.979627 -152.981623)
			(xy 430.035031 -153.004572) (xy 430.086965 -153.034556) (xy 430.134541 -153.071062) (xy 430.176946 -153.113467)
			(xy 430.213452 -153.161043) (xy 430.243436 -153.212977) (xy 430.266385 -153.268381) (xy 430.281906 -153.326306)
			(xy 430.289734 -153.385762) (xy 430.290224 -153.415746) (xy 430.290224 -154.279346) (xy 430.289734 -154.30933)
			(xy 430.281906 -154.368786) (xy 430.266385 -154.426711) (xy 430.243436 -154.482115) (xy 430.213452 -154.534049)
			(xy 430.176946 -154.581625) (xy 430.134541 -154.62403) (xy 430.086965 -154.660536) (xy 430.035031 -154.69052)
			(xy 429.979627 -154.713469) (xy 429.921702 -154.72899) (xy 429.862246 -154.736818) (xy 429.802278 -154.736818)
			(xy 429.742822 -154.72899) (xy 429.684897 -154.713469) (xy 429.629493 -154.69052) (xy 429.577559 -154.660536)
			(xy 429.529983 -154.62403) (xy 429.487578 -154.581625) (xy 429.451072 -154.534049) (xy 429.421088 -154.482115)
			(xy 429.398139 -154.426711) (xy 429.382618 -154.368786) (xy 429.37479 -154.30933) (xy 429.3743 -154.279346)
			(xy 415.815272 -154.279346) (xy 415.815272 -154.28722) (xy 415.814782 -154.317204) (xy 415.806954 -154.37666)
			(xy 415.791433 -154.434585) (xy 415.768484 -154.489989) (xy 415.7385 -154.541923) (xy 415.701994 -154.589499)
			(xy 415.659589 -154.631904) (xy 415.612013 -154.66841) (xy 415.560079 -154.698394) (xy 415.504675 -154.721343)
			(xy 415.44675 -154.736864) (xy 415.387294 -154.744692) (xy 415.327326 -154.744692) (xy 415.26787 -154.736864)
			(xy 415.209945 -154.721343) (xy 415.154541 -154.698394) (xy 415.102607 -154.66841) (xy 415.055031 -154.631904)
			(xy 415.012626 -154.589499) (xy 414.97612 -154.541923) (xy 414.946136 -154.489989) (xy 414.923187 -154.434585)
			(xy 414.907666 -154.37666) (xy 414.899838 -154.317204) (xy 414.899348 -154.28722) (xy 314.189743 -154.28722)
			(xy 314.189382 -154.309314) (xy 314.181559 -154.368736) (xy 314.166046 -154.426629) (xy 314.14311 -154.482002)
			(xy 314.113143 -154.533908) (xy 314.076656 -154.581458) (xy 314.034276 -154.623838) (xy 313.986726 -154.660325)
			(xy 313.93482 -154.690292) (xy 313.879447 -154.713228) (xy 313.821554 -154.728741) (xy 313.762132 -154.736564)
			(xy 313.702196 -154.736564) (xy 313.642774 -154.728741) (xy 313.584881 -154.713228) (xy 313.529508 -154.690292)
			(xy 313.477602 -154.660325) (xy 313.430052 -154.623838) (xy 313.387672 -154.581458) (xy 313.351185 -154.533908)
			(xy 313.321218 -154.482002) (xy 313.298282 -154.426629) (xy 313.282769 -154.368736) (xy 313.274946 -154.309314)
			(xy 313.274456 -154.279346) (xy 299.71492 -154.279346) (xy 299.71492 -154.28722) (xy 299.71443 -154.317188)
			(xy 299.706607 -154.37661) (xy 299.691094 -154.434503) (xy 299.668158 -154.489876) (xy 299.638191 -154.541782)
			(xy 299.601704 -154.589332) (xy 299.559324 -154.631712) (xy 299.511774 -154.668199) (xy 299.459868 -154.698166)
			(xy 299.404495 -154.721102) (xy 299.346602 -154.736615) (xy 299.28718 -154.744438) (xy 299.227244 -154.744438)
			(xy 299.167822 -154.736615) (xy 299.109929 -154.721102) (xy 299.054556 -154.698166) (xy 299.00265 -154.668199)
			(xy 298.9551 -154.631712) (xy 298.91272 -154.589332) (xy 298.876233 -154.541782) (xy 298.846266 -154.489876)
			(xy 298.82333 -154.434503) (xy 298.807817 -154.37661) (xy 298.799994 -154.317188) (xy 298.799504 -154.28722)
			(xy 198.089899 -154.28722) (xy 198.089538 -154.309314) (xy 198.081715 -154.368736) (xy 198.066202 -154.426629)
			(xy 198.043266 -154.482002) (xy 198.013299 -154.533908) (xy 197.976812 -154.581458) (xy 197.934432 -154.623838)
			(xy 197.886882 -154.660325) (xy 197.834976 -154.690292) (xy 197.779603 -154.713228) (xy 197.72171 -154.728741)
			(xy 197.662288 -154.736564) (xy 197.602352 -154.736564) (xy 197.54293 -154.728741) (xy 197.485037 -154.713228)
			(xy 197.429664 -154.690292) (xy 197.377758 -154.660325) (xy 197.330208 -154.623838) (xy 197.287828 -154.581458)
			(xy 197.251341 -154.533908) (xy 197.221374 -154.482002) (xy 197.198438 -154.426629) (xy 197.182925 -154.368736)
			(xy 197.175102 -154.309314) (xy 197.174612 -154.279346) (xy 183.615076 -154.279346) (xy 183.615076 -154.28722)
			(xy 183.614586 -154.317188) (xy 183.606763 -154.37661) (xy 183.59125 -154.434503) (xy 183.568314 -154.489876)
			(xy 183.538347 -154.541782) (xy 183.50186 -154.589332) (xy 183.45948 -154.631712) (xy 183.41193 -154.668199)
			(xy 183.360024 -154.698166) (xy 183.304651 -154.721102) (xy 183.246758 -154.736615) (xy 183.187336 -154.744438)
			(xy 183.1274 -154.744438) (xy 183.067978 -154.736615) (xy 183.010085 -154.721102) (xy 182.954712 -154.698166)
			(xy 182.902806 -154.668199) (xy 182.855256 -154.631712) (xy 182.812876 -154.589332) (xy 182.776389 -154.541782)
			(xy 182.746422 -154.489876) (xy 182.723486 -154.434503) (xy 182.707973 -154.37661) (xy 182.70015 -154.317188)
			(xy 182.69966 -154.28722) (xy 81.990055 -154.28722) (xy 81.989694 -154.30933) (xy 81.981866 -154.368786)
			(xy 81.966345 -154.426711) (xy 81.943396 -154.482115) (xy 81.913412 -154.534049) (xy 81.876906 -154.581625)
			(xy 81.834501 -154.62403) (xy 81.786925 -154.660536) (xy 81.734991 -154.69052) (xy 81.679587 -154.713469)
			(xy 81.621662 -154.72899) (xy 81.562206 -154.736818) (xy 81.502238 -154.736818) (xy 81.442782 -154.72899)
			(xy 81.384857 -154.713469) (xy 81.329453 -154.69052) (xy 81.277519 -154.660536) (xy 81.229943 -154.62403)
			(xy 81.187538 -154.581625) (xy 81.151032 -154.534049) (xy 81.121048 -154.482115) (xy 81.098099 -154.426711)
			(xy 81.082578 -154.368786) (xy 81.07475 -154.30933) (xy 81.07426 -154.279346) (xy 67.515232 -154.279346)
			(xy 67.515232 -154.28722) (xy 67.514742 -154.317204) (xy 67.506914 -154.37666) (xy 67.491393 -154.434585)
			(xy 67.468444 -154.489989) (xy 67.43846 -154.541923) (xy 67.401954 -154.589499) (xy 67.359549 -154.631904)
			(xy 67.311973 -154.66841) (xy 67.260039 -154.698394) (xy 67.204635 -154.721343) (xy 67.14671 -154.736864)
			(xy 67.087254 -154.744692) (xy 67.027286 -154.744692) (xy 66.96783 -154.736864) (xy 66.909905 -154.721343)
			(xy 66.854501 -154.698394) (xy 66.802567 -154.66841) (xy 66.754991 -154.631904) (xy 66.712586 -154.589499)
			(xy 66.67608 -154.541923) (xy 66.646096 -154.489989) (xy 66.623147 -154.434585) (xy 66.607626 -154.37666)
			(xy 66.599798 -154.317204) (xy 66.599308 -154.28722) (xy 5.324094 -154.28722) (xy 5.324094 -156.087318)
			(xy 64.745108 -156.087318) (xy 64.745108 -155.223718) (xy 64.745598 -155.193734) (xy 64.753426 -155.134278)
			(xy 64.768947 -155.076353) (xy 64.791896 -155.020949) (xy 64.82188 -154.969015) (xy 64.858386 -154.921439)
			(xy 64.900791 -154.879034) (xy 64.948367 -154.842528) (xy 65.000301 -154.812544) (xy 65.055705 -154.789595)
			(xy 65.11363 -154.774074) (xy 65.173086 -154.766246) (xy 65.233054 -154.766246) (xy 65.29251 -154.774074)
			(xy 65.350435 -154.789595) (xy 65.405839 -154.812544) (xy 65.457773 -154.842528) (xy 65.505349 -154.879034)
			(xy 65.547754 -154.921439) (xy 65.58426 -154.969015) (xy 65.614244 -155.020949) (xy 65.637193 -155.076353)
			(xy 65.652714 -155.134278) (xy 65.660542 -155.193734) (xy 65.661032 -155.223718) (xy 65.661032 -156.085794)
			(xy 83.716368 -156.085794) (xy 83.716368 -155.222194) (xy 83.716858 -155.19221) (xy 83.724686 -155.132754)
			(xy 83.740207 -155.074829) (xy 83.763156 -155.019425) (xy 83.79314 -154.967491) (xy 83.829646 -154.919915)
			(xy 83.872051 -154.87751) (xy 83.919627 -154.841004) (xy 83.971561 -154.81102) (xy 84.026965 -154.788071)
			(xy 84.08489 -154.77255) (xy 84.144346 -154.764722) (xy 84.204314 -154.764722) (xy 84.26377 -154.77255)
			(xy 84.321695 -154.788071) (xy 84.377099 -154.81102) (xy 84.429033 -154.841004) (xy 84.476609 -154.87751)
			(xy 84.519014 -154.919915) (xy 84.55552 -154.967491) (xy 84.585504 -155.019425) (xy 84.608453 -155.074829)
			(xy 84.623974 -155.132754) (xy 84.631802 -155.19221) (xy 84.632292 -155.222194) (xy 84.632292 -156.085794)
			(xy 84.632267 -156.087318) (xy 180.84546 -156.087318) (xy 180.84546 -155.223718) (xy 180.84595 -155.19375)
			(xy 180.853773 -155.134328) (xy 180.869286 -155.076435) (xy 180.892222 -155.021062) (xy 180.922189 -154.969156)
			(xy 180.958676 -154.921606) (xy 181.001056 -154.879226) (xy 181.048606 -154.842739) (xy 181.100512 -154.812772)
			(xy 181.155885 -154.789836) (xy 181.213778 -154.774323) (xy 181.2732 -154.7665) (xy 181.333136 -154.7665)
			(xy 181.392558 -154.774323) (xy 181.450451 -154.789836) (xy 181.505824 -154.812772) (xy 181.55773 -154.842739)
			(xy 181.60528 -154.879226) (xy 181.64766 -154.921606) (xy 181.684147 -154.969156) (xy 181.714114 -155.021062)
			(xy 181.73705 -155.076435) (xy 181.752563 -155.134328) (xy 181.760386 -155.19375) (xy 181.760876 -155.223718)
			(xy 181.760876 -156.085794) (xy 199.81672 -156.085794) (xy 199.81672 -155.222194) (xy 199.81721 -155.192226)
			(xy 199.825033 -155.132804) (xy 199.840546 -155.074911) (xy 199.863482 -155.019538) (xy 199.893449 -154.967632)
			(xy 199.929936 -154.920082) (xy 199.972316 -154.877702) (xy 200.019866 -154.841215) (xy 200.071772 -154.811248)
			(xy 200.127145 -154.788312) (xy 200.185038 -154.772799) (xy 200.24446 -154.764976) (xy 200.304396 -154.764976)
			(xy 200.363818 -154.772799) (xy 200.421711 -154.788312) (xy 200.477084 -154.811248) (xy 200.52899 -154.841215)
			(xy 200.57654 -154.877702) (xy 200.61892 -154.920082) (xy 200.655407 -154.967632) (xy 200.685374 -155.019538)
			(xy 200.70831 -155.074911) (xy 200.723823 -155.132804) (xy 200.731646 -155.192226) (xy 200.732136 -155.222194)
			(xy 200.732136 -156.085794) (xy 200.732111 -156.087318) (xy 296.945304 -156.087318) (xy 296.945304 -155.223718)
			(xy 296.945794 -155.19375) (xy 296.953617 -155.134328) (xy 296.96913 -155.076435) (xy 296.992066 -155.021062)
			(xy 297.022033 -154.969156) (xy 297.05852 -154.921606) (xy 297.1009 -154.879226) (xy 297.14845 -154.842739)
			(xy 297.200356 -154.812772) (xy 297.255729 -154.789836) (xy 297.313622 -154.774323) (xy 297.373044 -154.7665)
			(xy 297.43298 -154.7665) (xy 297.492402 -154.774323) (xy 297.550295 -154.789836) (xy 297.605668 -154.812772)
			(xy 297.657574 -154.842739) (xy 297.705124 -154.879226) (xy 297.747504 -154.921606) (xy 297.783991 -154.969156)
			(xy 297.813958 -155.021062) (xy 297.836894 -155.076435) (xy 297.852407 -155.134328) (xy 297.86023 -155.19375)
			(xy 297.86072 -155.223718) (xy 297.86072 -156.085794) (xy 315.916564 -156.085794) (xy 315.916564 -155.222194)
			(xy 315.917054 -155.192226) (xy 315.924877 -155.132804) (xy 315.94039 -155.074911) (xy 315.963326 -155.019538)
			(xy 315.993293 -154.967632) (xy 316.02978 -154.920082) (xy 316.07216 -154.877702) (xy 316.11971 -154.841215)
			(xy 316.171616 -154.811248) (xy 316.226989 -154.788312) (xy 316.284882 -154.772799) (xy 316.344304 -154.764976)
			(xy 316.40424 -154.764976) (xy 316.463662 -154.772799) (xy 316.521555 -154.788312) (xy 316.576928 -154.811248)
			(xy 316.628834 -154.841215) (xy 316.676384 -154.877702) (xy 316.718764 -154.920082) (xy 316.755251 -154.967632)
			(xy 316.785218 -155.019538) (xy 316.808154 -155.074911) (xy 316.823667 -155.132804) (xy 316.83149 -155.192226)
			(xy 316.83198 -155.222194) (xy 316.83198 -156.085794) (xy 316.831955 -156.087318) (xy 413.045148 -156.087318)
			(xy 413.045148 -155.223718) (xy 413.045638 -155.193734) (xy 413.053466 -155.134278) (xy 413.068987 -155.076353)
			(xy 413.091936 -155.020949) (xy 413.12192 -154.969015) (xy 413.158426 -154.921439) (xy 413.200831 -154.879034)
			(xy 413.248407 -154.842528) (xy 413.300341 -154.812544) (xy 413.355745 -154.789595) (xy 413.41367 -154.774074)
			(xy 413.473126 -154.766246) (xy 413.533094 -154.766246) (xy 413.59255 -154.774074) (xy 413.650475 -154.789595)
			(xy 413.705879 -154.812544) (xy 413.757813 -154.842528) (xy 413.805389 -154.879034) (xy 413.847794 -154.921439)
			(xy 413.8843 -154.969015) (xy 413.914284 -155.020949) (xy 413.937233 -155.076353) (xy 413.952754 -155.134278)
			(xy 413.960582 -155.193734) (xy 413.961072 -155.223718) (xy 413.961072 -156.085794) (xy 432.016408 -156.085794)
			(xy 432.016408 -155.222194) (xy 432.016898 -155.19221) (xy 432.024726 -155.132754) (xy 432.040247 -155.074829)
			(xy 432.063196 -155.019425) (xy 432.09318 -154.967491) (xy 432.129686 -154.919915) (xy 432.172091 -154.87751)
			(xy 432.219667 -154.841004) (xy 432.271601 -154.81102) (xy 432.327005 -154.788071) (xy 432.38493 -154.77255)
			(xy 432.444386 -154.764722) (xy 432.504354 -154.764722) (xy 432.56381 -154.77255) (xy 432.621735 -154.788071)
			(xy 432.677139 -154.81102) (xy 432.729073 -154.841004) (xy 432.776649 -154.87751) (xy 432.819054 -154.919915)
			(xy 432.85556 -154.967491) (xy 432.885544 -155.019425) (xy 432.908493 -155.074829) (xy 432.924014 -155.132754)
			(xy 432.931842 -155.19221) (xy 432.932332 -155.222194) (xy 432.932332 -156.085794) (xy 432.931842 -156.115778)
			(xy 432.924014 -156.175234) (xy 432.908493 -156.233159) (xy 432.885544 -156.288563) (xy 432.85556 -156.340497)
			(xy 432.819054 -156.388073) (xy 432.776649 -156.430478) (xy 432.729073 -156.466984) (xy 432.677139 -156.496968)
			(xy 432.621735 -156.519917) (xy 432.56381 -156.535438) (xy 432.504354 -156.543266) (xy 432.444386 -156.543266)
			(xy 432.38493 -156.535438) (xy 432.327005 -156.519917) (xy 432.271601 -156.496968) (xy 432.219667 -156.466984)
			(xy 432.172091 -156.430478) (xy 432.129686 -156.388073) (xy 432.09318 -156.340497) (xy 432.063196 -156.288563)
			(xy 432.040247 -156.233159) (xy 432.024726 -156.175234) (xy 432.016898 -156.115778) (xy 432.016408 -156.085794)
			(xy 413.961072 -156.085794) (xy 413.961072 -156.087318) (xy 413.960582 -156.117302) (xy 413.952754 -156.176758)
			(xy 413.937233 -156.234683) (xy 413.914284 -156.290087) (xy 413.8843 -156.342021) (xy 413.847794 -156.389597)
			(xy 413.805389 -156.432002) (xy 413.757813 -156.468508) (xy 413.705879 -156.498492) (xy 413.650475 -156.521441)
			(xy 413.59255 -156.536962) (xy 413.533094 -156.54479) (xy 413.473126 -156.54479) (xy 413.41367 -156.536962)
			(xy 413.355745 -156.521441) (xy 413.300341 -156.498492) (xy 413.248407 -156.468508) (xy 413.200831 -156.432002)
			(xy 413.158426 -156.389597) (xy 413.12192 -156.342021) (xy 413.091936 -156.290087) (xy 413.068987 -156.234683)
			(xy 413.053466 -156.176758) (xy 413.045638 -156.117302) (xy 413.045148 -156.087318) (xy 316.831955 -156.087318)
			(xy 316.83149 -156.115762) (xy 316.823667 -156.175184) (xy 316.808154 -156.233077) (xy 316.785218 -156.28845)
			(xy 316.755251 -156.340356) (xy 316.718764 -156.387906) (xy 316.676384 -156.430286) (xy 316.628834 -156.466773)
			(xy 316.576928 -156.49674) (xy 316.521555 -156.519676) (xy 316.463662 -156.535189) (xy 316.40424 -156.543012)
			(xy 316.344304 -156.543012) (xy 316.284882 -156.535189) (xy 316.226989 -156.519676) (xy 316.171616 -156.49674)
			(xy 316.11971 -156.466773) (xy 316.07216 -156.430286) (xy 316.02978 -156.387906) (xy 315.993293 -156.340356)
			(xy 315.963326 -156.28845) (xy 315.94039 -156.233077) (xy 315.924877 -156.175184) (xy 315.917054 -156.115762)
			(xy 315.916564 -156.085794) (xy 297.86072 -156.085794) (xy 297.86072 -156.087318) (xy 297.86023 -156.117286)
			(xy 297.852407 -156.176708) (xy 297.836894 -156.234601) (xy 297.813958 -156.289974) (xy 297.783991 -156.34188)
			(xy 297.747504 -156.38943) (xy 297.705124 -156.43181) (xy 297.657574 -156.468297) (xy 297.605668 -156.498264)
			(xy 297.550295 -156.5212) (xy 297.492402 -156.536713) (xy 297.43298 -156.544536) (xy 297.373044 -156.544536)
			(xy 297.313622 -156.536713) (xy 297.255729 -156.5212) (xy 297.200356 -156.498264) (xy 297.14845 -156.468297)
			(xy 297.1009 -156.43181) (xy 297.05852 -156.38943) (xy 297.022033 -156.34188) (xy 296.992066 -156.289974)
			(xy 296.96913 -156.234601) (xy 296.953617 -156.176708) (xy 296.945794 -156.117286) (xy 296.945304 -156.087318)
			(xy 200.732111 -156.087318) (xy 200.731646 -156.115762) (xy 200.723823 -156.175184) (xy 200.70831 -156.233077)
			(xy 200.685374 -156.28845) (xy 200.655407 -156.340356) (xy 200.61892 -156.387906) (xy 200.57654 -156.430286)
			(xy 200.52899 -156.466773) (xy 200.477084 -156.49674) (xy 200.421711 -156.519676) (xy 200.363818 -156.535189)
			(xy 200.304396 -156.543012) (xy 200.24446 -156.543012) (xy 200.185038 -156.535189) (xy 200.127145 -156.519676)
			(xy 200.071772 -156.49674) (xy 200.019866 -156.466773) (xy 199.972316 -156.430286) (xy 199.929936 -156.387906)
			(xy 199.893449 -156.340356) (xy 199.863482 -156.28845) (xy 199.840546 -156.233077) (xy 199.825033 -156.175184)
			(xy 199.81721 -156.115762) (xy 199.81672 -156.085794) (xy 181.760876 -156.085794) (xy 181.760876 -156.087318)
			(xy 181.760386 -156.117286) (xy 181.752563 -156.176708) (xy 181.73705 -156.234601) (xy 181.714114 -156.289974)
			(xy 181.684147 -156.34188) (xy 181.64766 -156.38943) (xy 181.60528 -156.43181) (xy 181.55773 -156.468297)
			(xy 181.505824 -156.498264) (xy 181.450451 -156.5212) (xy 181.392558 -156.536713) (xy 181.333136 -156.544536)
			(xy 181.2732 -156.544536) (xy 181.213778 -156.536713) (xy 181.155885 -156.5212) (xy 181.100512 -156.498264)
			(xy 181.048606 -156.468297) (xy 181.001056 -156.43181) (xy 180.958676 -156.38943) (xy 180.922189 -156.34188)
			(xy 180.892222 -156.289974) (xy 180.869286 -156.234601) (xy 180.853773 -156.176708) (xy 180.84595 -156.117286)
			(xy 180.84546 -156.087318) (xy 84.632267 -156.087318) (xy 84.631802 -156.115778) (xy 84.623974 -156.175234)
			(xy 84.608453 -156.233159) (xy 84.585504 -156.288563) (xy 84.55552 -156.340497) (xy 84.519014 -156.388073)
			(xy 84.476609 -156.430478) (xy 84.429033 -156.466984) (xy 84.377099 -156.496968) (xy 84.321695 -156.519917)
			(xy 84.26377 -156.535438) (xy 84.204314 -156.543266) (xy 84.144346 -156.543266) (xy 84.08489 -156.535438)
			(xy 84.026965 -156.519917) (xy 83.971561 -156.496968) (xy 83.919627 -156.466984) (xy 83.872051 -156.430478)
			(xy 83.829646 -156.388073) (xy 83.79314 -156.340497) (xy 83.763156 -156.288563) (xy 83.740207 -156.233159)
			(xy 83.724686 -156.175234) (xy 83.716858 -156.115778) (xy 83.716368 -156.085794) (xy 65.661032 -156.085794)
			(xy 65.661032 -156.087318) (xy 65.660542 -156.117302) (xy 65.652714 -156.176758) (xy 65.637193 -156.234683)
			(xy 65.614244 -156.290087) (xy 65.58426 -156.342021) (xy 65.547754 -156.389597) (xy 65.505349 -156.432002)
			(xy 65.457773 -156.468508) (xy 65.405839 -156.498492) (xy 65.350435 -156.521441) (xy 65.29251 -156.536962)
			(xy 65.233054 -156.54479) (xy 65.173086 -156.54479) (xy 65.11363 -156.536962) (xy 65.055705 -156.521441)
			(xy 65.000301 -156.498492) (xy 64.948367 -156.468508) (xy 64.900791 -156.432002) (xy 64.858386 -156.389597)
			(xy 64.82188 -156.342021) (xy 64.791896 -156.290087) (xy 64.768947 -156.234683) (xy 64.753426 -156.176758)
			(xy 64.745598 -156.117302) (xy 64.745108 -156.087318) (xy 5.324094 -156.087318) (xy 5.324094 -157.900066)
			(xy 228.314505 -157.900066) (xy 228.314505 -157.840134) (xy 228.322328 -157.780714) (xy 228.33784 -157.722823)
			(xy 228.360775 -157.667453) (xy 228.390741 -157.61555) (xy 228.427226 -157.568002) (xy 228.469605 -157.525624)
			(xy 228.517153 -157.489139) (xy 228.569056 -157.459173) (xy 228.624427 -157.436238) (xy 228.682318 -157.420727)
			(xy 228.741738 -157.412905) (xy 228.771704 -157.412436) (xy 229.635304 -157.412436) (xy 229.665274 -157.412838)
			(xy 229.724702 -157.420663) (xy 229.7826 -157.436177) (xy 229.837978 -157.459116) (xy 229.889888 -157.489086)
			(xy 229.937442 -157.525576) (xy 229.979827 -157.567961) (xy 230.016316 -157.615515) (xy 230.046286 -157.667425)
			(xy 230.069224 -157.722803) (xy 230.084738 -157.780702) (xy 230.092562 -157.84013) (xy 230.092562 -157.90007)
			(xy 230.089876 -157.920473) (xy 230.557725 -157.920473) (xy 230.557725 -157.860527) (xy 230.56555 -157.801095)
			(xy 230.581066 -157.743192) (xy 230.604007 -157.68781) (xy 230.633981 -157.635897) (xy 230.670475 -157.58834)
			(xy 230.712864 -157.545953) (xy 230.760423 -157.509463) (xy 230.812339 -157.479493) (xy 230.867722 -157.456555)
			(xy 230.925626 -157.441044) (xy 230.985059 -157.433223) (xy 231.015032 -157.432756) (xy 231.878632 -157.432756)
			(xy 231.908596 -157.43332) (xy 231.968011 -157.441146) (xy 232.025896 -157.45666) (xy 232.081261 -157.479596)
			(xy 232.133158 -157.509563) (xy 232.180701 -157.546046) (xy 232.223075 -157.588423) (xy 232.259555 -157.635968)
			(xy 232.289518 -157.687868) (xy 232.31245 -157.743235) (xy 232.32796 -157.801121) (xy 232.335782 -157.860536)
			(xy 232.335782 -157.920464) (xy 232.32796 -157.979879) (xy 232.31245 -158.037765) (xy 232.289518 -158.093132)
			(xy 232.259555 -158.145032) (xy 232.223075 -158.192577) (xy 232.180701 -158.234954) (xy 232.133158 -158.271437)
			(xy 232.081261 -158.301404) (xy 232.025896 -158.32434) (xy 231.968011 -158.339854) (xy 231.908596 -158.34768)
			(xy 231.878632 -158.348172) (xy 231.015032 -158.348172) (xy 230.985059 -158.347777) (xy 230.925626 -158.339956)
			(xy 230.867722 -158.324445) (xy 230.812339 -158.301507) (xy 230.760423 -158.271537) (xy 230.712864 -158.235047)
			(xy 230.670475 -158.19266) (xy 230.633981 -158.145103) (xy 230.604007 -158.09319) (xy 230.581066 -158.037808)
			(xy 230.56555 -157.979905) (xy 230.557725 -157.920473) (xy 230.089876 -157.920473) (xy 230.084738 -157.959498)
			(xy 230.069224 -158.017397) (xy 230.046286 -158.072775) (xy 230.016316 -158.124685) (xy 229.979827 -158.172239)
			(xy 229.937442 -158.214624) (xy 229.889888 -158.251114) (xy 229.837978 -158.281084) (xy 229.7826 -158.304023)
			(xy 229.724702 -158.319537) (xy 229.665274 -158.327362) (xy 229.635304 -158.327852) (xy 228.771704 -158.327852)
			(xy 228.741738 -158.327295) (xy 228.682318 -158.319473) (xy 228.624427 -158.303962) (xy 228.569056 -158.281027)
			(xy 228.517153 -158.251061) (xy 228.469605 -158.214576) (xy 228.427226 -158.172198) (xy 228.390741 -158.12465)
			(xy 228.360775 -158.072747) (xy 228.33784 -158.017377) (xy 228.322328 -157.959486) (xy 228.314505 -157.900066)
			(xy 5.324094 -157.900066) (xy 5.324094 -160.1851) (xy 45.524179 -160.1851) (xy 45.528134 -160.093263)
			(xy 45.539969 -160.002106) (xy 45.559596 -159.912303) (xy 45.58687 -159.824521) (xy 45.62159 -159.739407)
			(xy 45.663498 -159.657594) (xy 45.712284 -159.579686) (xy 45.767587 -159.506261) (xy 45.828997 -159.437861)
			(xy 45.896059 -159.374994) (xy 45.968278 -159.318124) (xy 46.045118 -159.267673) (xy 46.126011 -159.224014)
			(xy 46.210357 -159.187471) (xy 46.297533 -159.158314) (xy 46.386892 -159.13676) (xy 46.477773 -159.122966)
			(xy 46.569504 -159.117036) (xy 46.661405 -159.119014) (xy 46.752796 -159.128885) (xy 46.843 -159.146575)
			(xy 46.931349 -159.171955) (xy 47.017189 -159.204835) (xy 47.099885 -159.244973) (xy 47.178825 -159.292072)
			(xy 47.253423 -159.345782) (xy 47.323129 -159.405706) (xy 47.387424 -159.4714) (xy 47.445835 -159.542378)
			(xy 47.497927 -159.618115) (xy 47.543316 -159.69805) (xy 47.581666 -159.78159) (xy 47.612691 -159.868118)
			(xy 47.636164 -159.956993) (xy 47.65191 -160.047557) (xy 47.659812 -160.139139) (xy 47.660306 -160.1851)
			(xy 69.888875 -160.1851) (xy 69.892831 -160.093241) (xy 69.904668 -160.002062) (xy 69.9243 -159.912238)
			(xy 69.951581 -159.824435) (xy 69.986309 -159.739302) (xy 70.028227 -159.657469) (xy 70.077025 -159.579542)
			(xy 70.13234 -159.506099) (xy 70.193765 -159.437683) (xy 70.260844 -159.374801) (xy 70.333079 -159.317918)
			(xy 70.409938 -159.267455) (xy 70.49085 -159.223786) (xy 70.575216 -159.187234) (xy 70.662412 -159.15807)
			(xy 70.751793 -159.13651) (xy 70.842696 -159.122714) (xy 70.934449 -159.116782) (xy 71.026371 -159.118761)
			(xy 71.117784 -159.128634) (xy 71.208009 -159.146329) (xy 71.29638 -159.171714) (xy 71.38224 -159.204602)
			(xy 71.464956 -159.24475) (xy 71.543914 -159.291859) (xy 71.618531 -159.345582) (xy 71.688252 -159.40552)
			(xy 71.752563 -159.47123) (xy 71.810988 -159.542226) (xy 71.863093 -159.61798) (xy 71.908492 -159.697934)
			(xy 71.946851 -159.781494) (xy 71.977884 -159.868043) (xy 72.001362 -159.956939) (xy 72.017112 -160.047524)
			(xy 72.025016 -160.139128) (xy 72.02551 -160.1851) (xy 161.624277 -160.1851) (xy 161.628232 -160.093263)
			(xy 161.640067 -160.002106) (xy 161.659694 -159.912303) (xy 161.686968 -159.824521) (xy 161.721688 -159.739407)
			(xy 161.763596 -159.657594) (xy 161.812382 -159.579686) (xy 161.867685 -159.506261) (xy 161.929095 -159.437861)
			(xy 161.996157 -159.374994) (xy 162.068376 -159.318124) (xy 162.145216 -159.267673) (xy 162.226109 -159.224014)
			(xy 162.310455 -159.187471) (xy 162.397631 -159.158314) (xy 162.48699 -159.13676) (xy 162.577871 -159.122966)
			(xy 162.669602 -159.117036) (xy 162.761503 -159.119014) (xy 162.852894 -159.128885) (xy 162.943098 -159.146575)
			(xy 163.031447 -159.171955) (xy 163.117287 -159.204835) (xy 163.199983 -159.244973) (xy 163.278923 -159.292072)
			(xy 163.353521 -159.345782) (xy 163.423227 -159.405706) (xy 163.487522 -159.4714) (xy 163.545933 -159.542378)
			(xy 163.598025 -159.618115) (xy 163.643414 -159.69805) (xy 163.681764 -159.78159) (xy 163.712789 -159.868118)
			(xy 163.736262 -159.956993) (xy 163.752008 -160.047557) (xy 163.75991 -160.139139) (xy 163.760404 -160.1851)
			(xy 185.988973 -160.1851) (xy 185.992929 -160.093241) (xy 186.004766 -160.002062) (xy 186.024398 -159.912238)
			(xy 186.051679 -159.824435) (xy 186.086407 -159.739302) (xy 186.128325 -159.657469) (xy 186.177123 -159.579542)
			(xy 186.232438 -159.506099) (xy 186.293863 -159.437683) (xy 186.360942 -159.374801) (xy 186.433177 -159.317918)
			(xy 186.510036 -159.267455) (xy 186.590948 -159.223786) (xy 186.675314 -159.187234) (xy 186.76251 -159.15807)
			(xy 186.851891 -159.13651) (xy 186.942794 -159.122714) (xy 187.034547 -159.116782) (xy 187.126469 -159.118761)
			(xy 187.217882 -159.128634) (xy 187.308107 -159.146329) (xy 187.396478 -159.171714) (xy 187.482338 -159.204602)
			(xy 187.565054 -159.24475) (xy 187.644012 -159.291859) (xy 187.718629 -159.345582) (xy 187.78835 -159.40552)
			(xy 187.852661 -159.47123) (xy 187.911086 -159.542226) (xy 187.963191 -159.61798) (xy 188.00859 -159.697934)
			(xy 188.046949 -159.781494) (xy 188.077982 -159.868043) (xy 188.10146 -159.956939) (xy 188.11721 -160.047524)
			(xy 188.125114 -160.139128) (xy 188.125608 -160.1851) (xy 277.724121 -160.1851) (xy 277.728076 -160.093263)
			(xy 277.739911 -160.002106) (xy 277.759538 -159.912303) (xy 277.786812 -159.824521) (xy 277.821532 -159.739407)
			(xy 277.86344 -159.657594) (xy 277.912226 -159.579686) (xy 277.967529 -159.506261) (xy 278.028939 -159.437861)
			(xy 278.096001 -159.374994) (xy 278.16822 -159.318124) (xy 278.24506 -159.267673) (xy 278.325953 -159.224014)
			(xy 278.410299 -159.187471) (xy 278.497475 -159.158314) (xy 278.586834 -159.13676) (xy 278.677715 -159.122966)
			(xy 278.769446 -159.117036) (xy 278.861347 -159.119014) (xy 278.952738 -159.128885) (xy 279.042942 -159.146575)
			(xy 279.131291 -159.171955) (xy 279.217131 -159.204835) (xy 279.299827 -159.244973) (xy 279.378767 -159.292072)
			(xy 279.453365 -159.345782) (xy 279.523071 -159.405706) (xy 279.587366 -159.4714) (xy 279.645777 -159.542378)
			(xy 279.697869 -159.618115) (xy 279.743258 -159.69805) (xy 279.781608 -159.78159) (xy 279.812633 -159.868118)
			(xy 279.836106 -159.956993) (xy 279.851852 -160.047557) (xy 279.859754 -160.139139) (xy 279.860248 -160.1851)
			(xy 302.088817 -160.1851) (xy 302.092773 -160.093241) (xy 302.10461 -160.002062) (xy 302.124242 -159.912238)
			(xy 302.151523 -159.824435) (xy 302.186251 -159.739302) (xy 302.228169 -159.657469) (xy 302.276967 -159.579542)
			(xy 302.332282 -159.506099) (xy 302.393707 -159.437683) (xy 302.460786 -159.374801) (xy 302.533021 -159.317918)
			(xy 302.60988 -159.267455) (xy 302.690792 -159.223786) (xy 302.775158 -159.187234) (xy 302.862354 -159.15807)
			(xy 302.951735 -159.13651) (xy 303.042638 -159.122714) (xy 303.134391 -159.116782) (xy 303.226313 -159.118761)
			(xy 303.317726 -159.128634) (xy 303.407951 -159.146329) (xy 303.496322 -159.171714) (xy 303.582182 -159.204602)
			(xy 303.664898 -159.24475) (xy 303.743856 -159.291859) (xy 303.818473 -159.345582) (xy 303.888194 -159.40552)
			(xy 303.952505 -159.47123) (xy 304.01093 -159.542226) (xy 304.063035 -159.61798) (xy 304.108434 -159.697934)
			(xy 304.146793 -159.781494) (xy 304.177826 -159.868043) (xy 304.201304 -159.956939) (xy 304.217054 -160.047524)
			(xy 304.224958 -160.139128) (xy 304.225452 -160.1851) (xy 393.824219 -160.1851) (xy 393.828174 -160.093263)
			(xy 393.840009 -160.002106) (xy 393.859636 -159.912303) (xy 393.88691 -159.824521) (xy 393.92163 -159.739407)
			(xy 393.963538 -159.657594) (xy 394.012324 -159.579686) (xy 394.067627 -159.506261) (xy 394.129037 -159.437861)
			(xy 394.196099 -159.374994) (xy 394.268318 -159.318124) (xy 394.345158 -159.267673) (xy 394.426051 -159.224014)
			(xy 394.510397 -159.187471) (xy 394.597573 -159.158314) (xy 394.686932 -159.13676) (xy 394.777813 -159.122966)
			(xy 394.869544 -159.117036) (xy 394.961445 -159.119014) (xy 395.052836 -159.128885) (xy 395.14304 -159.146575)
			(xy 395.231389 -159.171955) (xy 395.317229 -159.204835) (xy 395.399925 -159.244973) (xy 395.478865 -159.292072)
			(xy 395.553463 -159.345782) (xy 395.623169 -159.405706) (xy 395.687464 -159.4714) (xy 395.745875 -159.542378)
			(xy 395.797967 -159.618115) (xy 395.843356 -159.69805) (xy 395.881706 -159.78159) (xy 395.912731 -159.868118)
			(xy 395.936204 -159.956993) (xy 395.95195 -160.047557) (xy 395.959852 -160.139139) (xy 395.960346 -160.1851)
			(xy 418.188915 -160.1851) (xy 418.192871 -160.093241) (xy 418.204708 -160.002062) (xy 418.22434 -159.912238)
			(xy 418.251621 -159.824435) (xy 418.286349 -159.739302) (xy 418.328267 -159.657469) (xy 418.377065 -159.579542)
			(xy 418.43238 -159.506099) (xy 418.493805 -159.437683) (xy 418.560884 -159.374801) (xy 418.633119 -159.317918)
			(xy 418.709978 -159.267455) (xy 418.79089 -159.223786) (xy 418.875256 -159.187234) (xy 418.962452 -159.15807)
			(xy 419.051833 -159.13651) (xy 419.142736 -159.122714) (xy 419.234489 -159.116782) (xy 419.326411 -159.118761)
			(xy 419.417824 -159.128634) (xy 419.508049 -159.146329) (xy 419.59642 -159.171714) (xy 419.68228 -159.204602)
			(xy 419.764996 -159.24475) (xy 419.843954 -159.291859) (xy 419.918571 -159.345582) (xy 419.988292 -159.40552)
			(xy 420.052603 -159.47123) (xy 420.111028 -159.542226) (xy 420.163133 -159.61798) (xy 420.208532 -159.697934)
			(xy 420.246891 -159.781494) (xy 420.277924 -159.868043) (xy 420.301402 -159.956939) (xy 420.317152 -160.047524)
			(xy 420.325056 -160.139128) (xy 420.32555 -160.1851) (xy 420.325056 -160.231072) (xy 420.317152 -160.322676)
			(xy 420.301402 -160.413261) (xy 420.277924 -160.502157) (xy 420.246891 -160.588706) (xy 420.208532 -160.672266)
			(xy 420.163133 -160.75222) (xy 420.111028 -160.827974) (xy 420.052603 -160.89897) (xy 419.988292 -160.96468)
			(xy 419.918571 -161.024618) (xy 419.843954 -161.078341) (xy 419.764996 -161.12545) (xy 419.68228 -161.165598)
			(xy 419.59642 -161.198486) (xy 419.508049 -161.223871) (xy 419.417824 -161.241566) (xy 419.326411 -161.251439)
			(xy 419.234489 -161.253418) (xy 419.142736 -161.247486) (xy 419.051833 -161.23369) (xy 418.962452 -161.21213)
			(xy 418.875256 -161.182966) (xy 418.79089 -161.146414) (xy 418.709978 -161.102745) (xy 418.633119 -161.052282)
			(xy 418.560884 -160.995399) (xy 418.493805 -160.932517) (xy 418.43238 -160.864101) (xy 418.377065 -160.790658)
			(xy 418.328267 -160.712731) (xy 418.286349 -160.630898) (xy 418.251621 -160.545765) (xy 418.22434 -160.457962)
			(xy 418.204708 -160.368138) (xy 418.192871 -160.276959) (xy 418.188915 -160.1851) (xy 395.960346 -160.1851)
			(xy 395.959852 -160.231061) (xy 395.95195 -160.322643) (xy 395.936204 -160.413207) (xy 395.912731 -160.502082)
			(xy 395.881706 -160.58861) (xy 395.843356 -160.67215) (xy 395.797967 -160.752085) (xy 395.745875 -160.827822)
			(xy 395.687464 -160.8988) (xy 395.623169 -160.964494) (xy 395.553463 -161.024418) (xy 395.478865 -161.078128)
			(xy 395.399925 -161.125227) (xy 395.317229 -161.165365) (xy 395.231389 -161.198245) (xy 395.14304 -161.223625)
			(xy 395.052836 -161.241315) (xy 394.961445 -161.251186) (xy 394.869544 -161.253164) (xy 394.777813 -161.247234)
			(xy 394.686932 -161.23344) (xy 394.597573 -161.211886) (xy 394.510397 -161.182729) (xy 394.426051 -161.146186)
			(xy 394.345158 -161.102527) (xy 394.268318 -161.052076) (xy 394.196099 -160.995206) (xy 394.129037 -160.932339)
			(xy 394.067627 -160.863939) (xy 394.012324 -160.790514) (xy 393.963538 -160.712606) (xy 393.92163 -160.630793)
			(xy 393.88691 -160.545679) (xy 393.859636 -160.457897) (xy 393.840009 -160.368094) (xy 393.828174 -160.276937)
			(xy 393.824219 -160.1851) (xy 304.225452 -160.1851) (xy 304.224958 -160.231072) (xy 304.217054 -160.322676)
			(xy 304.201304 -160.413261) (xy 304.177826 -160.502157) (xy 304.146793 -160.588706) (xy 304.108434 -160.672266)
			(xy 304.063035 -160.75222) (xy 304.01093 -160.827974) (xy 303.952505 -160.89897) (xy 303.888194 -160.96468)
			(xy 303.818473 -161.024618) (xy 303.743856 -161.078341) (xy 303.664898 -161.12545) (xy 303.582182 -161.165598)
			(xy 303.496322 -161.198486) (xy 303.407951 -161.223871) (xy 303.317726 -161.241566) (xy 303.226313 -161.251439)
			(xy 303.134391 -161.253418) (xy 303.042638 -161.247486) (xy 302.951735 -161.23369) (xy 302.862354 -161.21213)
			(xy 302.775158 -161.182966) (xy 302.690792 -161.146414) (xy 302.60988 -161.102745) (xy 302.533021 -161.052282)
			(xy 302.460786 -160.995399) (xy 302.393707 -160.932517) (xy 302.332282 -160.864101) (xy 302.276967 -160.790658)
			(xy 302.228169 -160.712731) (xy 302.186251 -160.630898) (xy 302.151523 -160.545765) (xy 302.124242 -160.457962)
			(xy 302.10461 -160.368138) (xy 302.092773 -160.276959) (xy 302.088817 -160.1851) (xy 279.860248 -160.1851)
			(xy 279.859754 -160.231061) (xy 279.851852 -160.322643) (xy 279.836106 -160.413207) (xy 279.812633 -160.502082)
			(xy 279.781608 -160.58861) (xy 279.743258 -160.67215) (xy 279.697869 -160.752085) (xy 279.645777 -160.827822)
			(xy 279.587366 -160.8988) (xy 279.523071 -160.964494) (xy 279.453365 -161.024418) (xy 279.378767 -161.078128)
			(xy 279.299827 -161.125227) (xy 279.217131 -161.165365) (xy 279.131291 -161.198245) (xy 279.042942 -161.223625)
			(xy 278.952738 -161.241315) (xy 278.861347 -161.251186) (xy 278.769446 -161.253164) (xy 278.677715 -161.247234)
			(xy 278.586834 -161.23344) (xy 278.497475 -161.211886) (xy 278.410299 -161.182729) (xy 278.325953 -161.146186)
			(xy 278.24506 -161.102527) (xy 278.16822 -161.052076) (xy 278.096001 -160.995206) (xy 278.028939 -160.932339)
			(xy 277.967529 -160.863939) (xy 277.912226 -160.790514) (xy 277.86344 -160.712606) (xy 277.821532 -160.630793)
			(xy 277.786812 -160.545679) (xy 277.759538 -160.457897) (xy 277.739911 -160.368094) (xy 277.728076 -160.276937)
			(xy 277.724121 -160.1851) (xy 188.125608 -160.1851) (xy 188.125114 -160.231072) (xy 188.11721 -160.322676)
			(xy 188.10146 -160.413261) (xy 188.077982 -160.502157) (xy 188.046949 -160.588706) (xy 188.00859 -160.672266)
			(xy 187.963191 -160.75222) (xy 187.911086 -160.827974) (xy 187.852661 -160.89897) (xy 187.78835 -160.96468)
			(xy 187.718629 -161.024618) (xy 187.644012 -161.078341) (xy 187.565054 -161.12545) (xy 187.482338 -161.165598)
			(xy 187.396478 -161.198486) (xy 187.308107 -161.223871) (xy 187.217882 -161.241566) (xy 187.126469 -161.251439)
			(xy 187.034547 -161.253418) (xy 186.942794 -161.247486) (xy 186.851891 -161.23369) (xy 186.76251 -161.21213)
			(xy 186.675314 -161.182966) (xy 186.590948 -161.146414) (xy 186.510036 -161.102745) (xy 186.433177 -161.052282)
			(xy 186.360942 -160.995399) (xy 186.293863 -160.932517) (xy 186.232438 -160.864101) (xy 186.177123 -160.790658)
			(xy 186.128325 -160.712731) (xy 186.086407 -160.630898) (xy 186.051679 -160.545765) (xy 186.024398 -160.457962)
			(xy 186.004766 -160.368138) (xy 185.992929 -160.276959) (xy 185.988973 -160.1851) (xy 163.760404 -160.1851)
			(xy 163.75991 -160.231061) (xy 163.752008 -160.322643) (xy 163.736262 -160.413207) (xy 163.712789 -160.502082)
			(xy 163.681764 -160.58861) (xy 163.643414 -160.67215) (xy 163.598025 -160.752085) (xy 163.545933 -160.827822)
			(xy 163.487522 -160.8988) (xy 163.423227 -160.964494) (xy 163.353521 -161.024418) (xy 163.278923 -161.078128)
			(xy 163.199983 -161.125227) (xy 163.117287 -161.165365) (xy 163.031447 -161.198245) (xy 162.943098 -161.223625)
			(xy 162.852894 -161.241315) (xy 162.761503 -161.251186) (xy 162.669602 -161.253164) (xy 162.577871 -161.247234)
			(xy 162.48699 -161.23344) (xy 162.397631 -161.211886) (xy 162.310455 -161.182729) (xy 162.226109 -161.146186)
			(xy 162.145216 -161.102527) (xy 162.068376 -161.052076) (xy 161.996157 -160.995206) (xy 161.929095 -160.932339)
			(xy 161.867685 -160.863939) (xy 161.812382 -160.790514) (xy 161.763596 -160.712606) (xy 161.721688 -160.630793)
			(xy 161.686968 -160.545679) (xy 161.659694 -160.457897) (xy 161.640067 -160.368094) (xy 161.628232 -160.276937)
			(xy 161.624277 -160.1851) (xy 72.02551 -160.1851) (xy 72.025016 -160.231072) (xy 72.017112 -160.322676)
			(xy 72.001362 -160.413261) (xy 71.977884 -160.502157) (xy 71.946851 -160.588706) (xy 71.908492 -160.672266)
			(xy 71.863093 -160.75222) (xy 71.810988 -160.827974) (xy 71.752563 -160.89897) (xy 71.688252 -160.96468)
			(xy 71.618531 -161.024618) (xy 71.543914 -161.078341) (xy 71.464956 -161.12545) (xy 71.38224 -161.165598)
			(xy 71.29638 -161.198486) (xy 71.208009 -161.223871) (xy 71.117784 -161.241566) (xy 71.026371 -161.251439)
			(xy 70.934449 -161.253418) (xy 70.842696 -161.247486) (xy 70.751793 -161.23369) (xy 70.662412 -161.21213)
			(xy 70.575216 -161.182966) (xy 70.49085 -161.146414) (xy 70.409938 -161.102745) (xy 70.333079 -161.052282)
			(xy 70.260844 -160.995399) (xy 70.193765 -160.932517) (xy 70.13234 -160.864101) (xy 70.077025 -160.790658)
			(xy 70.028227 -160.712731) (xy 69.986309 -160.630898) (xy 69.951581 -160.545765) (xy 69.9243 -160.457962)
			(xy 69.904668 -160.368138) (xy 69.892831 -160.276959) (xy 69.888875 -160.1851) (xy 47.660306 -160.1851)
			(xy 47.659812 -160.231061) (xy 47.65191 -160.322643) (xy 47.636164 -160.413207) (xy 47.612691 -160.502082)
			(xy 47.581666 -160.58861) (xy 47.543316 -160.67215) (xy 47.497927 -160.752085) (xy 47.445835 -160.827822)
			(xy 47.387424 -160.8988) (xy 47.323129 -160.964494) (xy 47.253423 -161.024418) (xy 47.178825 -161.078128)
			(xy 47.099885 -161.125227) (xy 47.017189 -161.165365) (xy 46.931349 -161.198245) (xy 46.843 -161.223625)
			(xy 46.752796 -161.241315) (xy 46.661405 -161.251186) (xy 46.569504 -161.253164) (xy 46.477773 -161.247234)
			(xy 46.386892 -161.23344) (xy 46.297533 -161.211886) (xy 46.210357 -161.182729) (xy 46.126011 -161.146186)
			(xy 46.045118 -161.102527) (xy 45.968278 -161.052076) (xy 45.896059 -160.995206) (xy 45.828997 -160.932339)
			(xy 45.767587 -160.863939) (xy 45.712284 -160.790514) (xy 45.663498 -160.712606) (xy 45.62159 -160.630793)
			(xy 45.58687 -160.545679) (xy 45.559596 -160.457897) (xy 45.539969 -160.368094) (xy 45.528134 -160.276937)
			(xy 45.524179 -160.1851) (xy 5.324094 -160.1851) (xy 5.324094 -168.065164) (xy 135.245906 -168.065164)
			(xy 135.245906 -168.005236) (xy 135.253728 -167.94582) (xy 135.269237 -167.887933) (xy 135.29217 -167.832566)
			(xy 135.322132 -167.780665) (xy 135.358612 -167.733119) (xy 135.400986 -167.690742) (xy 135.448529 -167.654257)
			(xy 135.500426 -167.624289) (xy 135.555791 -167.601351) (xy 135.613677 -167.585836) (xy 135.673092 -167.578009)
			(xy 135.703056 -167.577516) (xy 136.566656 -167.577516) (xy 136.596628 -167.577934) (xy 136.656061 -167.585754)
			(xy 136.713965 -167.601264) (xy 136.769348 -167.6242) (xy 136.821264 -167.654169) (xy 136.868823 -167.690658)
			(xy 136.911213 -167.733044) (xy 136.947707 -167.7806) (xy 136.977681 -167.832512) (xy 137.000622 -167.887894)
			(xy 137.016138 -167.945796) (xy 137.023963 -168.005228) (xy 137.023963 -168.065172) (xy 137.016138 -168.124604)
			(xy 137.000622 -168.182506) (xy 136.977681 -168.237888) (xy 136.947707 -168.2898) (xy 136.911213 -168.337356)
			(xy 136.868823 -168.379742) (xy 136.821264 -168.416231) (xy 136.769348 -168.4462) (xy 136.713965 -168.469136)
			(xy 136.656061 -168.484646) (xy 136.596628 -168.492466) (xy 136.566656 -168.492932) (xy 135.703056 -168.492932)
			(xy 135.673092 -168.492391) (xy 135.613677 -168.484564) (xy 135.555791 -168.469049) (xy 135.500426 -168.446111)
			(xy 135.448529 -168.416143) (xy 135.400986 -168.379658) (xy 135.358612 -168.337281) (xy 135.322132 -168.289735)
			(xy 135.29217 -168.237834) (xy 135.269237 -168.182467) (xy 135.253728 -168.12458) (xy 135.245906 -168.065164)
			(xy 5.324094 -168.065164) (xy 5.324094 -168.700164) (xy 133.213906 -168.700164) (xy 133.213906 -168.640236)
			(xy 133.221728 -168.58082) (xy 133.237237 -168.522933) (xy 133.26017 -168.467566) (xy 133.290132 -168.415665)
			(xy 133.326612 -168.368119) (xy 133.368986 -168.325742) (xy 133.416529 -168.289257) (xy 133.468426 -168.259289)
			(xy 133.523791 -168.236351) (xy 133.581677 -168.220836) (xy 133.641092 -168.213009) (xy 133.671056 -168.212516)
			(xy 134.534656 -168.212516) (xy 134.564628 -168.212934) (xy 134.624061 -168.220754) (xy 134.681965 -168.236264)
			(xy 134.737348 -168.2592) (xy 134.789264 -168.289169) (xy 134.836823 -168.325658) (xy 134.879213 -168.368044)
			(xy 134.915707 -168.4156) (xy 134.945681 -168.467512) (xy 134.968622 -168.522894) (xy 134.984138 -168.580796)
			(xy 134.991963 -168.640228) (xy 134.991963 -168.700172) (xy 134.984138 -168.759604) (xy 134.968622 -168.817506)
			(xy 134.945681 -168.872888) (xy 134.915707 -168.9248) (xy 134.879213 -168.972356) (xy 134.836823 -169.014742)
			(xy 134.789264 -169.051231) (xy 134.737348 -169.0812) (xy 134.681965 -169.104136) (xy 134.624061 -169.119646)
			(xy 134.564628 -169.127466) (xy 134.534656 -169.127932) (xy 133.671056 -169.127932) (xy 133.641092 -169.127391)
			(xy 133.581677 -169.119564) (xy 133.523791 -169.104049) (xy 133.468426 -169.081111) (xy 133.416529 -169.051143)
			(xy 133.368986 -169.014658) (xy 133.326612 -168.972281) (xy 133.290132 -168.924735) (xy 133.26017 -168.872834)
			(xy 133.237237 -168.817467) (xy 133.221728 -168.75958) (xy 133.213906 -168.700164) (xy 5.324094 -168.700164)
			(xy 5.324094 -169.61389) (xy 245.108869 -169.61389) (xy 245.108869 -169.55391) (xy 245.116699 -169.494444)
			(xy 245.132223 -169.436508) (xy 245.155178 -169.381095) (xy 245.185169 -169.329152) (xy 245.221684 -169.281569)
			(xy 245.264097 -169.239158) (xy 245.311684 -169.202648) (xy 245.363629 -169.172661) (xy 245.419045 -169.149711)
			(xy 245.476981 -169.134191) (xy 245.536448 -169.126367) (xy 245.566438 -169.1259) (xy 246.430038 -169.1259)
			(xy 246.460018 -169.126468) (xy 246.519465 -169.134299) (xy 246.577381 -169.149822) (xy 246.632776 -169.172772)
			(xy 246.684702 -169.202755) (xy 246.73227 -169.239259) (xy 246.774667 -169.281659) (xy 246.811166 -169.32923)
			(xy 246.841145 -169.381158) (xy 246.86409 -169.436555) (xy 246.879608 -169.494472) (xy 246.887434 -169.55392)
			(xy 246.887434 -169.61388) (xy 246.879608 -169.673328) (xy 246.86409 -169.731245) (xy 246.841145 -169.786642)
			(xy 246.811166 -169.83857) (xy 246.774667 -169.886141) (xy 246.73227 -169.928541) (xy 246.684702 -169.965045)
			(xy 246.632776 -169.995028) (xy 246.577381 -170.017978) (xy 246.519465 -170.033501) (xy 246.460018 -170.041332)
			(xy 246.430038 -170.041824) (xy 245.566438 -170.041824) (xy 245.536448 -170.041433) (xy 245.476981 -170.033609)
			(xy 245.419045 -170.018089) (xy 245.363629 -169.995139) (xy 245.311684 -169.965152) (xy 245.264097 -169.928642)
			(xy 245.221684 -169.886231) (xy 245.185169 -169.838648) (xy 245.155178 -169.786705) (xy 245.132223 -169.731292)
			(xy 245.116699 -169.673356) (xy 245.108869 -169.61389) (xy 5.324094 -169.61389) (xy 5.324094 -174.805086)
			(xy 141.546072 -174.805086) (xy 141.546072 -173.941486) (xy 141.546562 -173.911518) (xy 141.554385 -173.852096)
			(xy 141.569898 -173.794203) (xy 141.592834 -173.73883) (xy 141.622801 -173.686924) (xy 141.659288 -173.639374)
			(xy 141.701668 -173.596994) (xy 141.749218 -173.560507) (xy 141.801124 -173.53054) (xy 141.856497 -173.507604)
			(xy 141.91439 -173.492091) (xy 141.973812 -173.484268) (xy 142.033748 -173.484268) (xy 142.09317 -173.492091)
			(xy 142.106698 -173.495716) (xy 257.519424 -173.495716) (xy 257.519424 -172.632116) (xy 257.519914 -172.602132)
			(xy 257.527742 -172.542676) (xy 257.543263 -172.484751) (xy 257.566212 -172.429347) (xy 257.596196 -172.377413)
			(xy 257.632702 -172.329837) (xy 257.675107 -172.287432) (xy 257.722683 -172.250926) (xy 257.774617 -172.220942)
			(xy 257.830021 -172.197993) (xy 257.887946 -172.182472) (xy 257.947402 -172.174644) (xy 258.00737 -172.174644)
			(xy 258.066826 -172.182472) (xy 258.124751 -172.197993) (xy 258.180155 -172.220942) (xy 258.232089 -172.250926)
			(xy 258.279665 -172.287432) (xy 258.32207 -172.329837) (xy 258.358576 -172.377413) (xy 258.38856 -172.429347)
			(xy 258.411509 -172.484751) (xy 258.42703 -172.542676) (xy 258.434858 -172.602132) (xy 258.435348 -172.632116)
			(xy 258.435348 -173.495716) (xy 258.434858 -173.5257) (xy 258.42703 -173.585156) (xy 258.411509 -173.643081)
			(xy 258.38856 -173.698485) (xy 258.358576 -173.750419) (xy 258.32207 -173.797995) (xy 258.279665 -173.8404)
			(xy 258.232089 -173.876906) (xy 258.180155 -173.90689) (xy 258.124751 -173.929839) (xy 258.066826 -173.94536)
			(xy 258.00737 -173.953188) (xy 257.947402 -173.953188) (xy 257.887946 -173.94536) (xy 257.830021 -173.929839)
			(xy 257.774617 -173.90689) (xy 257.722683 -173.876906) (xy 257.675107 -173.8404) (xy 257.632702 -173.797995)
			(xy 257.596196 -173.750419) (xy 257.566212 -173.698485) (xy 257.543263 -173.643081) (xy 257.527742 -173.585156)
			(xy 257.519914 -173.5257) (xy 257.519424 -173.495716) (xy 142.106698 -173.495716) (xy 142.151063 -173.507604)
			(xy 142.206436 -173.53054) (xy 142.258342 -173.560507) (xy 142.305892 -173.596994) (xy 142.348272 -173.639374)
			(xy 142.384759 -173.686924) (xy 142.414726 -173.73883) (xy 142.437662 -173.794203) (xy 142.453175 -173.852096)
			(xy 142.460998 -173.911518) (xy 142.461488 -173.941486) (xy 142.461488 -174.805086) (xy 142.460998 -174.835054)
			(xy 142.453175 -174.894476) (xy 142.437662 -174.952369) (xy 142.414726 -175.007742) (xy 142.384759 -175.059648)
			(xy 142.348272 -175.107198) (xy 142.305892 -175.149578) (xy 142.258342 -175.186065) (xy 142.206436 -175.216032)
			(xy 142.151063 -175.238968) (xy 142.09317 -175.254481) (xy 142.033748 -175.262304) (xy 141.973812 -175.262304)
			(xy 141.91439 -175.254481) (xy 141.856497 -175.238968) (xy 141.801124 -175.216032) (xy 141.749218 -175.186065)
			(xy 141.701668 -175.149578) (xy 141.659288 -175.107198) (xy 141.622801 -175.059648) (xy 141.592834 -175.007742)
			(xy 141.569898 -174.952369) (xy 141.554385 -174.894476) (xy 141.546562 -174.835054) (xy 141.546072 -174.805086)
			(xy 5.324094 -174.805086) (xy 5.324094 -176.837086) (xy 142.181072 -176.837086) (xy 142.181072 -175.973486)
			(xy 142.181562 -175.943518) (xy 142.189385 -175.884096) (xy 142.204898 -175.826203) (xy 142.227834 -175.77083)
			(xy 142.257801 -175.718924) (xy 142.294288 -175.671374) (xy 142.336668 -175.628994) (xy 142.384218 -175.592507)
			(xy 142.436124 -175.56254) (xy 142.491497 -175.539604) (xy 142.54939 -175.524091) (xy 142.608812 -175.516268)
			(xy 142.668748 -175.516268) (xy 142.72817 -175.524091) (xy 142.786063 -175.539604) (xy 142.841436 -175.56254)
			(xy 142.893342 -175.592507) (xy 142.940892 -175.628994) (xy 142.983272 -175.671374) (xy 143.019759 -175.718924)
			(xy 143.049726 -175.77083) (xy 143.072662 -175.826203) (xy 143.088175 -175.884096) (xy 143.095998 -175.943518)
			(xy 143.096488 -175.973486) (xy 143.096488 -176.837086) (xy 143.095998 -176.867054) (xy 143.088175 -176.926476)
			(xy 143.072662 -176.984369) (xy 143.049726 -177.039742) (xy 143.019759 -177.091648) (xy 142.983272 -177.139198)
			(xy 142.940892 -177.181578) (xy 142.893342 -177.218065) (xy 142.841436 -177.248032) (xy 142.786063 -177.270968)
			(xy 142.72817 -177.286481) (xy 142.668748 -177.294304) (xy 142.608812 -177.294304) (xy 142.54939 -177.286481)
			(xy 142.491497 -177.270968) (xy 142.436124 -177.248032) (xy 142.384218 -177.218065) (xy 142.336668 -177.181578)
			(xy 142.294288 -177.139198) (xy 142.257801 -177.091648) (xy 142.227834 -177.039742) (xy 142.204898 -176.984369)
			(xy 142.189385 -176.926476) (xy 142.181562 -176.867054) (xy 142.181072 -176.837086) (xy 5.324094 -176.837086)
			(xy 5.324094 -178.995324) (xy 123.198636 -178.995324) (xy 123.198636 -178.131724) (xy 123.199126 -178.10174)
			(xy 123.206954 -178.042284) (xy 123.222475 -177.984359) (xy 123.245424 -177.928955) (xy 123.275408 -177.877021)
			(xy 123.311914 -177.829445) (xy 123.354319 -177.78704) (xy 123.401895 -177.750534) (xy 123.453829 -177.72055)
			(xy 123.509233 -177.697601) (xy 123.567158 -177.68208) (xy 123.626614 -177.674252) (xy 123.686582 -177.674252)
			(xy 123.746038 -177.68208) (xy 123.803963 -177.697601) (xy 123.859367 -177.72055) (xy 123.911301 -177.750534)
			(xy 123.958877 -177.78704) (xy 124.001282 -177.829445) (xy 124.037788 -177.877021) (xy 124.067772 -177.928955)
			(xy 124.090721 -177.984359) (xy 124.106242 -178.042284) (xy 124.11407 -178.10174) (xy 124.11456 -178.131724)
			(xy 124.11456 -178.869086) (xy 141.546072 -178.869086) (xy 141.546072 -178.005486) (xy 141.546562 -177.975518)
			(xy 141.554385 -177.916096) (xy 141.569898 -177.858203) (xy 141.592834 -177.80283) (xy 141.622801 -177.750924)
			(xy 141.659288 -177.703374) (xy 141.701668 -177.660994) (xy 141.749218 -177.624507) (xy 141.801124 -177.59454)
			(xy 141.856497 -177.571604) (xy 141.91439 -177.556091) (xy 141.973812 -177.548268) (xy 142.033748 -177.548268)
			(xy 142.09317 -177.556091) (xy 142.151063 -177.571604) (xy 142.206436 -177.59454) (xy 142.258342 -177.624507)
			(xy 142.305892 -177.660994) (xy 142.348272 -177.703374) (xy 142.384759 -177.750924) (xy 142.414726 -177.80283)
			(xy 142.437662 -177.858203) (xy 142.453175 -177.916096) (xy 142.460998 -177.975518) (xy 142.461488 -178.005486)
			(xy 142.461488 -178.869086) (xy 142.460998 -178.899054) (xy 142.453175 -178.958476) (xy 142.437662 -179.016369)
			(xy 142.414726 -179.071742) (xy 142.384759 -179.123648) (xy 142.348272 -179.171198) (xy 142.305892 -179.213578)
			(xy 142.258342 -179.250065) (xy 142.206436 -179.280032) (xy 142.151063 -179.302968) (xy 142.09317 -179.318481)
			(xy 142.033748 -179.326304) (xy 141.973812 -179.326304) (xy 141.91439 -179.318481) (xy 141.856497 -179.302968)
			(xy 141.801124 -179.280032) (xy 141.749218 -179.250065) (xy 141.701668 -179.213578) (xy 141.659288 -179.171198)
			(xy 141.622801 -179.123648) (xy 141.592834 -179.071742) (xy 141.569898 -179.016369) (xy 141.554385 -178.958476)
			(xy 141.546562 -178.899054) (xy 141.546072 -178.869086) (xy 124.11456 -178.869086) (xy 124.11456 -178.995324)
			(xy 124.11407 -179.025308) (xy 124.106242 -179.084764) (xy 124.090721 -179.142689) (xy 124.067772 -179.198093)
			(xy 124.037788 -179.250027) (xy 124.001282 -179.297603) (xy 123.958877 -179.340008) (xy 123.911301 -179.376514)
			(xy 123.859367 -179.406498) (xy 123.803963 -179.429447) (xy 123.746038 -179.444968) (xy 123.686582 -179.452796)
			(xy 123.626614 -179.452796) (xy 123.567158 -179.444968) (xy 123.509233 -179.429447) (xy 123.453829 -179.406498)
			(xy 123.401895 -179.376514) (xy 123.354319 -179.340008) (xy 123.311914 -179.297603) (xy 123.275408 -179.250027)
			(xy 123.245424 -179.198093) (xy 123.222475 -179.142689) (xy 123.206954 -179.084764) (xy 123.199126 -179.025308)
			(xy 123.198636 -178.995324) (xy 5.324094 -178.995324) (xy 5.324094 -180.901086) (xy 142.181072 -180.901086)
			(xy 142.181072 -180.037486) (xy 142.181562 -180.007518) (xy 142.189385 -179.948096) (xy 142.204898 -179.890203)
			(xy 142.227834 -179.83483) (xy 142.257801 -179.782924) (xy 142.294288 -179.735374) (xy 142.336668 -179.692994)
			(xy 142.384218 -179.656507) (xy 142.436124 -179.62654) (xy 142.491497 -179.603604) (xy 142.54939 -179.588091)
			(xy 142.608812 -179.580268) (xy 142.668748 -179.580268) (xy 142.72817 -179.588091) (xy 142.786063 -179.603604)
			(xy 142.841436 -179.62654) (xy 142.893342 -179.656507) (xy 142.940892 -179.692994) (xy 142.983272 -179.735374)
			(xy 143.019759 -179.782924) (xy 143.049726 -179.83483) (xy 143.072662 -179.890203) (xy 143.088175 -179.948096)
			(xy 143.095998 -180.007518) (xy 143.096488 -180.037486) (xy 143.096488 -180.901086) (xy 143.095998 -180.931054)
			(xy 143.088175 -180.990476) (xy 143.072662 -181.048369) (xy 143.049726 -181.103742) (xy 143.019759 -181.155648)
			(xy 142.983272 -181.203198) (xy 142.940892 -181.245578) (xy 142.893342 -181.282065) (xy 142.841436 -181.312032)
			(xy 142.786063 -181.334968) (xy 142.72817 -181.350481) (xy 142.668748 -181.358304) (xy 142.608812 -181.358304)
			(xy 142.54939 -181.350481) (xy 142.491497 -181.334968) (xy 142.436124 -181.312032) (xy 142.384218 -181.282065)
			(xy 142.336668 -181.245578) (xy 142.294288 -181.203198) (xy 142.257801 -181.155648) (xy 142.227834 -181.103742)
			(xy 142.204898 -181.048369) (xy 142.189385 -180.990476) (xy 142.181562 -180.931054) (xy 142.181072 -180.901086)
			(xy 5.324094 -180.901086) (xy 5.324094 -182.933086) (xy 141.546072 -182.933086) (xy 141.546072 -182.069486)
			(xy 141.546562 -182.039518) (xy 141.554385 -181.980096) (xy 141.569898 -181.922203) (xy 141.592834 -181.86683)
			(xy 141.622801 -181.814924) (xy 141.659288 -181.767374) (xy 141.701668 -181.724994) (xy 141.749218 -181.688507)
			(xy 141.801124 -181.65854) (xy 141.856497 -181.635604) (xy 141.91439 -181.620091) (xy 141.973812 -181.612268)
			(xy 142.033748 -181.612268) (xy 142.09317 -181.620091) (xy 142.151063 -181.635604) (xy 142.206436 -181.65854)
			(xy 142.258342 -181.688507) (xy 142.305892 -181.724994) (xy 142.348272 -181.767374) (xy 142.384759 -181.814924)
			(xy 142.414726 -181.86683) (xy 142.437662 -181.922203) (xy 142.453175 -181.980096) (xy 142.460998 -182.039518)
			(xy 142.461488 -182.069486) (xy 142.461488 -182.933086) (xy 142.460998 -182.963054) (xy 142.453175 -183.022476)
			(xy 142.437662 -183.080369) (xy 142.414726 -183.135742) (xy 142.384759 -183.187648) (xy 142.348272 -183.235198)
			(xy 142.305892 -183.277578) (xy 142.258342 -183.314065) (xy 142.206436 -183.344032) (xy 142.151063 -183.366968)
			(xy 142.09317 -183.382481) (xy 142.033748 -183.390304) (xy 141.973812 -183.390304) (xy 141.91439 -183.382481)
			(xy 141.856497 -183.366968) (xy 141.801124 -183.344032) (xy 141.749218 -183.314065) (xy 141.701668 -183.277578)
			(xy 141.659288 -183.235198) (xy 141.622801 -183.187648) (xy 141.592834 -183.135742) (xy 141.569898 -183.080369)
			(xy 141.554385 -183.022476) (xy 141.546562 -182.963054) (xy 141.546072 -182.933086) (xy 5.324094 -182.933086)
			(xy 5.324094 -187.124582) (xy 135.58115 -187.124582) (xy 135.58115 -187.064618) (xy 135.588977 -187.005166)
			(xy 135.604497 -186.947244) (xy 135.627444 -186.891844) (xy 135.657426 -186.839912) (xy 135.69393 -186.792339)
			(xy 135.736331 -186.749937) (xy 135.783904 -186.713432) (xy 135.835835 -186.683448) (xy 135.891235 -186.6605)
			(xy 135.949156 -186.644979) (xy 136.008608 -186.637151) (xy 136.03859 -186.63666) (xy 136.90219 -186.63666)
			(xy 136.932178 -186.637085) (xy 136.99164 -186.644912) (xy 137.049571 -186.660433) (xy 137.104981 -186.683384)
			(xy 137.156922 -186.713371) (xy 137.204504 -186.749881) (xy 137.246913 -186.792289) (xy 137.283424 -186.83987)
			(xy 137.313412 -186.89181) (xy 137.336363 -186.947219) (xy 137.351886 -187.005151) (xy 137.359715 -187.064612)
			(xy 137.359715 -187.124588) (xy 137.351886 -187.184049) (xy 137.336363 -187.241981) (xy 137.313412 -187.29739)
			(xy 137.283424 -187.34933) (xy 137.246913 -187.396911) (xy 137.204504 -187.439319) (xy 137.156922 -187.475829)
			(xy 137.104981 -187.505816) (xy 137.049571 -187.528767) (xy 136.99164 -187.544288) (xy 136.932178 -187.552115)
			(xy 136.90219 -187.552584) (xy 136.03859 -187.552584) (xy 136.008608 -187.552049) (xy 135.949156 -187.544221)
			(xy 135.891235 -187.5287) (xy 135.835835 -187.505752) (xy 135.783904 -187.475768) (xy 135.736331 -187.439263)
			(xy 135.69393 -187.396861) (xy 135.657426 -187.349288) (xy 135.627444 -187.297356) (xy 135.604497 -187.241956)
			(xy 135.588977 -187.184034) (xy 135.58115 -187.124582) (xy 5.324094 -187.124582) (xy 5.324094 -188.252885)
			(xy 128.656818 -188.252885) (xy 128.656818 -188.192915) (xy 128.664646 -188.133459) (xy 128.680167 -188.075533)
			(xy 128.703116 -188.020128) (xy 128.733101 -187.968193) (xy 128.769608 -187.920615) (xy 128.812012 -187.87821)
			(xy 128.859589 -187.841703) (xy 128.911524 -187.811718) (xy 128.966929 -187.788768) (xy 129.024855 -187.773246)
			(xy 129.084311 -187.765418) (xy 129.114296 -187.764928) (xy 129.977896 -187.764928) (xy 130.007881 -187.765417)
			(xy 130.067339 -187.773244) (xy 130.125266 -187.788765) (xy 130.180671 -187.811714) (xy 130.232607 -187.841699)
			(xy 130.280185 -187.878207) (xy 130.322591 -187.920612) (xy 130.359098 -187.96819) (xy 130.389084 -188.020125)
			(xy 130.412034 -188.075531) (xy 130.427555 -188.133458) (xy 130.435383 -188.192915) (xy 130.435383 -188.252885)
			(xy 130.434185 -188.261981) (xy 131.046262 -188.261981) (xy 131.046262 -188.202019) (xy 131.054088 -188.14257)
			(xy 131.069607 -188.084651) (xy 131.092553 -188.029253) (xy 131.122533 -187.977324) (xy 131.159034 -187.929752)
			(xy 131.201432 -187.887351) (xy 131.249002 -187.850847) (xy 131.30093 -187.820864) (xy 131.356326 -187.797915)
			(xy 131.414244 -187.782393) (xy 131.473693 -187.774564) (xy 131.503674 -187.774072) (xy 132.367274 -187.774072)
			(xy 132.397263 -187.774472) (xy 132.456728 -187.782297) (xy 132.514663 -187.797818) (xy 132.570077 -187.820768)
			(xy 132.62202 -187.850755) (xy 132.669605 -187.887266) (xy 132.712017 -187.929675) (xy 132.74853 -187.977258)
			(xy 132.77852 -188.0292) (xy 132.801474 -188.084612) (xy 132.816998 -188.142546) (xy 132.824827 -188.202011)
			(xy 132.824827 -188.261989) (xy 132.816998 -188.321454) (xy 132.801474 -188.379388) (xy 132.79518 -188.394582)
			(xy 133.54915 -188.394582) (xy 133.54915 -188.334618) (xy 133.556977 -188.275166) (xy 133.572497 -188.217244)
			(xy 133.595444 -188.161844) (xy 133.625426 -188.109912) (xy 133.66193 -188.062339) (xy 133.704331 -188.019937)
			(xy 133.751904 -187.983432) (xy 133.803835 -187.953448) (xy 133.859235 -187.9305) (xy 133.917156 -187.914979)
			(xy 133.976608 -187.907151) (xy 134.00659 -187.90666) (xy 134.87019 -187.90666) (xy 134.900178 -187.907085)
			(xy 134.95964 -187.914912) (xy 135.017571 -187.930433) (xy 135.072981 -187.953384) (xy 135.124922 -187.983371)
			(xy 135.172504 -188.019881) (xy 135.214913 -188.062289) (xy 135.251424 -188.10987) (xy 135.281412 -188.16181)
			(xy 135.304363 -188.217219) (xy 135.319886 -188.275151) (xy 135.327715 -188.334612) (xy 135.327715 -188.394588)
			(xy 135.319886 -188.454049) (xy 135.304363 -188.511981) (xy 135.281412 -188.56739) (xy 135.251424 -188.61933)
			(xy 135.214913 -188.666911) (xy 135.172504 -188.709319) (xy 135.124922 -188.745829) (xy 135.072981 -188.775816)
			(xy 135.017571 -188.798767) (xy 134.95964 -188.814288) (xy 134.900178 -188.822115) (xy 134.87019 -188.822584)
			(xy 134.00659 -188.822584) (xy 133.976608 -188.822049) (xy 133.917156 -188.814221) (xy 133.859235 -188.7987)
			(xy 133.803835 -188.775752) (xy 133.751904 -188.745768) (xy 133.704331 -188.709263) (xy 133.66193 -188.666861)
			(xy 133.625426 -188.619288) (xy 133.595444 -188.567356) (xy 133.572497 -188.511956) (xy 133.556977 -188.454034)
			(xy 133.54915 -188.394582) (xy 132.79518 -188.394582) (xy 132.77852 -188.4348) (xy 132.74853 -188.486742)
			(xy 132.712017 -188.534325) (xy 132.669605 -188.576734) (xy 132.62202 -188.613245) (xy 132.570077 -188.643232)
			(xy 132.514663 -188.666182) (xy 132.456728 -188.681703) (xy 132.397263 -188.689528) (xy 132.367274 -188.689996)
			(xy 131.503674 -188.689996) (xy 131.473693 -188.689436) (xy 131.414244 -188.681607) (xy 131.356326 -188.666085)
			(xy 131.30093 -188.643136) (xy 131.249002 -188.613153) (xy 131.201432 -188.576649) (xy 131.159034 -188.534248)
			(xy 131.122533 -188.486676) (xy 131.092553 -188.434747) (xy 131.069607 -188.379349) (xy 131.054088 -188.32143)
			(xy 131.046262 -188.261981) (xy 130.434185 -188.261981) (xy 130.427555 -188.312342) (xy 130.412034 -188.370269)
			(xy 130.389084 -188.425675) (xy 130.359098 -188.47761) (xy 130.322591 -188.525188) (xy 130.280185 -188.567593)
			(xy 130.232607 -188.604101) (xy 130.180671 -188.634086) (xy 130.125266 -188.657035) (xy 130.067339 -188.672556)
			(xy 130.007881 -188.680383) (xy 129.977896 -188.680852) (xy 129.114296 -188.680852) (xy 129.084311 -188.680382)
			(xy 129.024855 -188.672554) (xy 128.966929 -188.657032) (xy 128.911524 -188.634082) (xy 128.859589 -188.604097)
			(xy 128.812012 -188.56759) (xy 128.769608 -188.525185) (xy 128.733101 -188.477607) (xy 128.703116 -188.425672)
			(xy 128.680167 -188.370267) (xy 128.664646 -188.312341) (xy 128.656818 -188.252885) (xy 5.324094 -188.252885)
			(xy 5.324094 -194.360038) (xy 10.541008 -194.360038) (xy 10.545012 -194.15485) (xy 10.557019 -193.949974)
			(xy 10.57701 -193.745723) (xy 10.604955 -193.542408) (xy 10.640811 -193.340337) (xy 10.684525 -193.139819)
			(xy 10.736028 -192.94116) (xy 10.795243 -192.744661) (xy 10.862079 -192.550622) (xy 10.936435 -192.359339)
			(xy 11.018198 -192.171102) (xy 11.107243 -191.986199) (xy 11.203434 -191.804911) (xy 11.306625 -191.627514)
			(xy 11.416659 -191.454277) (xy 11.533368 -191.285466) (xy 11.656574 -191.121337) (xy 11.786091 -190.96214)
			(xy 11.92172 -190.808118) (xy 12.063255 -190.659504) (xy 12.21048 -190.516526) (xy 12.363172 -190.379401)
			(xy 12.521098 -190.248337) (xy 12.684017 -190.123535) (xy 12.851682 -190.005185) (xy 13.023836 -189.893466)
			(xy 13.200218 -189.788549) (xy 13.380559 -189.690594) (xy 13.564585 -189.59975) (xy 13.752015 -189.516154)
			(xy 13.942564 -189.439935) (xy 14.135941 -189.371209) (xy 14.331853 -189.31008) (xy 14.53 -189.256641)
			(xy 14.730082 -189.210974) (xy 14.931793 -189.173147) (xy 15.134826 -189.14322) (xy 15.338873 -189.121237)
			(xy 15.543622 -189.107232) (xy 15.748761 -189.101226) (xy 15.953978 -189.103228) (xy 16.158961 -189.113236)
			(xy 16.363398 -189.131233) (xy 16.566976 -189.157193) (xy 16.769387 -189.191076) (xy 16.970321 -189.232831)
			(xy 17.169474 -189.282394) (xy 17.366541 -189.339689) (xy 17.561223 -189.404629) (xy 17.753223 -189.477115)
			(xy 17.942248 -189.557038) (xy 18.128011 -189.644274) (xy 18.310229 -189.738692) (xy 18.488625 -189.840147)
			(xy 18.662926 -189.948486) (xy 18.832868 -190.063542) (xy 18.998191 -190.185142) (xy 19.158644 -190.313099)
			(xy 19.313983 -190.447218) (xy 19.46397 -190.587297) (xy 19.608378 -190.733121) (xy 19.746986 -190.884467)
			(xy 19.879584 -191.041107) (xy 20.00597 -191.202801) (xy 20.12595 -191.369303) (xy 20.239343 -191.540359)
			(xy 20.345976 -191.715709) (xy 20.445686 -191.895086) (xy 20.538322 -192.078216) (xy 20.623742 -192.264822)
			(xy 20.701816 -192.454618) (xy 20.772426 -192.647316) (xy 20.835463 -192.842622) (xy 20.890833 -193.040238)
			(xy 20.93845 -193.239865) (xy 20.978242 -193.441197) (xy 21.010149 -193.643929) (xy 21.034122 -193.847751)
			(xy 21.050124 -194.052354) (xy 21.058131 -194.257424) (xy 21.058632 -194.360038) (xy 112.440982 -194.360038)
			(xy 112.444986 -194.15485) (xy 112.456993 -193.949974) (xy 112.476984 -193.745723) (xy 112.504929 -193.542408)
			(xy 112.540785 -193.340337) (xy 112.584499 -193.139819) (xy 112.636002 -192.94116) (xy 112.695217 -192.744661)
			(xy 112.762053 -192.550622) (xy 112.836409 -192.359339) (xy 112.918172 -192.171102) (xy 113.007217 -191.986199)
			(xy 113.103408 -191.804911) (xy 113.206599 -191.627514) (xy 113.316633 -191.454277) (xy 113.433342 -191.285466)
			(xy 113.556548 -191.121337) (xy 113.686065 -190.96214) (xy 113.821694 -190.808118) (xy 113.963229 -190.659504)
			(xy 114.110454 -190.516526) (xy 114.263146 -190.379401) (xy 114.421072 -190.248337) (xy 114.583991 -190.123535)
			(xy 114.751656 -190.005185) (xy 114.92381 -189.893466) (xy 115.100192 -189.788549) (xy 115.280533 -189.690594)
			(xy 115.464559 -189.59975) (xy 115.651989 -189.516154) (xy 115.842538 -189.439935) (xy 116.035915 -189.371209)
			(xy 116.231827 -189.31008) (xy 116.429974 -189.256641) (xy 116.630056 -189.210974) (xy 116.831767 -189.173147)
			(xy 117.0348 -189.14322) (xy 117.238847 -189.121237) (xy 117.443596 -189.107232) (xy 117.648735 -189.101226)
			(xy 117.853952 -189.103228) (xy 118.058935 -189.113236) (xy 118.263372 -189.131233) (xy 118.46695 -189.157193)
			(xy 118.669361 -189.191076) (xy 118.870295 -189.232831) (xy 119.069448 -189.282394) (xy 119.266515 -189.339689)
			(xy 119.461197 -189.404629) (xy 119.653197 -189.477115) (xy 119.842222 -189.557038) (xy 120.027985 -189.644274)
			(xy 120.210203 -189.738692) (xy 120.388599 -189.840147) (xy 120.5629 -189.948486) (xy 120.732842 -190.063542)
			(xy 120.898165 -190.185142) (xy 121.058618 -190.313099) (xy 121.213957 -190.447218) (xy 121.363944 -190.587297)
			(xy 121.508352 -190.733121) (xy 121.64696 -190.884467) (xy 121.779558 -191.041107) (xy 121.905944 -191.202801)
			(xy 122.025924 -191.369303) (xy 122.139317 -191.540359) (xy 122.24595 -191.715709) (xy 122.34566 -191.895086)
			(xy 122.438296 -192.078216) (xy 122.523716 -192.264822) (xy 122.60179 -192.454618) (xy 122.6724 -192.647316)
			(xy 122.735437 -192.842622) (xy 122.790807 -193.040238) (xy 122.838424 -193.239865) (xy 122.878216 -193.441197)
			(xy 122.910123 -193.643929) (xy 122.934096 -193.847751) (xy 122.950098 -194.052354) (xy 122.958105 -194.257424)
			(xy 122.958605 -194.359784) (xy 228.54108 -194.359784) (xy 228.545084 -194.154596) (xy 228.557091 -193.94972)
			(xy 228.577082 -193.745469) (xy 228.605027 -193.542154) (xy 228.640883 -193.340083) (xy 228.684597 -193.139565)
			(xy 228.7361 -192.940906) (xy 228.795315 -192.744407) (xy 228.862151 -192.550368) (xy 228.936507 -192.359085)
			(xy 229.01827 -192.170848) (xy 229.107315 -191.985945) (xy 229.203506 -191.804657) (xy 229.306697 -191.62726)
			(xy 229.416731 -191.454023) (xy 229.53344 -191.285212) (xy 229.656646 -191.121083) (xy 229.786163 -190.961886)
			(xy 229.921792 -190.807864) (xy 230.063327 -190.65925) (xy 230.210552 -190.516272) (xy 230.363244 -190.379147)
			(xy 230.52117 -190.248083) (xy 230.684089 -190.123281) (xy 230.851754 -190.004931) (xy 231.023908 -189.893212)
			(xy 231.20029 -189.788295) (xy 231.380631 -189.69034) (xy 231.564657 -189.599496) (xy 231.752087 -189.5159)
			(xy 231.942636 -189.439681) (xy 232.136013 -189.370955) (xy 232.331925 -189.309826) (xy 232.530072 -189.256387)
			(xy 232.730154 -189.21072) (xy 232.931865 -189.172893) (xy 233.134898 -189.142966) (xy 233.338945 -189.120983)
			(xy 233.543694 -189.106978) (xy 233.748833 -189.100972) (xy 233.95405 -189.102974) (xy 234.159033 -189.112982)
			(xy 234.36347 -189.130979) (xy 234.567048 -189.156939) (xy 234.769459 -189.190822) (xy 234.970393 -189.232577)
			(xy 235.169546 -189.28214) (xy 235.366613 -189.339435) (xy 235.561295 -189.404375) (xy 235.753295 -189.476861)
			(xy 235.94232 -189.556784) (xy 236.128083 -189.64402) (xy 236.310301 -189.738438) (xy 236.488697 -189.839893)
			(xy 236.662998 -189.948232) (xy 236.83294 -190.063288) (xy 236.998263 -190.184888) (xy 237.158716 -190.312845)
			(xy 237.314055 -190.446964) (xy 237.464042 -190.587043) (xy 237.60845 -190.732867) (xy 237.747058 -190.884213)
			(xy 237.879656 -191.040853) (xy 238.006042 -191.202547) (xy 238.126022 -191.369049) (xy 238.239415 -191.540105)
			(xy 238.346048 -191.715455) (xy 238.445758 -191.894832) (xy 238.538394 -192.077962) (xy 238.623814 -192.264568)
			(xy 238.701888 -192.454364) (xy 238.772498 -192.647062) (xy 238.835535 -192.842368) (xy 238.890905 -193.039984)
			(xy 238.938522 -193.239611) (xy 238.978314 -193.440943) (xy 239.010221 -193.643675) (xy 239.034194 -193.847497)
			(xy 239.050196 -194.0521) (xy 239.058203 -194.25717) (xy 239.058704 -194.359784) (xy 239.058703 -194.360038)
			(xy 344.640924 -194.360038) (xy 344.644928 -194.15485) (xy 344.656935 -193.949974) (xy 344.676926 -193.745723)
			(xy 344.704871 -193.542408) (xy 344.740727 -193.340337) (xy 344.784441 -193.139819) (xy 344.835944 -192.94116)
			(xy 344.895159 -192.744661) (xy 344.961995 -192.550622) (xy 345.036351 -192.359339) (xy 345.118114 -192.171102)
			(xy 345.207159 -191.986199) (xy 345.30335 -191.804911) (xy 345.406541 -191.627514) (xy 345.516575 -191.454277)
			(xy 345.633284 -191.285466) (xy 345.75649 -191.121337) (xy 345.886007 -190.96214) (xy 346.021636 -190.808118)
			(xy 346.163171 -190.659504) (xy 346.310396 -190.516526) (xy 346.463088 -190.379401) (xy 346.621014 -190.248337)
			(xy 346.783933 -190.123535) (xy 346.951598 -190.005185) (xy 347.123752 -189.893466) (xy 347.300134 -189.788549)
			(xy 347.480475 -189.690594) (xy 347.664501 -189.59975) (xy 347.851931 -189.516154) (xy 348.04248 -189.439935)
			(xy 348.235857 -189.371209) (xy 348.431769 -189.31008) (xy 348.629916 -189.256641) (xy 348.829998 -189.210974)
			(xy 349.031709 -189.173147) (xy 349.234742 -189.14322) (xy 349.438789 -189.121237) (xy 349.643538 -189.107232)
			(xy 349.848677 -189.101226) (xy 350.053894 -189.103228) (xy 350.258877 -189.113236) (xy 350.463314 -189.131233)
			(xy 350.666892 -189.157193) (xy 350.869303 -189.191076) (xy 351.070237 -189.232831) (xy 351.26939 -189.282394)
			(xy 351.466457 -189.339689) (xy 351.661139 -189.404629) (xy 351.853139 -189.477115) (xy 352.042164 -189.557038)
			(xy 352.227927 -189.644274) (xy 352.410145 -189.738692) (xy 352.588541 -189.840147) (xy 352.762842 -189.948486)
			(xy 352.932784 -190.063542) (xy 353.098107 -190.185142) (xy 353.25856 -190.313099) (xy 353.413899 -190.447218)
			(xy 353.563886 -190.587297) (xy 353.708294 -190.733121) (xy 353.846902 -190.884467) (xy 353.9795 -191.041107)
			(xy 354.105886 -191.202801) (xy 354.225866 -191.369303) (xy 354.339259 -191.540359) (xy 354.445892 -191.715709)
			(xy 354.545602 -191.895086) (xy 354.638238 -192.078216) (xy 354.723658 -192.264822) (xy 354.801732 -192.454618)
			(xy 354.872342 -192.647316) (xy 354.935379 -192.842622) (xy 354.990749 -193.040238) (xy 355.038366 -193.239865)
			(xy 355.078158 -193.441197) (xy 355.110065 -193.643929) (xy 355.134038 -193.847751) (xy 355.15004 -194.052354)
			(xy 355.158047 -194.257424) (xy 355.158548 -194.360038) (xy 446.540898 -194.360038) (xy 446.544902 -194.15485)
			(xy 446.556909 -193.949974) (xy 446.5769 -193.745723) (xy 446.604845 -193.542408) (xy 446.640701 -193.340337)
			(xy 446.684415 -193.139819) (xy 446.735918 -192.94116) (xy 446.795133 -192.744661) (xy 446.861969 -192.550622)
			(xy 446.936325 -192.359339) (xy 447.018088 -192.171102) (xy 447.107133 -191.986199) (xy 447.203324 -191.804911)
			(xy 447.306515 -191.627514) (xy 447.416549 -191.454277) (xy 447.533258 -191.285466) (xy 447.656464 -191.121337)
			(xy 447.785981 -190.96214) (xy 447.92161 -190.808118) (xy 448.063145 -190.659504) (xy 448.21037 -190.516526)
			(xy 448.363062 -190.379401) (xy 448.520988 -190.248337) (xy 448.683907 -190.123535) (xy 448.851572 -190.005185)
			(xy 449.023726 -189.893466) (xy 449.200108 -189.788549) (xy 449.380449 -189.690594) (xy 449.564475 -189.59975)
			(xy 449.751905 -189.516154) (xy 449.942454 -189.439935) (xy 450.135831 -189.371209) (xy 450.331743 -189.31008)
			(xy 450.52989 -189.256641) (xy 450.729972 -189.210974) (xy 450.931683 -189.173147) (xy 451.134716 -189.14322)
			(xy 451.338763 -189.121237) (xy 451.543512 -189.107232) (xy 451.748651 -189.101226) (xy 451.953868 -189.103228)
			(xy 452.158851 -189.113236) (xy 452.363288 -189.131233) (xy 452.566866 -189.157193) (xy 452.769277 -189.191076)
			(xy 452.970211 -189.232831) (xy 453.169364 -189.282394) (xy 453.366431 -189.339689) (xy 453.561113 -189.404629)
			(xy 453.753113 -189.477115) (xy 453.942138 -189.557038) (xy 454.127901 -189.644274) (xy 454.310119 -189.738692)
			(xy 454.488515 -189.840147) (xy 454.662816 -189.948486) (xy 454.832758 -190.063542) (xy 454.998081 -190.185142)
			(xy 455.158534 -190.313099) (xy 455.313873 -190.447218) (xy 455.46386 -190.587297) (xy 455.608268 -190.733121)
			(xy 455.746876 -190.884467) (xy 455.879474 -191.041107) (xy 456.00586 -191.202801) (xy 456.12584 -191.369303)
			(xy 456.239233 -191.540359) (xy 456.345866 -191.715709) (xy 456.445576 -191.895086) (xy 456.538212 -192.078216)
			(xy 456.623632 -192.264822) (xy 456.701706 -192.454618) (xy 456.772316 -192.647316) (xy 456.835353 -192.842622)
			(xy 456.890723 -193.040238) (xy 456.93834 -193.239865) (xy 456.978132 -193.441197) (xy 457.010039 -193.643929)
			(xy 457.034012 -193.847751) (xy 457.050014 -194.052354) (xy 457.058021 -194.257424) (xy 457.058522 -194.360038)
			(xy 457.058021 -194.462652) (xy 457.050014 -194.667722) (xy 457.034012 -194.872325) (xy 457.010039 -195.076147)
			(xy 456.978132 -195.278879) (xy 456.93834 -195.480211) (xy 456.890723 -195.679838) (xy 456.835353 -195.877454)
			(xy 456.772316 -196.07276) (xy 456.701706 -196.265458) (xy 456.623632 -196.455254) (xy 456.538212 -196.64186)
			(xy 456.445576 -196.82499) (xy 456.345866 -197.004367) (xy 456.239233 -197.179717) (xy 456.12584 -197.350773)
			(xy 456.00586 -197.517275) (xy 455.879474 -197.678969) (xy 455.746876 -197.835609) (xy 455.608268 -197.986955)
			(xy 455.46386 -198.132779) (xy 455.313873 -198.272858) (xy 455.158534 -198.406977) (xy 454.998081 -198.534934)
			(xy 454.832758 -198.656534) (xy 454.662816 -198.77159) (xy 454.488515 -198.879929) (xy 454.310119 -198.981384)
			(xy 454.127901 -199.075802) (xy 453.942138 -199.163038) (xy 453.753113 -199.242961) (xy 453.561113 -199.315447)
			(xy 453.366431 -199.380387) (xy 453.169364 -199.437682) (xy 452.970211 -199.487245) (xy 452.769277 -199.529)
			(xy 452.566866 -199.562883) (xy 452.363288 -199.588843) (xy 452.158851 -199.60684) (xy 451.953868 -199.616848)
			(xy 451.748651 -199.61885) (xy 451.543512 -199.612844) (xy 451.338763 -199.598839) (xy 451.134716 -199.576856)
			(xy 450.931683 -199.546929) (xy 450.729972 -199.509102) (xy 450.52989 -199.463435) (xy 450.331743 -199.409996)
			(xy 450.135831 -199.348867) (xy 449.942454 -199.280141) (xy 449.751905 -199.203922) (xy 449.564475 -199.120326)
			(xy 449.380449 -199.029482) (xy 449.200108 -198.931527) (xy 449.023726 -198.82661) (xy 448.851572 -198.714891)
			(xy 448.683907 -198.596541) (xy 448.520988 -198.471739) (xy 448.363062 -198.340675) (xy 448.21037 -198.20355)
			(xy 448.063145 -198.060572) (xy 447.92161 -197.911958) (xy 447.785981 -197.757936) (xy 447.656464 -197.598739)
			(xy 447.533258 -197.43461) (xy 447.416549 -197.265799) (xy 447.306515 -197.092562) (xy 447.203324 -196.915165)
			(xy 447.107133 -196.733877) (xy 447.018088 -196.548974) (xy 446.936325 -196.360737) (xy 446.861969 -196.169454)
			(xy 446.795133 -195.975415) (xy 446.735918 -195.778916) (xy 446.684415 -195.580257) (xy 446.640701 -195.379739)
			(xy 446.604845 -195.177668) (xy 446.5769 -194.974353) (xy 446.556909 -194.770102) (xy 446.544902 -194.565226)
			(xy 446.540898 -194.360038) (xy 355.158548 -194.360038) (xy 355.158047 -194.462652) (xy 355.15004 -194.667722)
			(xy 355.134038 -194.872325) (xy 355.110065 -195.076147) (xy 355.078158 -195.278879) (xy 355.038366 -195.480211)
			(xy 354.990749 -195.679838) (xy 354.935379 -195.877454) (xy 354.872342 -196.07276) (xy 354.801732 -196.265458)
			(xy 354.723658 -196.455254) (xy 354.638238 -196.64186) (xy 354.545602 -196.82499) (xy 354.445892 -197.004367)
			(xy 354.339259 -197.179717) (xy 354.225866 -197.350773) (xy 354.105886 -197.517275) (xy 353.9795 -197.678969)
			(xy 353.846902 -197.835609) (xy 353.708294 -197.986955) (xy 353.563886 -198.132779) (xy 353.413899 -198.272858)
			(xy 353.25856 -198.406977) (xy 353.098107 -198.534934) (xy 352.932784 -198.656534) (xy 352.762842 -198.77159)
			(xy 352.588541 -198.879929) (xy 352.410145 -198.981384) (xy 352.227927 -199.075802) (xy 352.042164 -199.163038)
			(xy 351.853139 -199.242961) (xy 351.661139 -199.315447) (xy 351.466457 -199.380387) (xy 351.26939 -199.437682)
			(xy 351.070237 -199.487245) (xy 350.869303 -199.529) (xy 350.666892 -199.562883) (xy 350.463314 -199.588843)
			(xy 350.258877 -199.60684) (xy 350.053894 -199.616848) (xy 349.848677 -199.61885) (xy 349.643538 -199.612844)
			(xy 349.438789 -199.598839) (xy 349.234742 -199.576856) (xy 349.031709 -199.546929) (xy 348.829998 -199.509102)
			(xy 348.629916 -199.463435) (xy 348.431769 -199.409996) (xy 348.235857 -199.348867) (xy 348.04248 -199.280141)
			(xy 347.851931 -199.203922) (xy 347.664501 -199.120326) (xy 347.480475 -199.029482) (xy 347.300134 -198.931527)
			(xy 347.123752 -198.82661) (xy 346.951598 -198.714891) (xy 346.783933 -198.596541) (xy 346.621014 -198.471739)
			(xy 346.463088 -198.340675) (xy 346.310396 -198.20355) (xy 346.163171 -198.060572) (xy 346.021636 -197.911958)
			(xy 345.886007 -197.757936) (xy 345.75649 -197.598739) (xy 345.633284 -197.43461) (xy 345.516575 -197.265799)
			(xy 345.406541 -197.092562) (xy 345.30335 -196.915165) (xy 345.207159 -196.733877) (xy 345.118114 -196.548974)
			(xy 345.036351 -196.360737) (xy 344.961995 -196.169454) (xy 344.895159 -195.975415) (xy 344.835944 -195.778916)
			(xy 344.784441 -195.580257) (xy 344.740727 -195.379739) (xy 344.704871 -195.177668) (xy 344.676926 -194.974353)
			(xy 344.656935 -194.770102) (xy 344.644928 -194.565226) (xy 344.640924 -194.360038) (xy 239.058703 -194.360038)
			(xy 239.058203 -194.462398) (xy 239.050196 -194.667468) (xy 239.034194 -194.872071) (xy 239.010221 -195.075893)
			(xy 238.978314 -195.278625) (xy 238.938522 -195.479957) (xy 238.890905 -195.679584) (xy 238.835535 -195.8772)
			(xy 238.772498 -196.072506) (xy 238.701888 -196.265204) (xy 238.623814 -196.455) (xy 238.538394 -196.641606)
			(xy 238.445758 -196.824736) (xy 238.346048 -197.004113) (xy 238.239415 -197.179463) (xy 238.126022 -197.350519)
			(xy 238.006042 -197.517021) (xy 237.879656 -197.678715) (xy 237.747058 -197.835355) (xy 237.60845 -197.986701)
			(xy 237.464042 -198.132525) (xy 237.314055 -198.272604) (xy 237.158716 -198.406723) (xy 236.998263 -198.53468)
			(xy 236.83294 -198.65628) (xy 236.662998 -198.771336) (xy 236.488697 -198.879675) (xy 236.310301 -198.98113)
			(xy 236.128083 -199.075548) (xy 235.94232 -199.162784) (xy 235.753295 -199.242707) (xy 235.561295 -199.315193)
			(xy 235.366613 -199.380133) (xy 235.169546 -199.437428) (xy 234.970393 -199.486991) (xy 234.769459 -199.528746)
			(xy 234.567048 -199.562629) (xy 234.36347 -199.588589) (xy 234.159033 -199.606586) (xy 233.95405 -199.616594)
			(xy 233.748833 -199.618596) (xy 233.543694 -199.61259) (xy 233.338945 -199.598585) (xy 233.134898 -199.576602)
			(xy 232.931865 -199.546675) (xy 232.730154 -199.508848) (xy 232.530072 -199.463181) (xy 232.331925 -199.409742)
			(xy 232.136013 -199.348613) (xy 231.942636 -199.279887) (xy 231.752087 -199.203668) (xy 231.564657 -199.120072)
			(xy 231.380631 -199.029228) (xy 231.20029 -198.931273) (xy 231.023908 -198.826356) (xy 230.851754 -198.714637)
			(xy 230.684089 -198.596287) (xy 230.52117 -198.471485) (xy 230.363244 -198.340421) (xy 230.210552 -198.203296)
			(xy 230.063327 -198.060318) (xy 229.921792 -197.911704) (xy 229.786163 -197.757682) (xy 229.656646 -197.598485)
			(xy 229.53344 -197.434356) (xy 229.416731 -197.265545) (xy 229.306697 -197.092308) (xy 229.203506 -196.914911)
			(xy 229.107315 -196.733623) (xy 229.01827 -196.54872) (xy 228.936507 -196.360483) (xy 228.862151 -196.1692)
			(xy 228.795315 -195.975161) (xy 228.7361 -195.778662) (xy 228.684597 -195.580003) (xy 228.640883 -195.379485)
			(xy 228.605027 -195.177414) (xy 228.577082 -194.974099) (xy 228.557091 -194.769848) (xy 228.545084 -194.564972)
			(xy 228.54108 -194.359784) (xy 122.958605 -194.359784) (xy 122.958606 -194.360038) (xy 122.958105 -194.462652)
			(xy 122.950098 -194.667722) (xy 122.934096 -194.872325) (xy 122.910123 -195.076147) (xy 122.878216 -195.278879)
			(xy 122.838424 -195.480211) (xy 122.790807 -195.679838) (xy 122.777848 -195.726088) (xy 126.922185 -195.726088)
			(xy 126.922185 -195.666112) (xy 126.930014 -195.606648) (xy 126.945538 -195.548715) (xy 126.968491 -195.493304)
			(xy 126.99848 -195.441364) (xy 127.034993 -195.393782) (xy 127.077404 -195.351373) (xy 127.124989 -195.314864)
			(xy 127.176931 -195.284878) (xy 127.232344 -195.261928) (xy 127.290278 -195.246408) (xy 127.349742 -195.238583)
			(xy 127.37973 -195.238116) (xy 128.24333 -195.238116) (xy 128.273312 -195.238652) (xy 128.332761 -195.246482)
			(xy 128.39068 -195.262005) (xy 128.446078 -195.284955) (xy 128.498007 -195.314939) (xy 128.545577 -195.351444)
			(xy 128.587976 -195.393845) (xy 128.624478 -195.441418) (xy 128.654459 -195.493349) (xy 128.677405 -195.548748)
			(xy 128.692924 -195.606668) (xy 128.70075 -195.666118) (xy 128.70075 -195.726082) (xy 128.692924 -195.785532)
			(xy 128.677405 -195.843452) (xy 128.654459 -195.898851) (xy 128.624478 -195.950782) (xy 128.587976 -195.998355)
			(xy 128.545577 -196.040756) (xy 128.498007 -196.077261) (xy 128.446078 -196.107245) (xy 128.39068 -196.130195)
			(xy 128.332761 -196.145718) (xy 128.273312 -196.153548) (xy 128.24333 -196.15404) (xy 127.37973 -196.15404)
			(xy 127.349742 -196.153617) (xy 127.290278 -196.145792) (xy 127.232344 -196.130272) (xy 127.176931 -196.107322)
			(xy 127.124989 -196.077336) (xy 127.077404 -196.040827) (xy 127.034993 -195.998418) (xy 126.99848 -195.950836)
			(xy 126.968491 -195.898896) (xy 126.945538 -195.843485) (xy 126.930014 -195.785552) (xy 126.922185 -195.726088)
			(xy 122.777848 -195.726088) (xy 122.735437 -195.877454) (xy 122.6724 -196.07276) (xy 122.60179 -196.265458)
			(xy 122.523716 -196.455254) (xy 122.438296 -196.64186) (xy 122.34566 -196.82499) (xy 122.24595 -197.004367)
			(xy 122.139317 -197.179717) (xy 122.025924 -197.350773) (xy 121.905944 -197.517275) (xy 121.779558 -197.678969)
			(xy 121.64696 -197.835609) (xy 121.508352 -197.986955) (xy 121.363944 -198.132779) (xy 121.213957 -198.272858)
			(xy 121.058618 -198.406977) (xy 120.898165 -198.534934) (xy 120.886189 -198.543743) (xy 138.243774 -198.543743)
			(xy 138.24519 -198.489257) (xy 138.254343 -198.435528) (xy 138.271047 -198.383647) (xy 138.294963 -198.33467)
			(xy 138.325603 -198.289594) (xy 138.362344 -198.249336) (xy 138.40444 -198.214715) (xy 138.451033 -198.186434)
			(xy 138.501175 -198.165071) (xy 138.553847 -198.151058) (xy 138.607977 -198.144682) (xy 138.635232 -198.144892)
			(xy 138.636502 -198.144892) (xy 139.488672 -198.144892) (xy 139.515926 -198.145353) (xy 139.56988 -198.153107)
			(xy 139.622181 -198.168461) (xy 139.671765 -198.191102) (xy 139.717622 -198.220569) (xy 139.758818 -198.256263)
			(xy 139.794514 -198.297456) (xy 139.823985 -198.34331) (xy 139.846629 -198.392892) (xy 139.861987 -198.445192)
			(xy 139.869745 -198.499146) (xy 139.869745 -198.553654) (xy 139.861987 -198.607608) (xy 139.846629 -198.659908)
			(xy 139.823985 -198.70949) (xy 139.794514 -198.755344) (xy 139.758818 -198.796537) (xy 139.717622 -198.832231)
			(xy 139.671765 -198.861698) (xy 139.622181 -198.884339) (xy 139.56988 -198.899693) (xy 139.515926 -198.907447)
			(xy 139.488672 -198.907908) (xy 139.477343 -198.907862) (xy 139.454723 -198.90659) (xy 139.44346 -198.905368)
			(xy 139.440412 -198.90486) (xy 138.672824 -198.90486) (xy 138.669776 -198.905368) (xy 138.642662 -198.908134)
			(xy 138.588177 -198.906693) (xy 138.534452 -198.897514) (xy 138.482579 -198.880785) (xy 138.433613 -198.856847)
			(xy 138.388552 -198.826185) (xy 138.348311 -198.789424) (xy 138.31371 -198.747312) (xy 138.285452 -198.700706)
			(xy 138.264112 -198.650554) (xy 138.250125 -198.597875) (xy 138.243774 -198.543743) (xy 120.886189 -198.543743)
			(xy 120.732842 -198.656534) (xy 120.5629 -198.77159) (xy 120.388599 -198.879929) (xy 120.210203 -198.981384)
			(xy 120.027985 -199.075802) (xy 119.842222 -199.163038) (xy 119.653197 -199.242961) (xy 119.461197 -199.315447)
			(xy 119.266515 -199.380387) (xy 119.069448 -199.437682) (xy 118.870295 -199.487245) (xy 118.669361 -199.529)
			(xy 118.46695 -199.562883) (xy 118.263372 -199.588843) (xy 118.058935 -199.60684) (xy 117.853952 -199.616848)
			(xy 117.648735 -199.61885) (xy 117.443596 -199.612844) (xy 117.238847 -199.598839) (xy 117.0348 -199.576856)
			(xy 116.831767 -199.546929) (xy 116.630056 -199.509102) (xy 116.429974 -199.463435) (xy 116.231827 -199.409996)
			(xy 116.035915 -199.348867) (xy 115.842538 -199.280141) (xy 115.651989 -199.203922) (xy 115.464559 -199.120326)
			(xy 115.280533 -199.029482) (xy 115.100192 -198.931527) (xy 114.92381 -198.82661) (xy 114.751656 -198.714891)
			(xy 114.583991 -198.596541) (xy 114.421072 -198.471739) (xy 114.263146 -198.340675) (xy 114.110454 -198.20355)
			(xy 113.963229 -198.060572) (xy 113.821694 -197.911958) (xy 113.686065 -197.757936) (xy 113.556548 -197.598739)
			(xy 113.433342 -197.43461) (xy 113.316633 -197.265799) (xy 113.206599 -197.092562) (xy 113.103408 -196.915165)
			(xy 113.007217 -196.733877) (xy 112.918172 -196.548974) (xy 112.836409 -196.360737) (xy 112.762053 -196.169454)
			(xy 112.695217 -195.975415) (xy 112.636002 -195.778916) (xy 112.584499 -195.580257) (xy 112.540785 -195.379739)
			(xy 112.504929 -195.177668) (xy 112.476984 -194.974353) (xy 112.456993 -194.770102) (xy 112.444986 -194.565226)
			(xy 112.440982 -194.360038) (xy 21.058632 -194.360038) (xy 21.058131 -194.462652) (xy 21.050124 -194.667722)
			(xy 21.034122 -194.872325) (xy 21.010149 -195.076147) (xy 20.978242 -195.278879) (xy 20.93845 -195.480211)
			(xy 20.890833 -195.679838) (xy 20.835463 -195.877454) (xy 20.772426 -196.07276) (xy 20.701816 -196.265458)
			(xy 20.623742 -196.455254) (xy 20.538322 -196.64186) (xy 20.445686 -196.82499) (xy 20.345976 -197.004367)
			(xy 20.239343 -197.179717) (xy 20.12595 -197.350773) (xy 20.00597 -197.517275) (xy 19.879584 -197.678969)
			(xy 19.746986 -197.835609) (xy 19.608378 -197.986955) (xy 19.46397 -198.132779) (xy 19.313983 -198.272858)
			(xy 19.158644 -198.406977) (xy 18.998191 -198.534934) (xy 18.832868 -198.656534) (xy 18.662926 -198.77159)
			(xy 18.488625 -198.879929) (xy 18.310229 -198.981384) (xy 18.128011 -199.075802) (xy 17.942248 -199.163038)
			(xy 17.753223 -199.242961) (xy 17.561223 -199.315447) (xy 17.366541 -199.380387) (xy 17.169474 -199.437682)
			(xy 16.970321 -199.487245) (xy 16.769387 -199.529) (xy 16.566976 -199.562883) (xy 16.363398 -199.588843)
			(xy 16.158961 -199.60684) (xy 15.953978 -199.616848) (xy 15.748761 -199.61885) (xy 15.543622 -199.612844)
			(xy 15.338873 -199.598839) (xy 15.134826 -199.576856) (xy 14.931793 -199.546929) (xy 14.730082 -199.509102)
			(xy 14.53 -199.463435) (xy 14.331853 -199.409996) (xy 14.135941 -199.348867) (xy 13.942564 -199.280141)
			(xy 13.752015 -199.203922) (xy 13.564585 -199.120326) (xy 13.380559 -199.029482) (xy 13.200218 -198.931527)
			(xy 13.023836 -198.82661) (xy 12.851682 -198.714891) (xy 12.684017 -198.596541) (xy 12.521098 -198.471739)
			(xy 12.363172 -198.340675) (xy 12.21048 -198.20355) (xy 12.063255 -198.060572) (xy 11.92172 -197.911958)
			(xy 11.786091 -197.757936) (xy 11.656574 -197.598739) (xy 11.533368 -197.43461) (xy 11.416659 -197.265799)
			(xy 11.306625 -197.092562) (xy 11.203434 -196.915165) (xy 11.107243 -196.733877) (xy 11.018198 -196.548974)
			(xy 10.936435 -196.360737) (xy 10.862079 -196.169454) (xy 10.795243 -195.975415) (xy 10.736028 -195.778916)
			(xy 10.684525 -195.580257) (xy 10.640811 -195.379739) (xy 10.604955 -195.177668) (xy 10.57701 -194.974353)
			(xy 10.557019 -194.770102) (xy 10.545012 -194.565226) (xy 10.541008 -194.360038) (xy 5.324094 -194.360038)
			(xy 5.324094 -201.379368) (xy 98.428551 -201.379368) (xy 98.428551 -201.324832) (xy 98.436313 -201.270851)
			(xy 98.451678 -201.218525) (xy 98.474333 -201.168917) (xy 98.503818 -201.123039) (xy 98.539531 -201.081824)
			(xy 98.580747 -201.046112) (xy 98.626626 -201.016628) (xy 98.676234 -200.993974) (xy 98.728561 -200.978611)
			(xy 98.782542 -200.970851) (xy 98.80981 -200.970388) (xy 99.67341 -200.970388) (xy 99.700682 -200.970775)
			(xy 99.754672 -200.978539) (xy 99.807007 -200.993907) (xy 99.856623 -201.016567) (xy 99.902508 -201.046057)
			(xy 99.94373 -201.081777) (xy 99.979449 -201.123) (xy 100.008938 -201.168886) (xy 100.031596 -201.218502)
			(xy 100.046963 -201.270838) (xy 100.054725 -201.324828) (xy 100.054725 -201.379372) (xy 100.046963 -201.433362)
			(xy 100.031596 -201.485698) (xy 100.008938 -201.535314) (xy 99.979449 -201.5812) (xy 99.94373 -201.622423)
			(xy 99.902508 -201.658143) (xy 99.856623 -201.687633) (xy 99.807007 -201.710293) (xy 99.754672 -201.725661)
			(xy 99.700682 -201.733425) (xy 99.67341 -201.733912) (xy 98.80981 -201.733912) (xy 98.782542 -201.733349)
			(xy 98.728561 -201.725589) (xy 98.676234 -201.710226) (xy 98.626626 -201.687572) (xy 98.580747 -201.658088)
			(xy 98.539531 -201.622376) (xy 98.503818 -201.581161) (xy 98.474333 -201.535283) (xy 98.451678 -201.485675)
			(xy 98.436313 -201.433349) (xy 98.428551 -201.379368) (xy 5.324094 -201.379368) (xy 5.324094 -209.380836)
			(xy 445.288416 -209.380836) (xy 445.288416 -208.517236) (xy 445.288906 -208.487268) (xy 445.296729 -208.427846)
			(xy 445.312242 -208.369953) (xy 445.335178 -208.31458) (xy 445.365145 -208.262674) (xy 445.401632 -208.215124)
			(xy 445.444012 -208.172744) (xy 445.491562 -208.136257) (xy 445.543468 -208.10629) (xy 445.598841 -208.083354)
			(xy 445.656734 -208.067841) (xy 445.716156 -208.060018) (xy 445.776092 -208.060018) (xy 445.835514 -208.067841)
			(xy 445.893407 -208.083354) (xy 445.94878 -208.10629) (xy 446.000686 -208.136257) (xy 446.048236 -208.172744)
			(xy 446.090616 -208.215124) (xy 446.127103 -208.262674) (xy 446.15707 -208.31458) (xy 446.180006 -208.369953)
			(xy 446.195519 -208.427846) (xy 446.203342 -208.487268) (xy 446.203832 -208.517236) (xy 446.203832 -209.380836)
			(xy 446.203342 -209.410804) (xy 446.195519 -209.470226) (xy 446.180006 -209.528119) (xy 446.15707 -209.583492)
			(xy 446.127103 -209.635398) (xy 446.090616 -209.682948) (xy 446.048236 -209.725328) (xy 446.000686 -209.761815)
			(xy 445.94878 -209.791782) (xy 445.893407 -209.814718) (xy 445.835514 -209.830231) (xy 445.776092 -209.838054)
			(xy 445.716156 -209.838054) (xy 445.656734 -209.830231) (xy 445.598841 -209.814718) (xy 445.543468 -209.791782)
			(xy 445.491562 -209.761815) (xy 445.444012 -209.725328) (xy 445.401632 -209.682948) (xy 445.365145 -209.635398)
			(xy 445.335178 -209.583492) (xy 445.312242 -209.528119) (xy 445.296729 -209.470226) (xy 445.288906 -209.410804)
			(xy 445.288416 -209.380836) (xy 5.324094 -209.380836) (xy 5.324094 -225.261473) (xy 239.822113 -225.261473)
			(xy 239.822113 -225.201527) (xy 239.829938 -225.142093) (xy 239.845454 -225.084189) (xy 239.868395 -225.028806)
			(xy 239.89837 -224.976891) (xy 239.934864 -224.929333) (xy 239.977254 -224.886945) (xy 240.024814 -224.850454)
			(xy 240.076731 -224.820483) (xy 240.132115 -224.797545) (xy 240.19002 -224.782032) (xy 240.249455 -224.774211)
			(xy 240.279428 -224.773744) (xy 241.143028 -224.773744) (xy 241.172991 -224.774332) (xy 241.232405 -224.782157)
			(xy 241.290289 -224.79767) (xy 241.345653 -224.820606) (xy 241.39755 -224.850571) (xy 241.445091 -224.887054)
			(xy 241.487465 -224.92943) (xy 241.523944 -224.976974) (xy 241.553907 -225.028872) (xy 241.576839 -225.084238)
			(xy 241.592348 -225.142123) (xy 241.60017 -225.201537) (xy 241.60017 -225.261463) (xy 241.592348 -225.320877)
			(xy 241.576839 -225.378762) (xy 241.553907 -225.434128) (xy 241.523944 -225.486026) (xy 241.487465 -225.53357)
			(xy 241.445091 -225.575946) (xy 241.39755 -225.612429) (xy 241.345653 -225.642394) (xy 241.290289 -225.66533)
			(xy 241.232405 -225.680843) (xy 241.172991 -225.688668) (xy 241.143028 -225.68916) (xy 240.279428 -225.68916)
			(xy 240.249455 -225.688789) (xy 240.19002 -225.680968) (xy 240.132115 -225.665455) (xy 240.076731 -225.642517)
			(xy 240.024814 -225.612546) (xy 239.977254 -225.576055) (xy 239.934864 -225.533667) (xy 239.89837 -225.486109)
			(xy 239.868395 -225.434194) (xy 239.845454 -225.378811) (xy 239.829938 -225.320907) (xy 239.822113 -225.261473)
			(xy 5.324094 -225.261473) (xy 5.324094 -230.903589) (xy 383.216061 -230.903589) (xy 383.216061 -230.843611)
			(xy 383.22389 -230.784147) (xy 383.239413 -230.726213) (xy 383.262366 -230.670801) (xy 383.292355 -230.618858)
			(xy 383.328867 -230.571275) (xy 383.371278 -230.528865) (xy 383.418862 -230.492353) (xy 383.470804 -230.462364)
			(xy 383.526216 -230.439412) (xy 383.584151 -230.423889) (xy 383.643615 -230.416061) (xy 383.673604 -230.415592)
			(xy 384.537204 -230.415592) (xy 384.567185 -230.416174) (xy 384.626634 -230.424001) (xy 384.684553 -230.439521)
			(xy 384.739951 -230.462468) (xy 384.79188 -230.492449) (xy 384.839451 -230.528952) (xy 384.88185 -230.571352)
			(xy 384.918353 -230.618924) (xy 384.948334 -230.670853) (xy 384.97128 -230.726251) (xy 384.986799 -230.78417)
			(xy 384.994626 -230.843619) (xy 384.994626 -230.903581) (xy 384.986799 -230.96303) (xy 384.97128 -231.020949)
			(xy 384.948334 -231.076347) (xy 384.918353 -231.128276) (xy 384.88185 -231.175848) (xy 384.839451 -231.218248)
			(xy 384.79188 -231.254751) (xy 384.739951 -231.284732) (xy 384.684553 -231.307679) (xy 384.626634 -231.323199)
			(xy 384.567185 -231.331026) (xy 384.537204 -231.331516) (xy 383.673604 -231.331516) (xy 383.643615 -231.331139)
			(xy 383.584151 -231.323311) (xy 383.526216 -231.307788) (xy 383.470804 -231.284836) (xy 383.418862 -231.254847)
			(xy 383.371278 -231.218335) (xy 383.328867 -231.175925) (xy 383.292355 -231.128342) (xy 383.262366 -231.076399)
			(xy 383.239413 -231.020987) (xy 383.22389 -230.963053) (xy 383.216061 -230.903589) (xy 5.324094 -230.903589)
			(xy 5.324094 -234.655869) (xy 448.021157 -234.655869) (xy 448.021157 -234.595931) (xy 448.028981 -234.536505)
			(xy 448.044494 -234.478608) (xy 448.067432 -234.423232) (xy 448.097401 -234.371324) (xy 448.13389 -234.323771)
			(xy 448.176273 -234.281388) (xy 448.223825 -234.2449) (xy 448.275734 -234.214931) (xy 448.33111 -234.191993)
			(xy 448.389007 -234.17648) (xy 448.448433 -234.168657) (xy 448.478402 -234.168188) (xy 449.342002 -234.168188)
			(xy 449.371969 -234.168686) (xy 449.431391 -234.176509) (xy 449.489283 -234.192022) (xy 449.544656 -234.214958)
			(xy 449.596561 -234.244925) (xy 449.64411 -234.281411) (xy 449.68649 -234.323792) (xy 449.722976 -234.371341)
			(xy 449.752943 -234.423246) (xy 449.775879 -234.478618) (xy 449.791391 -234.536511) (xy 449.799214 -234.595933)
			(xy 449.799214 -234.655867) (xy 449.791391 -234.715289) (xy 449.775879 -234.773182) (xy 449.752943 -234.828554)
			(xy 449.722976 -234.880459) (xy 449.68649 -234.928008) (xy 449.64411 -234.970389) (xy 449.596561 -235.006875)
			(xy 449.544656 -235.036842) (xy 449.489283 -235.059778) (xy 449.431391 -235.075291) (xy 449.371969 -235.083114)
			(xy 449.342002 -235.083604) (xy 448.478402 -235.083604) (xy 448.448433 -235.083143) (xy 448.389007 -235.07532)
			(xy 448.33111 -235.059807) (xy 448.275734 -235.036869) (xy 448.223825 -235.0069) (xy 448.176273 -234.970412)
			(xy 448.13389 -234.928029) (xy 448.097401 -234.880476) (xy 448.067432 -234.828568) (xy 448.044494 -234.773192)
			(xy 448.028981 -234.715295) (xy 448.021157 -234.655869) (xy 5.324094 -234.655869) (xy 5.324094 -239.07907)
			(xy 153.398934 -239.07907) (xy 153.398934 -239.01913) (xy 153.406758 -238.959703) (xy 153.422271 -238.901805)
			(xy 153.445208 -238.846427) (xy 153.475178 -238.794517) (xy 153.511666 -238.746963) (xy 153.554049 -238.704578)
			(xy 153.601602 -238.668088) (xy 153.653511 -238.638116) (xy 153.708888 -238.615177) (xy 153.766785 -238.599661)
			(xy 153.826212 -238.591835) (xy 153.856182 -238.591344) (xy 154.719782 -238.591344) (xy 154.749749 -238.591908)
			(xy 154.809169 -238.599729) (xy 154.867061 -238.615239) (xy 154.922433 -238.638172) (xy 154.974337 -238.668138)
			(xy 155.021886 -238.704622) (xy 155.064267 -238.747) (xy 155.100752 -238.794548) (xy 155.13072 -238.846451)
			(xy 155.153656 -238.901822) (xy 155.169168 -238.959713) (xy 155.176991 -239.019133) (xy 155.176991 -239.079067)
			(xy 155.169168 -239.138487) (xy 155.153656 -239.196378) (xy 155.13072 -239.251749) (xy 155.100752 -239.303652)
			(xy 155.064267 -239.3512) (xy 155.021886 -239.393578) (xy 154.974337 -239.430062) (xy 154.922433 -239.460028)
			(xy 154.867061 -239.482961) (xy 154.809169 -239.498471) (xy 154.749749 -239.506292) (xy 154.719782 -239.50676)
			(xy 153.856182 -239.50676) (xy 153.826212 -239.506365) (xy 153.766785 -239.498539) (xy 153.708888 -239.483023)
			(xy 153.653511 -239.460084) (xy 153.601602 -239.430112) (xy 153.554049 -239.393622) (xy 153.511666 -239.351237)
			(xy 153.475178 -239.303683) (xy 153.445208 -239.251773) (xy 153.422271 -239.196395) (xy 153.406758 -239.138497)
			(xy 153.398934 -239.07907) (xy 5.324094 -239.07907) (xy 5.324094 -241.031776) (xy 5.32356 -241.118274)
			(xy 5.315049 -241.29106) (xy 5.29807 -241.46322) (xy 5.272664 -241.63434) (xy 5.238892 -241.804008)
			(xy 5.196835 -241.971813) (xy 5.146594 -242.137353) (xy 5.088292 -242.300228) (xy 5.022067 -242.460046)
			(xy 4.948081 -242.616423) (xy 4.86651 -242.76898) (xy 4.777552 -242.917351) (xy 4.681421 -243.061178)
			(xy 4.578348 -243.200115) (xy 4.468582 -243.333827) (xy 4.352387 -243.461992) (xy 4.291584 -243.523516)
			(xy 1.663446 -246.151654) (xy 1.641773 -246.174052) (xy 1.603834 -246.223499) (xy 1.572669 -246.277474)
			(xy 1.548812 -246.335052) (xy 1.53267 -246.395251) (xy 1.524519 -246.457041) (xy 1.524 -246.488204)
			(xy 1.524 -270.89989) (xy 24.898611 -270.89989) (xy 24.902617 -270.704835) (xy 24.914627 -270.510109)
			(xy 24.934622 -270.31604) (xy 24.962567 -270.122956) (xy 24.998416 -269.931181) (xy 25.042108 -269.741041)
			(xy 25.093569 -269.552854) (xy 25.152713 -269.366939) (xy 25.21944 -269.183608) (xy 25.293637 -269.003172)
			(xy 25.375179 -268.825934) (xy 25.46393 -268.652193) (xy 25.559738 -268.482242) (xy 25.662443 -268.316368)
			(xy 25.771871 -268.15485) (xy 25.887838 -267.997961) (xy 26.010149 -267.845966) (xy 26.138596 -267.69912)
			(xy 26.272964 -267.557671) (xy 26.413026 -267.421858) (xy 26.558545 -267.291909) (xy 26.709277 -267.168045)
			(xy 26.864967 -267.050473) (xy 27.025353 -266.939393) (xy 27.190164 -266.83499) (xy 27.359122 -266.737442)
			(xy 27.531943 -266.646913) (xy 27.708335 -266.563555) (xy 27.888 -266.487509) (xy 28.070635 -266.418904)
			(xy 28.255934 -266.357854) (xy 28.443582 -266.304464) (xy 28.633264 -266.258822) (xy 28.824661 -266.221006)
			(xy 29.017448 -266.19108) (xy 29.211301 -266.169094) (xy 29.405894 -266.155085) (xy 29.600897 -266.149077)
			(xy 29.795983 -266.15108) (xy 29.990822 -266.161091) (xy 30.185086 -266.179092) (xy 30.378447 -266.205054)
			(xy 30.57058 -266.238932) (xy 30.761159 -266.280669) (xy 30.949864 -266.330196) (xy 31.136377 -266.387428)
			(xy 31.320383 -266.452269) (xy 31.501571 -266.52461) (xy 31.679637 -266.604328) (xy 31.85428 -266.69129)
			(xy 32.025206 -266.785349) (xy 32.192125 -266.886345) (xy 32.354758 -266.99411) (xy 32.512829 -267.10846)
			(xy 32.666072 -267.229203) (xy 32.814229 -267.356137) (xy 32.95705 -267.489045) (xy 33.094294 -267.627705)
			(xy 33.22573 -267.771883) (xy 33.351135 -267.921336) (xy 33.470299 -268.07581) (xy 33.58302 -268.235047)
			(xy 33.689109 -268.398778) (xy 33.788387 -268.566725) (xy 33.880685 -268.738608) (xy 33.96585 -268.914134)
			(xy 34.043736 -269.093009) (xy 34.114213 -269.274931) (xy 34.177161 -269.459593) (xy 34.232476 -269.646683)
			(xy 34.280062 -269.835887) (xy 34.319841 -270.026884) (xy 34.351745 -270.219354) (xy 34.37572 -270.412972)
			(xy 34.391726 -270.60741) (xy 34.399735 -270.802342) (xy 34.400236 -270.89989) (xy 34.399735 -270.997438)
			(xy 34.391726 -271.19237) (xy 34.37572 -271.386808) (xy 34.351745 -271.580426) (xy 34.319841 -271.772896)
			(xy 34.280062 -271.963893) (xy 34.232476 -272.153097) (xy 34.177161 -272.340187) (xy 34.114213 -272.524849)
			(xy 34.043736 -272.706771) (xy 33.96585 -272.885646) (xy 33.880685 -273.061172) (xy 33.788387 -273.233055)
			(xy 33.689109 -273.401002) (xy 33.58302 -273.564733) (xy 33.470299 -273.72397) (xy 33.351135 -273.878444)
			(xy 33.22573 -274.027897) (xy 33.094294 -274.172075) (xy 32.95705 -274.310735) (xy 32.814229 -274.443643)
			(xy 32.666072 -274.570577) (xy 32.512829 -274.69132) (xy 32.354758 -274.80567) (xy 32.192125 -274.913435)
			(xy 32.025206 -275.014431) (xy 31.85428 -275.10849) (xy 31.679637 -275.195452) (xy 31.501571 -275.27517)
			(xy 31.320383 -275.347511) (xy 31.136377 -275.412352) (xy 30.949864 -275.469584) (xy 30.761159 -275.519111)
			(xy 30.57058 -275.560848) (xy 30.378447 -275.594726) (xy 30.185086 -275.620688) (xy 29.990822 -275.638689)
			(xy 29.795983 -275.6487) (xy 29.600897 -275.650703) (xy 29.405894 -275.644695) (xy 29.211301 -275.630686)
			(xy 29.017448 -275.6087) (xy 28.824661 -275.578774) (xy 28.633264 -275.540958) (xy 28.443582 -275.495316)
			(xy 28.255934 -275.441926) (xy 28.070635 -275.380876) (xy 27.888 -275.312271) (xy 27.708335 -275.236225)
			(xy 27.531943 -275.152867) (xy 27.359122 -275.062338) (xy 27.190164 -274.96479) (xy 27.025353 -274.860387)
			(xy 26.864967 -274.749307) (xy 26.709277 -274.631735) (xy 26.558545 -274.507871) (xy 26.413026 -274.377922)
			(xy 26.272964 -274.242109) (xy 26.138596 -274.10066) (xy 26.010149 -273.953814) (xy 25.887838 -273.801819)
			(xy 25.771871 -273.64493) (xy 25.662443 -273.483412) (xy 25.559738 -273.317538) (xy 25.46393 -273.147587)
			(xy 25.375179 -272.973846) (xy 25.293637 -272.796608) (xy 25.21944 -272.616172) (xy 25.152713 -272.432841)
			(xy 25.093569 -272.246926) (xy 25.042108 -272.058739) (xy 24.998416 -271.868599) (xy 24.962567 -271.676824)
			(xy 24.934622 -271.48374) (xy 24.914627 -271.289671) (xy 24.902617 -271.094945) (xy 24.898611 -270.89989)
			(xy 1.524 -270.89989) (xy 1.524 -301.410116) (xy 16.770865 -301.410116) (xy 16.774873 -301.24559)
			(xy 16.786886 -301.081455) (xy 16.806876 -300.918099) (xy 16.834796 -300.75591) (xy 16.870579 -300.595273)
			(xy 16.914141 -300.436569) (xy 16.965379 -300.280174) (xy 17.02417 -300.126459) (xy 17.090375 -299.975788)
			(xy 17.163838 -299.82852) (xy 17.244383 -299.685003) (xy 17.331821 -299.545577) (xy 17.425943 -299.410575)
			(xy 17.526527 -299.280315) (xy 17.633333 -299.155106) (xy 17.746109 -299.035246) (xy 17.864587 -298.92102)
			(xy 17.988485 -298.812697) (xy 18.117511 -298.710534) (xy 18.251357 -298.614775) (xy 18.389708 -298.525647)
			(xy 18.532233 -298.443359) (xy 18.678596 -298.368109) (xy 18.828449 -298.300074) (xy 18.981437 -298.239415)
			(xy 19.137197 -298.186278) (xy 19.295359 -298.140786) (xy 19.455549 -298.10305) (xy 19.617386 -298.073157)
			(xy 19.780486 -298.051179) (xy 19.944463 -298.037168) (xy 20.108927 -298.031158) (xy 20.27349 -298.033161)
			(xy 20.437759 -298.043175) (xy 20.601346 -298.061175) (xy 20.763863 -298.087118) (xy 20.924924 -298.120943)
			(xy 21.084147 -298.162569) (xy 21.241154 -298.211898) (xy 21.395574 -298.268813) (xy 21.547039 -298.333179)
			(xy 21.695191 -298.404843) (xy 21.839679 -298.483635) (xy 21.980158 -298.569369) (xy 22.116297 -298.66184)
			(xy 22.247772 -298.76083) (xy 22.374272 -298.866104) (xy 22.495496 -298.977412) (xy 22.611157 -299.09449)
			(xy 22.72098 -299.21706) (xy 22.727388 -299.224954) (xy 36.043616 -299.224954) (xy 36.044009 -299.203033)
			(xy 36.049872 -299.159582) (xy 36.0553 -299.13834) (xy 36.057078 -299.131736) (xy 36.057078 -297.417998)
			(xy 36.0553 -297.411394) (xy 36.049868 -297.390152) (xy 36.044006 -297.346702) (xy 36.043616 -297.32478)
			(xy 36.044014 -297.302859) (xy 36.049874 -297.259409) (xy 36.0553 -297.238166) (xy 36.057078 -297.231562)
			(xy 36.057078 -294.566848) (xy 36.0553 -294.560244) (xy 36.050082 -294.539295) (xy 36.044475 -294.496487)
			(xy 36.044124 -294.4749) (xy 36.044448 -294.453311) (xy 36.050052 -294.4105) (xy 36.0553 -294.389556)
			(xy 36.057078 -294.382952) (xy 36.057078 -292.666928) (xy 36.0553 -292.660324) (xy 36.050078 -292.639375)
			(xy 36.044474 -292.596567) (xy 36.044124 -292.57498) (xy 36.044444 -292.553391) (xy 36.050051 -292.510579)
			(xy 36.0553 -292.489636) (xy 36.057078 -292.483032) (xy 36.057078 -291.716714) (xy 36.0553 -291.71011)
			(xy 36.050075 -291.689162) (xy 36.044473 -291.646353) (xy 36.044124 -291.624766) (xy 36.044441 -291.603177)
			(xy 36.05005 -291.560365) (xy 36.0553 -291.539422) (xy 36.057078 -291.532818) (xy 36.057078 -290.766754)
			(xy 36.0553 -290.76015) (xy 36.050083 -290.7392) (xy 36.044476 -290.696393) (xy 36.044124 -290.674806)
			(xy 36.044449 -290.653217) (xy 36.050052 -290.610406) (xy 36.0553 -290.589462) (xy 36.057078 -290.582858)
			(xy 36.057078 -289.816794) (xy 36.0553 -289.81019) (xy 36.050072 -289.789243) (xy 36.044472 -289.746433)
			(xy 36.044124 -289.724846) (xy 36.044437 -289.703257) (xy 36.050048 -289.660445) (xy 36.0553 -289.639502)
			(xy 36.057078 -289.632898) (xy 36.057078 -288.866834) (xy 36.0553 -288.86023) (xy 36.054538 -288.85769)
			(xy 36.054538 -288.857182) (xy 36.049642 -288.836833) (xy 36.044415 -288.795306) (xy 36.044124 -288.774378)
			(xy 36.044417 -288.752662) (xy 36.050025 -288.709594) (xy 36.0553 -288.688526) (xy 36.057078 -288.681922)
			(xy 36.057078 -287.916874) (xy 36.0553 -287.91027) (xy 36.050087 -287.889319) (xy 36.044477 -287.846512)
			(xy 36.044124 -287.824926) (xy 36.044453 -287.803337) (xy 36.050053 -287.760526) (xy 36.0553 -287.739582)
			(xy 36.057078 -287.732978) (xy 36.057078 -286.966914) (xy 36.0553 -286.96031) (xy 36.050075 -286.939362)
			(xy 36.044473 -286.896553) (xy 36.044124 -286.874966) (xy 36.044441 -286.853377) (xy 36.05005 -286.810565)
			(xy 36.0553 -286.789622) (xy 36.057078 -286.783018) (xy 36.057078 -286.0167) (xy 36.0553 -286.010096)
			(xy 36.050073 -285.989149) (xy 36.044472 -285.946339) (xy 36.044124 -285.924752) (xy 36.044438 -285.903163)
			(xy 36.050049 -285.860351) (xy 36.0553 -285.839408) (xy 36.057078 -285.832804) (xy 36.057078 -285.06674)
			(xy 36.0553 -285.060136) (xy 36.05008 -285.039187) (xy 36.044475 -284.996379) (xy 36.044124 -284.974792)
			(xy 36.044446 -284.953203) (xy 36.050051 -284.910392) (xy 36.0553 -284.889448) (xy 36.057078 -284.882844)
			(xy 36.057078 -284.11678) (xy 36.0553 -284.110176) (xy 36.050088 -284.089225) (xy 36.044477 -284.046418)
			(xy 36.044124 -284.024832) (xy 36.044454 -284.003243) (xy 36.050054 -283.960432) (xy 36.0553 -283.939488)
			(xy 36.057078 -283.932884) (xy 36.057078 -283.16682) (xy 36.0553 -283.160216) (xy 36.050076 -283.139268)
			(xy 36.044474 -283.096459) (xy 36.044124 -283.074872) (xy 36.044442 -283.053283) (xy 36.05005 -283.010471)
			(xy 36.0553 -282.989528) (xy 36.057078 -282.982924) (xy 36.057078 -282.21686) (xy 36.0553 -282.210256)
			(xy 36.050084 -282.189306) (xy 36.044476 -282.146499) (xy 36.044124 -282.124912) (xy 36.04445 -282.103323)
			(xy 36.050053 -282.060512) (xy 36.0553 -282.039568) (xy 36.057078 -282.032964) (xy 36.057078 -281.2669)
			(xy 36.0553 -281.260296) (xy 36.050073 -281.239349) (xy 36.044472 -281.196539) (xy 36.044124 -281.174952)
			(xy 36.044438 -281.153363) (xy 36.050049 -281.110551) (xy 36.0553 -281.089608) (xy 36.057078 -281.083004)
			(xy 36.057078 -280.316686) (xy 36.0553 -280.310082) (xy 36.050089 -280.289131) (xy 36.044478 -280.246324)
			(xy 36.044124 -280.224738) (xy 36.044455 -280.20315) (xy 36.050054 -280.160338) (xy 36.0553 -280.139394)
			(xy 36.057078 -280.13279) (xy 36.057078 -279.366726) (xy 36.0553 -279.360122) (xy 36.050078 -279.339174)
			(xy 36.044474 -279.296365) (xy 36.044124 -279.274778) (xy 36.044443 -279.253189) (xy 36.05005 -279.210377)
			(xy 36.0553 -279.189434) (xy 36.057078 -279.18283) (xy 36.057078 -278.416766) (xy 36.0553 -278.410162)
			(xy 36.050085 -278.389212) (xy 36.044477 -278.346404) (xy 36.044124 -278.324818) (xy 36.044451 -278.303229)
			(xy 36.050053 -278.260418) (xy 36.0553 -278.239474) (xy 36.057078 -278.23287) (xy 36.057078 -277.466806)
			(xy 36.0553 -277.460202) (xy 36.050074 -277.439254) (xy 36.044473 -277.396445) (xy 36.044124 -277.374858)
			(xy 36.044439 -277.353269) (xy 36.050049 -277.310457) (xy 36.0553 -277.289514) (xy 36.057078 -277.28291)
			(xy 36.057078 -276.516846) (xy 36.0553 -276.510242) (xy 36.050081 -276.489293) (xy 36.044475 -276.446485)
			(xy 36.044124 -276.424898) (xy 36.044447 -276.403309) (xy 36.050052 -276.360498) (xy 36.0553 -276.339554)
			(xy 36.057078 -276.33295) (xy 36.057078 -275.566886) (xy 36.0553 -275.560282) (xy 36.050089 -275.539331)
			(xy 36.044478 -275.496524) (xy 36.044124 -275.474938) (xy 36.044455 -275.45335) (xy 36.050054 -275.410538)
			(xy 36.0553 -275.389594) (xy 36.057078 -275.38299) (xy 36.057078 -272.53819) (xy 36.057578 -272.513241)
			(xy 36.065391 -272.463958) (xy 36.080807 -272.416501) (xy 36.103448 -272.372035) (xy 36.132757 -272.331652)
			(xy 36.150042 -272.313654) (xy 36.698428 -271.765268) (xy 36.716401 -271.747952) (xy 36.756781 -271.718624)
			(xy 36.801251 -271.695974) (xy 36.848717 -271.680561) (xy 36.898011 -271.672763) (xy 36.922964 -271.672304)
			(xy 84.844382 -271.672304) (xy 84.855307 -271.671772) (xy 84.875182 -271.662689) (xy 84.882736 -271.654778)
			(xy 84.94014 -271.588738) (xy 84.94649 -271.567402) (xy 84.944966 -271.556734) (xy 84.930472 -271.448248)
			(xy 84.910277 -271.230286) (xy 84.900148 -271.011624) (xy 84.8995 -270.902176) (xy 84.8995 -270.89989)
			(xy 84.899994 -270.802981) (xy 84.9079 -270.609323) (xy 84.923698 -270.416149) (xy 84.947362 -270.22378)
			(xy 84.978853 -270.032537) (xy 85.018118 -269.842737) (xy 85.065092 -269.654697) (xy 85.119697 -269.468729)
			(xy 85.181842 -269.285143) (xy 85.251424 -269.104245) (xy 85.328326 -268.926335) (xy 85.412421 -268.751711)
			(xy 85.503568 -268.580661) (xy 85.601617 -268.413472) (xy 85.706403 -268.250421) (xy 85.817753 -268.09178)
			(xy 85.935481 -267.937813) (xy 86.059391 -267.788776) (xy 86.189277 -267.644917) (xy 86.324923 -267.506476)
			(xy 86.466102 -267.373682) (xy 86.612581 -267.246758) (xy 86.764114 -267.125914) (xy 86.920451 -267.011351)
			(xy 87.08133 -266.903261) (xy 87.246485 -266.801822) (xy 87.415639 -266.707204) (xy 87.588512 -266.619565)
			(xy 87.764816 -266.53905) (xy 87.944257 -266.465793) (xy 88.126537 -266.399916) (xy 88.311352 -266.341528)
			(xy 88.498395 -266.290728) (xy 88.687355 -266.247599) (xy 88.877916 -266.212214) (xy 89.069762 -266.184631)
			(xy 89.262573 -266.164895) (xy 89.456029 -266.153041) (xy 89.649808 -266.149088) (xy 89.843587 -266.153041)
			(xy 90.037043 -266.164895) (xy 90.229854 -266.184631) (xy 90.4217 -266.212214) (xy 90.612261 -266.247599)
			(xy 90.801221 -266.290728) (xy 90.988264 -266.341528) (xy 91.173079 -266.399916) (xy 91.355359 -266.465793)
			(xy 91.5348 -266.53905) (xy 91.711104 -266.619565) (xy 91.883977 -266.707204) (xy 92.053131 -266.801822)
			(xy 92.218286 -266.903261) (xy 92.379165 -267.011351) (xy 92.535502 -267.125914) (xy 92.687035 -267.246758)
			(xy 92.833514 -267.373682) (xy 92.974693 -267.506476) (xy 93.110339 -267.644917) (xy 93.240225 -267.788776)
			(xy 93.364135 -267.937813) (xy 93.481863 -268.09178) (xy 93.593213 -268.250421) (xy 93.697999 -268.413472)
			(xy 93.796048 -268.580661) (xy 93.887195 -268.751711) (xy 93.97129 -268.926335) (xy 94.048192 -269.104245)
			(xy 94.117774 -269.285143) (xy 94.179919 -269.468729) (xy 94.234524 -269.654697) (xy 94.281498 -269.842737)
			(xy 94.320763 -270.032537) (xy 94.352254 -270.22378) (xy 94.375918 -270.416149) (xy 94.391716 -270.609323)
			(xy 94.399622 -270.802981) (xy 94.400116 -270.89989) (xy 94.400116 -270.902176) (xy 94.399461 -271.011624)
			(xy 94.389325 -271.230284) (xy 94.369133 -271.448247) (xy 94.35465 -271.556734) (xy 94.353126 -271.567402)
			(xy 94.359476 -271.588738) (xy 94.41688 -271.654778) (xy 94.424418 -271.662709) (xy 94.444304 -271.671787)
			(xy 94.455234 -271.672304) (xy 130.632962 -271.672304) (xy 130.643032 -271.671884) (xy 130.661632 -271.664162)
			(xy 130.66903 -271.657318) (xy 132.33019 -269.996158) (xy 132.348178 -269.978859) (xy 132.388554 -269.949529)
			(xy 132.433021 -269.926876) (xy 132.480483 -269.911459) (xy 132.529774 -269.903656) (xy 132.554726 -269.903194)
			(xy 140.895832 -269.903194) (xy 140.919633 -269.903631) (xy 140.966698 -269.910777) (xy 140.989558 -269.917418)
			(xy 140.99968 -269.919988) (xy 141.020407 -269.91763) (xy 141.02969 -269.912846) (xy 141.103604 -269.870174)
			(xy 141.11605 -269.853156) (xy 141.118336 -269.842742) (xy 141.140395 -269.748371) (xy 141.1912 -269.561321)
			(xy 141.249591 -269.376498) (xy 141.315473 -269.194211) (xy 141.388735 -269.014763) (xy 141.469255 -268.838452)
			(xy 141.5569 -268.665573) (xy 141.651523 -268.496412) (xy 141.752967 -268.331251) (xy 141.861063 -268.170366)
			(xy 141.975632 -268.014023) (xy 142.096482 -267.862484) (xy 142.223412 -267.716) (xy 142.356212 -267.574815)
			(xy 142.49466 -267.439164) (xy 142.638525 -267.309273) (xy 142.787569 -267.185358) (xy 142.941543 -267.067626)
			(xy 143.100191 -266.956271) (xy 143.263249 -266.851481) (xy 143.430445 -266.753428) (xy 143.601502 -266.662277)
			(xy 143.776134 -266.578179) (xy 143.954051 -266.501273) (xy 144.134957 -266.431688) (xy 144.318551 -266.36954)
			(xy 144.504526 -266.314933) (xy 144.692574 -266.267956) (xy 144.882382 -266.228688) (xy 145.073634 -266.197195)
			(xy 145.266011 -266.173529) (xy 145.459193 -266.15773) (xy 145.652858 -266.149823) (xy 145.749772 -266.149328)
			(xy 145.84796 -266.14982) (xy 146.044169 -266.157935) (xy 146.239875 -266.174151) (xy 146.434744 -266.198441)
			(xy 146.628443 -266.230764) (xy 146.82064 -266.271064) (xy 147.011007 -266.319272) (xy 147.19922 -266.375307)
			(xy 147.384956 -266.439072) (xy 147.567898 -266.510458) (xy 147.747733 -266.589344) (xy 147.924155 -266.675594)
			(xy 148.096862 -266.769062) (xy 148.265559 -266.869587) (xy 148.429957 -266.976998) (xy 148.589775 -267.091112)
			(xy 148.744741 -267.211732) (xy 148.89459 -267.338654) (xy 149.039066 -267.47166) (xy 149.177921 -267.610523)
			(xy 149.31092 -267.755006) (xy 149.437833 -267.904862) (xy 149.558445 -268.059835) (xy 149.67255 -268.21966)
			(xy 149.779951 -268.384064) (xy 149.880467 -268.552766) (xy 149.973925 -268.725478) (xy 150.060166 -268.901904)
			(xy 150.139042 -269.081744) (xy 150.210418 -269.26469) (xy 150.274173 -269.45043) (xy 150.330197 -269.638646)
			(xy 150.378395 -269.829016) (xy 150.418685 -270.021215) (xy 150.450997 -270.214915) (xy 150.475276 -270.409785)
			(xy 150.491482 -270.605492) (xy 150.499585 -270.801702) (xy 150.50008 -270.89989) (xy 200.998589 -270.89989)
			(xy 201.002595 -270.704835) (xy 201.014605 -270.510109) (xy 201.0346 -270.31604) (xy 201.062545 -270.122956)
			(xy 201.098394 -269.931181) (xy 201.142086 -269.741041) (xy 201.193547 -269.552854) (xy 201.252691 -269.366939)
			(xy 201.319418 -269.183608) (xy 201.393615 -269.003172) (xy 201.475157 -268.825934) (xy 201.563908 -268.652193)
			(xy 201.659716 -268.482242) (xy 201.762421 -268.316368) (xy 201.871849 -268.15485) (xy 201.987816 -267.997961)
			(xy 202.110127 -267.845966) (xy 202.238574 -267.69912) (xy 202.372942 -267.557671) (xy 202.513004 -267.421858)
			(xy 202.658523 -267.291909) (xy 202.809255 -267.168045) (xy 202.964945 -267.050473) (xy 203.125331 -266.939393)
			(xy 203.290142 -266.83499) (xy 203.4591 -266.737442) (xy 203.631921 -266.646913) (xy 203.808313 -266.563555)
			(xy 203.987978 -266.487509) (xy 204.170613 -266.418904) (xy 204.355912 -266.357854) (xy 204.54356 -266.304464)
			(xy 204.733242 -266.258822) (xy 204.924639 -266.221006) (xy 205.117426 -266.19108) (xy 205.311279 -266.169094)
			(xy 205.505872 -266.155085) (xy 205.700875 -266.149077) (xy 205.895961 -266.15108) (xy 206.0908 -266.161091)
			(xy 206.285064 -266.179092) (xy 206.478425 -266.205054) (xy 206.670558 -266.238932) (xy 206.861137 -266.280669)
			(xy 207.049842 -266.330196) (xy 207.236355 -266.387428) (xy 207.420361 -266.452269) (xy 207.601549 -266.52461)
			(xy 207.779615 -266.604328) (xy 207.954258 -266.69129) (xy 208.125184 -266.785349) (xy 208.292103 -266.886345)
			(xy 208.454736 -266.99411) (xy 208.612807 -267.10846) (xy 208.76605 -267.229203) (xy 208.914207 -267.356137)
			(xy 209.057028 -267.489045) (xy 209.194272 -267.627705) (xy 209.325708 -267.771883) (xy 209.451113 -267.921336)
			(xy 209.570277 -268.07581) (xy 209.682998 -268.235047) (xy 209.789087 -268.398778) (xy 209.888365 -268.566725)
			(xy 209.980663 -268.738608) (xy 210.065828 -268.914134) (xy 210.143714 -269.093009) (xy 210.214191 -269.274931)
			(xy 210.277139 -269.459593) (xy 210.332454 -269.646683) (xy 210.38004 -269.835887) (xy 210.419819 -270.026884)
			(xy 210.451723 -270.219354) (xy 210.475698 -270.412972) (xy 210.491704 -270.60741) (xy 210.499713 -270.802342)
			(xy 210.500214 -270.89989) (xy 257.098807 -270.89989) (xy 257.102813 -270.704835) (xy 257.114823 -270.510109)
			(xy 257.134818 -270.31604) (xy 257.162763 -270.122956) (xy 257.198612 -269.931181) (xy 257.242304 -269.741041)
			(xy 257.293765 -269.552854) (xy 257.352909 -269.366939) (xy 257.419636 -269.183608) (xy 257.493833 -269.003172)
			(xy 257.575375 -268.825934) (xy 257.664126 -268.652193) (xy 257.759934 -268.482242) (xy 257.862639 -268.316368)
			(xy 257.972067 -268.15485) (xy 258.088034 -267.997961) (xy 258.210345 -267.845966) (xy 258.338792 -267.69912)
			(xy 258.47316 -267.557671) (xy 258.613222 -267.421858) (xy 258.758741 -267.291909) (xy 258.909473 -267.168045)
			(xy 259.065163 -267.050473) (xy 259.225549 -266.939393) (xy 259.39036 -266.83499) (xy 259.559318 -266.737442)
			(xy 259.732139 -266.646913) (xy 259.908531 -266.563555) (xy 260.088196 -266.487509) (xy 260.270831 -266.418904)
			(xy 260.45613 -266.357854) (xy 260.643778 -266.304464) (xy 260.83346 -266.258822) (xy 261.024857 -266.221006)
			(xy 261.217644 -266.19108) (xy 261.411497 -266.169094) (xy 261.60609 -266.155085) (xy 261.801093 -266.149077)
			(xy 261.996179 -266.15108) (xy 262.191018 -266.161091) (xy 262.385282 -266.179092) (xy 262.578643 -266.205054)
			(xy 262.770776 -266.238932) (xy 262.961355 -266.280669) (xy 263.15006 -266.330196) (xy 263.336573 -266.387428)
			(xy 263.520579 -266.452269) (xy 263.701767 -266.52461) (xy 263.879833 -266.604328) (xy 264.054476 -266.69129)
			(xy 264.225402 -266.785349) (xy 264.392321 -266.886345) (xy 264.554954 -266.99411) (xy 264.713025 -267.10846)
			(xy 264.866268 -267.229203) (xy 265.014425 -267.356137) (xy 265.157246 -267.489045) (xy 265.29449 -267.627705)
			(xy 265.425926 -267.771883) (xy 265.551331 -267.921336) (xy 265.670495 -268.07581) (xy 265.783216 -268.235047)
			(xy 265.889305 -268.398778) (xy 265.988583 -268.566725) (xy 266.080881 -268.738608) (xy 266.166046 -268.914134)
			(xy 266.243932 -269.093009) (xy 266.314409 -269.274931) (xy 266.377357 -269.459593) (xy 266.432672 -269.646683)
			(xy 266.480258 -269.835887) (xy 266.520037 -270.026884) (xy 266.551941 -270.219354) (xy 266.575916 -270.412972)
			(xy 266.591922 -270.60741) (xy 266.599931 -270.802342) (xy 266.600432 -270.89989) (xy 266.599931 -270.997438)
			(xy 266.591922 -271.19237) (xy 266.575916 -271.386808) (xy 266.551941 -271.580426) (xy 266.520037 -271.772896)
			(xy 266.480258 -271.963893) (xy 266.432672 -272.153097) (xy 266.377357 -272.340187) (xy 266.314409 -272.524849)
			(xy 266.243932 -272.706771) (xy 266.166046 -272.885646) (xy 266.080881 -273.061172) (xy 265.988583 -273.233055)
			(xy 265.889305 -273.401002) (xy 265.783216 -273.564733) (xy 265.670495 -273.72397) (xy 265.551331 -273.878444)
			(xy 265.425926 -274.027897) (xy 265.29449 -274.172075) (xy 265.157246 -274.310735) (xy 265.014425 -274.443643)
			(xy 264.866268 -274.570577) (xy 264.713025 -274.69132) (xy 264.554954 -274.80567) (xy 264.392321 -274.913435)
			(xy 264.225402 -275.014431) (xy 264.054476 -275.10849) (xy 263.879833 -275.195452) (xy 263.701767 -275.27517)
			(xy 263.520579 -275.347511) (xy 263.336573 -275.412352) (xy 263.15006 -275.469584) (xy 262.961355 -275.519111)
			(xy 262.770776 -275.560848) (xy 262.578643 -275.594726) (xy 262.385282 -275.620688) (xy 262.191018 -275.638689)
			(xy 261.996179 -275.6487) (xy 261.801093 -275.650703) (xy 261.60609 -275.644695) (xy 261.411497 -275.630686)
			(xy 261.217644 -275.6087) (xy 261.024857 -275.578774) (xy 260.83346 -275.540958) (xy 260.643778 -275.495316)
			(xy 260.45613 -275.441926) (xy 260.270831 -275.380876) (xy 260.088196 -275.312271) (xy 259.908531 -275.236225)
			(xy 259.732139 -275.152867) (xy 259.559318 -275.062338) (xy 259.39036 -274.96479) (xy 259.225549 -274.860387)
			(xy 259.065163 -274.749307) (xy 258.909473 -274.631735) (xy 258.758741 -274.507871) (xy 258.613222 -274.377922)
			(xy 258.47316 -274.242109) (xy 258.338792 -274.10066) (xy 258.210345 -273.953814) (xy 258.088034 -273.801819)
			(xy 257.972067 -273.64493) (xy 257.862639 -273.483412) (xy 257.759934 -273.317538) (xy 257.664126 -273.147587)
			(xy 257.575375 -272.973846) (xy 257.493833 -272.796608) (xy 257.419636 -272.616172) (xy 257.352909 -272.432841)
			(xy 257.293765 -272.246926) (xy 257.242304 -272.058739) (xy 257.198612 -271.868599) (xy 257.162763 -271.676824)
			(xy 257.134818 -271.48374) (xy 257.114823 -271.289671) (xy 257.102813 -271.094945) (xy 257.098807 -270.89989)
			(xy 210.500214 -270.89989) (xy 210.499713 -270.997438) (xy 210.491704 -271.19237) (xy 210.475698 -271.386808)
			(xy 210.451723 -271.580426) (xy 210.419819 -271.772896) (xy 210.38004 -271.963893) (xy 210.332454 -272.153097)
			(xy 210.277139 -272.340187) (xy 210.214191 -272.524849) (xy 210.143714 -272.706771) (xy 210.065828 -272.885646)
			(xy 209.980663 -273.061172) (xy 209.888365 -273.233055) (xy 209.789087 -273.401002) (xy 209.682998 -273.564733)
			(xy 209.570277 -273.72397) (xy 209.451113 -273.878444) (xy 209.325708 -274.027897) (xy 209.194272 -274.172075)
			(xy 209.057028 -274.310735) (xy 208.914207 -274.443643) (xy 208.76605 -274.570577) (xy 208.612807 -274.69132)
			(xy 208.454736 -274.80567) (xy 208.292103 -274.913435) (xy 208.125184 -275.014431) (xy 207.954258 -275.10849)
			(xy 207.779615 -275.195452) (xy 207.601549 -275.27517) (xy 207.420361 -275.347511) (xy 207.236355 -275.412352)
			(xy 207.049842 -275.469584) (xy 206.861137 -275.519111) (xy 206.670558 -275.560848) (xy 206.478425 -275.594726)
			(xy 206.285064 -275.620688) (xy 206.0908 -275.638689) (xy 205.895961 -275.6487) (xy 205.700875 -275.650703)
			(xy 205.505872 -275.644695) (xy 205.311279 -275.630686) (xy 205.117426 -275.6087) (xy 204.924639 -275.578774)
			(xy 204.733242 -275.540958) (xy 204.54356 -275.495316) (xy 204.355912 -275.441926) (xy 204.170613 -275.380876)
			(xy 203.987978 -275.312271) (xy 203.808313 -275.236225) (xy 203.631921 -275.152867) (xy 203.4591 -275.062338)
			(xy 203.290142 -274.96479) (xy 203.125331 -274.860387) (xy 202.964945 -274.749307) (xy 202.809255 -274.631735)
			(xy 202.658523 -274.507871) (xy 202.513004 -274.377922) (xy 202.372942 -274.242109) (xy 202.238574 -274.10066)
			(xy 202.110127 -273.953814) (xy 201.987816 -273.801819) (xy 201.871849 -273.64493) (xy 201.762421 -273.483412)
			(xy 201.659716 -273.317538) (xy 201.563908 -273.147587) (xy 201.475157 -272.973846) (xy 201.393615 -272.796608)
			(xy 201.319418 -272.616172) (xy 201.252691 -272.432841) (xy 201.193547 -272.246926) (xy 201.142086 -272.058739)
			(xy 201.098394 -271.868599) (xy 201.062545 -271.676824) (xy 201.0346 -271.48374) (xy 201.014605 -271.289671)
			(xy 201.002595 -271.094945) (xy 200.998589 -270.89989) (xy 150.50008 -270.89989) (xy 150.499478 -271.009719)
			(xy 150.489377 -271.229145) (xy 150.46915 -271.447869) (xy 150.454614 -271.556734) (xy 150.45309 -271.567402)
			(xy 150.45944 -271.588738) (xy 150.516844 -271.654778) (xy 150.524397 -271.662692) (xy 150.544271 -271.67178)
			(xy 150.555198 -271.672304) (xy 198.205344 -271.672304) (xy 198.223806 -271.672584) (xy 198.260477 -271.676909)
			(xy 198.278496 -271.68094) (xy 198.284338 -271.68221) (xy 198.340472 -271.68221) (xy 198.36542 -271.682725)
			(xy 198.414703 -271.690532) (xy 198.46216 -271.705944) (xy 198.506627 -271.728582) (xy 198.54701 -271.75789)
			(xy 198.565008 -271.775174) (xy 199.249538 -272.459704) (xy 199.266843 -272.477687) (xy 199.296173 -272.518064)
			(xy 199.318824 -272.562532) (xy 199.33424 -272.609996) (xy 199.342041 -272.659287) (xy 199.342502 -272.68424)
			(xy 199.342502 -289.632136) (xy 199.34428 -289.638486) (xy 199.349644 -289.659671) (xy 199.355377 -289.702995)
			(xy 199.35571 -289.724846) (xy 199.35537 -289.746696) (xy 199.349631 -289.790018) (xy 199.34428 -289.811206)
			(xy 199.342502 -289.817556) (xy 199.342502 -290.582096) (xy 199.34428 -290.588446) (xy 199.349636 -290.609633)
			(xy 199.355374 -290.652955) (xy 199.35571 -290.674806) (xy 199.355362 -290.696656) (xy 199.349628 -290.739978)
			(xy 199.34428 -290.761166) (xy 199.342502 -290.767516) (xy 199.342502 -291.532056) (xy 199.34428 -291.538406)
			(xy 199.349648 -291.55959) (xy 199.355378 -291.602915) (xy 199.35571 -291.624766) (xy 199.355354 -291.646616)
			(xy 199.349626 -291.689938) (xy 199.34428 -291.711126) (xy 199.342502 -291.717476) (xy 199.342502 -292.48227)
			(xy 199.34428 -292.48862) (xy 199.34965 -292.509804) (xy 199.355379 -292.553129) (xy 199.35571 -292.57498)
			(xy 199.355357 -292.59683) (xy 199.349627 -292.640152) (xy 199.34428 -292.66134) (xy 199.342502 -292.66769)
			(xy 199.342502 -293.43223) (xy 199.34428 -293.43858) (xy 199.349643 -293.459765) (xy 199.355376 -293.503089)
			(xy 199.35571 -293.52494) (xy 199.355369 -293.54679) (xy 199.349631 -293.590112) (xy 199.34428 -293.6113)
			(xy 199.342502 -293.61765) (xy 199.342502 -294.38219) (xy 199.34428 -294.38854) (xy 199.349635 -294.409727)
			(xy 199.355374 -294.453049) (xy 199.35571 -294.4749) (xy 199.355361 -294.49675) (xy 199.349628 -294.540072)
			(xy 199.34428 -294.56126) (xy 199.342502 -294.56761) (xy 199.342502 -296.28211) (xy 199.34428 -296.28846)
			(xy 199.349639 -296.309646) (xy 199.355375 -296.352969) (xy 199.35571 -296.37482) (xy 199.355365 -296.39667)
			(xy 199.349629 -296.439992) (xy 199.34428 -296.46118) (xy 199.342502 -296.46753) (xy 199.342502 -297.23207)
			(xy 199.34428 -297.23842) (xy 199.34965 -297.259604) (xy 199.355379 -297.302929) (xy 199.35571 -297.32478)
			(xy 199.355357 -297.34663) (xy 199.352267 -297.369992) (xy 248.970807 -297.369992) (xy 248.974815 -297.205466)
			(xy 248.986828 -297.041331) (xy 249.006818 -296.877975) (xy 249.034738 -296.715786) (xy 249.070521 -296.555149)
			(xy 249.114083 -296.396445) (xy 249.165321 -296.24005) (xy 249.224112 -296.086335) (xy 249.290317 -295.935664)
			(xy 249.36378 -295.788396) (xy 249.444325 -295.644879) (xy 249.531763 -295.505453) (xy 249.625885 -295.370451)
			(xy 249.726469 -295.240191) (xy 249.833275 -295.114982) (xy 249.946051 -294.995122) (xy 250.064529 -294.880896)
			(xy 250.188427 -294.772573) (xy 250.317453 -294.67041) (xy 250.451299 -294.574651) (xy 250.58965 -294.485523)
			(xy 250.732175 -294.403235) (xy 250.878538 -294.327985) (xy 251.028391 -294.25995) (xy 251.181379 -294.199291)
			(xy 251.337139 -294.146154) (xy 251.495301 -294.100662) (xy 251.655491 -294.062926) (xy 251.817328 -294.033033)
			(xy 251.980428 -294.011055) (xy 252.144405 -293.997044) (xy 252.308869 -293.991034) (xy 252.473432 -293.993037)
			(xy 252.637701 -294.003051) (xy 252.801288 -294.021051) (xy 252.963805 -294.046994) (xy 253.124866 -294.080819)
			(xy 253.284089 -294.122445) (xy 253.441096 -294.171774) (xy 253.595516 -294.228689) (xy 253.746981 -294.293055)
			(xy 253.895133 -294.364719) (xy 254.039621 -294.443511) (xy 254.1801 -294.529245) (xy 254.316239 -294.621716)
			(xy 254.447714 -294.720706) (xy 254.574214 -294.82598) (xy 254.695438 -294.937288) (xy 254.811099 -295.054366)
			(xy 254.920922 -295.176936) (xy 255.024648 -295.304708) (xy 255.12203 -295.437379) (xy 255.212837 -295.574634)
			(xy 255.296853 -295.716147) (xy 255.37388 -295.861583) (xy 255.443735 -296.010596) (xy 255.506252 -296.162834)
			(xy 255.561282 -296.317935) (xy 255.608696 -296.475532) (xy 255.64838 -296.63525) (xy 255.680242 -296.796711)
			(xy 255.704204 -296.959531) (xy 255.72021 -297.123326) (xy 255.728223 -297.287705) (xy 255.728724 -297.369992)
			(xy 255.728223 -297.452279) (xy 255.72021 -297.616658) (xy 255.704204 -297.780453) (xy 255.680242 -297.943273)
			(xy 255.64838 -298.104734) (xy 255.608696 -298.264452) (xy 255.561282 -298.422049) (xy 255.506252 -298.57715)
			(xy 255.443735 -298.729388) (xy 255.37388 -298.878401) (xy 255.296853 -299.023837) (xy 255.212837 -299.16535)
			(xy 255.173403 -299.224954) (xy 268.243812 -299.224954) (xy 268.244151 -299.203041) (xy 268.249883 -299.159591)
			(xy 268.255242 -299.13834) (xy 268.25702 -299.131736) (xy 268.25702 -297.417998) (xy 268.255242 -297.411394)
			(xy 268.249862 -297.390147) (xy 268.244131 -297.346695) (xy 268.243812 -297.32478) (xy 268.244156 -297.302867)
			(xy 268.249884 -297.259417) (xy 268.255242 -297.238166) (xy 268.25702 -297.231562) (xy 268.25702 -294.566848)
			(xy 268.255242 -294.560244) (xy 268.250025 -294.539294) (xy 268.244417 -294.496487) (xy 268.244066 -294.4749)
			(xy 268.244388 -294.453311) (xy 268.249993 -294.410499) (xy 268.255242 -294.389556) (xy 268.25702 -294.382952)
			(xy 268.25702 -292.666928) (xy 268.255242 -292.660324) (xy 268.250021 -292.639375) (xy 268.244416 -292.596567)
			(xy 268.244066 -292.57498) (xy 268.244384 -292.553391) (xy 268.249992 -292.510579) (xy 268.255242 -292.489636)
			(xy 268.25702 -292.483032) (xy 268.25702 -291.716714) (xy 268.255242 -291.71011) (xy 268.250018 -291.689162)
			(xy 268.244415 -291.646353) (xy 268.244066 -291.624766) (xy 268.244382 -291.603177) (xy 268.249991 -291.560365)
			(xy 268.255242 -291.539422) (xy 268.25702 -291.532818) (xy 268.25702 -290.766754) (xy 268.255242 -290.76015)
			(xy 268.250026 -290.7392) (xy 268.244418 -290.696393) (xy 268.244066 -290.674806) (xy 268.244389 -290.653217)
			(xy 268.249994 -290.610406) (xy 268.255242 -290.589462) (xy 268.25702 -290.582858) (xy 268.25702 -289.816794)
			(xy 268.255242 -289.81019) (xy 268.250014 -289.789243) (xy 268.244414 -289.746433) (xy 268.244066 -289.724846)
			(xy 268.244378 -289.703257) (xy 268.24999 -289.660445) (xy 268.255242 -289.639502) (xy 268.25702 -289.632898)
			(xy 268.25702 -288.866834) (xy 268.255242 -288.86023) (xy 268.250022 -288.839281) (xy 268.244417 -288.796473)
			(xy 268.244066 -288.774886) (xy 268.244386 -288.753297) (xy 268.249992 -288.710485) (xy 268.255242 -288.689542)
			(xy 268.25702 -288.682938) (xy 268.25702 -287.916874) (xy 268.255242 -287.91027) (xy 268.250029 -287.889319)
			(xy 268.244419 -287.846512) (xy 268.244066 -287.824926) (xy 268.244393 -287.803337) (xy 268.249995 -287.760526)
			(xy 268.255242 -287.739582) (xy 268.25702 -287.732978) (xy 268.25702 -286.966914) (xy 268.255242 -286.96031)
			(xy 268.250018 -286.939362) (xy 268.244415 -286.896553) (xy 268.244066 -286.874966) (xy 268.244382 -286.853377)
			(xy 268.249991 -286.810565) (xy 268.255242 -286.789622) (xy 268.25702 -286.783018) (xy 268.25702 -286.0167)
			(xy 268.255242 -286.010096) (xy 268.250015 -285.989148) (xy 268.244414 -285.946339) (xy 268.244066 -285.924752)
			(xy 268.244379 -285.903163) (xy 268.24999 -285.860351) (xy 268.255242 -285.839408) (xy 268.25702 -285.832804)
			(xy 268.25702 -285.06674) (xy 268.255242 -285.060136) (xy 268.250023 -285.039187) (xy 268.244417 -284.996379)
			(xy 268.244066 -284.974792) (xy 268.244387 -284.953203) (xy 268.249993 -284.910391) (xy 268.255242 -284.889448)
			(xy 268.25702 -284.882844) (xy 268.25702 -284.11678) (xy 268.255242 -284.110176) (xy 268.250031 -284.089225)
			(xy 268.24442 -284.046418) (xy 268.244066 -284.024832) (xy 268.244394 -284.003243) (xy 268.249995 -283.960432)
			(xy 268.255242 -283.939488) (xy 268.25702 -283.932884) (xy 268.25702 -283.16682) (xy 268.255242 -283.160216)
			(xy 268.250019 -283.139268) (xy 268.244416 -283.096459) (xy 268.244066 -283.074872) (xy 268.244383 -283.053283)
			(xy 268.249991 -283.010471) (xy 268.255242 -282.989528) (xy 268.25702 -282.982924) (xy 268.25702 -282.21686)
			(xy 268.255242 -282.210256) (xy 268.250027 -282.189306) (xy 268.244418 -282.146499) (xy 268.244066 -282.124912)
			(xy 268.244391 -282.103323) (xy 268.249994 -282.060512) (xy 268.255242 -282.039568) (xy 268.25702 -282.032964)
			(xy 268.25702 -281.2669) (xy 268.255242 -281.260296) (xy 268.250015 -281.239348) (xy 268.244414 -281.196539)
			(xy 268.244066 -281.174952) (xy 268.244379 -281.153363) (xy 268.24999 -281.110551) (xy 268.255242 -281.089608)
			(xy 268.25702 -281.083004) (xy 268.25702 -280.316686) (xy 268.255242 -280.310082) (xy 268.250032 -280.289131)
			(xy 268.24442 -280.246324) (xy 268.244066 -280.224738) (xy 268.244396 -280.203149) (xy 268.249996 -280.160338)
			(xy 268.255242 -280.139394) (xy 268.25702 -280.13279) (xy 268.25702 -279.366726) (xy 268.255242 -279.360122)
			(xy 268.25002 -279.339173) (xy 268.244416 -279.296365) (xy 268.244066 -279.274778) (xy 268.244384 -279.253189)
			(xy 268.249992 -279.210377) (xy 268.255242 -279.189434) (xy 268.25702 -279.18283) (xy 268.25702 -278.416766)
			(xy 268.255242 -278.410162) (xy 268.250028 -278.389212) (xy 268.244419 -278.346404) (xy 268.244066 -278.324818)
			(xy 268.244392 -278.303229) (xy 268.249994 -278.260418) (xy 268.255242 -278.239474) (xy 268.25702 -278.23287)
			(xy 268.25702 -277.466806) (xy 268.255242 -277.460202) (xy 268.250017 -277.439254) (xy 268.244415 -277.396445)
			(xy 268.244066 -277.374858) (xy 268.24438 -277.353269) (xy 268.249991 -277.310457) (xy 268.255242 -277.289514)
			(xy 268.25702 -277.28291) (xy 268.25702 -276.516846) (xy 268.255242 -276.510242) (xy 268.250024 -276.489292)
			(xy 268.244417 -276.446485) (xy 268.244066 -276.424898) (xy 268.244388 -276.403309) (xy 268.249993 -276.360497)
			(xy 268.255242 -276.339554) (xy 268.25702 -276.33295) (xy 268.25702 -275.566886) (xy 268.255242 -275.560282)
			(xy 268.250032 -275.539331) (xy 268.24442 -275.496524) (xy 268.244066 -275.474938) (xy 268.244396 -275.453349)
			(xy 268.249996 -275.410538) (xy 268.255242 -275.389594) (xy 268.25702 -275.38299) (xy 268.25702 -272.53819)
			(xy 268.257537 -272.513242) (xy 268.265348 -272.463961) (xy 268.280761 -272.416504) (xy 268.303398 -272.372038)
			(xy 268.332702 -272.331654) (xy 268.349984 -272.313654) (xy 268.89837 -271.765268) (xy 268.916369 -271.74798)
			(xy 268.956741 -271.718648) (xy 269.001205 -271.695993) (xy 269.048666 -271.680573) (xy 269.097955 -271.672767)
			(xy 269.122906 -271.672304) (xy 272.559526 -271.672304) (xy 272.569633 -271.671831) (xy 272.588301 -271.664082)
			(xy 272.602551 -271.649747) (xy 272.60677 -271.640554) (xy 272.60677 -271.6403) (xy 272.617778 -271.614094)
			(xy 272.646425 -271.565002) (xy 272.682038 -271.520704) (xy 272.723831 -271.482182) (xy 272.770877 -271.450287)
			(xy 272.822136 -271.425727) (xy 272.876471 -271.409045) (xy 272.932681 -271.400611) (xy 272.989519 -271.400611)
			(xy 273.045729 -271.409045) (xy 273.100064 -271.425727) (xy 273.151323 -271.450287) (xy 273.198369 -271.482182)
			(xy 273.240162 -271.520704) (xy 273.275775 -271.565002) (xy 273.304422 -271.614094) (xy 273.31543 -271.6403)
			(xy 273.31543 -271.640554) (xy 273.319588 -271.649796) (xy 273.333828 -271.664196) (xy 273.352545 -271.671929)
			(xy 273.362674 -271.672304) (xy 317.044324 -271.672304) (xy 317.055252 -271.671795) (xy 317.075127 -271.662696)
			(xy 317.082678 -271.654778) (xy 317.140082 -271.588738) (xy 317.146432 -271.567402) (xy 317.144908 -271.556734)
			(xy 317.130333 -271.447872) (xy 317.110021 -271.229149) (xy 317.099834 -271.009722) (xy 317.099188 -270.89989)
			(xy 317.099682 -270.802975) (xy 317.107588 -270.609307) (xy 317.123387 -270.416123) (xy 317.147052 -270.223744)
			(xy 317.178545 -270.03249) (xy 317.217812 -269.84268) (xy 317.264789 -269.65463) (xy 317.319397 -269.468652)
			(xy 317.381546 -269.285057) (xy 317.451131 -269.104149) (xy 317.528037 -268.92623) (xy 317.612136 -268.751596)
			(xy 317.703289 -268.580537) (xy 317.801343 -268.413339) (xy 317.906135 -268.25028) (xy 318.01749 -268.09163)
			(xy 318.135224 -267.937655) (xy 318.259141 -267.78861) (xy 318.389034 -267.644743) (xy 318.524687 -267.506294)
			(xy 318.665874 -267.373494) (xy 318.81236 -267.246563) (xy 318.963902 -267.125712) (xy 319.120247 -267.011143)
			(xy 319.281135 -266.903047) (xy 319.446298 -266.801603) (xy 319.615462 -266.70698) (xy 319.788344 -266.619336)
			(xy 319.964657 -266.538816) (xy 320.144108 -266.465555) (xy 320.326398 -266.399675) (xy 320.511223 -266.341285)
			(xy 320.698276 -266.290482) (xy 320.887245 -266.247351) (xy 321.077817 -266.211963) (xy 321.269673 -266.184379)
			(xy 321.462495 -266.164642) (xy 321.655961 -266.152787) (xy 321.84975 -266.148834) (xy 322.043539 -266.152787)
			(xy 322.237005 -266.164642) (xy 322.429827 -266.184379) (xy 322.621683 -266.211963) (xy 322.812255 -266.247351)
			(xy 323.001224 -266.290482) (xy 323.188277 -266.341285) (xy 323.373102 -266.399675) (xy 323.555392 -266.465555)
			(xy 323.734843 -266.538816) (xy 323.911156 -266.619336) (xy 324.084038 -266.70698) (xy 324.253202 -266.801603)
			(xy 324.418365 -266.903047) (xy 324.579253 -267.011143) (xy 324.735598 -267.125712) (xy 324.88714 -267.246563)
			(xy 325.033626 -267.373494) (xy 325.174813 -267.506294) (xy 325.310466 -267.644743) (xy 325.440359 -267.78861)
			(xy 325.564276 -267.937655) (xy 325.68201 -268.09163) (xy 325.793365 -268.25028) (xy 325.898157 -268.413339)
			(xy 325.996211 -268.580537) (xy 326.087364 -268.751596) (xy 326.171463 -268.92623) (xy 326.248369 -269.104149)
			(xy 326.317954 -269.285057) (xy 326.380103 -269.468652) (xy 326.434711 -269.65463) (xy 326.481688 -269.84268)
			(xy 326.520955 -270.03249) (xy 326.552448 -270.223744) (xy 326.576113 -270.416123) (xy 326.591912 -270.609307)
			(xy 326.599818 -270.802975) (xy 326.600312 -270.89989) (xy 326.599669 -271.009722) (xy 326.589491 -271.22915)
			(xy 326.569175 -271.447873) (xy 326.554592 -271.556734) (xy 326.553068 -271.567402) (xy 326.559418 -271.588738)
			(xy 326.616822 -271.654778) (xy 326.624343 -271.662728) (xy 326.644242 -271.671795) (xy 326.655176 -271.672304)
			(xy 362.833158 -271.672304) (xy 362.843228 -271.671882) (xy 362.861827 -271.664162) (xy 362.869226 -271.657318)
			(xy 364.530386 -269.996158) (xy 364.548376 -269.978861) (xy 364.588751 -269.949531) (xy 364.633217 -269.926878)
			(xy 364.68068 -269.911459) (xy 364.72997 -269.903656) (xy 364.754922 -269.903194) (xy 373.096536 -269.903194)
			(xy 373.120136 -269.903641) (xy 373.166812 -269.910653) (xy 373.1895 -269.917164) (xy 373.19966 -269.920466)
			(xy 373.220488 -269.917926) (xy 373.303546 -269.870174) (xy 373.315992 -269.853156) (xy 373.318278 -269.842742)
			(xy 373.340297 -269.748361) (xy 373.391103 -269.56131) (xy 373.449495 -269.376487) (xy 373.515377 -269.194199)
			(xy 373.58864 -269.01475) (xy 373.669161 -268.838439) (xy 373.756807 -268.665559) (xy 373.851431 -268.496397)
			(xy 373.952876 -268.331236) (xy 374.060974 -268.17035) (xy 374.175544 -268.014007) (xy 374.296395 -267.862468)
			(xy 374.423327 -267.715983) (xy 374.556128 -267.574798) (xy 374.694577 -267.439148) (xy 374.838444 -267.309257)
			(xy 374.987489 -267.185342) (xy 375.141465 -267.06761) (xy 375.300114 -266.956256) (xy 375.463173 -266.851466)
			(xy 375.630371 -266.753414) (xy 375.801429 -266.662263) (xy 375.976063 -266.578165) (xy 376.153981 -266.501261)
			(xy 376.334889 -266.431677) (xy 376.518484 -266.36953) (xy 376.704461 -266.314923) (xy 376.89251 -266.267948)
			(xy 377.082319 -266.228681) (xy 377.273572 -266.19719) (xy 377.46595 -266.173525) (xy 377.659133 -266.157727)
			(xy 377.8528 -266.149822) (xy 377.949714 -266.149328) (xy 378.047904 -266.149832) (xy 378.244116 -266.157947)
			(xy 378.439825 -266.174165) (xy 378.634696 -266.198456) (xy 378.828398 -266.23078) (xy 379.020598 -266.27108)
			(xy 379.210968 -266.319289) (xy 379.399184 -266.375324) (xy 379.584923 -266.439088) (xy 379.767868 -266.510474)
			(xy 379.947708 -266.589359) (xy 380.124133 -266.675609) (xy 380.296844 -266.769076) (xy 380.465544 -266.8696)
			(xy 380.629947 -266.977009) (xy 380.78977 -267.091121) (xy 380.944741 -267.21174) (xy 381.094595 -267.33866)
			(xy 381.239077 -267.471665) (xy 381.377938 -267.610526) (xy 381.510942 -267.755008) (xy 381.637862 -267.904862)
			(xy 381.758481 -268.059833) (xy 381.872593 -268.219656) (xy 381.980002 -268.384059) (xy 382.080526 -268.55276)
			(xy 382.173993 -268.72547) (xy 382.260242 -268.901896) (xy 382.339127 -269.081735) (xy 382.410513 -269.264681)
			(xy 382.474278 -269.45042) (xy 382.530312 -269.638636) (xy 382.578521 -269.829006) (xy 382.618821 -270.021206)
			(xy 382.651144 -270.214908) (xy 382.675436 -270.409779) (xy 382.691653 -270.605488) (xy 382.699769 -270.8017)
			(xy 382.700276 -270.89989) (xy 433.198785 -270.89989) (xy 433.202791 -270.704835) (xy 433.214801 -270.510109)
			(xy 433.234796 -270.31604) (xy 433.262741 -270.122956) (xy 433.29859 -269.931181) (xy 433.342282 -269.741041)
			(xy 433.393743 -269.552854) (xy 433.452887 -269.366939) (xy 433.519614 -269.183608) (xy 433.593811 -269.003172)
			(xy 433.675353 -268.825934) (xy 433.764104 -268.652193) (xy 433.859912 -268.482242) (xy 433.962617 -268.316368)
			(xy 434.072045 -268.15485) (xy 434.188012 -267.997961) (xy 434.310323 -267.845966) (xy 434.43877 -267.69912)
			(xy 434.573138 -267.557671) (xy 434.7132 -267.421858) (xy 434.858719 -267.291909) (xy 435.009451 -267.168045)
			(xy 435.165141 -267.050473) (xy 435.325527 -266.939393) (xy 435.490338 -266.83499) (xy 435.659296 -266.737442)
			(xy 435.832117 -266.646913) (xy 436.008509 -266.563555) (xy 436.188174 -266.487509) (xy 436.370809 -266.418904)
			(xy 436.556108 -266.357854) (xy 436.743756 -266.304464) (xy 436.933438 -266.258822) (xy 437.124835 -266.221006)
			(xy 437.317622 -266.19108) (xy 437.511475 -266.169094) (xy 437.706068 -266.155085) (xy 437.901071 -266.149077)
			(xy 438.096157 -266.15108) (xy 438.290996 -266.161091) (xy 438.48526 -266.179092) (xy 438.678621 -266.205054)
			(xy 438.870754 -266.238932) (xy 439.061333 -266.280669) (xy 439.250038 -266.330196) (xy 439.436551 -266.387428)
			(xy 439.620557 -266.452269) (xy 439.801745 -266.52461) (xy 439.979811 -266.604328) (xy 440.154454 -266.69129)
			(xy 440.32538 -266.785349) (xy 440.492299 -266.886345) (xy 440.654932 -266.99411) (xy 440.813003 -267.10846)
			(xy 440.966246 -267.229203) (xy 441.114403 -267.356137) (xy 441.257224 -267.489045) (xy 441.394468 -267.627705)
			(xy 441.525904 -267.771883) (xy 441.651309 -267.921336) (xy 441.770473 -268.07581) (xy 441.883194 -268.235047)
			(xy 441.989283 -268.398778) (xy 442.088561 -268.566725) (xy 442.180859 -268.738608) (xy 442.266024 -268.914134)
			(xy 442.34391 -269.093009) (xy 442.414387 -269.274931) (xy 442.477335 -269.459593) (xy 442.53265 -269.646683)
			(xy 442.580236 -269.835887) (xy 442.620015 -270.026884) (xy 442.651919 -270.219354) (xy 442.675894 -270.412972)
			(xy 442.6919 -270.60741) (xy 442.699909 -270.802342) (xy 442.70041 -270.89989) (xy 442.699909 -270.997438)
			(xy 442.6919 -271.19237) (xy 442.675894 -271.386808) (xy 442.651919 -271.580426) (xy 442.620015 -271.772896)
			(xy 442.580236 -271.963893) (xy 442.53265 -272.153097) (xy 442.477335 -272.340187) (xy 442.414387 -272.524849)
			(xy 442.34391 -272.706771) (xy 442.266024 -272.885646) (xy 442.180859 -273.061172) (xy 442.088561 -273.233055)
			(xy 441.989283 -273.401002) (xy 441.883194 -273.564733) (xy 441.770473 -273.72397) (xy 441.651309 -273.878444)
			(xy 441.525904 -274.027897) (xy 441.394468 -274.172075) (xy 441.257224 -274.310735) (xy 441.114403 -274.443643)
			(xy 440.966246 -274.570577) (xy 440.813003 -274.69132) (xy 440.654932 -274.80567) (xy 440.492299 -274.913435)
			(xy 440.32538 -275.014431) (xy 440.154454 -275.10849) (xy 439.979811 -275.195452) (xy 439.801745 -275.27517)
			(xy 439.620557 -275.347511) (xy 439.436551 -275.412352) (xy 439.250038 -275.469584) (xy 439.061333 -275.519111)
			(xy 438.870754 -275.560848) (xy 438.678621 -275.594726) (xy 438.48526 -275.620688) (xy 438.290996 -275.638689)
			(xy 438.096157 -275.6487) (xy 437.901071 -275.650703) (xy 437.706068 -275.644695) (xy 437.511475 -275.630686)
			(xy 437.317622 -275.6087) (xy 437.124835 -275.578774) (xy 436.933438 -275.540958) (xy 436.743756 -275.495316)
			(xy 436.556108 -275.441926) (xy 436.370809 -275.380876) (xy 436.188174 -275.312271) (xy 436.008509 -275.236225)
			(xy 435.832117 -275.152867) (xy 435.659296 -275.062338) (xy 435.490338 -274.96479) (xy 435.325527 -274.860387)
			(xy 435.165141 -274.749307) (xy 435.009451 -274.631735) (xy 434.858719 -274.507871) (xy 434.7132 -274.377922)
			(xy 434.573138 -274.242109) (xy 434.43877 -274.10066) (xy 434.310323 -273.953814) (xy 434.188012 -273.801819)
			(xy 434.072045 -273.64493) (xy 433.962617 -273.483412) (xy 433.859912 -273.317538) (xy 433.764104 -273.147587)
			(xy 433.675353 -272.973846) (xy 433.593811 -272.796608) (xy 433.519614 -272.616172) (xy 433.452887 -272.432841)
			(xy 433.393743 -272.246926) (xy 433.342282 -272.058739) (xy 433.29859 -271.868599) (xy 433.262741 -271.676824)
			(xy 433.234796 -271.48374) (xy 433.214801 -271.289671) (xy 433.202791 -271.094945) (xy 433.198785 -270.89989)
			(xy 382.700276 -270.89989) (xy 382.699633 -271.009722) (xy 382.689455 -271.22915) (xy 382.66914 -271.447873)
			(xy 382.654556 -271.556734) (xy 382.653032 -271.567402) (xy 382.659382 -271.588738) (xy 382.716786 -271.654778)
			(xy 382.724322 -271.662711) (xy 382.744209 -271.671788) (xy 382.75514 -271.672304) (xy 430.40554 -271.672304)
			(xy 430.424002 -271.672585) (xy 430.460673 -271.676909) (xy 430.478692 -271.68094) (xy 430.484534 -271.68221)
			(xy 430.540414 -271.68221) (xy 430.565364 -271.682698) (xy 430.614647 -271.690512) (xy 430.662105 -271.705931)
			(xy 430.706571 -271.728574) (xy 430.746953 -271.757888) (xy 430.76495 -271.775174) (xy 431.44948 -272.459704)
			(xy 431.466773 -272.477697) (xy 431.496097 -272.518073) (xy 431.518745 -272.562539) (xy 431.534158 -272.610001)
			(xy 431.541958 -272.659289) (xy 431.542444 -272.68424) (xy 431.542444 -288.682176) (xy 431.544222 -288.688526)
			(xy 431.549575 -288.709714) (xy 431.555315 -288.753035) (xy 431.555652 -288.774886) (xy 431.555302 -288.796736)
			(xy 431.54957 -288.840058) (xy 431.544222 -288.861246) (xy 431.542444 -288.867596) (xy 431.542444 -289.632136)
			(xy 431.544222 -289.638486) (xy 431.549587 -289.659671) (xy 431.555319 -289.702995) (xy 431.555652 -289.724846)
			(xy 431.555314 -289.746696) (xy 431.549574 -289.790018) (xy 431.544222 -289.811206) (xy 431.542444 -289.817556)
			(xy 431.542444 -290.582096) (xy 431.544222 -290.588446) (xy 431.549579 -290.609633) (xy 431.555316 -290.652955)
			(xy 431.555652 -290.674806) (xy 431.555306 -290.696656) (xy 431.549571 -290.739978) (xy 431.544222 -290.761166)
			(xy 431.542444 -290.767516) (xy 431.542444 -291.532056) (xy 431.544222 -291.538406) (xy 431.54959 -291.55959)
			(xy 431.55532 -291.602915) (xy 431.555652 -291.624766) (xy 431.555298 -291.646616) (xy 431.549569 -291.689938)
			(xy 431.544222 -291.711126) (xy 431.542444 -291.717476) (xy 431.542444 -292.48227) (xy 431.544222 -292.48862)
			(xy 431.549593 -292.509803) (xy 431.555321 -292.553129) (xy 431.555652 -292.57498) (xy 431.555301 -292.59683)
			(xy 431.54957 -292.640152) (xy 431.544222 -292.66134) (xy 431.542444 -292.66769) (xy 431.542444 -293.43223)
			(xy 431.544222 -293.43858) (xy 431.549585 -293.459765) (xy 431.555318 -293.503089) (xy 431.555652 -293.52494)
			(xy 431.555313 -293.54679) (xy 431.549573 -293.590112) (xy 431.544222 -293.6113) (xy 431.542444 -293.61765)
			(xy 431.542444 -294.38219) (xy 431.544222 -294.38854) (xy 431.549578 -294.409727) (xy 431.555316 -294.453049)
			(xy 431.555652 -294.4749) (xy 431.555305 -294.49675) (xy 431.549571 -294.540072) (xy 431.544222 -294.56126)
			(xy 431.542444 -294.56761) (xy 431.542444 -296.28211) (xy 431.544222 -296.28846) (xy 431.549582 -296.309646)
			(xy 431.555317 -296.352969) (xy 431.555652 -296.37482) (xy 431.555309 -296.39667) (xy 431.549572 -296.439992)
			(xy 431.544222 -296.46118) (xy 431.542444 -296.46753) (xy 431.542444 -297.23207) (xy 431.544222 -297.23842)
			(xy 431.549593 -297.259603) (xy 431.555321 -297.302929) (xy 431.555652 -297.32478) (xy 431.555301 -297.34663)
			(xy 431.54957 -297.389952) (xy 431.544222 -297.41114) (xy 431.542444 -297.41749) (xy 431.542444 -298.18203)
			(xy 431.544222 -298.18838) (xy 431.549585 -298.209565) (xy 431.555318 -298.252889) (xy 431.555652 -298.27474)
			(xy 431.555313 -298.29659) (xy 431.549573 -298.339912) (xy 431.544222 -298.3611) (xy 431.542444 -298.36745)
			(xy 431.542444 -299.132244) (xy 431.544222 -299.138594) (xy 431.549588 -299.159779) (xy 431.555319 -299.203103)
			(xy 431.555652 -299.224954) (xy 431.555296 -299.246804) (xy 431.549568 -299.290126) (xy 431.544222 -299.311314)
			(xy 431.542444 -299.317664) (xy 431.542444 -300.082204) (xy 431.544222 -300.088554) (xy 431.54958 -300.10974)
			(xy 431.555317 -300.153063) (xy 431.555652 -300.174914) (xy 431.555308 -300.196764) (xy 431.549572 -300.240086)
			(xy 431.544222 -300.261274) (xy 431.542444 -300.267624) (xy 431.542444 -301.032164) (xy 431.544222 -301.038514)
			(xy 431.549592 -301.059698) (xy 431.555321 -301.103023) (xy 431.555652 -301.124874) (xy 431.5553 -301.146724)
			(xy 431.549569 -301.190046) (xy 431.544222 -301.211234) (xy 431.542444 -301.217584) (xy 431.542444 -301.982124)
			(xy 431.544222 -301.988474) (xy 431.549584 -302.009659) (xy 431.555318 -302.052983) (xy 431.555652 -302.074834)
			(xy 431.555311 -302.096684) (xy 431.549573 -302.140006) (xy 431.544222 -302.161194) (xy 431.542444 -302.167544)
			(xy 431.542444 -308.61) (xy 444.070747 -308.61) (xy 444.074755 -308.445474) (xy 444.086768 -308.281339)
			(xy 444.106758 -308.117983) (xy 444.134678 -307.955794) (xy 444.170461 -307.795157) (xy 444.214023 -307.636453)
			(xy 444.265261 -307.480058) (xy 444.324052 -307.326343) (xy 444.390257 -307.175672) (xy 444.46372 -307.028404)
			(xy 444.544265 -306.884887) (xy 444.631703 -306.745461) (xy 444.725825 -306.610459) (xy 444.826409 -306.480199)
			(xy 444.933215 -306.35499) (xy 445.045991 -306.23513) (xy 445.164469 -306.120904) (xy 445.288367 -306.012581)
			(xy 445.417393 -305.910418) (xy 445.551239 -305.814659) (xy 445.68959 -305.725531) (xy 445.832115 -305.643243)
			(xy 445.978478 -305.567993) (xy 446.128331 -305.499958) (xy 446.281319 -305.439299) (xy 446.437079 -305.386162)
			(xy 446.595241 -305.34067) (xy 446.755431 -305.302934) (xy 446.917268 -305.273041) (xy 447.080368 -305.251063)
			(xy 447.244345 -305.237052) (xy 447.408809 -305.231042) (xy 447.573372 -305.233045) (xy 447.737641 -305.243059)
			(xy 447.901228 -305.261059) (xy 448.063745 -305.287002) (xy 448.224806 -305.320827) (xy 448.384029 -305.362453)
			(xy 448.541036 -305.411782) (xy 448.695456 -305.468697) (xy 448.846921 -305.533063) (xy 448.995073 -305.604727)
			(xy 449.139561 -305.683519) (xy 449.28004 -305.769253) (xy 449.416179 -305.861724) (xy 449.547654 -305.960714)
			(xy 449.674154 -306.065988) (xy 449.795378 -306.177296) (xy 449.911039 -306.294374) (xy 450.020862 -306.416944)
			(xy 450.124588 -306.544716) (xy 450.22197 -306.677387) (xy 450.312777 -306.814642) (xy 450.396793 -306.956155)
			(xy 450.47382 -307.101591) (xy 450.543675 -307.250604) (xy 450.606192 -307.402842) (xy 450.661222 -307.557943)
			(xy 450.676197 -307.607716) (xy 462.556604 -307.607716) (xy 462.560677 -307.552057) (xy 462.572812 -307.497584)
			(xy 462.592748 -307.445458) (xy 462.620062 -307.39679) (xy 462.65417 -307.352618) (xy 462.694347 -307.313883)
			(xy 462.739735 -307.281411) (xy 462.789367 -307.255893) (xy 462.842187 -307.237874) (xy 462.897066 -307.227737)
			(xy 462.952837 -307.225699) (xy 463.008311 -307.231802) (xy 463.062304 -307.245918) (xy 463.113667 -307.267745)
			(xy 463.161305 -307.296818) (xy 463.204201 -307.332517) (xy 463.241443 -307.374081) (xy 463.272237 -307.420625)
			(xy 463.295925 -307.471156) (xy 463.312003 -307.524598) (xy 463.320129 -307.579812) (xy 463.320638 -307.607716)
			(xy 463.320129 -307.63562) (xy 463.312003 -307.690834) (xy 463.295925 -307.744276) (xy 463.272237 -307.794807)
			(xy 463.241443 -307.841351) (xy 463.204201 -307.882915) (xy 463.161305 -307.918614) (xy 463.113667 -307.947687)
			(xy 463.062304 -307.969514) (xy 463.008311 -307.98363) (xy 462.952837 -307.989733) (xy 462.897066 -307.987695)
			(xy 462.842187 -307.977558) (xy 462.789367 -307.959539) (xy 462.739735 -307.934021) (xy 462.694347 -307.901549)
			(xy 462.65417 -307.862814) (xy 462.620062 -307.818642) (xy 462.592748 -307.769974) (xy 462.572812 -307.717848)
			(xy 462.560677 -307.663375) (xy 462.556604 -307.607716) (xy 450.676197 -307.607716) (xy 450.708636 -307.71554)
			(xy 450.74832 -307.875258) (xy 450.780182 -308.036719) (xy 450.804144 -308.199539) (xy 450.82015 -308.363334)
			(xy 450.828163 -308.527713) (xy 450.828664 -308.61) (xy 450.828163 -308.692287) (xy 450.828163 -308.692296)
			(xy 462.556604 -308.692296) (xy 462.560677 -308.636637) (xy 462.572812 -308.582164) (xy 462.592748 -308.530038)
			(xy 462.620062 -308.48137) (xy 462.65417 -308.437198) (xy 462.694347 -308.398463) (xy 462.739735 -308.365991)
			(xy 462.789367 -308.340473) (xy 462.842187 -308.322454) (xy 462.897066 -308.312317) (xy 462.952837 -308.310279)
			(xy 463.008311 -308.316382) (xy 463.062304 -308.330498) (xy 463.113667 -308.352325) (xy 463.161305 -308.381398)
			(xy 463.204201 -308.417097) (xy 463.241443 -308.458661) (xy 463.272237 -308.505205) (xy 463.295925 -308.555736)
			(xy 463.312003 -308.609178) (xy 463.320129 -308.664392) (xy 463.320638 -308.692296) (xy 463.320129 -308.7202)
			(xy 463.312003 -308.775414) (xy 463.295925 -308.828856) (xy 463.272237 -308.879387) (xy 463.241443 -308.925931)
			(xy 463.204201 -308.967495) (xy 463.161305 -309.003194) (xy 463.113667 -309.032267) (xy 463.062304 -309.054094)
			(xy 463.008311 -309.06821) (xy 462.952837 -309.074313) (xy 462.897066 -309.072275) (xy 462.842187 -309.062138)
			(xy 462.789367 -309.044119) (xy 462.739735 -309.018601) (xy 462.694347 -308.986129) (xy 462.65417 -308.947394)
			(xy 462.620062 -308.903222) (xy 462.592748 -308.854554) (xy 462.572812 -308.802428) (xy 462.560677 -308.747955)
			(xy 462.556604 -308.692296) (xy 450.828163 -308.692296) (xy 450.82015 -308.856666) (xy 450.804144 -309.020461)
			(xy 450.780182 -309.183281) (xy 450.74832 -309.344742) (xy 450.708636 -309.50446) (xy 450.661222 -309.662057)
			(xy 450.606192 -309.817158) (xy 450.543675 -309.969396) (xy 450.47382 -310.118409) (xy 450.396793 -310.263845)
			(xy 450.312777 -310.405358) (xy 450.22197 -310.542613) (xy 450.124588 -310.675284) (xy 450.020862 -310.803056)
			(xy 449.911039 -310.925626) (xy 449.795378 -311.042704) (xy 449.674154 -311.154012) (xy 449.547654 -311.259286)
			(xy 449.416179 -311.358276) (xy 449.28004 -311.450747) (xy 449.139561 -311.536481) (xy 448.995073 -311.615273)
			(xy 448.846921 -311.686937) (xy 448.695456 -311.751303) (xy 448.541036 -311.808218) (xy 448.384029 -311.857547)
			(xy 448.224806 -311.899173) (xy 448.063745 -311.932998) (xy 447.901228 -311.958941) (xy 447.737641 -311.976941)
			(xy 447.573372 -311.986955) (xy 447.408809 -311.988958) (xy 447.244345 -311.982948) (xy 447.080368 -311.968937)
			(xy 446.917268 -311.946959) (xy 446.755431 -311.917066) (xy 446.595241 -311.87933) (xy 446.437079 -311.833838)
			(xy 446.281319 -311.780701) (xy 446.128331 -311.720042) (xy 445.978478 -311.652007) (xy 445.832115 -311.576757)
			(xy 445.68959 -311.494469) (xy 445.551239 -311.405341) (xy 445.417393 -311.309582) (xy 445.288367 -311.207419)
			(xy 445.164469 -311.099096) (xy 445.045991 -310.98487) (xy 444.933215 -310.86501) (xy 444.826409 -310.739801)
			(xy 444.725825 -310.609541) (xy 444.631703 -310.474539) (xy 444.544265 -310.335113) (xy 444.46372 -310.191596)
			(xy 444.390257 -310.044328) (xy 444.324052 -309.893657) (xy 444.265261 -309.739942) (xy 444.214023 -309.583547)
			(xy 444.170461 -309.424843) (xy 444.134678 -309.264206) (xy 444.106758 -309.102017) (xy 444.086768 -308.938661)
			(xy 444.074755 -308.774526) (xy 444.070747 -308.61) (xy 431.542444 -308.61) (xy 431.542444 -318.213232)
			(xy 431.542698 -318.224916) (xy 431.542698 -320.900044) (xy 433.198785 -320.900044) (xy 433.202791 -320.704989)
			(xy 433.214801 -320.510263) (xy 433.234796 -320.316194) (xy 433.262741 -320.12311) (xy 433.29859 -319.931335)
			(xy 433.342282 -319.741195) (xy 433.393743 -319.553008) (xy 433.452887 -319.367093) (xy 433.519614 -319.183762)
			(xy 433.593811 -319.003326) (xy 433.675353 -318.826088) (xy 433.764104 -318.652347) (xy 433.859912 -318.482396)
			(xy 433.962617 -318.316522) (xy 434.072045 -318.155004) (xy 434.188012 -317.998115) (xy 434.310323 -317.84612)
			(xy 434.43877 -317.699274) (xy 434.573138 -317.557825) (xy 434.7132 -317.422012) (xy 434.858719 -317.292063)
			(xy 435.009451 -317.168199) (xy 435.165141 -317.050627) (xy 435.325527 -316.939547) (xy 435.490338 -316.835144)
			(xy 435.659296 -316.737596) (xy 435.832117 -316.647067) (xy 436.008509 -316.563709) (xy 436.188174 -316.487663)
			(xy 436.370809 -316.419058) (xy 436.556108 -316.358008) (xy 436.743756 -316.304618) (xy 436.933438 -316.258976)
			(xy 437.124835 -316.22116) (xy 437.317622 -316.191234) (xy 437.511475 -316.169248) (xy 437.706068 -316.155239)
			(xy 437.901071 -316.149231) (xy 438.096157 -316.151234) (xy 438.290996 -316.161245) (xy 438.48526 -316.179246)
			(xy 438.678621 -316.205208) (xy 438.870754 -316.239086) (xy 439.061333 -316.280823) (xy 439.250038 -316.33035)
			(xy 439.436551 -316.387582) (xy 439.620557 -316.452423) (xy 439.801745 -316.524764) (xy 439.979811 -316.604482)
			(xy 440.154454 -316.691444) (xy 440.32538 -316.785503) (xy 440.492299 -316.886499) (xy 440.654932 -316.994264)
			(xy 440.813003 -317.108614) (xy 440.966246 -317.229357) (xy 441.114403 -317.356291) (xy 441.257224 -317.489199)
			(xy 441.394468 -317.627859) (xy 441.525904 -317.772037) (xy 441.651309 -317.92149) (xy 441.770473 -318.075964)
			(xy 441.883194 -318.235201) (xy 441.989283 -318.398932) (xy 442.088561 -318.566879) (xy 442.180859 -318.738762)
			(xy 442.266024 -318.914288) (xy 442.34391 -319.093163) (xy 442.414387 -319.275085) (xy 442.477335 -319.459747)
			(xy 442.53265 -319.646837) (xy 442.580236 -319.836041) (xy 442.620015 -320.027038) (xy 442.651919 -320.219508)
			(xy 442.675894 -320.413126) (xy 442.6919 -320.607564) (xy 442.699909 -320.802496) (xy 442.70041 -320.900044)
			(xy 442.699909 -320.997592) (xy 442.6919 -321.192524) (xy 442.675894 -321.386962) (xy 442.651919 -321.58058)
			(xy 442.620015 -321.77305) (xy 442.580236 -321.964047) (xy 442.53265 -322.153251) (xy 442.477335 -322.340341)
			(xy 442.414387 -322.525003) (xy 442.34391 -322.706925) (xy 442.266024 -322.8858) (xy 442.180859 -323.061326)
			(xy 442.088561 -323.233209) (xy 441.989283 -323.401156) (xy 441.883194 -323.564887) (xy 441.770473 -323.724124)
			(xy 441.651309 -323.878598) (xy 441.525904 -324.028051) (xy 441.394468 -324.172229) (xy 441.257224 -324.310889)
			(xy 441.114403 -324.443797) (xy 440.966246 -324.570731) (xy 440.813003 -324.691474) (xy 440.654932 -324.805824)
			(xy 440.492299 -324.913589) (xy 440.32538 -325.014585) (xy 440.154454 -325.108644) (xy 439.979811 -325.195606)
			(xy 439.801745 -325.275324) (xy 439.620557 -325.347665) (xy 439.436551 -325.412506) (xy 439.250038 -325.469738)
			(xy 439.061333 -325.519265) (xy 438.870754 -325.561002) (xy 438.678621 -325.59488) (xy 438.48526 -325.620842)
			(xy 438.290996 -325.638843) (xy 438.096157 -325.648854) (xy 437.901071 -325.650857) (xy 437.706068 -325.644849)
			(xy 437.511475 -325.63084) (xy 437.317622 -325.608854) (xy 437.124835 -325.578928) (xy 436.933438 -325.541112)
			(xy 436.743756 -325.49547) (xy 436.556108 -325.44208) (xy 436.370809 -325.38103) (xy 436.188174 -325.312425)
			(xy 436.008509 -325.236379) (xy 435.832117 -325.153021) (xy 435.659296 -325.062492) (xy 435.490338 -324.964944)
			(xy 435.325527 -324.860541) (xy 435.165141 -324.749461) (xy 435.009451 -324.631889) (xy 434.858719 -324.508025)
			(xy 434.7132 -324.378076) (xy 434.573138 -324.242263) (xy 434.43877 -324.100814) (xy 434.310323 -323.953968)
			(xy 434.188012 -323.801973) (xy 434.072045 -323.645084) (xy 433.962617 -323.483566) (xy 433.859912 -323.317692)
			(xy 433.764104 -323.147741) (xy 433.675353 -322.974) (xy 433.593811 -322.796762) (xy 433.519614 -322.616326)
			(xy 433.452887 -322.432995) (xy 433.393743 -322.24708) (xy 433.342282 -322.058893) (xy 433.29859 -321.868753)
			(xy 433.262741 -321.676978) (xy 433.234796 -321.483894) (xy 433.214801 -321.289825) (xy 433.202791 -321.095099)
			(xy 433.198785 -320.900044) (xy 431.542698 -320.900044) (xy 431.542698 -326.560434) (xy 431.542952 -326.572118)
			(xy 431.542952 -336.935064) (xy 431.542477 -336.960014) (xy 431.534657 -337.009297) (xy 431.519235 -337.056754)
			(xy 431.496588 -337.10122) (xy 431.467274 -337.141602) (xy 431.449988 -337.1596) (xy 430.210214 -338.399374)
			(xy 430.192213 -338.416657) (xy 430.151839 -338.445983) (xy 430.107375 -338.468633) (xy 430.059915 -338.484048)
			(xy 430.010628 -338.491851) (xy 429.985678 -338.492338) (xy 269.13205 -338.492338) (xy 269.1071 -338.491858)
			(xy 269.057817 -338.48404) (xy 269.01036 -338.468619) (xy 268.965894 -338.445974) (xy 268.925512 -338.41666)
			(xy 268.907514 -338.399374) (xy 268.350238 -337.842098) (xy 268.332949 -337.824102) (xy 268.303623 -337.783727)
			(xy 268.280975 -337.739261) (xy 268.26556 -337.6918) (xy 268.25776 -337.642513) (xy 268.257274 -337.617562)
			(xy 268.257274 -326.632824) (xy 268.25702 -326.62114) (xy 268.25702 -299.318172) (xy 268.255242 -299.311568)
			(xy 268.249876 -299.290318) (xy 268.244136 -299.246868) (xy 268.243812 -299.224954) (xy 255.173403 -299.224954)
			(xy 255.12203 -299.302605) (xy 255.024648 -299.435276) (xy 254.920922 -299.563048) (xy 254.811099 -299.685618)
			(xy 254.695438 -299.802696) (xy 254.574214 -299.914004) (xy 254.447714 -300.019278) (xy 254.316239 -300.118268)
			(xy 254.1801 -300.210739) (xy 254.039621 -300.296473) (xy 253.895133 -300.375265) (xy 253.746981 -300.446929)
			(xy 253.595516 -300.511295) (xy 253.441096 -300.56821) (xy 253.284089 -300.617539) (xy 253.124866 -300.659165)
			(xy 252.963805 -300.69299) (xy 252.801288 -300.718933) (xy 252.637701 -300.736933) (xy 252.473432 -300.746947)
			(xy 252.308869 -300.74895) (xy 252.144405 -300.74294) (xy 251.980428 -300.728929) (xy 251.817328 -300.706951)
			(xy 251.655491 -300.677058) (xy 251.495301 -300.639322) (xy 251.337139 -300.59383) (xy 251.181379 -300.540693)
			(xy 251.028391 -300.480034) (xy 250.878538 -300.411999) (xy 250.732175 -300.336749) (xy 250.58965 -300.254461)
			(xy 250.451299 -300.165333) (xy 250.317453 -300.069574) (xy 250.188427 -299.967411) (xy 250.064529 -299.859088)
			(xy 249.946051 -299.744862) (xy 249.833275 -299.625002) (xy 249.726469 -299.499793) (xy 249.625885 -299.369533)
			(xy 249.531763 -299.234531) (xy 249.444325 -299.095105) (xy 249.36378 -298.951588) (xy 249.290317 -298.80432)
			(xy 249.224112 -298.653649) (xy 249.165321 -298.499934) (xy 249.114083 -298.343539) (xy 249.070521 -298.184835)
			(xy 249.034738 -298.024198) (xy 249.006818 -297.862009) (xy 248.986828 -297.698653) (xy 248.974815 -297.534518)
			(xy 248.970807 -297.369992) (xy 199.352267 -297.369992) (xy 199.349627 -297.389952) (xy 199.34428 -297.41114)
			(xy 199.342502 -297.41749) (xy 199.342502 -298.18203) (xy 199.34428 -298.18838) (xy 199.349643 -298.209565)
			(xy 199.355376 -298.252889) (xy 199.35571 -298.27474) (xy 199.355369 -298.29659) (xy 199.349631 -298.339912)
			(xy 199.34428 -298.3611) (xy 199.342502 -298.36745) (xy 199.342502 -299.132244) (xy 199.34428 -299.138594)
			(xy 199.349645 -299.159779) (xy 199.355377 -299.203103) (xy 199.35571 -299.224954) (xy 199.355352 -299.246804)
			(xy 199.349625 -299.290126) (xy 199.34428 -299.311314) (xy 199.342502 -299.317664) (xy 199.342502 -300.082204)
			(xy 199.34428 -300.088554) (xy 199.349638 -300.109741) (xy 199.355375 -300.153063) (xy 199.35571 -300.174914)
			(xy 199.355364 -300.196764) (xy 199.349629 -300.240086) (xy 199.34428 -300.261274) (xy 199.342502 -300.267624)
			(xy 199.342502 -301.032164) (xy 199.34428 -301.038514) (xy 199.349649 -301.059698) (xy 199.355379 -301.103023)
			(xy 199.35571 -301.124874) (xy 199.355356 -301.146724) (xy 199.349626 -301.190046) (xy 199.34428 -301.211234)
			(xy 199.342502 -301.217584) (xy 199.342502 -301.982124) (xy 199.34428 -301.988474) (xy 199.349641 -302.00966)
			(xy 199.355376 -302.052983) (xy 199.35571 -302.074834) (xy 199.355368 -302.096684) (xy 199.34963 -302.140006)
			(xy 199.34428 -302.161194) (xy 199.342502 -302.167544) (xy 199.342502 -307.484272) (xy 231.935526 -307.484272)
			(xy 231.939599 -307.428613) (xy 231.951734 -307.37414) (xy 231.97167 -307.322014) (xy 231.998984 -307.273346)
			(xy 232.033092 -307.229174) (xy 232.073269 -307.190439) (xy 232.118657 -307.157967) (xy 232.168289 -307.132449)
			(xy 232.221109 -307.11443) (xy 232.275988 -307.104293) (xy 232.331759 -307.102255) (xy 232.387233 -307.108358)
			(xy 232.441226 -307.122474) (xy 232.492589 -307.144301) (xy 232.540227 -307.173374) (xy 232.583123 -307.209073)
			(xy 232.620365 -307.250637) (xy 232.651159 -307.297181) (xy 232.674847 -307.347712) (xy 232.690925 -307.401154)
			(xy 232.699051 -307.456368) (xy 232.69956 -307.484272) (xy 248.185684 -307.484272) (xy 248.189757 -307.428613)
			(xy 248.201892 -307.37414) (xy 248.221828 -307.322014) (xy 248.249142 -307.273346) (xy 248.28325 -307.229174)
			(xy 248.323427 -307.190439) (xy 248.368815 -307.157967) (xy 248.418447 -307.132449) (xy 248.471267 -307.11443)
			(xy 248.526146 -307.104293) (xy 248.581917 -307.102255) (xy 248.637391 -307.108358) (xy 248.691384 -307.122474)
			(xy 248.742747 -307.144301) (xy 248.790385 -307.173374) (xy 248.833281 -307.209073) (xy 248.870523 -307.250637)
			(xy 248.901317 -307.297181) (xy 248.925005 -307.347712) (xy 248.941083 -307.401154) (xy 248.949209 -307.456368)
			(xy 248.949718 -307.484272) (xy 248.949209 -307.512176) (xy 248.941083 -307.56739) (xy 248.925005 -307.620832)
			(xy 248.901317 -307.671363) (xy 248.870523 -307.717907) (xy 248.833281 -307.759471) (xy 248.790385 -307.79517)
			(xy 248.742747 -307.824243) (xy 248.691384 -307.84607) (xy 248.637391 -307.860186) (xy 248.581917 -307.866289)
			(xy 248.526146 -307.864251) (xy 248.471267 -307.854114) (xy 248.418447 -307.836095) (xy 248.368815 -307.810577)
			(xy 248.323427 -307.778105) (xy 248.28325 -307.73937) (xy 248.249142 -307.695198) (xy 248.221828 -307.64653)
			(xy 248.201892 -307.594404) (xy 248.189757 -307.539931) (xy 248.185684 -307.484272) (xy 232.69956 -307.484272)
			(xy 232.699051 -307.512176) (xy 232.690925 -307.56739) (xy 232.674847 -307.620832) (xy 232.651159 -307.671363)
			(xy 232.620365 -307.717907) (xy 232.583123 -307.759471) (xy 232.540227 -307.79517) (xy 232.492589 -307.824243)
			(xy 232.441226 -307.84607) (xy 232.387233 -307.860186) (xy 232.331759 -307.866289) (xy 232.275988 -307.864251)
			(xy 232.221109 -307.854114) (xy 232.168289 -307.836095) (xy 232.118657 -307.810577) (xy 232.073269 -307.778105)
			(xy 232.033092 -307.73937) (xy 231.998984 -307.695198) (xy 231.97167 -307.64653) (xy 231.951734 -307.594404)
			(xy 231.939599 -307.539931) (xy 231.935526 -307.484272) (xy 199.342502 -307.484272) (xy 199.342502 -311.179972)
			(xy 213.610705 -311.179972) (xy 213.614713 -311.015446) (xy 213.626726 -310.851311) (xy 213.646716 -310.687955)
			(xy 213.674636 -310.525766) (xy 213.710419 -310.365129) (xy 213.753981 -310.206425) (xy 213.805219 -310.05003)
			(xy 213.86401 -309.896315) (xy 213.930215 -309.745644) (xy 214.003678 -309.598376) (xy 214.084223 -309.454859)
			(xy 214.171661 -309.315433) (xy 214.265783 -309.180431) (xy 214.366367 -309.050171) (xy 214.473173 -308.924962)
			(xy 214.585949 -308.805102) (xy 214.704427 -308.690876) (xy 214.828325 -308.582553) (xy 214.957351 -308.48039)
			(xy 215.091197 -308.384631) (xy 215.229548 -308.295503) (xy 215.372073 -308.213215) (xy 215.518436 -308.137965)
			(xy 215.668289 -308.06993) (xy 215.821277 -308.009271) (xy 215.977037 -307.956134) (xy 216.135199 -307.910642)
			(xy 216.295389 -307.872906) (xy 216.457226 -307.843013) (xy 216.620326 -307.821035) (xy 216.784303 -307.807024)
			(xy 216.948767 -307.801014) (xy 217.11333 -307.803017) (xy 217.277599 -307.813031) (xy 217.441186 -307.831031)
			(xy 217.603703 -307.856974) (xy 217.764764 -307.890799) (xy 217.923987 -307.932425) (xy 218.080994 -307.981754)
			(xy 218.235414 -308.038669) (xy 218.386879 -308.103035) (xy 218.535031 -308.174699) (xy 218.679519 -308.253491)
			(xy 218.819998 -308.339225) (xy 218.956137 -308.431696) (xy 219.087612 -308.530686) (xy 219.133473 -308.568852)
			(xy 231.935526 -308.568852) (xy 231.939599 -308.513193) (xy 231.951734 -308.45872) (xy 231.97167 -308.406594)
			(xy 231.998984 -308.357926) (xy 232.033092 -308.313754) (xy 232.073269 -308.275019) (xy 232.118657 -308.242547)
			(xy 232.168289 -308.217029) (xy 232.221109 -308.19901) (xy 232.275988 -308.188873) (xy 232.331759 -308.186835)
			(xy 232.387233 -308.192938) (xy 232.441226 -308.207054) (xy 232.492589 -308.228881) (xy 232.540227 -308.257954)
			(xy 232.583123 -308.293653) (xy 232.620365 -308.335217) (xy 232.651159 -308.381761) (xy 232.674847 -308.432292)
			(xy 232.690925 -308.485734) (xy 232.699051 -308.540948) (xy 232.69956 -308.568852) (xy 248.185684 -308.568852)
			(xy 248.189757 -308.513193) (xy 248.201892 -308.45872) (xy 248.221828 -308.406594) (xy 248.249142 -308.357926)
			(xy 248.28325 -308.313754) (xy 248.323427 -308.275019) (xy 248.368815 -308.242547) (xy 248.418447 -308.217029)
			(xy 248.471267 -308.19901) (xy 248.526146 -308.188873) (xy 248.581917 -308.186835) (xy 248.637391 -308.192938)
			(xy 248.691384 -308.207054) (xy 248.742747 -308.228881) (xy 248.790385 -308.257954) (xy 248.833281 -308.293653)
			(xy 248.870523 -308.335217) (xy 248.901317 -308.381761) (xy 248.925005 -308.432292) (xy 248.941083 -308.485734)
			(xy 248.949209 -308.540948) (xy 248.949718 -308.568852) (xy 248.949209 -308.596756) (xy 248.941083 -308.65197)
			(xy 248.925005 -308.705412) (xy 248.901317 -308.755943) (xy 248.870523 -308.802487) (xy 248.833281 -308.844051)
			(xy 248.790385 -308.87975) (xy 248.742747 -308.908823) (xy 248.691384 -308.93065) (xy 248.637391 -308.944766)
			(xy 248.581917 -308.950869) (xy 248.526146 -308.948831) (xy 248.471267 -308.938694) (xy 248.418447 -308.920675)
			(xy 248.368815 -308.895157) (xy 248.323427 -308.862685) (xy 248.28325 -308.82395) (xy 248.249142 -308.779778)
			(xy 248.221828 -308.73111) (xy 248.201892 -308.678984) (xy 248.189757 -308.624511) (xy 248.185684 -308.568852)
			(xy 232.69956 -308.568852) (xy 232.699051 -308.596756) (xy 232.690925 -308.65197) (xy 232.674847 -308.705412)
			(xy 232.651159 -308.755943) (xy 232.620365 -308.802487) (xy 232.583123 -308.844051) (xy 232.540227 -308.87975)
			(xy 232.492589 -308.908823) (xy 232.441226 -308.93065) (xy 232.387233 -308.944766) (xy 232.331759 -308.950869)
			(xy 232.275988 -308.948831) (xy 232.221109 -308.938694) (xy 232.168289 -308.920675) (xy 232.118657 -308.895157)
			(xy 232.073269 -308.862685) (xy 232.033092 -308.82395) (xy 231.998984 -308.779778) (xy 231.97167 -308.73111)
			(xy 231.951734 -308.678984) (xy 231.939599 -308.624511) (xy 231.935526 -308.568852) (xy 219.133473 -308.568852)
			(xy 219.214112 -308.63596) (xy 219.335336 -308.747268) (xy 219.450997 -308.864346) (xy 219.56082 -308.986916)
			(xy 219.664546 -309.114688) (xy 219.761928 -309.247359) (xy 219.852735 -309.384614) (xy 219.936751 -309.526127)
			(xy 220.013778 -309.671563) (xy 220.083633 -309.820576) (xy 220.14615 -309.972814) (xy 220.20118 -310.127915)
			(xy 220.248594 -310.285512) (xy 220.288278 -310.44523) (xy 220.32014 -310.606691) (xy 220.344102 -310.769511)
			(xy 220.360108 -310.933306) (xy 220.368121 -311.097685) (xy 220.368622 -311.179972) (xy 220.368121 -311.262259)
			(xy 220.360108 -311.426638) (xy 220.344102 -311.590433) (xy 220.32014 -311.753253) (xy 220.288278 -311.914714)
			(xy 220.248594 -312.074432) (xy 220.20118 -312.232029) (xy 220.14615 -312.38713) (xy 220.083633 -312.539368)
			(xy 220.013778 -312.688381) (xy 219.936751 -312.833817) (xy 219.852735 -312.97533) (xy 219.761928 -313.112585)
			(xy 219.664546 -313.245256) (xy 219.56082 -313.373028) (xy 219.450997 -313.495598) (xy 219.335336 -313.612676)
			(xy 219.214112 -313.723984) (xy 219.087612 -313.829258) (xy 218.956137 -313.928248) (xy 218.819998 -314.020719)
			(xy 218.679519 -314.106453) (xy 218.535031 -314.185245) (xy 218.386879 -314.256909) (xy 218.235414 -314.321275)
			(xy 218.080994 -314.37819) (xy 217.923987 -314.427519) (xy 217.764764 -314.469145) (xy 217.603703 -314.50297)
			(xy 217.441186 -314.528913) (xy 217.277599 -314.546913) (xy 217.11333 -314.556927) (xy 216.948767 -314.55893)
			(xy 216.784303 -314.55292) (xy 216.620326 -314.538909) (xy 216.457226 -314.516931) (xy 216.295389 -314.487038)
			(xy 216.135199 -314.449302) (xy 215.977037 -314.40381) (xy 215.821277 -314.350673) (xy 215.668289 -314.290014)
			(xy 215.518436 -314.221979) (xy 215.372073 -314.146729) (xy 215.229548 -314.064441) (xy 215.091197 -313.975313)
			(xy 214.957351 -313.879554) (xy 214.828325 -313.777391) (xy 214.704427 -313.669068) (xy 214.585949 -313.554842)
			(xy 214.473173 -313.434982) (xy 214.366367 -313.309773) (xy 214.265783 -313.179513) (xy 214.171661 -313.044511)
			(xy 214.084223 -312.905085) (xy 214.003678 -312.761568) (xy 213.930215 -312.6143) (xy 213.86401 -312.463629)
			(xy 213.805219 -312.309914) (xy 213.753981 -312.153519) (xy 213.710419 -311.994815) (xy 213.674636 -311.834178)
			(xy 213.646716 -311.671989) (xy 213.626726 -311.508633) (xy 213.614713 -311.344498) (xy 213.610705 -311.179972)
			(xy 199.342502 -311.179972) (xy 199.342502 -318.213232) (xy 199.342756 -318.224916) (xy 199.342756 -320.900044)
			(xy 200.998589 -320.900044) (xy 201.002595 -320.704989) (xy 201.014605 -320.510263) (xy 201.0346 -320.316194)
			(xy 201.062545 -320.12311) (xy 201.098394 -319.931335) (xy 201.142086 -319.741195) (xy 201.193547 -319.553008)
			(xy 201.252691 -319.367093) (xy 201.319418 -319.183762) (xy 201.393615 -319.003326) (xy 201.475157 -318.826088)
			(xy 201.563908 -318.652347) (xy 201.659716 -318.482396) (xy 201.762421 -318.316522) (xy 201.871849 -318.155004)
			(xy 201.987816 -317.998115) (xy 202.110127 -317.84612) (xy 202.238574 -317.699274) (xy 202.372942 -317.557825)
			(xy 202.513004 -317.422012) (xy 202.658523 -317.292063) (xy 202.809255 -317.168199) (xy 202.964945 -317.050627)
			(xy 203.125331 -316.939547) (xy 203.290142 -316.835144) (xy 203.4591 -316.737596) (xy 203.631921 -316.647067)
			(xy 203.808313 -316.563709) (xy 203.987978 -316.487663) (xy 204.170613 -316.419058) (xy 204.355912 -316.358008)
			(xy 204.54356 -316.304618) (xy 204.733242 -316.258976) (xy 204.924639 -316.22116) (xy 205.117426 -316.191234)
			(xy 205.311279 -316.169248) (xy 205.505872 -316.155239) (xy 205.700875 -316.149231) (xy 205.895961 -316.151234)
			(xy 206.0908 -316.161245) (xy 206.285064 -316.179246) (xy 206.478425 -316.205208) (xy 206.670558 -316.239086)
			(xy 206.861137 -316.280823) (xy 207.049842 -316.33035) (xy 207.236355 -316.387582) (xy 207.420361 -316.452423)
			(xy 207.601549 -316.524764) (xy 207.779615 -316.604482) (xy 207.954258 -316.691444) (xy 208.125184 -316.785503)
			(xy 208.292103 -316.886499) (xy 208.454736 -316.994264) (xy 208.612807 -317.108614) (xy 208.76605 -317.229357)
			(xy 208.914207 -317.356291) (xy 209.057028 -317.489199) (xy 209.194272 -317.627859) (xy 209.325708 -317.772037)
			(xy 209.451113 -317.92149) (xy 209.570277 -318.075964) (xy 209.682998 -318.235201) (xy 209.789087 -318.398932)
			(xy 209.888365 -318.566879) (xy 209.980663 -318.738762) (xy 210.065828 -318.914288) (xy 210.143714 -319.093163)
			(xy 210.214191 -319.275085) (xy 210.277139 -319.459747) (xy 210.332454 -319.646837) (xy 210.38004 -319.836041)
			(xy 210.419819 -320.027038) (xy 210.451723 -320.219508) (xy 210.475698 -320.413126) (xy 210.491704 -320.607564)
			(xy 210.499713 -320.802496) (xy 210.500214 -320.900044) (xy 257.098807 -320.900044) (xy 257.102813 -320.704989)
			(xy 257.114823 -320.510263) (xy 257.134818 -320.316194) (xy 257.162763 -320.12311) (xy 257.198612 -319.931335)
			(xy 257.242304 -319.741195) (xy 257.293765 -319.553008) (xy 257.352909 -319.367093) (xy 257.419636 -319.183762)
			(xy 257.493833 -319.003326) (xy 257.575375 -318.826088) (xy 257.664126 -318.652347) (xy 257.759934 -318.482396)
			(xy 257.862639 -318.316522) (xy 257.972067 -318.155004) (xy 258.088034 -317.998115) (xy 258.210345 -317.84612)
			(xy 258.338792 -317.699274) (xy 258.47316 -317.557825) (xy 258.613222 -317.422012) (xy 258.758741 -317.292063)
			(xy 258.909473 -317.168199) (xy 259.065163 -317.050627) (xy 259.225549 -316.939547) (xy 259.39036 -316.835144)
			(xy 259.559318 -316.737596) (xy 259.732139 -316.647067) (xy 259.908531 -316.563709) (xy 260.088196 -316.487663)
			(xy 260.270831 -316.419058) (xy 260.45613 -316.358008) (xy 260.643778 -316.304618) (xy 260.83346 -316.258976)
			(xy 261.024857 -316.22116) (xy 261.217644 -316.191234) (xy 261.411497 -316.169248) (xy 261.60609 -316.155239)
			(xy 261.801093 -316.149231) (xy 261.996179 -316.151234) (xy 262.191018 -316.161245) (xy 262.385282 -316.179246)
			(xy 262.578643 -316.205208) (xy 262.770776 -316.239086) (xy 262.961355 -316.280823) (xy 263.15006 -316.33035)
			(xy 263.336573 -316.387582) (xy 263.520579 -316.452423) (xy 263.701767 -316.524764) (xy 263.879833 -316.604482)
			(xy 264.054476 -316.691444) (xy 264.225402 -316.785503) (xy 264.392321 -316.886499) (xy 264.554954 -316.994264)
			(xy 264.713025 -317.108614) (xy 264.866268 -317.229357) (xy 265.014425 -317.356291) (xy 265.157246 -317.489199)
			(xy 265.29449 -317.627859) (xy 265.425926 -317.772037) (xy 265.551331 -317.92149) (xy 265.670495 -318.075964)
			(xy 265.783216 -318.235201) (xy 265.889305 -318.398932) (xy 265.988583 -318.566879) (xy 266.080881 -318.738762)
			(xy 266.166046 -318.914288) (xy 266.243932 -319.093163) (xy 266.314409 -319.275085) (xy 266.377357 -319.459747)
			(xy 266.432672 -319.646837) (xy 266.480258 -319.836041) (xy 266.520037 -320.027038) (xy 266.551941 -320.219508)
			(xy 266.575916 -320.413126) (xy 266.591922 -320.607564) (xy 266.599931 -320.802496) (xy 266.600432 -320.900044)
			(xy 266.599931 -320.997592) (xy 266.591922 -321.192524) (xy 266.575916 -321.386962) (xy 266.551941 -321.58058)
			(xy 266.520037 -321.77305) (xy 266.480258 -321.964047) (xy 266.432672 -322.153251) (xy 266.377357 -322.340341)
			(xy 266.314409 -322.525003) (xy 266.243932 -322.706925) (xy 266.166046 -322.8858) (xy 266.080881 -323.061326)
			(xy 265.988583 -323.233209) (xy 265.889305 -323.401156) (xy 265.783216 -323.564887) (xy 265.670495 -323.724124)
			(xy 265.551331 -323.878598) (xy 265.425926 -324.028051) (xy 265.29449 -324.172229) (xy 265.157246 -324.310889)
			(xy 265.014425 -324.443797) (xy 264.866268 -324.570731) (xy 264.713025 -324.691474) (xy 264.554954 -324.805824)
			(xy 264.392321 -324.913589) (xy 264.225402 -325.014585) (xy 264.054476 -325.108644) (xy 263.879833 -325.195606)
			(xy 263.701767 -325.275324) (xy 263.520579 -325.347665) (xy 263.336573 -325.412506) (xy 263.15006 -325.469738)
			(xy 262.961355 -325.519265) (xy 262.770776 -325.561002) (xy 262.578643 -325.59488) (xy 262.385282 -325.620842)
			(xy 262.191018 -325.638843) (xy 261.996179 -325.648854) (xy 261.801093 -325.650857) (xy 261.60609 -325.644849)
			(xy 261.411497 -325.63084) (xy 261.217644 -325.608854) (xy 261.024857 -325.578928) (xy 260.83346 -325.541112)
			(xy 260.643778 -325.49547) (xy 260.45613 -325.44208) (xy 260.270831 -325.38103) (xy 260.088196 -325.312425)
			(xy 259.908531 -325.236379) (xy 259.732139 -325.153021) (xy 259.559318 -325.062492) (xy 259.39036 -324.964944)
			(xy 259.225549 -324.860541) (xy 259.065163 -324.749461) (xy 258.909473 -324.631889) (xy 258.758741 -324.508025)
			(xy 258.613222 -324.378076) (xy 258.47316 -324.242263) (xy 258.338792 -324.100814) (xy 258.210345 -323.953968)
			(xy 258.088034 -323.801973) (xy 257.972067 -323.645084) (xy 257.862639 -323.483566) (xy 257.759934 -323.317692)
			(xy 257.664126 -323.147741) (xy 257.575375 -322.974) (xy 257.493833 -322.796762) (xy 257.419636 -322.616326)
			(xy 257.352909 -322.432995) (xy 257.293765 -322.24708) (xy 257.242304 -322.058893) (xy 257.198612 -321.868753)
			(xy 257.162763 -321.676978) (xy 257.134818 -321.483894) (xy 257.114823 -321.289825) (xy 257.102813 -321.095099)
			(xy 257.098807 -320.900044) (xy 210.500214 -320.900044) (xy 210.499713 -320.997592) (xy 210.491704 -321.192524)
			(xy 210.475698 -321.386962) (xy 210.451723 -321.58058) (xy 210.419819 -321.77305) (xy 210.38004 -321.964047)
			(xy 210.332454 -322.153251) (xy 210.277139 -322.340341) (xy 210.214191 -322.525003) (xy 210.143714 -322.706925)
			(xy 210.065828 -322.8858) (xy 209.980663 -323.061326) (xy 209.888365 -323.233209) (xy 209.789087 -323.401156)
			(xy 209.682998 -323.564887) (xy 209.570277 -323.724124) (xy 209.451113 -323.878598) (xy 209.325708 -324.028051)
			(xy 209.194272 -324.172229) (xy 209.057028 -324.310889) (xy 208.914207 -324.443797) (xy 208.76605 -324.570731)
			(xy 208.612807 -324.691474) (xy 208.454736 -324.805824) (xy 208.292103 -324.913589) (xy 208.125184 -325.014585)
			(xy 207.954258 -325.108644) (xy 207.779615 -325.195606) (xy 207.601549 -325.275324) (xy 207.420361 -325.347665)
			(xy 207.236355 -325.412506) (xy 207.049842 -325.469738) (xy 206.861137 -325.519265) (xy 206.670558 -325.561002)
			(xy 206.478425 -325.59488) (xy 206.285064 -325.620842) (xy 206.0908 -325.638843) (xy 205.895961 -325.648854)
			(xy 205.700875 -325.650857) (xy 205.505872 -325.644849) (xy 205.311279 -325.63084) (xy 205.117426 -325.608854)
			(xy 204.924639 -325.578928) (xy 204.733242 -325.541112) (xy 204.54356 -325.49547) (xy 204.355912 -325.44208)
			(xy 204.170613 -325.38103) (xy 203.987978 -325.312425) (xy 203.808313 -325.236379) (xy 203.631921 -325.153021)
			(xy 203.4591 -325.062492) (xy 203.290142 -324.964944) (xy 203.125331 -324.860541) (xy 202.964945 -324.749461)
			(xy 202.809255 -324.631889) (xy 202.658523 -324.508025) (xy 202.513004 -324.378076) (xy 202.372942 -324.242263)
			(xy 202.238574 -324.100814) (xy 202.110127 -323.953968) (xy 201.987816 -323.801973) (xy 201.871849 -323.645084)
			(xy 201.762421 -323.483566) (xy 201.659716 -323.317692) (xy 201.563908 -323.147741) (xy 201.475157 -322.974)
			(xy 201.393615 -322.796762) (xy 201.319418 -322.616326) (xy 201.252691 -322.432995) (xy 201.193547 -322.24708)
			(xy 201.142086 -322.058893) (xy 201.098394 -321.868753) (xy 201.062545 -321.676978) (xy 201.0346 -321.483894)
			(xy 201.014605 -321.289825) (xy 201.002595 -321.095099) (xy 200.998589 -320.900044) (xy 199.342756 -320.900044)
			(xy 199.342756 -336.935064) (xy 199.34228 -336.960014) (xy 199.33446 -337.009297) (xy 199.319038 -337.056754)
			(xy 199.296392 -337.10122) (xy 199.267078 -337.141602) (xy 199.249792 -337.1596) (xy 199.143366 -337.266026)
			(xy 234.403392 -337.266026) (xy 234.403392 -336.402426) (xy 234.403882 -336.372458) (xy 234.411705 -336.313036)
			(xy 234.427218 -336.255143) (xy 234.450154 -336.19977) (xy 234.480121 -336.147864) (xy 234.516608 -336.100314)
			(xy 234.558988 -336.057934) (xy 234.606538 -336.021447) (xy 234.658444 -335.99148) (xy 234.713817 -335.968544)
			(xy 234.77171 -335.953031) (xy 234.831132 -335.945208) (xy 234.891068 -335.945208) (xy 234.95049 -335.953031)
			(xy 235.008383 -335.968544) (xy 235.063756 -335.99148) (xy 235.115662 -336.021447) (xy 235.163212 -336.057934)
			(xy 235.205592 -336.100314) (xy 235.242079 -336.147864) (xy 235.272046 -336.19977) (xy 235.294982 -336.255143)
			(xy 235.310495 -336.313036) (xy 235.318318 -336.372458) (xy 235.318808 -336.402426) (xy 235.318808 -337.266026)
			(xy 235.318318 -337.295994) (xy 235.310495 -337.355416) (xy 235.294982 -337.413309) (xy 235.272046 -337.468682)
			(xy 235.242079 -337.520588) (xy 235.205592 -337.568138) (xy 235.163212 -337.610518) (xy 235.115662 -337.647005)
			(xy 235.063756 -337.676972) (xy 235.008383 -337.699908) (xy 234.95049 -337.715421) (xy 234.891068 -337.723244)
			(xy 234.831132 -337.723244) (xy 234.77171 -337.715421) (xy 234.713817 -337.699908) (xy 234.658444 -337.676972)
			(xy 234.606538 -337.647005) (xy 234.558988 -337.610518) (xy 234.516608 -337.568138) (xy 234.480121 -337.520588)
			(xy 234.450154 -337.468682) (xy 234.427218 -337.413309) (xy 234.411705 -337.355416) (xy 234.403882 -337.295994)
			(xy 234.403392 -337.266026) (xy 199.143366 -337.266026) (xy 198.010018 -338.399374) (xy 197.992015 -338.416655)
			(xy 197.951641 -338.445982) (xy 197.907178 -338.468632) (xy 197.859719 -338.484048) (xy 197.810432 -338.49185)
			(xy 197.785482 -338.492338) (xy 36.931854 -338.492338) (xy 36.906904 -338.491856) (xy 36.857621 -338.484038)
			(xy 36.810164 -338.468618) (xy 36.765698 -338.445973) (xy 36.725316 -338.41666) (xy 36.707318 -338.399374)
			(xy 36.150042 -337.842098) (xy 36.132754 -337.824101) (xy 36.103428 -337.783726) (xy 36.080779 -337.739261)
			(xy 36.065365 -337.6918) (xy 36.057564 -337.642513) (xy 36.057078 -337.617562) (xy 36.057078 -299.318172)
			(xy 36.0553 -299.311568) (xy 36.049863 -299.290328) (xy 36.044004 -299.246876) (xy 36.043616 -299.224954)
			(xy 22.727388 -299.224954) (xy 22.824706 -299.344832) (xy 22.922088 -299.477503) (xy 23.012895 -299.614758)
			(xy 23.096911 -299.756271) (xy 23.173938 -299.901707) (xy 23.243793 -300.05072) (xy 23.30631 -300.202958)
			(xy 23.36134 -300.358059) (xy 23.408754 -300.515656) (xy 23.448438 -300.675374) (xy 23.4803 -300.836835)
			(xy 23.504262 -300.999655) (xy 23.520268 -301.16345) (xy 23.528281 -301.327829) (xy 23.528782 -301.410116)
			(xy 23.528281 -301.492403) (xy 23.520268 -301.656782) (xy 23.504262 -301.820577) (xy 23.4803 -301.983397)
			(xy 23.448438 -302.144858) (xy 23.408754 -302.304576) (xy 23.36134 -302.462173) (xy 23.30631 -302.617274)
			(xy 23.243793 -302.769512) (xy 23.173938 -302.918525) (xy 23.096911 -303.063961) (xy 23.012895 -303.205474)
			(xy 22.922088 -303.342729) (xy 22.824706 -303.4754) (xy 22.72098 -303.603172) (xy 22.611157 -303.725742)
			(xy 22.495496 -303.84282) (xy 22.374272 -303.954128) (xy 22.247772 -304.059402) (xy 22.116297 -304.158392)
			(xy 21.980158 -304.250863) (xy 21.839679 -304.336597) (xy 21.695191 -304.415389) (xy 21.547039 -304.487053)
			(xy 21.395574 -304.551419) (xy 21.241154 -304.608334) (xy 21.084147 -304.657663) (xy 20.924924 -304.699289)
			(xy 20.763863 -304.733114) (xy 20.601346 -304.759057) (xy 20.437759 -304.777057) (xy 20.27349 -304.787071)
			(xy 20.108927 -304.789074) (xy 19.944463 -304.783064) (xy 19.780486 -304.769053) (xy 19.617386 -304.747075)
			(xy 19.455549 -304.717182) (xy 19.295359 -304.679446) (xy 19.137197 -304.633954) (xy 18.981437 -304.580817)
			(xy 18.828449 -304.520158) (xy 18.678596 -304.452123) (xy 18.532233 -304.376873) (xy 18.389708 -304.294585)
			(xy 18.251357 -304.205457) (xy 18.117511 -304.109698) (xy 17.988485 -304.007535) (xy 17.864587 -303.899212)
			(xy 17.746109 -303.784986) (xy 17.633333 -303.665126) (xy 17.526527 -303.539917) (xy 17.425943 -303.409657)
			(xy 17.331821 -303.274655) (xy 17.244383 -303.135229) (xy 17.163838 -302.991712) (xy 17.090375 -302.844444)
			(xy 17.02417 -302.693773) (xy 16.965379 -302.540058) (xy 16.914141 -302.383663) (xy 16.870579 -302.224959)
			(xy 16.834796 -302.064322) (xy 16.806876 -301.902133) (xy 16.786886 -301.738777) (xy 16.774873 -301.574642)
			(xy 16.770865 -301.410116) (xy 1.524 -301.410116) (xy 1.524 -305.19751) (xy 17.638266 -305.19751)
			(xy 17.642339 -305.141851) (xy 17.654474 -305.087378) (xy 17.67441 -305.035252) (xy 17.701724 -304.986584)
			(xy 17.735832 -304.942412) (xy 17.776009 -304.903677) (xy 17.821397 -304.871205) (xy 17.871029 -304.845687)
			(xy 17.923849 -304.827668) (xy 17.978728 -304.817531) (xy 18.034499 -304.815493) (xy 18.089973 -304.821596)
			(xy 18.143966 -304.835712) (xy 18.195329 -304.857539) (xy 18.242967 -304.886612) (xy 18.285863 -304.922311)
			(xy 18.323105 -304.963875) (xy 18.353899 -305.010419) (xy 18.377587 -305.06095) (xy 18.393665 -305.114392)
			(xy 18.401791 -305.169606) (xy 18.4023 -305.19751) (xy 18.401791 -305.225414) (xy 18.393665 -305.280628)
			(xy 18.377587 -305.33407) (xy 18.353899 -305.384601) (xy 18.323105 -305.431145) (xy 18.285863 -305.472709)
			(xy 18.242967 -305.508408) (xy 18.195329 -305.537481) (xy 18.143966 -305.559308) (xy 18.089973 -305.573424)
			(xy 18.034499 -305.579527) (xy 17.978728 -305.577489) (xy 17.923849 -305.567352) (xy 17.871029 -305.549333)
			(xy 17.821397 -305.523815) (xy 17.776009 -305.491343) (xy 17.735832 -305.452608) (xy 17.701724 -305.408436)
			(xy 17.67441 -305.359768) (xy 17.654474 -305.307642) (xy 17.642339 -305.253169) (xy 17.638266 -305.19751)
			(xy 1.524 -305.19751) (xy 1.524 -306.28209) (xy 17.638266 -306.28209) (xy 17.642339 -306.226431)
			(xy 17.654474 -306.171958) (xy 17.67441 -306.119832) (xy 17.701724 -306.071164) (xy 17.735832 -306.026992)
			(xy 17.776009 -305.988257) (xy 17.821397 -305.955785) (xy 17.871029 -305.930267) (xy 17.923849 -305.912248)
			(xy 17.978728 -305.902111) (xy 18.034499 -305.900073) (xy 18.089973 -305.906176) (xy 18.143966 -305.920292)
			(xy 18.195329 -305.942119) (xy 18.242967 -305.971192) (xy 18.285863 -306.006891) (xy 18.323105 -306.048455)
			(xy 18.353899 -306.094999) (xy 18.377587 -306.14553) (xy 18.393665 -306.198972) (xy 18.401791 -306.254186)
			(xy 18.4023 -306.28209) (xy 18.401791 -306.309994) (xy 18.393665 -306.365208) (xy 18.377587 -306.41865)
			(xy 18.353899 -306.469181) (xy 18.323105 -306.515725) (xy 18.285863 -306.557289) (xy 18.242967 -306.592988)
			(xy 18.195329 -306.622061) (xy 18.143966 -306.643888) (xy 18.089973 -306.658004) (xy 18.034499 -306.664107)
			(xy 17.978728 -306.662069) (xy 17.923849 -306.651932) (xy 17.871029 -306.633913) (xy 17.821397 -306.608395)
			(xy 17.776009 -306.575923) (xy 17.735832 -306.537188) (xy 17.701724 -306.493016) (xy 17.67441 -306.444348)
			(xy 17.654474 -306.392222) (xy 17.642339 -306.337749) (xy 17.638266 -306.28209) (xy 1.524 -306.28209)
			(xy 1.524 -308.477666) (xy 1.524327 -308.486785) (xy 1.530648 -308.503889) (xy 1.542597 -308.517662)
			(xy 1.550416 -308.52237) (xy 1.64084 -308.571646) (xy 1.66878 -308.57063) (xy 1.68021 -308.563264)
			(xy 1.74792 -308.520543) (xy 1.886767 -308.440797) (xy 2.029236 -308.367717) (xy 2.175007 -308.301468)
			(xy 2.323752 -308.242198) (xy 2.475137 -308.19004) (xy 2.628824 -308.145112) (xy 2.784466 -308.107515)
			(xy 2.941714 -308.077332) (xy 3.100215 -308.054632) (xy 3.259614 -308.039465) (xy 3.419553 -308.031866)
			(xy 3.499612 -308.031388) (xy 3.50012 -308.031388) (xy 3.581774 -308.031881) (xy 3.744892 -308.039771)
			(xy 3.907438 -308.055533) (xy 4.069032 -308.079129) (xy 4.229298 -308.110505) (xy 4.387861 -308.149587)
			(xy 4.544351 -308.196284) (xy 4.698401 -308.250488) (xy 4.849653 -308.31207) (xy 4.997754 -308.380889)
			(xy 5.142356 -308.456782) (xy 5.283123 -308.539573) (xy 5.419725 -308.629068) (xy 5.551844 -308.725058)
			(xy 5.679172 -308.827319) (xy 5.80141 -308.935613) (xy 5.918273 -309.049685) (xy 6.029489 -309.169271)
			(xy 6.134797 -309.29409) (xy 6.233951 -309.423851) (xy 6.326721 -309.558251) (xy 6.412889 -309.696977)
			(xy 6.492254 -309.839703) (xy 6.564631 -309.986097) (xy 6.629851 -310.135817) (xy 6.687761 -310.288512)
			(xy 6.738226 -310.443828) (xy 6.781128 -310.6014) (xy 6.816367 -310.760861) (xy 6.843862 -310.921838)
			(xy 6.863546 -311.083956) (xy 6.875375 -311.246835) (xy 6.879322 -311.410096) (xy 6.875375 -311.573357)
			(xy 6.863546 -311.736236) (xy 6.843862 -311.898354) (xy 6.816367 -312.059331) (xy 6.781128 -312.218792)
			(xy 6.738226 -312.376364) (xy 6.687761 -312.53168) (xy 6.629851 -312.684375) (xy 6.564631 -312.834095)
			(xy 6.492254 -312.980489) (xy 6.412889 -313.123215) (xy 6.326721 -313.261941) (xy 6.233951 -313.396341)
			(xy 6.134797 -313.526102) (xy 6.029489 -313.650921) (xy 5.918273 -313.770507) (xy 5.80141 -313.884579)
			(xy 5.679172 -313.992873) (xy 5.551844 -314.095134) (xy 5.419725 -314.191124) (xy 5.283123 -314.280619)
			(xy 5.142356 -314.36341) (xy 4.997754 -314.439303) (xy 4.849653 -314.508122) (xy 4.698401 -314.569704)
			(xy 4.544351 -314.623908) (xy 4.387861 -314.670605) (xy 4.229298 -314.709687) (xy 4.069032 -314.741063)
			(xy 3.907438 -314.764659) (xy 3.744892 -314.780421) (xy 3.581774 -314.788311) (xy 3.50012 -314.788804)
			(xy 3.499612 -314.788804) (xy 3.419553 -314.788328) (xy 3.259614 -314.780732) (xy 3.100214 -314.765567)
			(xy 2.941712 -314.742868) (xy 2.784464 -314.712686) (xy 2.628821 -314.675089) (xy 2.475135 -314.630161)
			(xy 2.323749 -314.578002) (xy 2.175004 -314.518731) (xy 2.029234 -314.45248) (xy 1.886766 -314.379398)
			(xy 1.747921 -314.299648) (xy 1.68021 -314.256928) (xy 1.66878 -314.249562) (xy 1.64084 -314.248546)
			(xy 1.550416 -314.297822) (xy 1.542626 -314.302548) (xy 1.53075 -314.31635) (xy 1.524421 -314.333422)
			(xy 1.524 -314.342526) (xy 1.524 -320.900044) (xy 24.898611 -320.900044) (xy 24.902617 -320.704989)
			(xy 24.914627 -320.510263) (xy 24.934622 -320.316194) (xy 24.962567 -320.12311) (xy 24.998416 -319.931335)
			(xy 25.042108 -319.741195) (xy 25.093569 -319.553008) (xy 25.152713 -319.367093) (xy 25.21944 -319.183762)
			(xy 25.293637 -319.003326) (xy 25.375179 -318.826088) (xy 25.46393 -318.652347) (xy 25.559738 -318.482396)
			(xy 25.662443 -318.316522) (xy 25.771871 -318.155004) (xy 25.887838 -317.998115) (xy 26.010149 -317.84612)
			(xy 26.138596 -317.699274) (xy 26.272964 -317.557825) (xy 26.413026 -317.422012) (xy 26.558545 -317.292063)
			(xy 26.709277 -317.168199) (xy 26.864967 -317.050627) (xy 27.025353 -316.939547) (xy 27.190164 -316.835144)
			(xy 27.359122 -316.737596) (xy 27.531943 -316.647067) (xy 27.708335 -316.563709) (xy 27.888 -316.487663)
			(xy 28.070635 -316.419058) (xy 28.255934 -316.358008) (xy 28.443582 -316.304618) (xy 28.633264 -316.258976)
			(xy 28.824661 -316.22116) (xy 29.017448 -316.191234) (xy 29.211301 -316.169248) (xy 29.405894 -316.155239)
			(xy 29.600897 -316.149231) (xy 29.795983 -316.151234) (xy 29.990822 -316.161245) (xy 30.185086 -316.179246)
			(xy 30.378447 -316.205208) (xy 30.57058 -316.239086) (xy 30.761159 -316.280823) (xy 30.949864 -316.33035)
			(xy 31.136377 -316.387582) (xy 31.320383 -316.452423) (xy 31.501571 -316.524764) (xy 31.679637 -316.604482)
			(xy 31.85428 -316.691444) (xy 32.025206 -316.785503) (xy 32.192125 -316.886499) (xy 32.354758 -316.994264)
			(xy 32.512829 -317.108614) (xy 32.666072 -317.229357) (xy 32.814229 -317.356291) (xy 32.95705 -317.489199)
			(xy 33.094294 -317.627859) (xy 33.22573 -317.772037) (xy 33.351135 -317.92149) (xy 33.470299 -318.075964)
			(xy 33.58302 -318.235201) (xy 33.689109 -318.398932) (xy 33.788387 -318.566879) (xy 33.880685 -318.738762)
			(xy 33.96585 -318.914288) (xy 34.043736 -319.093163) (xy 34.114213 -319.275085) (xy 34.177161 -319.459747)
			(xy 34.232476 -319.646837) (xy 34.280062 -319.836041) (xy 34.319841 -320.027038) (xy 34.351745 -320.219508)
			(xy 34.37572 -320.413126) (xy 34.391726 -320.607564) (xy 34.399735 -320.802496) (xy 34.400236 -320.900044)
			(xy 34.399735 -320.997592) (xy 34.391726 -321.192524) (xy 34.37572 -321.386962) (xy 34.351745 -321.58058)
			(xy 34.319841 -321.77305) (xy 34.280062 -321.964047) (xy 34.232476 -322.153251) (xy 34.177161 -322.340341)
			(xy 34.114213 -322.525003) (xy 34.043736 -322.706925) (xy 33.96585 -322.8858) (xy 33.880685 -323.061326)
			(xy 33.788387 -323.233209) (xy 33.689109 -323.401156) (xy 33.58302 -323.564887) (xy 33.470299 -323.724124)
			(xy 33.351135 -323.878598) (xy 33.22573 -324.028051) (xy 33.094294 -324.172229) (xy 32.95705 -324.310889)
			(xy 32.814229 -324.443797) (xy 32.666072 -324.570731) (xy 32.512829 -324.691474) (xy 32.354758 -324.805824)
			(xy 32.192125 -324.913589) (xy 32.025206 -325.014585) (xy 31.85428 -325.108644) (xy 31.679637 -325.195606)
			(xy 31.501571 -325.275324) (xy 31.320383 -325.347665) (xy 31.136377 -325.412506) (xy 30.949864 -325.469738)
			(xy 30.761159 -325.519265) (xy 30.57058 -325.561002) (xy 30.378447 -325.59488) (xy 30.185086 -325.620842)
			(xy 29.990822 -325.638843) (xy 29.795983 -325.648854) (xy 29.600897 -325.650857) (xy 29.405894 -325.644849)
			(xy 29.211301 -325.63084) (xy 29.017448 -325.608854) (xy 28.824661 -325.578928) (xy 28.633264 -325.541112)
			(xy 28.443582 -325.49547) (xy 28.255934 -325.44208) (xy 28.070635 -325.38103) (xy 27.888 -325.312425)
			(xy 27.708335 -325.236379) (xy 27.531943 -325.153021) (xy 27.359122 -325.062492) (xy 27.190164 -324.964944)
			(xy 27.025353 -324.860541) (xy 26.864967 -324.749461) (xy 26.709277 -324.631889) (xy 26.558545 -324.508025)
			(xy 26.413026 -324.378076) (xy 26.272964 -324.242263) (xy 26.138596 -324.100814) (xy 26.010149 -323.953968)
			(xy 25.887838 -323.801973) (xy 25.771871 -323.645084) (xy 25.662443 -323.483566) (xy 25.559738 -323.317692)
			(xy 25.46393 -323.147741) (xy 25.375179 -322.974) (xy 25.293637 -322.796762) (xy 25.21944 -322.616326)
			(xy 25.152713 -322.432995) (xy 25.093569 -322.24708) (xy 25.042108 -322.058893) (xy 24.998416 -321.868753)
			(xy 24.962567 -321.676978) (xy 24.934622 -321.483894) (xy 24.914627 -321.289825) (xy 24.902617 -321.095099)
			(xy 24.898611 -320.900044) (xy 1.524 -320.900044) (xy 1.524 -342.466769) (xy 18.951172 -342.466769)
			(xy 18.951172 -342.412231) (xy 18.958934 -342.358247) (xy 18.974299 -342.305917) (xy 18.996956 -342.256307)
			(xy 19.026441 -342.210426) (xy 19.062157 -342.169208) (xy 19.103374 -342.133493) (xy 19.149255 -342.104007)
			(xy 19.198865 -342.08135) (xy 19.251195 -342.065985) (xy 19.305179 -342.058223) (xy 19.332448 -342.057736)
			(xy 20.196048 -342.057736) (xy 20.223319 -342.058203) (xy 20.277306 -342.065965) (xy 20.329638 -342.081331)
			(xy 20.379252 -342.103989) (xy 20.425135 -342.133476) (xy 20.466355 -342.169193) (xy 20.502073 -342.210413)
			(xy 20.53156 -342.256297) (xy 20.554218 -342.30591) (xy 20.569584 -342.358242) (xy 20.577347 -342.412229)
			(xy 20.577347 -342.466771) (xy 20.577347 -342.466772) (xy 22.0601 -342.466772) (xy 22.0601 -342.412228)
			(xy 22.067862 -342.358241) (xy 22.083229 -342.305907) (xy 22.105887 -342.256293) (xy 22.135375 -342.210409)
			(xy 22.171094 -342.169188) (xy 22.212315 -342.133471) (xy 22.2582 -342.103983) (xy 22.307815 -342.081326)
			(xy 22.360148 -342.06596) (xy 22.414136 -342.058199) (xy 22.441408 -342.057736) (xy 23.305008 -342.057736)
			(xy 23.332277 -342.058227) (xy 23.386259 -342.06599) (xy 23.438588 -342.081355) (xy 23.488197 -342.104012)
			(xy 23.534076 -342.133498) (xy 23.575293 -342.169213) (xy 23.611007 -342.21043) (xy 23.640492 -342.256311)
			(xy 23.663147 -342.30592) (xy 23.678512 -342.358249) (xy 23.686274 -342.412231) (xy 23.686274 -342.466768)
			(xy 25.169122 -342.466768) (xy 25.169122 -342.412232) (xy 25.176883 -342.358251) (xy 25.192247 -342.305924)
			(xy 25.214901 -342.256315) (xy 25.244384 -342.210436) (xy 25.280096 -342.169219) (xy 25.32131 -342.133503)
			(xy 25.367187 -342.104016) (xy 25.416794 -342.081358) (xy 25.46912 -342.06599) (xy 25.5231 -342.058225)
			(xy 25.550368 -342.057736) (xy 26.413968 -342.057736) (xy 26.44124 -342.058201) (xy 26.49523 -342.06596)
			(xy 26.547567 -342.081323) (xy 26.597184 -342.103979) (xy 26.643071 -342.133465) (xy 26.684295 -342.169183)
			(xy 26.720015 -342.210403) (xy 26.749506 -342.256288) (xy 26.772166 -342.305903) (xy 26.787533 -342.358238)
			(xy 26.795296 -342.412228) (xy 26.795296 -342.466772) (xy 28.278 -342.466772) (xy 28.278 -342.412228)
			(xy 28.285762 -342.358238) (xy 28.30113 -342.305903) (xy 28.32379 -342.256288) (xy 28.35328 -342.210402)
			(xy 28.389001 -342.169181) (xy 28.430225 -342.133464) (xy 28.476112 -342.103977) (xy 28.525729 -342.08132)
			(xy 28.578065 -342.065957) (xy 28.632056 -342.058198) (xy 28.659328 -342.057736) (xy 29.522928 -342.057736)
			(xy 29.550196 -342.058228) (xy 29.604176 -342.065993) (xy 29.656502 -342.081361) (xy 29.706109 -342.104019)
			(xy 29.751986 -342.133505) (xy 29.7932 -342.16922) (xy 29.828912 -342.210437) (xy 29.858395 -342.256316)
			(xy 29.881049 -342.305924) (xy 29.896413 -342.358251) (xy 29.904174 -342.412232) (xy 29.904174 -342.466768)
			(xy 29.904174 -342.466769) (xy 31.387022 -342.466769) (xy 31.387022 -342.412231) (xy 31.394784 -342.358248)
			(xy 31.410149 -342.305919) (xy 31.432804 -342.25631) (xy 31.462289 -342.210429) (xy 31.498003 -342.169212)
			(xy 31.53922 -342.133496) (xy 31.585099 -342.10401) (xy 31.634708 -342.081353) (xy 31.687036 -342.065986)
			(xy 31.741019 -342.058223) (xy 31.768288 -342.057736) (xy 32.631888 -342.057736) (xy 32.659159 -342.058203)
			(xy 32.713147 -342.065963) (xy 32.765481 -342.081329) (xy 32.815096 -342.103985) (xy 32.86098 -342.133472)
			(xy 32.902202 -342.16919) (xy 32.93792 -342.21041) (xy 32.967409 -342.256294) (xy 32.990067 -342.305908)
			(xy 33.005434 -342.358241) (xy 33.013196 -342.412229) (xy 33.013196 -342.466771) (xy 33.013196 -342.466773)
			(xy 34.4959 -342.466773) (xy 34.4959 -342.412227) (xy 34.503663 -342.358235) (xy 34.519032 -342.305899)
			(xy 34.541693 -342.256282) (xy 34.571185 -342.210396) (xy 34.606908 -342.169174) (xy 34.648134 -342.133456)
			(xy 34.694024 -342.10397) (xy 34.743644 -342.081315) (xy 34.795982 -342.065953) (xy 34.849975 -342.058196)
			(xy 34.877248 -342.057736) (xy 35.740848 -342.057736) (xy 35.768115 -342.05823) (xy 35.822093 -342.065997)
			(xy 35.874417 -342.081366) (xy 35.92402 -342.104025) (xy 35.969895 -342.133512) (xy 36.011107 -342.169227)
			(xy 36.046817 -342.210443) (xy 36.076298 -342.256322) (xy 36.098951 -342.305928) (xy 36.114313 -342.358254)
			(xy 36.122074 -342.412233) (xy 36.122074 -342.466767) (xy 36.122073 -342.466772) (xy 37.6049 -342.466772)
			(xy 37.6049 -342.412228) (xy 37.612662 -342.358241) (xy 37.628029 -342.305907) (xy 37.650687 -342.256293)
			(xy 37.680175 -342.210409) (xy 37.715894 -342.169188) (xy 37.757115 -342.133471) (xy 37.803 -342.103983)
			(xy 37.852615 -342.081326) (xy 37.904948 -342.06596) (xy 37.958936 -342.058199) (xy 37.986208 -342.057736)
			(xy 38.849808 -342.057736) (xy 38.877077 -342.058227) (xy 38.931059 -342.06599) (xy 38.983388 -342.081355)
			(xy 39.032997 -342.104012) (xy 39.078876 -342.133498) (xy 39.120093 -342.169213) (xy 39.155807 -342.21043)
			(xy 39.185292 -342.256311) (xy 39.207947 -342.30592) (xy 39.223312 -342.358249) (xy 39.231074 -342.412231)
			(xy 39.231074 -342.466768) (xy 40.713922 -342.466768) (xy 40.713922 -342.412232) (xy 40.721683 -342.358251)
			(xy 40.737047 -342.305924) (xy 40.759701 -342.256315) (xy 40.789184 -342.210436) (xy 40.824896 -342.169219)
			(xy 40.86611 -342.133503) (xy 40.911987 -342.104016) (xy 40.961594 -342.081358) (xy 41.01392 -342.06599)
			(xy 41.0679 -342.058225) (xy 41.095168 -342.057736) (xy 41.958768 -342.057736) (xy 41.98604 -342.058201)
			(xy 42.04003 -342.06596) (xy 42.092367 -342.081323) (xy 42.141984 -342.103979) (xy 42.187871 -342.133465)
			(xy 42.229095 -342.169183) (xy 42.264815 -342.210403) (xy 42.294306 -342.256288) (xy 42.316966 -342.305903)
			(xy 42.332333 -342.358238) (xy 42.340096 -342.412228) (xy 42.340096 -342.466772) (xy 43.8228 -342.466772)
			(xy 43.8228 -342.412228) (xy 43.830562 -342.358238) (xy 43.84593 -342.305903) (xy 43.86859 -342.256288)
			(xy 43.89808 -342.210402) (xy 43.933801 -342.169181) (xy 43.975025 -342.133464) (xy 44.020912 -342.103977)
			(xy 44.070529 -342.08132) (xy 44.122865 -342.065957) (xy 44.176856 -342.058198) (xy 44.204128 -342.057736)
			(xy 45.067728 -342.057736) (xy 45.094996 -342.058228) (xy 45.148976 -342.065993) (xy 45.201302 -342.081361)
			(xy 45.250909 -342.104019) (xy 45.296786 -342.133505) (xy 45.338 -342.16922) (xy 45.373712 -342.210437)
			(xy 45.403195 -342.256316) (xy 45.425849 -342.305924) (xy 45.441213 -342.358251) (xy 45.448974 -342.412232)
			(xy 45.448974 -342.466768) (xy 45.448974 -342.466769) (xy 46.931822 -342.466769) (xy 46.931822 -342.412231)
			(xy 46.939584 -342.358248) (xy 46.954949 -342.305919) (xy 46.977604 -342.25631) (xy 47.007089 -342.210429)
			(xy 47.042803 -342.169212) (xy 47.08402 -342.133496) (xy 47.129899 -342.10401) (xy 47.179508 -342.081353)
			(xy 47.231836 -342.065986) (xy 47.285819 -342.058223) (xy 47.313088 -342.057736) (xy 48.176688 -342.057736)
			(xy 48.203959 -342.058203) (xy 48.257947 -342.065963) (xy 48.310281 -342.081329) (xy 48.359896 -342.103985)
			(xy 48.40578 -342.133472) (xy 48.447002 -342.16919) (xy 48.48272 -342.21041) (xy 48.512209 -342.256294)
			(xy 48.534867 -342.305908) (xy 48.550234 -342.358241) (xy 48.557996 -342.412229) (xy 48.557996 -342.466771)
			(xy 48.557996 -342.466773) (xy 50.0407 -342.466773) (xy 50.0407 -342.412227) (xy 50.048463 -342.358235)
			(xy 50.063832 -342.305899) (xy 50.086493 -342.256282) (xy 50.115985 -342.210396) (xy 50.151708 -342.169174)
			(xy 50.192934 -342.133456) (xy 50.238824 -342.10397) (xy 50.288444 -342.081315) (xy 50.340782 -342.065953)
			(xy 50.394775 -342.058196) (xy 50.422048 -342.057736) (xy 51.285648 -342.057736) (xy 51.312915 -342.05823)
			(xy 51.366893 -342.065997) (xy 51.419217 -342.081366) (xy 51.46882 -342.104025) (xy 51.514695 -342.133512)
			(xy 51.555907 -342.169227) (xy 51.591617 -342.210443) (xy 51.621098 -342.256322) (xy 51.643751 -342.305928)
			(xy 51.659113 -342.358254) (xy 51.666874 -342.412233) (xy 51.666874 -342.466767) (xy 51.666873 -342.466773)
			(xy 60.9909 -342.466773) (xy 60.9909 -342.412227) (xy 60.998663 -342.358236) (xy 61.014031 -342.3059)
			(xy 61.036692 -342.256284) (xy 61.066184 -342.210398) (xy 61.101906 -342.169176) (xy 61.143131 -342.133459)
			(xy 61.18902 -342.103972) (xy 61.238639 -342.081317) (xy 61.290977 -342.065954) (xy 61.344969 -342.058197)
			(xy 61.372242 -342.057736) (xy 62.235842 -342.057736) (xy 62.263109 -342.058229) (xy 62.317088 -342.065996)
			(xy 62.369412 -342.081365) (xy 62.419017 -342.104023) (xy 62.464892 -342.13351) (xy 62.506105 -342.169225)
			(xy 62.541815 -342.210441) (xy 62.571297 -342.25632) (xy 62.59395 -342.305927) (xy 62.609313 -342.358253)
			(xy 62.617074 -342.412233) (xy 62.617074 -342.466767) (xy 62.617073 -342.466771) (xy 64.099899 -342.466771)
			(xy 64.099899 -342.412229) (xy 64.107662 -342.358241) (xy 64.123028 -342.305908) (xy 64.145686 -342.256295)
			(xy 64.175174 -342.210411) (xy 64.210892 -342.16919) (xy 64.252112 -342.133473) (xy 64.297997 -342.103985)
			(xy 64.34761 -342.081327) (xy 64.399943 -342.065961) (xy 64.453931 -342.058199) (xy 64.481202 -342.057736)
			(xy 65.344802 -342.057736) (xy 65.372071 -342.058227) (xy 65.426054 -342.065988) (xy 65.478383 -342.081354)
			(xy 65.527993 -342.10401) (xy 65.573873 -342.133496) (xy 65.615091 -342.169211) (xy 65.650805 -342.210428)
			(xy 65.680291 -342.256309) (xy 65.702947 -342.305919) (xy 65.718312 -342.358248) (xy 65.726074 -342.412231)
			(xy 65.726074 -342.466768) (xy 67.208922 -342.466768) (xy 67.208922 -342.412232) (xy 67.216683 -342.358252)
			(xy 67.232047 -342.305925) (xy 67.2547 -342.256317) (xy 67.284183 -342.210438) (xy 67.319894 -342.169221)
			(xy 67.361107 -342.133505) (xy 67.406984 -342.104018) (xy 67.456589 -342.08136) (xy 67.508914 -342.065991)
			(xy 67.562894 -342.058225) (xy 67.590162 -342.057736) (xy 68.453762 -342.057736) (xy 68.481035 -342.058201)
			(xy 68.535025 -342.065959) (xy 68.587362 -342.081321) (xy 68.63698 -342.103977) (xy 68.682868 -342.133463)
			(xy 68.724093 -342.16918) (xy 68.759814 -342.210401) (xy 68.789305 -342.256287) (xy 68.811965 -342.305902)
			(xy 68.827333 -342.358237) (xy 68.835096 -342.412227) (xy 68.835096 -342.466772) (xy 70.3178 -342.466772)
			(xy 70.3178 -342.412228) (xy 70.325562 -342.358239) (xy 70.34093 -342.305904) (xy 70.363589 -342.256289)
			(xy 70.393079 -342.210404) (xy 70.428799 -342.169183) (xy 70.470022 -342.133466) (xy 70.515909 -342.103979)
			(xy 70.565525 -342.081322) (xy 70.61786 -342.065958) (xy 70.67185 -342.058198) (xy 70.699122 -342.057736)
			(xy 71.562722 -342.057736) (xy 71.58999 -342.058228) (xy 71.643971 -342.065992) (xy 71.696298 -342.081359)
			(xy 71.745905 -342.104017) (xy 71.791783 -342.133503) (xy 71.832998 -342.169218) (xy 71.86871 -342.210435)
			(xy 71.898194 -342.256314) (xy 71.920848 -342.305923) (xy 71.936213 -342.35825) (xy 71.943974 -342.412232)
			(xy 71.943974 -342.466768) (xy 71.943974 -342.466769) (xy 73.426822 -342.466769) (xy 73.426822 -342.412231)
			(xy 73.434584 -342.358249) (xy 73.449948 -342.305921) (xy 73.472603 -342.256311) (xy 73.502087 -342.210431)
			(xy 73.537801 -342.169214) (xy 73.579017 -342.133498) (xy 73.624896 -342.104012) (xy 73.674504 -342.081354)
			(xy 73.726831 -342.065987) (xy 73.780813 -342.058224) (xy 73.808082 -342.057736) (xy 74.671682 -342.057736)
			(xy 74.698954 -342.058202) (xy 74.752942 -342.065962) (xy 74.805277 -342.081327) (xy 74.854892 -342.103983)
			(xy 74.900778 -342.13347) (xy 74.942 -342.169188) (xy 74.977719 -342.210408) (xy 75.007208 -342.256292)
			(xy 75.029867 -342.305906) (xy 75.045234 -342.35824) (xy 75.052996 -342.412228) (xy 75.052996 -342.466772)
			(xy 75.052996 -342.466773) (xy 76.5357 -342.466773) (xy 76.5357 -342.412227) (xy 76.543463 -342.358236)
			(xy 76.558831 -342.3059) (xy 76.581492 -342.256284) (xy 76.610984 -342.210398) (xy 76.646706 -342.169176)
			(xy 76.687931 -342.133459) (xy 76.73382 -342.103972) (xy 76.783439 -342.081317) (xy 76.835777 -342.065954)
			(xy 76.889769 -342.058197) (xy 76.917042 -342.057736) (xy 77.780642 -342.057736) (xy 77.807909 -342.058229)
			(xy 77.861888 -342.065996) (xy 77.914212 -342.081365) (xy 77.963817 -342.104023) (xy 78.009692 -342.13351)
			(xy 78.050905 -342.169225) (xy 78.086615 -342.210441) (xy 78.116097 -342.25632) (xy 78.13875 -342.305927)
			(xy 78.154113 -342.358253) (xy 78.161874 -342.412233) (xy 78.161874 -342.466767) (xy 78.161873 -342.466771)
			(xy 79.644699 -342.466771) (xy 79.644699 -342.412229) (xy 79.652462 -342.358241) (xy 79.667828 -342.305908)
			(xy 79.690486 -342.256295) (xy 79.719974 -342.210411) (xy 79.755692 -342.16919) (xy 79.796912 -342.133473)
			(xy 79.842797 -342.103985) (xy 79.89241 -342.081327) (xy 79.944743 -342.065961) (xy 79.998731 -342.058199)
			(xy 80.026002 -342.057736) (xy 80.889602 -342.057736) (xy 80.916871 -342.058227) (xy 80.970854 -342.065988)
			(xy 81.023183 -342.081354) (xy 81.072793 -342.10401) (xy 81.118673 -342.133496) (xy 81.159891 -342.169211)
			(xy 81.195605 -342.210428) (xy 81.225091 -342.256309) (xy 81.247747 -342.305919) (xy 81.263112 -342.358248)
			(xy 81.270874 -342.412231) (xy 81.270874 -342.466768) (xy 82.753722 -342.466768) (xy 82.753722 -342.412232)
			(xy 82.761483 -342.358252) (xy 82.776847 -342.305925) (xy 82.7995 -342.256317) (xy 82.828983 -342.210438)
			(xy 82.864694 -342.169221) (xy 82.905907 -342.133505) (xy 82.951784 -342.104018) (xy 83.001389 -342.08136)
			(xy 83.053714 -342.065991) (xy 83.107694 -342.058225) (xy 83.134962 -342.057736) (xy 83.998562 -342.057736)
			(xy 84.025835 -342.058201) (xy 84.079825 -342.065959) (xy 84.132162 -342.081321) (xy 84.18178 -342.103977)
			(xy 84.227668 -342.133463) (xy 84.268893 -342.16918) (xy 84.304614 -342.210401) (xy 84.334105 -342.256287)
			(xy 84.356765 -342.305902) (xy 84.372133 -342.358237) (xy 84.379896 -342.412227) (xy 84.379896 -342.466772)
			(xy 85.8626 -342.466772) (xy 85.8626 -342.412228) (xy 85.870362 -342.358239) (xy 85.88573 -342.305904)
			(xy 85.908389 -342.256289) (xy 85.937879 -342.210404) (xy 85.973599 -342.169183) (xy 86.014822 -342.133466)
			(xy 86.060709 -342.103979) (xy 86.110325 -342.081322) (xy 86.16266 -342.065958) (xy 86.21665 -342.058198)
			(xy 86.243922 -342.057736) (xy 87.107522 -342.057736) (xy 87.13479 -342.058228) (xy 87.188771 -342.065992)
			(xy 87.241098 -342.081359) (xy 87.290705 -342.104017) (xy 87.336583 -342.133503) (xy 87.377798 -342.169218)
			(xy 87.41351 -342.210435) (xy 87.442994 -342.256314) (xy 87.465648 -342.305923) (xy 87.481013 -342.35825)
			(xy 87.488774 -342.412232) (xy 87.488774 -342.466768) (xy 87.488774 -342.466769) (xy 88.971622 -342.466769)
			(xy 88.971622 -342.412231) (xy 88.979384 -342.358249) (xy 88.994748 -342.305921) (xy 89.017403 -342.256311)
			(xy 89.046887 -342.210431) (xy 89.082601 -342.169214) (xy 89.123817 -342.133498) (xy 89.169696 -342.104012)
			(xy 89.219304 -342.081354) (xy 89.271631 -342.065987) (xy 89.325613 -342.058224) (xy 89.352882 -342.057736)
			(xy 90.216482 -342.057736) (xy 90.243754 -342.058202) (xy 90.297742 -342.065962) (xy 90.350077 -342.081327)
			(xy 90.399692 -342.103983) (xy 90.445578 -342.13347) (xy 90.4868 -342.169188) (xy 90.522519 -342.210408)
			(xy 90.552008 -342.256292) (xy 90.574667 -342.305906) (xy 90.590034 -342.35824) (xy 90.597796 -342.412228)
			(xy 90.597796 -342.466772) (xy 90.597796 -342.466773) (xy 92.0805 -342.466773) (xy 92.0805 -342.412227)
			(xy 92.088263 -342.358236) (xy 92.103631 -342.3059) (xy 92.126292 -342.256284) (xy 92.155784 -342.210398)
			(xy 92.191506 -342.169176) (xy 92.232731 -342.133459) (xy 92.27862 -342.103972) (xy 92.328239 -342.081317)
			(xy 92.380577 -342.065954) (xy 92.434569 -342.058197) (xy 92.461842 -342.057736) (xy 93.325442 -342.057736)
			(xy 93.352709 -342.058229) (xy 93.406688 -342.065996) (xy 93.459012 -342.081365) (xy 93.508617 -342.104023)
			(xy 93.554492 -342.13351) (xy 93.595705 -342.169225) (xy 93.631415 -342.210441) (xy 93.660897 -342.25632)
			(xy 93.68355 -342.305927) (xy 93.698913 -342.358253) (xy 93.706674 -342.412233) (xy 93.706674 -342.466767)
			(xy 93.698913 -342.520747) (xy 93.68355 -342.573073) (xy 93.660897 -342.62268) (xy 93.631415 -342.668559)
			(xy 93.60914 -342.694268) (xy 102.35157 -342.694268) (xy 102.35157 -342.634332) (xy 102.359393 -342.574909)
			(xy 102.374905 -342.517016) (xy 102.397841 -342.461642) (xy 102.427809 -342.409736) (xy 102.464294 -342.362185)
			(xy 102.506675 -342.319804) (xy 102.554224 -342.283316) (xy 102.60613 -342.253347) (xy 102.661502 -342.23041)
			(xy 102.719395 -342.214896) (xy 102.778818 -342.207071) (xy 102.808786 -342.20658) (xy 103.672386 -342.20658)
			(xy 103.702355 -342.207072) (xy 103.76178 -342.214894) (xy 103.819676 -342.230405) (xy 103.875051 -342.253341)
			(xy 103.926959 -342.283309) (xy 103.974512 -342.319796) (xy 104.016895 -342.362178) (xy 104.053383 -342.409729)
			(xy 104.083352 -342.461636) (xy 104.085479 -342.466772) (xy 111.4808 -342.466772) (xy 111.4808 -342.412228)
			(xy 111.488562 -342.358241) (xy 111.503929 -342.305907) (xy 111.526587 -342.256293) (xy 111.556075 -342.210409)
			(xy 111.591794 -342.169188) (xy 111.633015 -342.133471) (xy 111.6789 -342.103983) (xy 111.728515 -342.081326)
			(xy 111.780848 -342.06596) (xy 111.834836 -342.058199) (xy 111.862108 -342.057736) (xy 112.725708 -342.057736)
			(xy 112.752977 -342.058227) (xy 112.806959 -342.06599) (xy 112.859288 -342.081355) (xy 112.908897 -342.104012)
			(xy 112.954776 -342.133498) (xy 112.995993 -342.169213) (xy 113.031707 -342.21043) (xy 113.061192 -342.256311)
			(xy 113.083847 -342.30592) (xy 113.099212 -342.358249) (xy 113.106974 -342.412231) (xy 113.106974 -342.466768)
			(xy 114.589822 -342.466768) (xy 114.589822 -342.412232) (xy 114.597583 -342.358251) (xy 114.612947 -342.305924)
			(xy 114.635601 -342.256315) (xy 114.665084 -342.210436) (xy 114.700796 -342.169219) (xy 114.74201 -342.133503)
			(xy 114.787887 -342.104016) (xy 114.837494 -342.081358) (xy 114.88982 -342.06599) (xy 114.9438 -342.058225)
			(xy 114.971068 -342.057736) (xy 115.834668 -342.057736) (xy 115.86194 -342.058201) (xy 115.91593 -342.06596)
			(xy 115.968267 -342.081323) (xy 116.017884 -342.103979) (xy 116.063771 -342.133465) (xy 116.104995 -342.169183)
			(xy 116.140715 -342.210403) (xy 116.170206 -342.256288) (xy 116.192866 -342.305903) (xy 116.208233 -342.358238)
			(xy 116.215996 -342.412228) (xy 116.215996 -342.466772) (xy 117.6987 -342.466772) (xy 117.6987 -342.412228)
			(xy 117.706462 -342.358238) (xy 117.72183 -342.305903) (xy 117.74449 -342.256288) (xy 117.77398 -342.210402)
			(xy 117.809701 -342.169181) (xy 117.850925 -342.133464) (xy 117.896812 -342.103977) (xy 117.946429 -342.08132)
			(xy 117.998765 -342.065957) (xy 118.052756 -342.058198) (xy 118.080028 -342.057736) (xy 118.943628 -342.057736)
			(xy 118.970896 -342.058228) (xy 119.024876 -342.065993) (xy 119.077202 -342.081361) (xy 119.126809 -342.104019)
			(xy 119.172686 -342.133505) (xy 119.2139 -342.16922) (xy 119.249612 -342.210437) (xy 119.279095 -342.256316)
			(xy 119.301749 -342.305924) (xy 119.317113 -342.358251) (xy 119.324874 -342.412232) (xy 119.324874 -342.466768)
			(xy 119.324874 -342.466769) (xy 120.807722 -342.466769) (xy 120.807722 -342.412231) (xy 120.815484 -342.358248)
			(xy 120.830849 -342.305919) (xy 120.853504 -342.25631) (xy 120.882989 -342.210429) (xy 120.918703 -342.169212)
			(xy 120.95992 -342.133496) (xy 121.005799 -342.10401) (xy 121.055408 -342.081353) (xy 121.107736 -342.065986)
			(xy 121.161719 -342.058223) (xy 121.188988 -342.057736) (xy 122.052588 -342.057736) (xy 122.079859 -342.058203)
			(xy 122.133847 -342.065963) (xy 122.186181 -342.081329) (xy 122.235796 -342.103985) (xy 122.28168 -342.133472)
			(xy 122.322902 -342.16919) (xy 122.35862 -342.21041) (xy 122.388109 -342.256294) (xy 122.410767 -342.305908)
			(xy 122.426134 -342.358241) (xy 122.433896 -342.412229) (xy 122.433896 -342.466771) (xy 122.433896 -342.466773)
			(xy 123.9166 -342.466773) (xy 123.9166 -342.412227) (xy 123.924363 -342.358235) (xy 123.939732 -342.305899)
			(xy 123.962393 -342.256282) (xy 123.991885 -342.210396) (xy 124.027608 -342.169174) (xy 124.068834 -342.133456)
			(xy 124.114724 -342.10397) (xy 124.164344 -342.081315) (xy 124.216682 -342.065953) (xy 124.270675 -342.058196)
			(xy 124.297948 -342.057736) (xy 125.161548 -342.057736) (xy 125.188815 -342.05823) (xy 125.242793 -342.065997)
			(xy 125.295117 -342.081366) (xy 125.34472 -342.104025) (xy 125.390595 -342.133512) (xy 125.431807 -342.169227)
			(xy 125.467517 -342.210443) (xy 125.496998 -342.256322) (xy 125.519651 -342.305928) (xy 125.535013 -342.358254)
			(xy 125.542774 -342.412233) (xy 125.542774 -342.466767) (xy 125.542773 -342.466772) (xy 127.0256 -342.466772)
			(xy 127.0256 -342.412228) (xy 127.033362 -342.358241) (xy 127.048729 -342.305907) (xy 127.071387 -342.256293)
			(xy 127.100875 -342.210409) (xy 127.136594 -342.169188) (xy 127.177815 -342.133471) (xy 127.2237 -342.103983)
			(xy 127.273315 -342.081326) (xy 127.325648 -342.06596) (xy 127.379636 -342.058199) (xy 127.406908 -342.057736)
			(xy 128.270508 -342.057736) (xy 128.297777 -342.058227) (xy 128.351759 -342.06599) (xy 128.404088 -342.081355)
			(xy 128.453697 -342.104012) (xy 128.499576 -342.133498) (xy 128.540793 -342.169213) (xy 128.576507 -342.21043)
			(xy 128.605992 -342.256311) (xy 128.628647 -342.30592) (xy 128.644012 -342.358249) (xy 128.651774 -342.412231)
			(xy 128.651774 -342.466768) (xy 130.134622 -342.466768) (xy 130.134622 -342.412232) (xy 130.142383 -342.358251)
			(xy 130.157747 -342.305924) (xy 130.180401 -342.256315) (xy 130.209884 -342.210436) (xy 130.245596 -342.169219)
			(xy 130.28681 -342.133503) (xy 130.332687 -342.104016) (xy 130.382294 -342.081358) (xy 130.43462 -342.06599)
			(xy 130.4886 -342.058225) (xy 130.515868 -342.057736) (xy 131.379468 -342.057736) (xy 131.40674 -342.058201)
			(xy 131.46073 -342.06596) (xy 131.513067 -342.081323) (xy 131.562684 -342.103979) (xy 131.608571 -342.133465)
			(xy 131.649795 -342.169183) (xy 131.685515 -342.210403) (xy 131.715006 -342.256288) (xy 131.737666 -342.305903)
			(xy 131.753033 -342.358238) (xy 131.760796 -342.412228) (xy 131.760796 -342.466772) (xy 133.2435 -342.466772)
			(xy 133.2435 -342.412228) (xy 133.251262 -342.358238) (xy 133.26663 -342.305903) (xy 133.28929 -342.256288)
			(xy 133.31878 -342.210402) (xy 133.354501 -342.169181) (xy 133.395725 -342.133464) (xy 133.441612 -342.103977)
			(xy 133.491229 -342.08132) (xy 133.543565 -342.065957) (xy 133.597556 -342.058198) (xy 133.624828 -342.057736)
			(xy 134.488428 -342.057736) (xy 134.515696 -342.058228) (xy 134.569676 -342.065993) (xy 134.622002 -342.081361)
			(xy 134.671609 -342.104019) (xy 134.717486 -342.133505) (xy 134.7587 -342.16922) (xy 134.794412 -342.210437)
			(xy 134.823895 -342.256316) (xy 134.846549 -342.305924) (xy 134.861913 -342.358251) (xy 134.869674 -342.412232)
			(xy 134.869674 -342.466768) (xy 134.869674 -342.466769) (xy 136.352522 -342.466769) (xy 136.352522 -342.412231)
			(xy 136.360284 -342.358248) (xy 136.375649 -342.305919) (xy 136.398304 -342.25631) (xy 136.427789 -342.210429)
			(xy 136.463503 -342.169212) (xy 136.50472 -342.133496) (xy 136.550599 -342.10401) (xy 136.600208 -342.081353)
			(xy 136.652536 -342.065986) (xy 136.706519 -342.058223) (xy 136.733788 -342.057736) (xy 137.597388 -342.057736)
			(xy 137.624659 -342.058203) (xy 137.678647 -342.065963) (xy 137.730981 -342.081329) (xy 137.780596 -342.103985)
			(xy 137.82648 -342.133472) (xy 137.867702 -342.16919) (xy 137.90342 -342.21041) (xy 137.932909 -342.256294)
			(xy 137.955567 -342.305908) (xy 137.970934 -342.358241) (xy 137.978696 -342.412229) (xy 137.978696 -342.466771)
			(xy 137.978696 -342.466773) (xy 139.4614 -342.466773) (xy 139.4614 -342.412227) (xy 139.469163 -342.358235)
			(xy 139.484532 -342.305899) (xy 139.507193 -342.256282) (xy 139.536685 -342.210396) (xy 139.572408 -342.169174)
			(xy 139.613634 -342.133456) (xy 139.659524 -342.10397) (xy 139.709144 -342.081315) (xy 139.761482 -342.065953)
			(xy 139.815475 -342.058196) (xy 139.842748 -342.057736) (xy 140.706348 -342.057736) (xy 140.733615 -342.05823)
			(xy 140.787593 -342.065997) (xy 140.839917 -342.081366) (xy 140.88952 -342.104025) (xy 140.935395 -342.133512)
			(xy 140.976607 -342.169227) (xy 141.012317 -342.210443) (xy 141.041798 -342.256322) (xy 141.064451 -342.305928)
			(xy 141.079813 -342.358254) (xy 141.087574 -342.412233) (xy 141.087574 -342.466767) (xy 141.087573 -342.466772)
			(xy 142.5704 -342.466772) (xy 142.5704 -342.412228) (xy 142.578162 -342.358241) (xy 142.593529 -342.305907)
			(xy 142.616187 -342.256293) (xy 142.645675 -342.210409) (xy 142.681394 -342.169188) (xy 142.722615 -342.133471)
			(xy 142.7685 -342.103983) (xy 142.818115 -342.081326) (xy 142.870448 -342.06596) (xy 142.924436 -342.058199)
			(xy 142.951708 -342.057736) (xy 143.815308 -342.057736) (xy 143.842577 -342.058227) (xy 143.896559 -342.06599)
			(xy 143.948888 -342.081355) (xy 143.998497 -342.104012) (xy 144.044376 -342.133498) (xy 144.085593 -342.169213)
			(xy 144.121307 -342.21043) (xy 144.150792 -342.256311) (xy 144.173447 -342.30592) (xy 144.188812 -342.358249)
			(xy 144.196574 -342.412231) (xy 144.196574 -342.466768) (xy 164.913822 -342.466768) (xy 164.913822 -342.412232)
			(xy 164.921583 -342.35825) (xy 164.936947 -342.305923) (xy 164.959602 -342.256314) (xy 164.989085 -342.210434)
			(xy 165.024797 -342.169217) (xy 165.066012 -342.133502) (xy 165.11189 -342.104015) (xy 165.161496 -342.081357)
			(xy 165.213823 -342.065989) (xy 165.267804 -342.058224) (xy 165.295072 -342.057736) (xy 166.158672 -342.057736)
			(xy 166.185944 -342.058202) (xy 166.239934 -342.06596) (xy 166.29227 -342.081324) (xy 166.341886 -342.10398)
			(xy 166.387773 -342.133467) (xy 166.428996 -342.169184) (xy 166.464716 -342.210405) (xy 166.494207 -342.256289)
			(xy 166.516866 -342.305904) (xy 166.532234 -342.358239) (xy 166.539996 -342.412228) (xy 166.539996 -342.466772)
			(xy 166.539996 -342.466773) (xy 168.0227 -342.466773) (xy 168.0227 -342.412227) (xy 168.030463 -342.358237)
			(xy 168.045831 -342.305902) (xy 168.068491 -342.256286) (xy 168.097981 -342.210401) (xy 168.133702 -342.16918)
			(xy 168.174927 -342.133462) (xy 168.220815 -342.103975) (xy 168.270432 -342.081319) (xy 168.322769 -342.065956)
			(xy 168.376759 -342.058197) (xy 168.404032 -342.057736) (xy 169.267632 -342.057736) (xy 169.2949 -342.058229)
			(xy 169.34888 -342.065994) (xy 169.401205 -342.081362) (xy 169.450811 -342.10402) (xy 169.496688 -342.133506)
			(xy 169.537901 -342.169222) (xy 169.573613 -342.210438) (xy 169.603095 -342.256317) (xy 169.625749 -342.305925)
			(xy 169.641113 -342.358252) (xy 169.648874 -342.412232) (xy 169.648874 -342.466768) (xy 169.648874 -342.466769)
			(xy 171.131722 -342.466769) (xy 171.131722 -342.412231) (xy 171.139484 -342.358248) (xy 171.154849 -342.305918)
			(xy 171.177505 -342.256309) (xy 171.20699 -342.210428) (xy 171.242705 -342.16921) (xy 171.283921 -342.133495)
			(xy 171.329802 -342.104009) (xy 171.379411 -342.081352) (xy 171.43174 -342.065986) (xy 171.485723 -342.058223)
			(xy 171.512992 -342.057736) (xy 172.376592 -342.057736) (xy 172.403863 -342.058203) (xy 172.457851 -342.065964)
			(xy 172.510184 -342.08133) (xy 172.559798 -342.103987) (xy 172.605682 -342.133474) (xy 172.646903 -342.169191)
			(xy 172.682621 -342.210411) (xy 172.71211 -342.256295) (xy 172.734768 -342.305908) (xy 172.750134 -342.358241)
			(xy 172.757896 -342.412229) (xy 172.757896 -342.466767) (xy 174.240722 -342.466767) (xy 174.240722 -342.412233)
			(xy 174.248483 -342.358253) (xy 174.263846 -342.305927) (xy 174.286499 -342.25632) (xy 174.31598 -342.210441)
			(xy 174.35169 -342.169224) (xy 174.392902 -342.133509) (xy 174.438778 -342.104022) (xy 174.488382 -342.081363)
			(xy 174.540706 -342.065993) (xy 174.594685 -342.058226) (xy 174.621952 -342.057736) (xy 175.485552 -342.057736)
			(xy 175.512825 -342.0582) (xy 175.566817 -342.065957) (xy 175.619155 -342.081319) (xy 175.668774 -342.103974)
			(xy 175.714663 -342.13346) (xy 175.755889 -342.169177) (xy 175.791612 -342.210398) (xy 175.821103 -342.256284)
			(xy 175.843764 -342.3059) (xy 175.859133 -342.358236) (xy 175.866896 -342.412227) (xy 175.866896 -342.466772)
			(xy 177.3496 -342.466772) (xy 177.3496 -342.412228) (xy 177.357362 -342.35824) (xy 177.372729 -342.305906)
			(xy 177.395388 -342.256292) (xy 177.424876 -342.210407) (xy 177.460595 -342.169187) (xy 177.501817 -342.133469)
			(xy 177.547703 -342.103982) (xy 177.597317 -342.081325) (xy 177.649652 -342.065959) (xy 177.70364 -342.058199)
			(xy 177.730912 -342.057736) (xy 178.594512 -342.057736) (xy 178.621781 -342.058227) (xy 178.675763 -342.06599)
			(xy 178.728091 -342.081357) (xy 178.777699 -342.104013) (xy 178.823578 -342.133499) (xy 178.864794 -342.169214)
			(xy 178.900508 -342.210432) (xy 178.929992 -342.256312) (xy 178.952648 -342.305921) (xy 178.968012 -342.358249)
			(xy 178.975774 -342.412231) (xy 178.975774 -342.466768) (xy 180.458622 -342.466768) (xy 180.458622 -342.412232)
			(xy 180.466383 -342.35825) (xy 180.481747 -342.305923) (xy 180.504402 -342.256314) (xy 180.533885 -342.210434)
			(xy 180.569597 -342.169217) (xy 180.610812 -342.133502) (xy 180.65669 -342.104015) (xy 180.706296 -342.081357)
			(xy 180.758623 -342.065989) (xy 180.812604 -342.058224) (xy 180.839872 -342.057736) (xy 181.703472 -342.057736)
			(xy 181.730744 -342.058202) (xy 181.784734 -342.06596) (xy 181.83707 -342.081324) (xy 181.886686 -342.10398)
			(xy 181.932573 -342.133467) (xy 181.973796 -342.169184) (xy 182.009516 -342.210405) (xy 182.039007 -342.256289)
			(xy 182.061666 -342.305904) (xy 182.077034 -342.358239) (xy 182.084796 -342.412228) (xy 182.084796 -342.466772)
			(xy 182.084796 -342.466773) (xy 183.5675 -342.466773) (xy 183.5675 -342.412227) (xy 183.575263 -342.358237)
			(xy 183.590631 -342.305902) (xy 183.613291 -342.256286) (xy 183.642781 -342.210401) (xy 183.678502 -342.16918)
			(xy 183.719727 -342.133462) (xy 183.765615 -342.103975) (xy 183.815232 -342.081319) (xy 183.867569 -342.065956)
			(xy 183.921559 -342.058197) (xy 183.948832 -342.057736) (xy 184.812432 -342.057736) (xy 184.8397 -342.058229)
			(xy 184.89368 -342.065994) (xy 184.946005 -342.081362) (xy 184.995611 -342.10402) (xy 185.041488 -342.133506)
			(xy 185.082701 -342.169222) (xy 185.118413 -342.210438) (xy 185.147895 -342.256317) (xy 185.170549 -342.305925)
			(xy 185.185913 -342.358252) (xy 185.193674 -342.412232) (xy 185.193674 -342.466768) (xy 185.193674 -342.466769)
			(xy 186.676522 -342.466769) (xy 186.676522 -342.412231) (xy 186.684284 -342.358248) (xy 186.699649 -342.305918)
			(xy 186.722305 -342.256309) (xy 186.75179 -342.210428) (xy 186.787505 -342.16921) (xy 186.828721 -342.133495)
			(xy 186.874602 -342.104009) (xy 186.924211 -342.081352) (xy 186.97654 -342.065986) (xy 187.030523 -342.058223)
			(xy 187.057792 -342.057736) (xy 187.921392 -342.057736) (xy 187.948663 -342.058203) (xy 188.002651 -342.065964)
			(xy 188.054984 -342.08133) (xy 188.104598 -342.103987) (xy 188.150482 -342.133474) (xy 188.191703 -342.169191)
			(xy 188.227421 -342.210411) (xy 188.25691 -342.256295) (xy 188.279568 -342.305908) (xy 188.294934 -342.358241)
			(xy 188.302696 -342.412229) (xy 188.302696 -342.466767) (xy 189.785522 -342.466767) (xy 189.785522 -342.412233)
			(xy 189.793283 -342.358253) (xy 189.808646 -342.305927) (xy 189.831299 -342.25632) (xy 189.86078 -342.210441)
			(xy 189.89649 -342.169224) (xy 189.937702 -342.133509) (xy 189.983578 -342.104022) (xy 190.033182 -342.081363)
			(xy 190.085506 -342.065993) (xy 190.139485 -342.058226) (xy 190.166752 -342.057736) (xy 191.030352 -342.057736)
			(xy 191.057625 -342.0582) (xy 191.111617 -342.065957) (xy 191.163955 -342.081319) (xy 191.213574 -342.103974)
			(xy 191.259463 -342.13346) (xy 191.300689 -342.169177) (xy 191.336412 -342.210398) (xy 191.365903 -342.256284)
			(xy 191.388564 -342.3059) (xy 191.403933 -342.358236) (xy 191.411696 -342.412227) (xy 191.411696 -342.466772)
			(xy 192.8944 -342.466772) (xy 192.8944 -342.412228) (xy 192.902162 -342.35824) (xy 192.917529 -342.305906)
			(xy 192.940188 -342.256292) (xy 192.969676 -342.210407) (xy 193.005395 -342.169187) (xy 193.046617 -342.133469)
			(xy 193.092503 -342.103982) (xy 193.142117 -342.081325) (xy 193.194452 -342.065959) (xy 193.24844 -342.058199)
			(xy 193.275712 -342.057736) (xy 194.139312 -342.057736) (xy 194.166581 -342.058227) (xy 194.220563 -342.06599)
			(xy 194.272891 -342.081357) (xy 194.322499 -342.104013) (xy 194.368378 -342.133499) (xy 194.409594 -342.169214)
			(xy 194.445308 -342.210432) (xy 194.474792 -342.256312) (xy 194.497448 -342.305921) (xy 194.512812 -342.358249)
			(xy 194.520574 -342.412231) (xy 194.520574 -342.466768) (xy 196.003422 -342.466768) (xy 196.003422 -342.412232)
			(xy 196.011183 -342.35825) (xy 196.026547 -342.305923) (xy 196.049202 -342.256314) (xy 196.078685 -342.210434)
			(xy 196.114397 -342.169217) (xy 196.155612 -342.133502) (xy 196.20149 -342.104015) (xy 196.251096 -342.081357)
			(xy 196.303423 -342.065989) (xy 196.357404 -342.058224) (xy 196.384672 -342.057736) (xy 197.248272 -342.057736)
			(xy 197.275544 -342.058202) (xy 197.28821 -342.060022) (xy 255.91262 -342.060022) (xy 255.91262 -341.196422)
			(xy 255.91311 -341.166438) (xy 255.920938 -341.106982) (xy 255.936459 -341.049057) (xy 255.959408 -340.993653)
			(xy 255.989392 -340.941719) (xy 256.025898 -340.894143) (xy 256.068303 -340.851738) (xy 256.115879 -340.815232)
			(xy 256.167813 -340.785248) (xy 256.223217 -340.762299) (xy 256.281142 -340.746778) (xy 256.340598 -340.73895)
			(xy 256.400566 -340.73895) (xy 256.460022 -340.746778) (xy 256.517947 -340.762299) (xy 256.573351 -340.785248)
			(xy 256.625285 -340.815232) (xy 256.672861 -340.851738) (xy 256.715266 -340.894143) (xy 256.751772 -340.941719)
			(xy 256.781756 -340.993653) (xy 256.804705 -341.049057) (xy 256.820226 -341.106982) (xy 256.828054 -341.166438)
			(xy 256.828544 -341.196422) (xy 256.828544 -342.060022) (xy 256.828054 -342.090006) (xy 256.820226 -342.149462)
			(xy 256.804705 -342.207387) (xy 256.781756 -342.262791) (xy 256.751772 -342.314725) (xy 256.715266 -342.362301)
			(xy 256.672861 -342.404706) (xy 256.625285 -342.441212) (xy 256.581015 -342.466771) (xy 267.515799 -342.466771)
			(xy 267.515799 -342.412229) (xy 267.523562 -342.358241) (xy 267.538928 -342.305908) (xy 267.561586 -342.256295)
			(xy 267.591074 -342.210411) (xy 267.626792 -342.16919) (xy 267.668012 -342.133473) (xy 267.713897 -342.103985)
			(xy 267.76351 -342.081327) (xy 267.815843 -342.065961) (xy 267.869831 -342.058199) (xy 267.897102 -342.057736)
			(xy 268.760702 -342.057736) (xy 268.787971 -342.058227) (xy 268.841954 -342.065988) (xy 268.894283 -342.081354)
			(xy 268.943893 -342.10401) (xy 268.989773 -342.133496) (xy 269.030991 -342.169211) (xy 269.066705 -342.210428)
			(xy 269.096191 -342.256309) (xy 269.118847 -342.305919) (xy 269.134212 -342.358248) (xy 269.141974 -342.412231)
			(xy 269.141974 -342.466768) (xy 270.624822 -342.466768) (xy 270.624822 -342.412232) (xy 270.632583 -342.358252)
			(xy 270.647947 -342.305925) (xy 270.6706 -342.256317) (xy 270.700083 -342.210438) (xy 270.735794 -342.169221)
			(xy 270.777007 -342.133505) (xy 270.822884 -342.104018) (xy 270.872489 -342.08136) (xy 270.924814 -342.065991)
			(xy 270.978794 -342.058225) (xy 271.006062 -342.057736) (xy 271.869662 -342.057736) (xy 271.896935 -342.058201)
			(xy 271.950925 -342.065959) (xy 272.003262 -342.081321) (xy 272.05288 -342.103977) (xy 272.098768 -342.133463)
			(xy 272.139993 -342.16918) (xy 272.175714 -342.210401) (xy 272.205205 -342.256287) (xy 272.227865 -342.305902)
			(xy 272.243233 -342.358237) (xy 272.250996 -342.412227) (xy 272.250996 -342.466772) (xy 273.7337 -342.466772)
			(xy 273.7337 -342.412228) (xy 273.741462 -342.358239) (xy 273.75683 -342.305904) (xy 273.779489 -342.256289)
			(xy 273.808979 -342.210404) (xy 273.844699 -342.169183) (xy 273.885922 -342.133466) (xy 273.931809 -342.103979)
			(xy 273.981425 -342.081322) (xy 274.03376 -342.065958) (xy 274.08775 -342.058198) (xy 274.115022 -342.057736)
			(xy 274.978622 -342.057736) (xy 275.00589 -342.058228) (xy 275.059871 -342.065992) (xy 275.112198 -342.081359)
			(xy 275.161805 -342.104017) (xy 275.207683 -342.133503) (xy 275.248898 -342.169218) (xy 275.28461 -342.210435)
			(xy 275.314094 -342.256314) (xy 275.336748 -342.305923) (xy 275.352113 -342.35825) (xy 275.359874 -342.412232)
			(xy 275.359874 -342.466768) (xy 275.359874 -342.466769) (xy 276.842722 -342.466769) (xy 276.842722 -342.412231)
			(xy 276.850484 -342.358249) (xy 276.865848 -342.305921) (xy 276.888503 -342.256311) (xy 276.917987 -342.210431)
			(xy 276.953701 -342.169214) (xy 276.994917 -342.133498) (xy 277.040796 -342.104012) (xy 277.090404 -342.081354)
			(xy 277.142731 -342.065987) (xy 277.196713 -342.058224) (xy 277.223982 -342.057736) (xy 278.087582 -342.057736)
			(xy 278.114854 -342.058202) (xy 278.168842 -342.065962) (xy 278.221177 -342.081327) (xy 278.270792 -342.103983)
			(xy 278.316678 -342.13347) (xy 278.3579 -342.169188) (xy 278.393619 -342.210408) (xy 278.423108 -342.256292)
			(xy 278.445767 -342.305906) (xy 278.461134 -342.35824) (xy 278.468896 -342.412228) (xy 278.468896 -342.466772)
			(xy 278.468896 -342.466773) (xy 279.9516 -342.466773) (xy 279.9516 -342.412227) (xy 279.959363 -342.358236)
			(xy 279.974731 -342.3059) (xy 279.997392 -342.256284) (xy 280.026884 -342.210398) (xy 280.062606 -342.169176)
			(xy 280.103831 -342.133459) (xy 280.14972 -342.103972) (xy 280.199339 -342.081317) (xy 280.251677 -342.065954)
			(xy 280.305669 -342.058197) (xy 280.332942 -342.057736) (xy 281.196542 -342.057736) (xy 281.223809 -342.058229)
			(xy 281.277788 -342.065996) (xy 281.330112 -342.081365) (xy 281.379717 -342.104023) (xy 281.425592 -342.13351)
			(xy 281.466805 -342.169225) (xy 281.502515 -342.210441) (xy 281.531997 -342.25632) (xy 281.55465 -342.305927)
			(xy 281.570013 -342.358253) (xy 281.577774 -342.412233) (xy 281.577774 -342.466767) (xy 281.577773 -342.466771)
			(xy 283.060599 -342.466771) (xy 283.060599 -342.412229) (xy 283.068362 -342.358241) (xy 283.083728 -342.305908)
			(xy 283.106386 -342.256295) (xy 283.135874 -342.210411) (xy 283.171592 -342.16919) (xy 283.212812 -342.133473)
			(xy 283.258697 -342.103985) (xy 283.30831 -342.081327) (xy 283.360643 -342.065961) (xy 283.414631 -342.058199)
			(xy 283.441902 -342.057736) (xy 284.305502 -342.057736) (xy 284.332771 -342.058227) (xy 284.386754 -342.065988)
			(xy 284.439083 -342.081354) (xy 284.488693 -342.10401) (xy 284.534573 -342.133496) (xy 284.575791 -342.169211)
			(xy 284.611505 -342.210428) (xy 284.640991 -342.256309) (xy 284.663647 -342.305919) (xy 284.679012 -342.358248)
			(xy 284.686774 -342.412231) (xy 284.686774 -342.466768) (xy 286.169622 -342.466768) (xy 286.169622 -342.412232)
			(xy 286.177383 -342.358252) (xy 286.192747 -342.305925) (xy 286.2154 -342.256317) (xy 286.244883 -342.210438)
			(xy 286.280594 -342.169221) (xy 286.321807 -342.133505) (xy 286.367684 -342.104018) (xy 286.417289 -342.08136)
			(xy 286.469614 -342.065991) (xy 286.523594 -342.058225) (xy 286.550862 -342.057736) (xy 287.414462 -342.057736)
			(xy 287.441735 -342.058201) (xy 287.495725 -342.065959) (xy 287.548062 -342.081321) (xy 287.59768 -342.103977)
			(xy 287.643568 -342.133463) (xy 287.684793 -342.16918) (xy 287.720514 -342.210401) (xy 287.750005 -342.256287)
			(xy 287.772665 -342.305902) (xy 287.788033 -342.358237) (xy 287.795796 -342.412227) (xy 287.795796 -342.466772)
			(xy 289.2785 -342.466772) (xy 289.2785 -342.412228) (xy 289.286262 -342.358239) (xy 289.30163 -342.305904)
			(xy 289.324289 -342.256289) (xy 289.353779 -342.210404) (xy 289.389499 -342.169183) (xy 289.430722 -342.133466)
			(xy 289.476609 -342.103979) (xy 289.526225 -342.081322) (xy 289.57856 -342.065958) (xy 289.63255 -342.058198)
			(xy 289.659822 -342.057736) (xy 290.523422 -342.057736) (xy 290.55069 -342.058228) (xy 290.604671 -342.065992)
			(xy 290.656998 -342.081359) (xy 290.706605 -342.104017) (xy 290.752483 -342.133503) (xy 290.793698 -342.169218)
			(xy 290.82941 -342.210435) (xy 290.858894 -342.256314) (xy 290.881548 -342.305923) (xy 290.896913 -342.35825)
			(xy 290.904674 -342.412232) (xy 290.904674 -342.466768) (xy 290.904674 -342.466769) (xy 292.387522 -342.466769)
			(xy 292.387522 -342.412231) (xy 292.395284 -342.358249) (xy 292.410648 -342.305921) (xy 292.433303 -342.256311)
			(xy 292.462787 -342.210431) (xy 292.498501 -342.169214) (xy 292.539717 -342.133498) (xy 292.585596 -342.104012)
			(xy 292.635204 -342.081354) (xy 292.687531 -342.065987) (xy 292.741513 -342.058224) (xy 292.768782 -342.057736)
			(xy 293.632382 -342.057736) (xy 293.659654 -342.058202) (xy 293.713642 -342.065962) (xy 293.765977 -342.081327)
			(xy 293.815592 -342.103983) (xy 293.861478 -342.13347) (xy 293.9027 -342.169188) (xy 293.938419 -342.210408)
			(xy 293.967908 -342.256292) (xy 293.990567 -342.305906) (xy 294.005934 -342.35824) (xy 294.013696 -342.412228)
			(xy 294.013696 -342.466772) (xy 294.013696 -342.466773) (xy 295.4964 -342.466773) (xy 295.4964 -342.412227)
			(xy 295.504163 -342.358236) (xy 295.519531 -342.3059) (xy 295.542192 -342.256284) (xy 295.571684 -342.210398)
			(xy 295.607406 -342.169176) (xy 295.648631 -342.133459) (xy 295.69452 -342.103972) (xy 295.744139 -342.081317)
			(xy 295.796477 -342.065954) (xy 295.850469 -342.058197) (xy 295.877742 -342.057736) (xy 296.741342 -342.057736)
			(xy 296.768609 -342.058229) (xy 296.822588 -342.065996) (xy 296.874912 -342.081365) (xy 296.924517 -342.104023)
			(xy 296.970392 -342.13351) (xy 297.011605 -342.169225) (xy 297.047315 -342.210441) (xy 297.076797 -342.25632)
			(xy 297.09945 -342.305927) (xy 297.114813 -342.358253) (xy 297.122574 -342.412233) (xy 297.122574 -342.466767)
			(xy 297.122573 -342.466771) (xy 298.605399 -342.466771) (xy 298.605399 -342.412229) (xy 298.613162 -342.358241)
			(xy 298.628528 -342.305908) (xy 298.651186 -342.256295) (xy 298.680674 -342.210411) (xy 298.716392 -342.16919)
			(xy 298.757612 -342.133473) (xy 298.803497 -342.103985) (xy 298.85311 -342.081327) (xy 298.905443 -342.065961)
			(xy 298.959431 -342.058199) (xy 298.986702 -342.057736) (xy 299.850302 -342.057736) (xy 299.877571 -342.058227)
			(xy 299.931554 -342.065988) (xy 299.983883 -342.081354) (xy 300.033493 -342.10401) (xy 300.079373 -342.133496)
			(xy 300.120591 -342.169211) (xy 300.156305 -342.210428) (xy 300.185791 -342.256309) (xy 300.208447 -342.305919)
			(xy 300.223812 -342.358248) (xy 300.231574 -342.412231) (xy 300.231574 -342.466769) (xy 300.231574 -342.466771)
			(xy 312.1215 -342.466771) (xy 312.1215 -342.412229) (xy 312.129262 -342.358241) (xy 312.144628 -342.305908)
			(xy 312.167286 -342.256294) (xy 312.196774 -342.21041) (xy 312.232493 -342.16919) (xy 312.273713 -342.133472)
			(xy 312.319598 -342.103984) (xy 312.369212 -342.081327) (xy 312.421545 -342.065961) (xy 312.475533 -342.058199)
			(xy 312.502804 -342.057736) (xy 313.366404 -342.057736) (xy 313.393673 -342.058227) (xy 313.447656 -342.065989)
			(xy 313.499985 -342.081354) (xy 313.549594 -342.104011) (xy 313.595474 -342.133497) (xy 313.636691 -342.169212)
			(xy 313.672406 -342.210429) (xy 313.701891 -342.256309) (xy 313.724547 -342.305919) (xy 313.739912 -342.358248)
			(xy 313.747674 -342.412231) (xy 313.747674 -342.466768) (xy 315.230522 -342.466768) (xy 315.230522 -342.412232)
			(xy 315.238283 -342.358251) (xy 315.253647 -342.305924) (xy 315.2763 -342.256316) (xy 315.305783 -342.210437)
			(xy 315.341495 -342.16922) (xy 315.382708 -342.133505) (xy 315.428585 -342.104018) (xy 315.478191 -342.081359)
			(xy 315.530516 -342.065991) (xy 315.584496 -342.058225) (xy 315.611764 -342.057736) (xy 316.475364 -342.057736)
			(xy 316.502637 -342.058201) (xy 316.556627 -342.065959) (xy 316.608964 -342.081322) (xy 316.658581 -342.103977)
			(xy 316.704469 -342.133464) (xy 316.745693 -342.169181) (xy 316.781414 -342.210402) (xy 316.810905 -342.256287)
			(xy 316.833565 -342.305902) (xy 316.848933 -342.358238) (xy 316.856696 -342.412228) (xy 316.856696 -342.466772)
			(xy 318.3394 -342.466772) (xy 318.3394 -342.412228) (xy 318.347162 -342.358239) (xy 318.36253 -342.305904)
			(xy 318.385189 -342.256289) (xy 318.414679 -342.210404) (xy 318.4504 -342.169183) (xy 318.491623 -342.133465)
			(xy 318.53751 -342.103978) (xy 318.587126 -342.081322) (xy 318.639462 -342.065957) (xy 318.693452 -342.058198)
			(xy 318.720724 -342.057736) (xy 319.584324 -342.057736) (xy 319.611592 -342.058228) (xy 319.665573 -342.065992)
			(xy 319.717899 -342.08136) (xy 319.767506 -342.104017) (xy 319.813384 -342.133504) (xy 319.854598 -342.169219)
			(xy 319.890311 -342.210435) (xy 319.919794 -342.256315) (xy 319.942449 -342.305923) (xy 319.957813 -342.358251)
			(xy 319.965574 -342.412232) (xy 319.965574 -342.466768) (xy 319.965574 -342.466769) (xy 321.448422 -342.466769)
			(xy 321.448422 -342.412231) (xy 321.456184 -342.358249) (xy 321.471548 -342.30592) (xy 321.494203 -342.256311)
			(xy 321.523688 -342.21043) (xy 321.559402 -342.169213) (xy 321.600618 -342.133498) (xy 321.646497 -342.104011)
			(xy 321.696105 -342.081354) (xy 321.748433 -342.065987) (xy 321.802415 -342.058224) (xy 321.829684 -342.057736)
			(xy 322.693284 -342.057736) (xy 322.720556 -342.058202) (xy 322.774544 -342.065963) (xy 322.826878 -342.081327)
			(xy 322.876493 -342.103984) (xy 322.922379 -342.133471) (xy 322.9636 -342.169188) (xy 322.999319 -342.210409)
			(xy 323.028808 -342.256293) (xy 323.051467 -342.305907) (xy 323.066834 -342.35824) (xy 323.074596 -342.412228)
			(xy 323.074596 -342.466772) (xy 323.074596 -342.466773) (xy 324.5573 -342.466773) (xy 324.5573 -342.412227)
			(xy 324.565063 -342.358236) (xy 324.580432 -342.305899) (xy 324.603092 -342.256283) (xy 324.632584 -342.210397)
			(xy 324.668307 -342.169176) (xy 324.709532 -342.133458) (xy 324.755422 -342.103971) (xy 324.805041 -342.081316)
			(xy 324.857379 -342.065954) (xy 324.911371 -342.058196) (xy 324.938644 -342.057736) (xy 325.802244 -342.057736)
			(xy 325.829511 -342.058229) (xy 325.88349 -342.065996) (xy 325.935814 -342.081365) (xy 325.985418 -342.104024)
			(xy 326.031293 -342.133511) (xy 326.072505 -342.169226) (xy 326.108216 -342.210442) (xy 326.137697 -342.256321)
			(xy 326.16035 -342.305928) (xy 326.175713 -342.358253) (xy 326.183474 -342.412233) (xy 326.183474 -342.466767)
			(xy 326.183473 -342.466771) (xy 327.6663 -342.466771) (xy 327.6663 -342.412229) (xy 327.674062 -342.358241)
			(xy 327.689428 -342.305908) (xy 327.712086 -342.256294) (xy 327.741574 -342.21041) (xy 327.777293 -342.16919)
			(xy 327.818513 -342.133472) (xy 327.864398 -342.103984) (xy 327.914012 -342.081327) (xy 327.966345 -342.065961)
			(xy 328.020333 -342.058199) (xy 328.047604 -342.057736) (xy 328.911204 -342.057736) (xy 328.938473 -342.058227)
			(xy 328.992456 -342.065989) (xy 329.044785 -342.081354) (xy 329.094394 -342.104011) (xy 329.140274 -342.133497)
			(xy 329.181491 -342.169212) (xy 329.217206 -342.210429) (xy 329.246691 -342.256309) (xy 329.269347 -342.305919)
			(xy 329.284712 -342.358248) (xy 329.292474 -342.412231) (xy 329.292474 -342.466768) (xy 330.775322 -342.466768)
			(xy 330.775322 -342.412232) (xy 330.783083 -342.358251) (xy 330.798447 -342.305924) (xy 330.8211 -342.256316)
			(xy 330.850583 -342.210437) (xy 330.886295 -342.16922) (xy 330.927508 -342.133505) (xy 330.973385 -342.104018)
			(xy 331.022991 -342.081359) (xy 331.075316 -342.065991) (xy 331.129296 -342.058225) (xy 331.156564 -342.057736)
			(xy 332.020164 -342.057736) (xy 332.047437 -342.058201) (xy 332.101427 -342.065959) (xy 332.153764 -342.081322)
			(xy 332.203381 -342.103977) (xy 332.249269 -342.133464) (xy 332.290493 -342.169181) (xy 332.326214 -342.210402)
			(xy 332.355705 -342.256287) (xy 332.378365 -342.305902) (xy 332.393733 -342.358238) (xy 332.401496 -342.412228)
			(xy 332.401496 -342.466772) (xy 333.8842 -342.466772) (xy 333.8842 -342.412228) (xy 333.891962 -342.358239)
			(xy 333.90733 -342.305904) (xy 333.929989 -342.256289) (xy 333.959479 -342.210404) (xy 333.9952 -342.169183)
			(xy 334.036423 -342.133465) (xy 334.08231 -342.103978) (xy 334.131926 -342.081322) (xy 334.184262 -342.065957)
			(xy 334.238252 -342.058198) (xy 334.265524 -342.057736) (xy 335.129124 -342.057736) (xy 335.156392 -342.058228)
			(xy 335.210373 -342.065992) (xy 335.262699 -342.08136) (xy 335.312306 -342.104017) (xy 335.358184 -342.133504)
			(xy 335.399398 -342.169219) (xy 335.435111 -342.210435) (xy 335.464594 -342.256315) (xy 335.487249 -342.305923)
			(xy 335.502613 -342.358251) (xy 335.510374 -342.412232) (xy 335.510374 -342.466768) (xy 335.510374 -342.466769)
			(xy 336.993222 -342.466769) (xy 336.993222 -342.412231) (xy 337.000984 -342.358249) (xy 337.016348 -342.30592)
			(xy 337.039003 -342.256311) (xy 337.068488 -342.21043) (xy 337.104202 -342.169213) (xy 337.145418 -342.133498)
			(xy 337.191297 -342.104011) (xy 337.240905 -342.081354) (xy 337.293233 -342.065987) (xy 337.347215 -342.058224)
			(xy 337.374484 -342.057736) (xy 338.238084 -342.057736) (xy 338.265356 -342.058202) (xy 338.319344 -342.065963)
			(xy 338.371678 -342.081327) (xy 338.421293 -342.103984) (xy 338.467179 -342.133471) (xy 338.5084 -342.169188)
			(xy 338.544119 -342.210409) (xy 338.573608 -342.256293) (xy 338.596267 -342.305907) (xy 338.611634 -342.35824)
			(xy 338.619396 -342.412228) (xy 338.619396 -342.466772) (xy 338.619396 -342.466773) (xy 340.1021 -342.466773)
			(xy 340.1021 -342.412227) (xy 340.109863 -342.358236) (xy 340.125232 -342.305899) (xy 340.147892 -342.256283)
			(xy 340.177384 -342.210397) (xy 340.213107 -342.169176) (xy 340.254332 -342.133458) (xy 340.300222 -342.103971)
			(xy 340.349841 -342.081316) (xy 340.402179 -342.065954) (xy 340.456171 -342.058196) (xy 340.483444 -342.057736)
			(xy 341.347044 -342.057736) (xy 341.374311 -342.058229) (xy 341.42829 -342.065996) (xy 341.480614 -342.081365)
			(xy 341.530218 -342.104024) (xy 341.576093 -342.133511) (xy 341.617305 -342.169226) (xy 341.653016 -342.210442)
			(xy 341.682497 -342.256321) (xy 341.70515 -342.305928) (xy 341.720513 -342.358253) (xy 341.728274 -342.412233)
			(xy 341.728274 -342.466767) (xy 341.728273 -342.466771) (xy 343.2111 -342.466771) (xy 343.2111 -342.412229)
			(xy 343.218862 -342.358241) (xy 343.234228 -342.305908) (xy 343.256886 -342.256294) (xy 343.286374 -342.21041)
			(xy 343.322093 -342.16919) (xy 343.363313 -342.133472) (xy 343.409198 -342.103984) (xy 343.458812 -342.081327)
			(xy 343.511145 -342.065961) (xy 343.565133 -342.058199) (xy 343.592404 -342.057736) (xy 344.456004 -342.057736)
			(xy 344.483273 -342.058227) (xy 344.537256 -342.065989) (xy 344.589585 -342.081354) (xy 344.639194 -342.104011)
			(xy 344.685074 -342.133497) (xy 344.726291 -342.169212) (xy 344.762006 -342.210429) (xy 344.791491 -342.256309)
			(xy 344.814147 -342.305919) (xy 344.829512 -342.358248) (xy 344.837274 -342.412231) (xy 344.837274 -342.466769)
			(xy 370.806722 -342.466769) (xy 370.806722 -342.412231) (xy 370.814484 -342.358249) (xy 370.829848 -342.305921)
			(xy 370.852503 -342.256312) (xy 370.881987 -342.210432) (xy 370.9177 -342.169214) (xy 370.958916 -342.133499)
			(xy 371.004794 -342.104012) (xy 371.054402 -342.081355) (xy 371.10673 -342.065988) (xy 371.160711 -342.058224)
			(xy 371.18798 -342.057736) (xy 372.05158 -342.057736) (xy 372.078852 -342.058202) (xy 372.132841 -342.065962)
			(xy 372.185175 -342.081326) (xy 372.234791 -342.103983) (xy 372.280677 -342.13347) (xy 372.321899 -342.169187)
			(xy 372.357618 -342.210407) (xy 372.387108 -342.256292) (xy 372.409767 -342.305906) (xy 372.425134 -342.35824)
			(xy 372.432896 -342.412228) (xy 372.432896 -342.466772) (xy 372.432896 -342.466773) (xy 373.9156 -342.466773)
			(xy 373.9156 -342.412227) (xy 373.923363 -342.358236) (xy 373.938731 -342.3059) (xy 373.961392 -342.256284)
			(xy 373.990883 -342.210398) (xy 374.026605 -342.169177) (xy 374.06783 -342.133459) (xy 374.113719 -342.103973)
			(xy 374.163338 -342.081317) (xy 374.215676 -342.065954) (xy 374.269667 -342.058197) (xy 374.29694 -342.057736)
			(xy 375.16054 -342.057736) (xy 375.187807 -342.058229) (xy 375.241786 -342.065995) (xy 375.294111 -342.081364)
			(xy 375.343716 -342.104022) (xy 375.389591 -342.133509) (xy 375.430804 -342.169224) (xy 375.466515 -342.210441)
			(xy 375.495997 -342.256319) (xy 375.51865 -342.305927) (xy 375.534013 -342.358253) (xy 375.541774 -342.412233)
			(xy 375.541774 -342.466767) (xy 375.541774 -342.46677) (xy 377.024622 -342.46677) (xy 377.024622 -342.41223)
			(xy 377.032384 -342.358247) (xy 377.04775 -342.305917) (xy 377.070406 -342.256306) (xy 377.099892 -342.210425)
			(xy 377.135607 -342.169207) (xy 377.176825 -342.133492) (xy 377.222706 -342.104006) (xy 377.272317 -342.08135)
			(xy 377.324647 -342.065984) (xy 377.37863 -342.058222) (xy 377.4059 -342.057736) (xy 378.2695 -342.057736)
			(xy 378.296769 -342.058226) (xy 378.350753 -342.065988) (xy 378.403082 -342.081353) (xy 378.452692 -342.104009)
			(xy 378.498572 -342.133495) (xy 378.53979 -342.16921) (xy 378.575505 -342.210428) (xy 378.604991 -342.256308)
			(xy 378.627647 -342.305918) (xy 378.643012 -342.358247) (xy 378.650774 -342.412231) (xy 378.650774 -342.466768)
			(xy 380.133622 -342.466768) (xy 380.133622 -342.412232) (xy 380.141383 -342.358252) (xy 380.156746 -342.305925)
			(xy 380.1794 -342.256318) (xy 380.208882 -342.210438) (xy 380.244593 -342.169222) (xy 380.285806 -342.133506)
			(xy 380.331682 -342.104019) (xy 380.381288 -342.08136) (xy 380.433613 -342.065991) (xy 380.487592 -342.058225)
			(xy 380.51486 -342.057736) (xy 381.37846 -342.057736) (xy 381.405733 -342.058201) (xy 381.459724 -342.065958)
			(xy 381.512061 -342.081321) (xy 381.561679 -342.103976) (xy 381.607567 -342.133463) (xy 381.648792 -342.16918)
			(xy 381.684513 -342.210401) (xy 381.714005 -342.256286) (xy 381.736665 -342.305902) (xy 381.752033 -342.358237)
			(xy 381.759796 -342.412227) (xy 381.759796 -342.466772) (xy 383.2425 -342.466772) (xy 383.2425 -342.412228)
			(xy 383.250262 -342.358239) (xy 383.26563 -342.305904) (xy 383.288289 -342.25629) (xy 383.317778 -342.210405)
			(xy 383.353498 -342.169184) (xy 383.394721 -342.133466) (xy 383.440607 -342.103979) (xy 383.490223 -342.081323)
			(xy 383.542559 -342.065958) (xy 383.596548 -342.058198) (xy 383.62382 -342.057736) (xy 384.48742 -342.057736)
			(xy 384.514688 -342.058228) (xy 384.568669 -342.065992) (xy 384.620996 -342.081359) (xy 384.670604 -342.104016)
			(xy 384.716482 -342.133502) (xy 384.757697 -342.169217) (xy 384.79341 -342.210434) (xy 384.822894 -342.256314)
			(xy 384.845548 -342.305922) (xy 384.860913 -342.35825) (xy 384.868674 -342.412232) (xy 384.868674 -342.466768)
			(xy 384.868674 -342.466769) (xy 386.351522 -342.466769) (xy 386.351522 -342.412231) (xy 386.359284 -342.358249)
			(xy 386.374648 -342.305921) (xy 386.397303 -342.256312) (xy 386.426787 -342.210432) (xy 386.4625 -342.169214)
			(xy 386.503716 -342.133499) (xy 386.549594 -342.104012) (xy 386.599202 -342.081355) (xy 386.65153 -342.065988)
			(xy 386.705511 -342.058224) (xy 386.73278 -342.057736) (xy 387.59638 -342.057736) (xy 387.623652 -342.058202)
			(xy 387.677641 -342.065962) (xy 387.729975 -342.081326) (xy 387.779591 -342.103983) (xy 387.825477 -342.13347)
			(xy 387.866699 -342.169187) (xy 387.902418 -342.210407) (xy 387.931908 -342.256292) (xy 387.954567 -342.305906)
			(xy 387.969934 -342.35824) (xy 387.977696 -342.412228) (xy 387.977696 -342.466772) (xy 387.977696 -342.466773)
			(xy 389.4604 -342.466773) (xy 389.4604 -342.412227) (xy 389.468163 -342.358236) (xy 389.483531 -342.3059)
			(xy 389.506192 -342.256284) (xy 389.535683 -342.210398) (xy 389.571405 -342.169177) (xy 389.61263 -342.133459)
			(xy 389.658519 -342.103973) (xy 389.708138 -342.081317) (xy 389.760476 -342.065954) (xy 389.814467 -342.058197)
			(xy 389.84174 -342.057736) (xy 390.70534 -342.057736) (xy 390.732607 -342.058229) (xy 390.786586 -342.065995)
			(xy 390.838911 -342.081364) (xy 390.888516 -342.104022) (xy 390.934391 -342.133509) (xy 390.975604 -342.169224)
			(xy 391.011315 -342.210441) (xy 391.040797 -342.256319) (xy 391.06345 -342.305927) (xy 391.078813 -342.358253)
			(xy 391.086574 -342.412233) (xy 391.086574 -342.466767) (xy 391.086574 -342.46677) (xy 392.569422 -342.46677)
			(xy 392.569422 -342.41223) (xy 392.577184 -342.358247) (xy 392.59255 -342.305917) (xy 392.615206 -342.256306)
			(xy 392.644692 -342.210425) (xy 392.680407 -342.169207) (xy 392.721625 -342.133492) (xy 392.767506 -342.104006)
			(xy 392.817117 -342.08135) (xy 392.869447 -342.065984) (xy 392.92343 -342.058222) (xy 392.9507 -342.057736)
			(xy 393.8143 -342.057736) (xy 393.841569 -342.058226) (xy 393.895553 -342.065988) (xy 393.947882 -342.081353)
			(xy 393.997492 -342.104009) (xy 394.043372 -342.133495) (xy 394.08459 -342.16921) (xy 394.120305 -342.210428)
			(xy 394.149791 -342.256308) (xy 394.172447 -342.305918) (xy 394.187812 -342.358247) (xy 394.195574 -342.412231)
			(xy 394.195574 -342.466768) (xy 395.678422 -342.466768) (xy 395.678422 -342.412232) (xy 395.686183 -342.358252)
			(xy 395.701546 -342.305925) (xy 395.7242 -342.256318) (xy 395.753682 -342.210438) (xy 395.789393 -342.169222)
			(xy 395.830606 -342.133506) (xy 395.876482 -342.104019) (xy 395.926088 -342.08136) (xy 395.978413 -342.065991)
			(xy 396.032392 -342.058225) (xy 396.05966 -342.057736) (xy 396.92326 -342.057736) (xy 396.950533 -342.058201)
			(xy 397.004524 -342.065958) (xy 397.056861 -342.081321) (xy 397.106479 -342.103976) (xy 397.152367 -342.133463)
			(xy 397.193592 -342.16918) (xy 397.229313 -342.210401) (xy 397.258805 -342.256286) (xy 397.281465 -342.305902)
			(xy 397.296833 -342.358237) (xy 397.304596 -342.412227) (xy 397.304596 -342.466772) (xy 398.7873 -342.466772)
			(xy 398.7873 -342.412228) (xy 398.795062 -342.358239) (xy 398.81043 -342.305904) (xy 398.833089 -342.25629)
			(xy 398.862578 -342.210405) (xy 398.898298 -342.169184) (xy 398.939521 -342.133466) (xy 398.985407 -342.103979)
			(xy 399.035023 -342.081323) (xy 399.087359 -342.065958) (xy 399.141348 -342.058198) (xy 399.16862 -342.057736)
			(xy 400.03222 -342.057736) (xy 400.059488 -342.058228) (xy 400.113469 -342.065992) (xy 400.165796 -342.081359)
			(xy 400.215404 -342.104016) (xy 400.261282 -342.133502) (xy 400.302497 -342.169217) (xy 400.33821 -342.210434)
			(xy 400.367694 -342.256314) (xy 400.390348 -342.305922) (xy 400.405713 -342.35825) (xy 400.413474 -342.412232)
			(xy 400.413474 -342.466768) (xy 400.413474 -342.466769) (xy 401.896322 -342.466769) (xy 401.896322 -342.412231)
			(xy 401.904084 -342.358249) (xy 401.919448 -342.305921) (xy 401.942103 -342.256312) (xy 401.971587 -342.210432)
			(xy 402.0073 -342.169214) (xy 402.048516 -342.133499) (xy 402.094394 -342.104012) (xy 402.144002 -342.081355)
			(xy 402.19633 -342.065988) (xy 402.250311 -342.058224) (xy 402.27758 -342.057736) (xy 403.14118 -342.057736)
			(xy 403.168452 -342.058202) (xy 403.222441 -342.065962) (xy 403.274775 -342.081326) (xy 403.324391 -342.103983)
			(xy 403.370277 -342.13347) (xy 403.411499 -342.169187) (xy 403.447218 -342.210407) (xy 403.476708 -342.256292)
			(xy 403.499367 -342.305906) (xy 403.514734 -342.35824) (xy 403.522496 -342.412228) (xy 403.522496 -342.466769)
			(xy 408.913822 -342.466769) (xy 408.913822 -342.412231) (xy 408.921584 -342.358248) (xy 408.936949 -342.305918)
			(xy 408.959605 -342.256309) (xy 408.98909 -342.210428) (xy 409.024805 -342.16921) (xy 409.066021 -342.133495)
			(xy 409.111902 -342.104009) (xy 409.161511 -342.081352) (xy 409.21384 -342.065986) (xy 409.267823 -342.058223)
			(xy 409.295092 -342.057736) (xy 410.158692 -342.057736) (xy 410.185963 -342.058203) (xy 410.239951 -342.065964)
			(xy 410.292284 -342.08133) (xy 410.341898 -342.103987) (xy 410.387782 -342.133474) (xy 410.429003 -342.169191)
			(xy 410.464721 -342.210411) (xy 410.49421 -342.256295) (xy 410.516868 -342.305908) (xy 410.532234 -342.358241)
			(xy 410.539996 -342.412229) (xy 410.539996 -342.466767) (xy 412.022822 -342.466767) (xy 412.022822 -342.412233)
			(xy 412.030583 -342.358253) (xy 412.045946 -342.305927) (xy 412.068599 -342.25632) (xy 412.09808 -342.210441)
			(xy 412.13379 -342.169224) (xy 412.175002 -342.133509) (xy 412.220878 -342.104022) (xy 412.270482 -342.081363)
			(xy 412.322806 -342.065993) (xy 412.376785 -342.058226) (xy 412.404052 -342.057736) (xy 413.267652 -342.057736)
			(xy 413.294925 -342.0582) (xy 413.348917 -342.065957) (xy 413.401255 -342.081319) (xy 413.450874 -342.103974)
			(xy 413.496763 -342.13346) (xy 413.537989 -342.169177) (xy 413.573712 -342.210398) (xy 413.603203 -342.256284)
			(xy 413.625864 -342.3059) (xy 413.641233 -342.358236) (xy 413.648996 -342.412227) (xy 413.648996 -342.466772)
			(xy 415.1317 -342.466772) (xy 415.1317 -342.412228) (xy 415.139462 -342.35824) (xy 415.154829 -342.305906)
			(xy 415.177488 -342.256292) (xy 415.206976 -342.210407) (xy 415.242695 -342.169187) (xy 415.283917 -342.133469)
			(xy 415.329803 -342.103982) (xy 415.379417 -342.081325) (xy 415.431752 -342.065959) (xy 415.48574 -342.058199)
			(xy 415.513012 -342.057736) (xy 416.376612 -342.057736) (xy 416.403881 -342.058227) (xy 416.457863 -342.06599)
			(xy 416.510191 -342.081357) (xy 416.559799 -342.104013) (xy 416.605678 -342.133499) (xy 416.646894 -342.169214)
			(xy 416.682608 -342.210432) (xy 416.712092 -342.256312) (xy 416.734748 -342.305921) (xy 416.750112 -342.358249)
			(xy 416.757874 -342.412231) (xy 416.757874 -342.466768) (xy 418.240722 -342.466768) (xy 418.240722 -342.412232)
			(xy 418.248483 -342.35825) (xy 418.263847 -342.305923) (xy 418.286502 -342.256314) (xy 418.315985 -342.210434)
			(xy 418.351697 -342.169217) (xy 418.392912 -342.133502) (xy 418.43879 -342.104015) (xy 418.488396 -342.081357)
			(xy 418.540723 -342.065989) (xy 418.594704 -342.058224) (xy 418.621972 -342.057736) (xy 419.485572 -342.057736)
			(xy 419.512844 -342.058202) (xy 419.566834 -342.06596) (xy 419.61917 -342.081324) (xy 419.668786 -342.10398)
			(xy 419.714673 -342.133467) (xy 419.755896 -342.169184) (xy 419.791616 -342.210405) (xy 419.821107 -342.256289)
			(xy 419.843766 -342.305904) (xy 419.859134 -342.358239) (xy 419.866896 -342.412228) (xy 419.866896 -342.466772)
			(xy 419.866896 -342.466773) (xy 421.3496 -342.466773) (xy 421.3496 -342.412227) (xy 421.357363 -342.358237)
			(xy 421.372731 -342.305902) (xy 421.395391 -342.256286) (xy 421.424881 -342.210401) (xy 421.460602 -342.16918)
			(xy 421.501827 -342.133462) (xy 421.547715 -342.103975) (xy 421.597332 -342.081319) (xy 421.649669 -342.065956)
			(xy 421.703659 -342.058197) (xy 421.730932 -342.057736) (xy 422.594532 -342.057736) (xy 422.6218 -342.058229)
			(xy 422.67578 -342.065994) (xy 422.728105 -342.081362) (xy 422.777711 -342.10402) (xy 422.823588 -342.133506)
			(xy 422.864801 -342.169222) (xy 422.900513 -342.210438) (xy 422.929995 -342.256317) (xy 422.952649 -342.305925)
			(xy 422.968013 -342.358252) (xy 422.975774 -342.412232) (xy 422.975774 -342.466768) (xy 422.975774 -342.466769)
			(xy 424.458622 -342.466769) (xy 424.458622 -342.412231) (xy 424.466384 -342.358248) (xy 424.481749 -342.305918)
			(xy 424.504405 -342.256309) (xy 424.53389 -342.210428) (xy 424.569605 -342.16921) (xy 424.610821 -342.133495)
			(xy 424.656702 -342.104009) (xy 424.706311 -342.081352) (xy 424.75864 -342.065986) (xy 424.812623 -342.058223)
			(xy 424.839892 -342.057736) (xy 425.703492 -342.057736) (xy 425.730763 -342.058203) (xy 425.784751 -342.065964)
			(xy 425.837084 -342.08133) (xy 425.886698 -342.103987) (xy 425.932582 -342.133474) (xy 425.973803 -342.169191)
			(xy 426.009521 -342.210411) (xy 426.03901 -342.256295) (xy 426.061668 -342.305908) (xy 426.077034 -342.358241)
			(xy 426.084796 -342.412229) (xy 426.084796 -342.466767) (xy 427.567622 -342.466767) (xy 427.567622 -342.412233)
			(xy 427.575383 -342.358253) (xy 427.590746 -342.305927) (xy 427.613399 -342.25632) (xy 427.64288 -342.210441)
			(xy 427.67859 -342.169224) (xy 427.719802 -342.133509) (xy 427.765678 -342.104022) (xy 427.815282 -342.081363)
			(xy 427.867606 -342.065993) (xy 427.921585 -342.058226) (xy 427.948852 -342.057736) (xy 428.812452 -342.057736)
			(xy 428.839725 -342.0582) (xy 428.893717 -342.065957) (xy 428.946055 -342.081319) (xy 428.995674 -342.103974)
			(xy 429.041563 -342.13346) (xy 429.082789 -342.169177) (xy 429.118512 -342.210398) (xy 429.148003 -342.256284)
			(xy 429.170664 -342.3059) (xy 429.186033 -342.358236) (xy 429.193796 -342.412227) (xy 429.193796 -342.466772)
			(xy 430.6765 -342.466772) (xy 430.6765 -342.412228) (xy 430.684262 -342.35824) (xy 430.699629 -342.305906)
			(xy 430.722288 -342.256292) (xy 430.751776 -342.210407) (xy 430.787495 -342.169187) (xy 430.828717 -342.133469)
			(xy 430.874603 -342.103982) (xy 430.924217 -342.081325) (xy 430.976552 -342.065959) (xy 431.03054 -342.058199)
			(xy 431.057812 -342.057736) (xy 431.921412 -342.057736) (xy 431.948681 -342.058227) (xy 432.002663 -342.06599)
			(xy 432.054991 -342.081357) (xy 432.104599 -342.104013) (xy 432.150478 -342.133499) (xy 432.191694 -342.169214)
			(xy 432.227408 -342.210432) (xy 432.256892 -342.256312) (xy 432.279548 -342.305921) (xy 432.294912 -342.358249)
			(xy 432.302674 -342.412231) (xy 432.302674 -342.466768) (xy 433.785522 -342.466768) (xy 433.785522 -342.412232)
			(xy 433.793283 -342.35825) (xy 433.808647 -342.305923) (xy 433.831302 -342.256314) (xy 433.860785 -342.210434)
			(xy 433.896497 -342.169217) (xy 433.937712 -342.133502) (xy 433.98359 -342.104015) (xy 434.033196 -342.081357)
			(xy 434.085523 -342.065989) (xy 434.139504 -342.058224) (xy 434.166772 -342.057736) (xy 435.030372 -342.057736)
			(xy 435.057644 -342.058202) (xy 435.111634 -342.06596) (xy 435.16397 -342.081324) (xy 435.213586 -342.10398)
			(xy 435.259473 -342.133467) (xy 435.300696 -342.169184) (xy 435.336416 -342.210405) (xy 435.365907 -342.256289)
			(xy 435.388566 -342.305904) (xy 435.403934 -342.358239) (xy 435.411696 -342.412228) (xy 435.411696 -342.466772)
			(xy 435.411696 -342.466773) (xy 436.8944 -342.466773) (xy 436.8944 -342.412227) (xy 436.902163 -342.358237)
			(xy 436.917531 -342.305902) (xy 436.940191 -342.256286) (xy 436.969681 -342.210401) (xy 437.005402 -342.16918)
			(xy 437.046627 -342.133462) (xy 437.092515 -342.103975) (xy 437.142132 -342.081319) (xy 437.194469 -342.065956)
			(xy 437.248459 -342.058197) (xy 437.275732 -342.057736) (xy 438.139332 -342.057736) (xy 438.1666 -342.058229)
			(xy 438.22058 -342.065994) (xy 438.272905 -342.081362) (xy 438.322511 -342.10402) (xy 438.368388 -342.133506)
			(xy 438.409601 -342.169222) (xy 438.445313 -342.210438) (xy 438.474795 -342.256317) (xy 438.497449 -342.305925)
			(xy 438.512813 -342.358252) (xy 438.520574 -342.412232) (xy 438.520574 -342.466768) (xy 438.520574 -342.466769)
			(xy 440.003422 -342.466769) (xy 440.003422 -342.412231) (xy 440.011184 -342.358248) (xy 440.026549 -342.305918)
			(xy 440.049205 -342.256309) (xy 440.07869 -342.210428) (xy 440.114405 -342.16921) (xy 440.155621 -342.133495)
			(xy 440.201502 -342.104009) (xy 440.251111 -342.081352) (xy 440.30344 -342.065986) (xy 440.357423 -342.058223)
			(xy 440.384692 -342.057736) (xy 441.248292 -342.057736) (xy 441.275563 -342.058203) (xy 441.329551 -342.065964)
			(xy 441.381884 -342.08133) (xy 441.431498 -342.103987) (xy 441.477382 -342.133474) (xy 441.518603 -342.169191)
			(xy 441.554321 -342.210411) (xy 441.58381 -342.256295) (xy 441.606468 -342.305908) (xy 441.621834 -342.358241)
			(xy 441.629596 -342.412229) (xy 441.629596 -342.466771) (xy 441.621834 -342.520759) (xy 441.606468 -342.573092)
			(xy 441.58381 -342.622705) (xy 441.554321 -342.668589) (xy 441.518603 -342.709809) (xy 441.477382 -342.745526)
			(xy 441.431498 -342.775013) (xy 441.381884 -342.79767) (xy 441.329551 -342.813036) (xy 441.275563 -342.820797)
			(xy 441.248292 -342.82126) (xy 440.384692 -342.82126) (xy 440.357423 -342.820777) (xy 440.30344 -342.813014)
			(xy 440.251111 -342.797648) (xy 440.201502 -342.774991) (xy 440.155621 -342.745505) (xy 440.114405 -342.70979)
			(xy 440.07869 -342.668572) (xy 440.049205 -342.622691) (xy 440.026549 -342.573082) (xy 440.011184 -342.520752)
			(xy 440.003422 -342.466769) (xy 438.520574 -342.466769) (xy 438.512813 -342.520748) (xy 438.497449 -342.573075)
			(xy 438.474795 -342.622683) (xy 438.445313 -342.668562) (xy 438.409601 -342.709778) (xy 438.368388 -342.745494)
			(xy 438.322511 -342.77498) (xy 438.272905 -342.797638) (xy 438.22058 -342.813006) (xy 438.1666 -342.820771)
			(xy 438.139332 -342.82126) (xy 437.275732 -342.82126) (xy 437.248459 -342.820803) (xy 437.194469 -342.813044)
			(xy 437.142132 -342.797681) (xy 437.092515 -342.775025) (xy 437.046627 -342.745538) (xy 437.005402 -342.70982)
			(xy 436.969681 -342.668599) (xy 436.940191 -342.622714) (xy 436.917531 -342.573098) (xy 436.902163 -342.520763)
			(xy 436.8944 -342.466773) (xy 435.411696 -342.466773) (xy 435.403934 -342.520761) (xy 435.388566 -342.573096)
			(xy 435.365907 -342.622711) (xy 435.336416 -342.668595) (xy 435.300696 -342.709816) (xy 435.259473 -342.745533)
			(xy 435.213586 -342.77502) (xy 435.16397 -342.797676) (xy 435.111634 -342.81304) (xy 435.057644 -342.820798)
			(xy 435.030372 -342.82126) (xy 434.166772 -342.82126) (xy 434.139504 -342.820776) (xy 434.085523 -342.813011)
			(xy 434.033196 -342.797643) (xy 433.98359 -342.774985) (xy 433.937712 -342.745498) (xy 433.896497 -342.709783)
			(xy 433.860785 -342.668566) (xy 433.831302 -342.622686) (xy 433.808647 -342.573077) (xy 433.793283 -342.52075)
			(xy 433.785522 -342.466768) (xy 432.302674 -342.466768) (xy 432.302674 -342.466769) (xy 432.294912 -342.520751)
			(xy 432.279548 -342.573079) (xy 432.256892 -342.622688) (xy 432.227408 -342.668568) (xy 432.191694 -342.709786)
			(xy 432.150478 -342.745501) (xy 432.104599 -342.774987) (xy 432.054991 -342.797643) (xy 432.002663 -342.81301)
			(xy 431.948681 -342.820773) (xy 431.921412 -342.82126) (xy 431.057812 -342.82126) (xy 431.03054 -342.820801)
			(xy 430.976552 -342.813041) (xy 430.924217 -342.797675) (xy 430.874603 -342.775018) (xy 430.828717 -342.745531)
			(xy 430.787495 -342.709813) (xy 430.751776 -342.668593) (xy 430.722288 -342.622708) (xy 430.699629 -342.573094)
			(xy 430.684262 -342.52076) (xy 430.6765 -342.466772) (xy 429.193796 -342.466772) (xy 429.193796 -342.466773)
			(xy 429.186033 -342.520764) (xy 429.170664 -342.5731) (xy 429.148003 -342.622716) (xy 429.118512 -342.668602)
			(xy 429.082789 -342.709823) (xy 429.041563 -342.74554) (xy 428.995674 -342.775026) (xy 428.946055 -342.797681)
			(xy 428.893717 -342.813043) (xy 428.839725 -342.8208) (xy 428.812452 -342.82126) (xy 427.948852 -342.82126)
			(xy 427.921585 -342.820774) (xy 427.867606 -342.813007) (xy 427.815282 -342.797637) (xy 427.765678 -342.774978)
			(xy 427.719802 -342.745491) (xy 427.67859 -342.709776) (xy 427.64288 -342.668559) (xy 427.613399 -342.62268)
			(xy 427.590746 -342.573073) (xy 427.575383 -342.520747) (xy 427.567622 -342.466767) (xy 426.084796 -342.466767)
			(xy 426.084796 -342.466771) (xy 426.077034 -342.520759) (xy 426.061668 -342.573092) (xy 426.03901 -342.622705)
			(xy 426.009521 -342.668589) (xy 425.973803 -342.709809) (xy 425.932582 -342.745526) (xy 425.886698 -342.775013)
			(xy 425.837084 -342.79767) (xy 425.784751 -342.813036) (xy 425.730763 -342.820797) (xy 425.703492 -342.82126)
			(xy 424.839892 -342.82126) (xy 424.812623 -342.820777) (xy 424.75864 -342.813014) (xy 424.706311 -342.797648)
			(xy 424.656702 -342.774991) (xy 424.610821 -342.745505) (xy 424.569605 -342.70979) (xy 424.53389 -342.668572)
			(xy 424.504405 -342.622691) (xy 424.481749 -342.573082) (xy 424.466384 -342.520752) (xy 424.458622 -342.466769)
			(xy 422.975774 -342.466769) (xy 422.968013 -342.520748) (xy 422.952649 -342.573075) (xy 422.929995 -342.622683)
			(xy 422.900513 -342.668562) (xy 422.864801 -342.709778) (xy 422.823588 -342.745494) (xy 422.777711 -342.77498)
			(xy 422.728105 -342.797638) (xy 422.67578 -342.813006) (xy 422.6218 -342.820771) (xy 422.594532 -342.82126)
			(xy 421.730932 -342.82126) (xy 421.703659 -342.820803) (xy 421.649669 -342.813044) (xy 421.597332 -342.797681)
			(xy 421.547715 -342.775025) (xy 421.501827 -342.745538) (xy 421.460602 -342.70982) (xy 421.424881 -342.668599)
			(xy 421.395391 -342.622714) (xy 421.372731 -342.573098) (xy 421.357363 -342.520763) (xy 421.3496 -342.466773)
			(xy 419.866896 -342.466773) (xy 419.859134 -342.520761) (xy 419.843766 -342.573096) (xy 419.821107 -342.622711)
			(xy 419.791616 -342.668595) (xy 419.755896 -342.709816) (xy 419.714673 -342.745533) (xy 419.668786 -342.77502)
			(xy 419.61917 -342.797676) (xy 419.566834 -342.81304) (xy 419.512844 -342.820798) (xy 419.485572 -342.82126)
			(xy 418.621972 -342.82126) (xy 418.594704 -342.820776) (xy 418.540723 -342.813011) (xy 418.488396 -342.797643)
			(xy 418.43879 -342.774985) (xy 418.392912 -342.745498) (xy 418.351697 -342.709783) (xy 418.315985 -342.668566)
			(xy 418.286502 -342.622686) (xy 418.263847 -342.573077) (xy 418.248483 -342.52075) (xy 418.240722 -342.466768)
			(xy 416.757874 -342.466768) (xy 416.757874 -342.466769) (xy 416.750112 -342.520751) (xy 416.734748 -342.573079)
			(xy 416.712092 -342.622688) (xy 416.682608 -342.668568) (xy 416.646894 -342.709786) (xy 416.605678 -342.745501)
			(xy 416.559799 -342.774987) (xy 416.510191 -342.797643) (xy 416.457863 -342.81301) (xy 416.403881 -342.820773)
			(xy 416.376612 -342.82126) (xy 415.513012 -342.82126) (xy 415.48574 -342.820801) (xy 415.431752 -342.813041)
			(xy 415.379417 -342.797675) (xy 415.329803 -342.775018) (xy 415.283917 -342.745531) (xy 415.242695 -342.709813)
			(xy 415.206976 -342.668593) (xy 415.177488 -342.622708) (xy 415.154829 -342.573094) (xy 415.139462 -342.52076)
			(xy 415.1317 -342.466772) (xy 413.648996 -342.466772) (xy 413.648996 -342.466773) (xy 413.641233 -342.520764)
			(xy 413.625864 -342.5731) (xy 413.603203 -342.622716) (xy 413.573712 -342.668602) (xy 413.537989 -342.709823)
			(xy 413.496763 -342.74554) (xy 413.450874 -342.775026) (xy 413.401255 -342.797681) (xy 413.348917 -342.813043)
			(xy 413.294925 -342.8208) (xy 413.267652 -342.82126) (xy 412.404052 -342.82126) (xy 412.376785 -342.820774)
			(xy 412.322806 -342.813007) (xy 412.270482 -342.797637) (xy 412.220878 -342.774978) (xy 412.175002 -342.745491)
			(xy 412.13379 -342.709776) (xy 412.09808 -342.668559) (xy 412.068599 -342.62268) (xy 412.045946 -342.573073)
			(xy 412.030583 -342.520747) (xy 412.022822 -342.466767) (xy 410.539996 -342.466767) (xy 410.539996 -342.466771)
			(xy 410.532234 -342.520759) (xy 410.516868 -342.573092) (xy 410.49421 -342.622705) (xy 410.464721 -342.668589)
			(xy 410.429003 -342.709809) (xy 410.387782 -342.745526) (xy 410.341898 -342.775013) (xy 410.292284 -342.79767)
			(xy 410.239951 -342.813036) (xy 410.185963 -342.820797) (xy 410.158692 -342.82126) (xy 409.295092 -342.82126)
			(xy 409.267823 -342.820777) (xy 409.21384 -342.813014) (xy 409.161511 -342.797648) (xy 409.111902 -342.774991)
			(xy 409.066021 -342.745505) (xy 409.024805 -342.70979) (xy 408.98909 -342.668572) (xy 408.959605 -342.622691)
			(xy 408.936949 -342.573082) (xy 408.921584 -342.520752) (xy 408.913822 -342.466769) (xy 403.522496 -342.466769)
			(xy 403.522496 -342.466772) (xy 403.514734 -342.52076) (xy 403.499367 -342.573094) (xy 403.476708 -342.622708)
			(xy 403.447218 -342.668593) (xy 403.411499 -342.709813) (xy 403.370277 -342.74553) (xy 403.324391 -342.775017)
			(xy 403.274775 -342.797674) (xy 403.222441 -342.813038) (xy 403.168452 -342.820798) (xy 403.14118 -342.82126)
			(xy 402.27758 -342.82126) (xy 402.250311 -342.820776) (xy 402.19633 -342.813012) (xy 402.144002 -342.797645)
			(xy 402.094394 -342.774988) (xy 402.048516 -342.745501) (xy 402.0073 -342.709786) (xy 401.971587 -342.668568)
			(xy 401.942103 -342.622688) (xy 401.919448 -342.573079) (xy 401.904084 -342.520751) (xy 401.896322 -342.466769)
			(xy 400.413474 -342.466769) (xy 400.405713 -342.52075) (xy 400.390348 -342.573078) (xy 400.367694 -342.622686)
			(xy 400.33821 -342.668566) (xy 400.302497 -342.709783) (xy 400.261282 -342.745498) (xy 400.215404 -342.774984)
			(xy 400.165796 -342.797641) (xy 400.113469 -342.813008) (xy 400.059488 -342.820772) (xy 400.03222 -342.82126)
			(xy 399.16862 -342.82126) (xy 399.141348 -342.820802) (xy 399.087359 -342.813042) (xy 399.035023 -342.797677)
			(xy 398.985407 -342.775021) (xy 398.939521 -342.745534) (xy 398.898298 -342.709816) (xy 398.862578 -342.668595)
			(xy 398.833089 -342.62271) (xy 398.81043 -342.573096) (xy 398.795062 -342.520761) (xy 398.7873 -342.466772)
			(xy 397.304596 -342.466772) (xy 397.304596 -342.466773) (xy 397.296833 -342.520763) (xy 397.281465 -342.573098)
			(xy 397.258805 -342.622714) (xy 397.229313 -342.668599) (xy 397.193592 -342.70982) (xy 397.152367 -342.745537)
			(xy 397.106479 -342.775024) (xy 397.056861 -342.797679) (xy 397.004524 -342.813042) (xy 396.950533 -342.820799)
			(xy 396.92326 -342.82126) (xy 396.05966 -342.82126) (xy 396.032392 -342.820775) (xy 395.978413 -342.813009)
			(xy 395.926088 -342.79764) (xy 395.876482 -342.774981) (xy 395.830606 -342.745494) (xy 395.789393 -342.709778)
			(xy 395.753682 -342.668562) (xy 395.7242 -342.622682) (xy 395.701546 -342.573075) (xy 395.686183 -342.520748)
			(xy 395.678422 -342.466768) (xy 394.195574 -342.466768) (xy 394.195574 -342.466769) (xy 394.187812 -342.520753)
			(xy 394.172447 -342.573082) (xy 394.149791 -342.622692) (xy 394.120305 -342.668572) (xy 394.08459 -342.70979)
			(xy 394.043372 -342.745505) (xy 393.997492 -342.774991) (xy 393.947882 -342.797647) (xy 393.895553 -342.813012)
			(xy 393.841569 -342.820774) (xy 393.8143 -342.82126) (xy 392.9507 -342.82126) (xy 392.92343 -342.820778)
			(xy 392.869447 -342.813016) (xy 392.817117 -342.79765) (xy 392.767506 -342.774994) (xy 392.721625 -342.745508)
			(xy 392.680407 -342.709793) (xy 392.644692 -342.668575) (xy 392.615206 -342.622694) (xy 392.59255 -342.573083)
			(xy 392.577184 -342.520753) (xy 392.569422 -342.46677) (xy 391.086574 -342.46677) (xy 391.078813 -342.520747)
			(xy 391.06345 -342.573073) (xy 391.040797 -342.622681) (xy 391.011315 -342.668559) (xy 390.975604 -342.709776)
			(xy 390.934391 -342.745491) (xy 390.888516 -342.774978) (xy 390.838911 -342.797636) (xy 390.786586 -342.813005)
			(xy 390.732607 -342.820771) (xy 390.70534 -342.82126) (xy 389.84174 -342.82126) (xy 389.814467 -342.820803)
			(xy 389.760476 -342.813046) (xy 389.708138 -342.797683) (xy 389.658519 -342.775027) (xy 389.61263 -342.745541)
			(xy 389.571405 -342.709823) (xy 389.535683 -342.668602) (xy 389.506192 -342.622716) (xy 389.483531 -342.5731)
			(xy 389.468163 -342.520764) (xy 389.4604 -342.466773) (xy 387.977696 -342.466773) (xy 387.969934 -342.52076)
			(xy 387.954567 -342.573094) (xy 387.931908 -342.622708) (xy 387.902418 -342.668593) (xy 387.866699 -342.709813)
			(xy 387.825477 -342.74553) (xy 387.779591 -342.775017) (xy 387.729975 -342.797674) (xy 387.677641 -342.813038)
			(xy 387.623652 -342.820798) (xy 387.59638 -342.82126) (xy 386.73278 -342.82126) (xy 386.705511 -342.820776)
			(xy 386.65153 -342.813012) (xy 386.599202 -342.797645) (xy 386.549594 -342.774988) (xy 386.503716 -342.745501)
			(xy 386.4625 -342.709786) (xy 386.426787 -342.668568) (xy 386.397303 -342.622688) (xy 386.374648 -342.573079)
			(xy 386.359284 -342.520751) (xy 386.351522 -342.466769) (xy 384.868674 -342.466769) (xy 384.860913 -342.52075)
			(xy 384.845548 -342.573078) (xy 384.822894 -342.622686) (xy 384.79341 -342.668566) (xy 384.757697 -342.709783)
			(xy 384.716482 -342.745498) (xy 384.670604 -342.774984) (xy 384.620996 -342.797641) (xy 384.568669 -342.813008)
			(xy 384.514688 -342.820772) (xy 384.48742 -342.82126) (xy 383.62382 -342.82126) (xy 383.596548 -342.820802)
			(xy 383.542559 -342.813042) (xy 383.490223 -342.797677) (xy 383.440607 -342.775021) (xy 383.394721 -342.745534)
			(xy 383.353498 -342.709816) (xy 383.317778 -342.668595) (xy 383.288289 -342.62271) (xy 383.26563 -342.573096)
			(xy 383.250262 -342.520761) (xy 383.2425 -342.466772) (xy 381.759796 -342.466772) (xy 381.759796 -342.466773)
			(xy 381.752033 -342.520763) (xy 381.736665 -342.573098) (xy 381.714005 -342.622714) (xy 381.684513 -342.668599)
			(xy 381.648792 -342.70982) (xy 381.607567 -342.745537) (xy 381.561679 -342.775024) (xy 381.512061 -342.797679)
			(xy 381.459724 -342.813042) (xy 381.405733 -342.820799) (xy 381.37846 -342.82126) (xy 380.51486 -342.82126)
			(xy 380.487592 -342.820775) (xy 380.433613 -342.813009) (xy 380.381288 -342.79764) (xy 380.331682 -342.774981)
			(xy 380.285806 -342.745494) (xy 380.244593 -342.709778) (xy 380.208882 -342.668562) (xy 380.1794 -342.622682)
			(xy 380.156746 -342.573075) (xy 380.141383 -342.520748) (xy 380.133622 -342.466768) (xy 378.650774 -342.466768)
			(xy 378.650774 -342.466769) (xy 378.643012 -342.520753) (xy 378.627647 -342.573082) (xy 378.604991 -342.622692)
			(xy 378.575505 -342.668572) (xy 378.53979 -342.70979) (xy 378.498572 -342.745505) (xy 378.452692 -342.774991)
			(xy 378.403082 -342.797647) (xy 378.350753 -342.813012) (xy 378.296769 -342.820774) (xy 378.2695 -342.82126)
			(xy 377.4059 -342.82126) (xy 377.37863 -342.820778) (xy 377.324647 -342.813016) (xy 377.272317 -342.79765)
			(xy 377.222706 -342.774994) (xy 377.176825 -342.745508) (xy 377.135607 -342.709793) (xy 377.099892 -342.668575)
			(xy 377.070406 -342.622694) (xy 377.04775 -342.573083) (xy 377.032384 -342.520753) (xy 377.024622 -342.46677)
			(xy 375.541774 -342.46677) (xy 375.534013 -342.520747) (xy 375.51865 -342.573073) (xy 375.495997 -342.622681)
			(xy 375.466515 -342.668559) (xy 375.430804 -342.709776) (xy 375.389591 -342.745491) (xy 375.343716 -342.774978)
			(xy 375.294111 -342.797636) (xy 375.241786 -342.813005) (xy 375.187807 -342.820771) (xy 375.16054 -342.82126)
			(xy 374.29694 -342.82126) (xy 374.269667 -342.820803) (xy 374.215676 -342.813046) (xy 374.163338 -342.797683)
			(xy 374.113719 -342.775027) (xy 374.06783 -342.745541) (xy 374.026605 -342.709823) (xy 373.990883 -342.668602)
			(xy 373.961392 -342.622716) (xy 373.938731 -342.5731) (xy 373.923363 -342.520764) (xy 373.9156 -342.466773)
			(xy 372.432896 -342.466773) (xy 372.425134 -342.52076) (xy 372.409767 -342.573094) (xy 372.387108 -342.622708)
			(xy 372.357618 -342.668593) (xy 372.321899 -342.709813) (xy 372.280677 -342.74553) (xy 372.234791 -342.775017)
			(xy 372.185175 -342.797674) (xy 372.132841 -342.813038) (xy 372.078852 -342.820798) (xy 372.05158 -342.82126)
			(xy 371.18798 -342.82126) (xy 371.160711 -342.820776) (xy 371.10673 -342.813012) (xy 371.054402 -342.797645)
			(xy 371.004794 -342.774988) (xy 370.958916 -342.745501) (xy 370.9177 -342.709786) (xy 370.881987 -342.668568)
			(xy 370.852503 -342.622688) (xy 370.829848 -342.573079) (xy 370.814484 -342.520751) (xy 370.806722 -342.466769)
			(xy 344.837274 -342.466769) (xy 344.829512 -342.520752) (xy 344.814147 -342.573081) (xy 344.791491 -342.622691)
			(xy 344.762006 -342.668571) (xy 344.726291 -342.709788) (xy 344.685074 -342.745503) (xy 344.639194 -342.774989)
			(xy 344.589585 -342.797646) (xy 344.537256 -342.813011) (xy 344.483273 -342.820773) (xy 344.456004 -342.82126)
			(xy 343.592404 -342.82126) (xy 343.565133 -342.820801) (xy 343.511145 -342.813039) (xy 343.458812 -342.797673)
			(xy 343.409198 -342.775016) (xy 343.363313 -342.745528) (xy 343.322093 -342.70981) (xy 343.286374 -342.66859)
			(xy 343.256886 -342.622706) (xy 343.234228 -342.573092) (xy 343.218862 -342.520759) (xy 343.2111 -342.466771)
			(xy 341.728273 -342.466771) (xy 341.720513 -342.520747) (xy 341.70515 -342.573072) (xy 341.682497 -342.622679)
			(xy 341.653016 -342.668558) (xy 341.617305 -342.709774) (xy 341.576093 -342.745489) (xy 341.530218 -342.774976)
			(xy 341.480614 -342.797635) (xy 341.42829 -342.813004) (xy 341.374311 -342.820771) (xy 341.347044 -342.82126)
			(xy 340.483444 -342.82126) (xy 340.456171 -342.820804) (xy 340.402179 -342.813046) (xy 340.349841 -342.797684)
			(xy 340.300222 -342.775029) (xy 340.254332 -342.745542) (xy 340.213107 -342.709824) (xy 340.177384 -342.668603)
			(xy 340.147892 -342.622717) (xy 340.125232 -342.573101) (xy 340.109863 -342.520764) (xy 340.1021 -342.466773)
			(xy 338.619396 -342.466773) (xy 338.611634 -342.52076) (xy 338.596267 -342.573093) (xy 338.573608 -342.622707)
			(xy 338.544119 -342.668591) (xy 338.5084 -342.709812) (xy 338.467179 -342.745529) (xy 338.421293 -342.775016)
			(xy 338.371678 -342.797673) (xy 338.319344 -342.813037) (xy 338.265356 -342.820798) (xy 338.238084 -342.82126)
			(xy 337.374484 -342.82126) (xy 337.347215 -342.820776) (xy 337.293233 -342.813013) (xy 337.240905 -342.797646)
			(xy 337.191297 -342.774989) (xy 337.145418 -342.745502) (xy 337.104202 -342.709787) (xy 337.068488 -342.66857)
			(xy 337.039003 -342.622689) (xy 337.016348 -342.57308) (xy 337.000984 -342.520751) (xy 336.993222 -342.466769)
			(xy 335.510374 -342.466769) (xy 335.502613 -342.520749) (xy 335.487249 -342.573077) (xy 335.464594 -342.622685)
			(xy 335.435111 -342.668565) (xy 335.399398 -342.709781) (xy 335.358184 -342.745496) (xy 335.312306 -342.774983)
			(xy 335.262699 -342.79764) (xy 335.210373 -342.813008) (xy 335.156392 -342.820772) (xy 335.129124 -342.82126)
			(xy 334.265524 -342.82126) (xy 334.238252 -342.820802) (xy 334.184262 -342.813043) (xy 334.131926 -342.797678)
			(xy 334.08231 -342.775022) (xy 334.036423 -342.745535) (xy 333.9952 -342.709817) (xy 333.959479 -342.668596)
			(xy 333.929989 -342.622711) (xy 333.90733 -342.573096) (xy 333.891962 -342.520761) (xy 333.8842 -342.466772)
			(xy 332.401496 -342.466772) (xy 332.393733 -342.520762) (xy 332.378365 -342.573098) (xy 332.355705 -342.622713)
			(xy 332.326214 -342.668598) (xy 332.290493 -342.709819) (xy 332.249269 -342.745536) (xy 332.203381 -342.775023)
			(xy 332.153764 -342.797678) (xy 332.101427 -342.813041) (xy 332.047437 -342.820799) (xy 332.020164 -342.82126)
			(xy 331.156564 -342.82126) (xy 331.129296 -342.820775) (xy 331.075316 -342.813009) (xy 331.022991 -342.797641)
			(xy 330.973385 -342.774982) (xy 330.927508 -342.745495) (xy 330.886295 -342.70978) (xy 330.850583 -342.668563)
			(xy 330.8211 -342.622684) (xy 330.798447 -342.573076) (xy 330.783083 -342.520749) (xy 330.775322 -342.466768)
			(xy 329.292474 -342.466768) (xy 329.292474 -342.466769) (xy 329.284712 -342.520752) (xy 329.269347 -342.573081)
			(xy 329.246691 -342.622691) (xy 329.217206 -342.668571) (xy 329.181491 -342.709788) (xy 329.140274 -342.745503)
			(xy 329.094394 -342.774989) (xy 329.044785 -342.797646) (xy 328.992456 -342.813011) (xy 328.938473 -342.820773)
			(xy 328.911204 -342.82126) (xy 328.047604 -342.82126) (xy 328.020333 -342.820801) (xy 327.966345 -342.813039)
			(xy 327.914012 -342.797673) (xy 327.864398 -342.775016) (xy 327.818513 -342.745528) (xy 327.777293 -342.70981)
			(xy 327.741574 -342.66859) (xy 327.712086 -342.622706) (xy 327.689428 -342.573092) (xy 327.674062 -342.520759)
			(xy 327.6663 -342.466771) (xy 326.183473 -342.466771) (xy 326.175713 -342.520747) (xy 326.16035 -342.573072)
			(xy 326.137697 -342.622679) (xy 326.108216 -342.668558) (xy 326.072505 -342.709774) (xy 326.031293 -342.745489)
			(xy 325.985418 -342.774976) (xy 325.935814 -342.797635) (xy 325.88349 -342.813004) (xy 325.829511 -342.820771)
			(xy 325.802244 -342.82126) (xy 324.938644 -342.82126) (xy 324.911371 -342.820804) (xy 324.857379 -342.813046)
			(xy 324.805041 -342.797684) (xy 324.755422 -342.775029) (xy 324.709532 -342.745542) (xy 324.668307 -342.709824)
			(xy 324.632584 -342.668603) (xy 324.603092 -342.622717) (xy 324.580432 -342.573101) (xy 324.565063 -342.520764)
			(xy 324.5573 -342.466773) (xy 323.074596 -342.466773) (xy 323.066834 -342.52076) (xy 323.051467 -342.573093)
			(xy 323.028808 -342.622707) (xy 322.999319 -342.668591) (xy 322.9636 -342.709812) (xy 322.922379 -342.745529)
			(xy 322.876493 -342.775016) (xy 322.826878 -342.797673) (xy 322.774544 -342.813037) (xy 322.720556 -342.820798)
			(xy 322.693284 -342.82126) (xy 321.829684 -342.82126) (xy 321.802415 -342.820776) (xy 321.748433 -342.813013)
			(xy 321.696105 -342.797646) (xy 321.646497 -342.774989) (xy 321.600618 -342.745502) (xy 321.559402 -342.709787)
			(xy 321.523688 -342.66857) (xy 321.494203 -342.622689) (xy 321.471548 -342.57308) (xy 321.456184 -342.520751)
			(xy 321.448422 -342.466769) (xy 319.965574 -342.466769) (xy 319.957813 -342.520749) (xy 319.942449 -342.573077)
			(xy 319.919794 -342.622685) (xy 319.890311 -342.668565) (xy 319.854598 -342.709781) (xy 319.813384 -342.745496)
			(xy 319.767506 -342.774983) (xy 319.717899 -342.79764) (xy 319.665573 -342.813008) (xy 319.611592 -342.820772)
			(xy 319.584324 -342.82126) (xy 318.720724 -342.82126) (xy 318.693452 -342.820802) (xy 318.639462 -342.813043)
			(xy 318.587126 -342.797678) (xy 318.53751 -342.775022) (xy 318.491623 -342.745535) (xy 318.4504 -342.709817)
			(xy 318.414679 -342.668596) (xy 318.385189 -342.622711) (xy 318.36253 -342.573096) (xy 318.347162 -342.520761)
			(xy 318.3394 -342.466772) (xy 316.856696 -342.466772) (xy 316.848933 -342.520762) (xy 316.833565 -342.573098)
			(xy 316.810905 -342.622713) (xy 316.781414 -342.668598) (xy 316.745693 -342.709819) (xy 316.704469 -342.745536)
			(xy 316.658581 -342.775023) (xy 316.608964 -342.797678) (xy 316.556627 -342.813041) (xy 316.502637 -342.820799)
			(xy 316.475364 -342.82126) (xy 315.611764 -342.82126) (xy 315.584496 -342.820775) (xy 315.530516 -342.813009)
			(xy 315.478191 -342.797641) (xy 315.428585 -342.774982) (xy 315.382708 -342.745495) (xy 315.341495 -342.70978)
			(xy 315.305783 -342.668563) (xy 315.2763 -342.622684) (xy 315.253647 -342.573076) (xy 315.238283 -342.520749)
			(xy 315.230522 -342.466768) (xy 313.747674 -342.466768) (xy 313.747674 -342.466769) (xy 313.739912 -342.520752)
			(xy 313.724547 -342.573081) (xy 313.701891 -342.622691) (xy 313.672406 -342.668571) (xy 313.636691 -342.709788)
			(xy 313.595474 -342.745503) (xy 313.549594 -342.774989) (xy 313.499985 -342.797646) (xy 313.447656 -342.813011)
			(xy 313.393673 -342.820773) (xy 313.366404 -342.82126) (xy 312.502804 -342.82126) (xy 312.475533 -342.820801)
			(xy 312.421545 -342.813039) (xy 312.369212 -342.797673) (xy 312.319598 -342.775016) (xy 312.273713 -342.745528)
			(xy 312.232493 -342.70981) (xy 312.196774 -342.66859) (xy 312.167286 -342.622706) (xy 312.144628 -342.573092)
			(xy 312.129262 -342.520759) (xy 312.1215 -342.466771) (xy 300.231574 -342.466771) (xy 300.223812 -342.520752)
			(xy 300.208447 -342.573081) (xy 300.185791 -342.622691) (xy 300.156305 -342.668572) (xy 300.120591 -342.709789)
			(xy 300.079373 -342.745504) (xy 300.033493 -342.77499) (xy 299.983883 -342.797646) (xy 299.931554 -342.813012)
			(xy 299.877571 -342.820773) (xy 299.850302 -342.82126) (xy 298.986702 -342.82126) (xy 298.959431 -342.820801)
			(xy 298.905443 -342.813039) (xy 298.85311 -342.797673) (xy 298.803497 -342.775015) (xy 298.757612 -342.745527)
			(xy 298.716392 -342.70981) (xy 298.680674 -342.668589) (xy 298.651186 -342.622705) (xy 298.628528 -342.573092)
			(xy 298.613162 -342.520759) (xy 298.605399 -342.466771) (xy 297.122573 -342.466771) (xy 297.114813 -342.520747)
			(xy 297.09945 -342.573073) (xy 297.076797 -342.62268) (xy 297.047315 -342.668559) (xy 297.011605 -342.709775)
			(xy 296.970392 -342.74549) (xy 296.924517 -342.774977) (xy 296.874912 -342.797635) (xy 296.822588 -342.813004)
			(xy 296.768609 -342.820771) (xy 296.741342 -342.82126) (xy 295.877742 -342.82126) (xy 295.850469 -342.820803)
			(xy 295.796477 -342.813046) (xy 295.744139 -342.797683) (xy 295.694521 -342.775028) (xy 295.648631 -342.745541)
			(xy 295.607406 -342.709824) (xy 295.571684 -342.668602) (xy 295.542192 -342.622716) (xy 295.519531 -342.5731)
			(xy 295.504163 -342.520764) (xy 295.4964 -342.466773) (xy 294.013696 -342.466773) (xy 294.005934 -342.52076)
			(xy 293.990567 -342.573094) (xy 293.967908 -342.622708) (xy 293.938419 -342.668592) (xy 293.9027 -342.709812)
			(xy 293.861478 -342.74553) (xy 293.815592 -342.775017) (xy 293.765977 -342.797673) (xy 293.713642 -342.813038)
			(xy 293.659654 -342.820798) (xy 293.632382 -342.82126) (xy 292.768782 -342.82126) (xy 292.741513 -342.820776)
			(xy 292.687531 -342.813013) (xy 292.635204 -342.797646) (xy 292.585596 -342.774988) (xy 292.539717 -342.745502)
			(xy 292.498501 -342.709786) (xy 292.462787 -342.668569) (xy 292.433303 -342.622689) (xy 292.410648 -342.573079)
			(xy 292.395284 -342.520751) (xy 292.387522 -342.466769) (xy 290.904674 -342.466769) (xy 290.896913 -342.52075)
			(xy 290.881548 -342.573077) (xy 290.858894 -342.622686) (xy 290.82941 -342.668565) (xy 290.793698 -342.709782)
			(xy 290.752483 -342.745497) (xy 290.706605 -342.774983) (xy 290.656998 -342.797641) (xy 290.604671 -342.813008)
			(xy 290.55069 -342.820772) (xy 290.523422 -342.82126) (xy 289.659822 -342.82126) (xy 289.63255 -342.820802)
			(xy 289.57856 -342.813042) (xy 289.526225 -342.797678) (xy 289.476609 -342.775021) (xy 289.430722 -342.745534)
			(xy 289.389499 -342.709817) (xy 289.353779 -342.668596) (xy 289.324289 -342.622711) (xy 289.30163 -342.573096)
			(xy 289.286262 -342.520761) (xy 289.2785 -342.466772) (xy 287.795796 -342.466772) (xy 287.795796 -342.466773)
			(xy 287.788033 -342.520763) (xy 287.772665 -342.573098) (xy 287.750005 -342.622713) (xy 287.720514 -342.668599)
			(xy 287.684793 -342.70982) (xy 287.643568 -342.745537) (xy 287.59768 -342.775023) (xy 287.548062 -342.797679)
			(xy 287.495725 -342.813041) (xy 287.441735 -342.820799) (xy 287.414462 -342.82126) (xy 286.550862 -342.82126)
			(xy 286.523594 -342.820775) (xy 286.469614 -342.813009) (xy 286.417289 -342.79764) (xy 286.367684 -342.774982)
			(xy 286.321807 -342.745495) (xy 286.280594 -342.709779) (xy 286.244883 -342.668562) (xy 286.2154 -342.622683)
			(xy 286.192747 -342.573075) (xy 286.177383 -342.520748) (xy 286.169622 -342.466768) (xy 284.686774 -342.466768)
			(xy 284.686774 -342.466769) (xy 284.679012 -342.520752) (xy 284.663647 -342.573081) (xy 284.640991 -342.622691)
			(xy 284.611505 -342.668572) (xy 284.575791 -342.709789) (xy 284.534573 -342.745504) (xy 284.488693 -342.77499)
			(xy 284.439083 -342.797646) (xy 284.386754 -342.813012) (xy 284.332771 -342.820773) (xy 284.305502 -342.82126)
			(xy 283.441902 -342.82126) (xy 283.414631 -342.820801) (xy 283.360643 -342.813039) (xy 283.30831 -342.797673)
			(xy 283.258697 -342.775015) (xy 283.212812 -342.745527) (xy 283.171592 -342.70981) (xy 283.135874 -342.668589)
			(xy 283.106386 -342.622705) (xy 283.083728 -342.573092) (xy 283.068362 -342.520759) (xy 283.060599 -342.466771)
			(xy 281.577773 -342.466771) (xy 281.570013 -342.520747) (xy 281.55465 -342.573073) (xy 281.531997 -342.62268)
			(xy 281.502515 -342.668559) (xy 281.466805 -342.709775) (xy 281.425592 -342.74549) (xy 281.379717 -342.774977)
			(xy 281.330112 -342.797635) (xy 281.277788 -342.813004) (xy 281.223809 -342.820771) (xy 281.196542 -342.82126)
			(xy 280.332942 -342.82126) (xy 280.305669 -342.820803) (xy 280.251677 -342.813046) (xy 280.199339 -342.797683)
			(xy 280.149721 -342.775028) (xy 280.103831 -342.745541) (xy 280.062606 -342.709824) (xy 280.026884 -342.668602)
			(xy 279.997392 -342.622716) (xy 279.974731 -342.5731) (xy 279.959363 -342.520764) (xy 279.9516 -342.466773)
			(xy 278.468896 -342.466773) (xy 278.461134 -342.52076) (xy 278.445767 -342.573094) (xy 278.423108 -342.622708)
			(xy 278.393619 -342.668592) (xy 278.3579 -342.709812) (xy 278.316678 -342.74553) (xy 278.270792 -342.775017)
			(xy 278.221177 -342.797673) (xy 278.168842 -342.813038) (xy 278.114854 -342.820798) (xy 278.087582 -342.82126)
			(xy 277.223982 -342.82126) (xy 277.196713 -342.820776) (xy 277.142731 -342.813013) (xy 277.090404 -342.797646)
			(xy 277.040796 -342.774988) (xy 276.994917 -342.745502) (xy 276.953701 -342.709786) (xy 276.917987 -342.668569)
			(xy 276.888503 -342.622689) (xy 276.865848 -342.573079) (xy 276.850484 -342.520751) (xy 276.842722 -342.466769)
			(xy 275.359874 -342.466769) (xy 275.352113 -342.52075) (xy 275.336748 -342.573077) (xy 275.314094 -342.622686)
			(xy 275.28461 -342.668565) (xy 275.248898 -342.709782) (xy 275.207683 -342.745497) (xy 275.161805 -342.774983)
			(xy 275.112198 -342.797641) (xy 275.059871 -342.813008) (xy 275.00589 -342.820772) (xy 274.978622 -342.82126)
			(xy 274.115022 -342.82126) (xy 274.08775 -342.820802) (xy 274.03376 -342.813042) (xy 273.981425 -342.797678)
			(xy 273.931809 -342.775021) (xy 273.885922 -342.745534) (xy 273.844699 -342.709817) (xy 273.808979 -342.668596)
			(xy 273.779489 -342.622711) (xy 273.75683 -342.573096) (xy 273.741462 -342.520761) (xy 273.7337 -342.466772)
			(xy 272.250996 -342.466772) (xy 272.250996 -342.466773) (xy 272.243233 -342.520763) (xy 272.227865 -342.573098)
			(xy 272.205205 -342.622713) (xy 272.175714 -342.668599) (xy 272.139993 -342.70982) (xy 272.098768 -342.745537)
			(xy 272.05288 -342.775023) (xy 272.003262 -342.797679) (xy 271.950925 -342.813041) (xy 271.896935 -342.820799)
			(xy 271.869662 -342.82126) (xy 271.006062 -342.82126) (xy 270.978794 -342.820775) (xy 270.924814 -342.813009)
			(xy 270.872489 -342.79764) (xy 270.822884 -342.774982) (xy 270.777007 -342.745495) (xy 270.735794 -342.709779)
			(xy 270.700083 -342.668562) (xy 270.6706 -342.622683) (xy 270.647947 -342.573075) (xy 270.632583 -342.520748)
			(xy 270.624822 -342.466768) (xy 269.141974 -342.466768) (xy 269.141974 -342.466769) (xy 269.134212 -342.520752)
			(xy 269.118847 -342.573081) (xy 269.096191 -342.622691) (xy 269.066705 -342.668572) (xy 269.030991 -342.709789)
			(xy 268.989773 -342.745504) (xy 268.943893 -342.77499) (xy 268.894283 -342.797646) (xy 268.841954 -342.813012)
			(xy 268.787971 -342.820773) (xy 268.760702 -342.82126) (xy 267.897102 -342.82126) (xy 267.869831 -342.820801)
			(xy 267.815843 -342.813039) (xy 267.76351 -342.797673) (xy 267.713897 -342.775015) (xy 267.668012 -342.745527)
			(xy 267.626792 -342.70981) (xy 267.591074 -342.668589) (xy 267.561586 -342.622705) (xy 267.538928 -342.573092)
			(xy 267.523562 -342.520759) (xy 267.515799 -342.466771) (xy 256.581015 -342.466771) (xy 256.573351 -342.471196)
			(xy 256.517947 -342.494145) (xy 256.460022 -342.509666) (xy 256.400566 -342.517494) (xy 256.340598 -342.517494)
			(xy 256.281142 -342.509666) (xy 256.223217 -342.494145) (xy 256.167813 -342.471196) (xy 256.115879 -342.441212)
			(xy 256.068303 -342.404706) (xy 256.025898 -342.362301) (xy 255.989392 -342.314725) (xy 255.959408 -342.262791)
			(xy 255.936459 -342.207387) (xy 255.920938 -342.149462) (xy 255.91311 -342.090006) (xy 255.91262 -342.060022)
			(xy 197.28821 -342.060022) (xy 197.329534 -342.06596) (xy 197.38187 -342.081324) (xy 197.431486 -342.10398)
			(xy 197.477373 -342.133467) (xy 197.518596 -342.169184) (xy 197.554316 -342.210405) (xy 197.583807 -342.256289)
			(xy 197.606466 -342.305904) (xy 197.621834 -342.358239) (xy 197.629596 -342.412228) (xy 197.629596 -342.466772)
			(xy 197.621834 -342.520761) (xy 197.606466 -342.573096) (xy 197.583807 -342.622711) (xy 197.554316 -342.668595)
			(xy 197.518596 -342.709816) (xy 197.477373 -342.745533) (xy 197.431486 -342.77502) (xy 197.38187 -342.797676)
			(xy 197.329534 -342.81304) (xy 197.275544 -342.820798) (xy 197.248272 -342.82126) (xy 196.384672 -342.82126)
			(xy 196.357404 -342.820776) (xy 196.303423 -342.813011) (xy 196.251096 -342.797643) (xy 196.20149 -342.774985)
			(xy 196.155612 -342.745498) (xy 196.114397 -342.709783) (xy 196.078685 -342.668566) (xy 196.049202 -342.622686)
			(xy 196.026547 -342.573077) (xy 196.011183 -342.52075) (xy 196.003422 -342.466768) (xy 194.520574 -342.466768)
			(xy 194.520574 -342.466769) (xy 194.512812 -342.520751) (xy 194.497448 -342.573079) (xy 194.474792 -342.622688)
			(xy 194.445308 -342.668568) (xy 194.409594 -342.709786) (xy 194.368378 -342.745501) (xy 194.322499 -342.774987)
			(xy 194.272891 -342.797643) (xy 194.220563 -342.81301) (xy 194.166581 -342.820773) (xy 194.139312 -342.82126)
			(xy 193.275712 -342.82126) (xy 193.24844 -342.820801) (xy 193.194452 -342.813041) (xy 193.142117 -342.797675)
			(xy 193.092503 -342.775018) (xy 193.046617 -342.745531) (xy 193.005395 -342.709813) (xy 192.969676 -342.668593)
			(xy 192.940188 -342.622708) (xy 192.917529 -342.573094) (xy 192.902162 -342.52076) (xy 192.8944 -342.466772)
			(xy 191.411696 -342.466772) (xy 191.411696 -342.466773) (xy 191.403933 -342.520764) (xy 191.388564 -342.5731)
			(xy 191.365903 -342.622716) (xy 191.336412 -342.668602) (xy 191.300689 -342.709823) (xy 191.259463 -342.74554)
			(xy 191.213574 -342.775026) (xy 191.163955 -342.797681) (xy 191.111617 -342.813043) (xy 191.057625 -342.8208)
			(xy 191.030352 -342.82126) (xy 190.166752 -342.82126) (xy 190.139485 -342.820774) (xy 190.085506 -342.813007)
			(xy 190.033182 -342.797637) (xy 189.983578 -342.774978) (xy 189.937702 -342.745491) (xy 189.89649 -342.709776)
			(xy 189.86078 -342.668559) (xy 189.831299 -342.62268) (xy 189.808646 -342.573073) (xy 189.793283 -342.520747)
			(xy 189.785522 -342.466767) (xy 188.302696 -342.466767) (xy 188.302696 -342.466771) (xy 188.294934 -342.520759)
			(xy 188.279568 -342.573092) (xy 188.25691 -342.622705) (xy 188.227421 -342.668589) (xy 188.191703 -342.709809)
			(xy 188.150482 -342.745526) (xy 188.104598 -342.775013) (xy 188.054984 -342.79767) (xy 188.002651 -342.813036)
			(xy 187.948663 -342.820797) (xy 187.921392 -342.82126) (xy 187.057792 -342.82126) (xy 187.030523 -342.820777)
			(xy 186.97654 -342.813014) (xy 186.924211 -342.797648) (xy 186.874602 -342.774991) (xy 186.828721 -342.745505)
			(xy 186.787505 -342.70979) (xy 186.75179 -342.668572) (xy 186.722305 -342.622691) (xy 186.699649 -342.573082)
			(xy 186.684284 -342.520752) (xy 186.676522 -342.466769) (xy 185.193674 -342.466769) (xy 185.185913 -342.520748)
			(xy 185.170549 -342.573075) (xy 185.147895 -342.622683) (xy 185.118413 -342.668562) (xy 185.082701 -342.709778)
			(xy 185.041488 -342.745494) (xy 184.995611 -342.77498) (xy 184.946005 -342.797638) (xy 184.89368 -342.813006)
			(xy 184.8397 -342.820771) (xy 184.812432 -342.82126) (xy 183.948832 -342.82126) (xy 183.921559 -342.820803)
			(xy 183.867569 -342.813044) (xy 183.815232 -342.797681) (xy 183.765615 -342.775025) (xy 183.719727 -342.745538)
			(xy 183.678502 -342.70982) (xy 183.642781 -342.668599) (xy 183.613291 -342.622714) (xy 183.590631 -342.573098)
			(xy 183.575263 -342.520763) (xy 183.5675 -342.466773) (xy 182.084796 -342.466773) (xy 182.077034 -342.520761)
			(xy 182.061666 -342.573096) (xy 182.039007 -342.622711) (xy 182.009516 -342.668595) (xy 181.973796 -342.709816)
			(xy 181.932573 -342.745533) (xy 181.886686 -342.77502) (xy 181.83707 -342.797676) (xy 181.784734 -342.81304)
			(xy 181.730744 -342.820798) (xy 181.703472 -342.82126) (xy 180.839872 -342.82126) (xy 180.812604 -342.820776)
			(xy 180.758623 -342.813011) (xy 180.706296 -342.797643) (xy 180.65669 -342.774985) (xy 180.610812 -342.745498)
			(xy 180.569597 -342.709783) (xy 180.533885 -342.668566) (xy 180.504402 -342.622686) (xy 180.481747 -342.573077)
			(xy 180.466383 -342.52075) (xy 180.458622 -342.466768) (xy 178.975774 -342.466768) (xy 178.975774 -342.466769)
			(xy 178.968012 -342.520751) (xy 178.952648 -342.573079) (xy 178.929992 -342.622688) (xy 178.900508 -342.668568)
			(xy 178.864794 -342.709786) (xy 178.823578 -342.745501) (xy 178.777699 -342.774987) (xy 178.728091 -342.797643)
			(xy 178.675763 -342.81301) (xy 178.621781 -342.820773) (xy 178.594512 -342.82126) (xy 177.730912 -342.82126)
			(xy 177.70364 -342.820801) (xy 177.649652 -342.813041) (xy 177.597317 -342.797675) (xy 177.547703 -342.775018)
			(xy 177.501817 -342.745531) (xy 177.460595 -342.709813) (xy 177.424876 -342.668593) (xy 177.395388 -342.622708)
			(xy 177.372729 -342.573094) (xy 177.357362 -342.52076) (xy 177.3496 -342.466772) (xy 175.866896 -342.466772)
			(xy 175.866896 -342.466773) (xy 175.859133 -342.520764) (xy 175.843764 -342.5731) (xy 175.821103 -342.622716)
			(xy 175.791612 -342.668602) (xy 175.755889 -342.709823) (xy 175.714663 -342.74554) (xy 175.668774 -342.775026)
			(xy 175.619155 -342.797681) (xy 175.566817 -342.813043) (xy 175.512825 -342.8208) (xy 175.485552 -342.82126)
			(xy 174.621952 -342.82126) (xy 174.594685 -342.820774) (xy 174.540706 -342.813007) (xy 174.488382 -342.797637)
			(xy 174.438778 -342.774978) (xy 174.392902 -342.745491) (xy 174.35169 -342.709776) (xy 174.31598 -342.668559)
			(xy 174.286499 -342.62268) (xy 174.263846 -342.573073) (xy 174.248483 -342.520747) (xy 174.240722 -342.466767)
			(xy 172.757896 -342.466767) (xy 172.757896 -342.466771) (xy 172.750134 -342.520759) (xy 172.734768 -342.573092)
			(xy 172.71211 -342.622705) (xy 172.682621 -342.668589) (xy 172.646903 -342.709809) (xy 172.605682 -342.745526)
			(xy 172.559798 -342.775013) (xy 172.510184 -342.79767) (xy 172.457851 -342.813036) (xy 172.403863 -342.820797)
			(xy 172.376592 -342.82126) (xy 171.512992 -342.82126) (xy 171.485723 -342.820777) (xy 171.43174 -342.813014)
			(xy 171.379411 -342.797648) (xy 171.329802 -342.774991) (xy 171.283921 -342.745505) (xy 171.242705 -342.70979)
			(xy 171.20699 -342.668572) (xy 171.177505 -342.622691) (xy 171.154849 -342.573082) (xy 171.139484 -342.520752)
			(xy 171.131722 -342.466769) (xy 169.648874 -342.466769) (xy 169.641113 -342.520748) (xy 169.625749 -342.573075)
			(xy 169.603095 -342.622683) (xy 169.573613 -342.668562) (xy 169.537901 -342.709778) (xy 169.496688 -342.745494)
			(xy 169.450811 -342.77498) (xy 169.401205 -342.797638) (xy 169.34888 -342.813006) (xy 169.2949 -342.820771)
			(xy 169.267632 -342.82126) (xy 168.404032 -342.82126) (xy 168.376759 -342.820803) (xy 168.322769 -342.813044)
			(xy 168.270432 -342.797681) (xy 168.220815 -342.775025) (xy 168.174927 -342.745538) (xy 168.133702 -342.70982)
			(xy 168.097981 -342.668599) (xy 168.068491 -342.622714) (xy 168.045831 -342.573098) (xy 168.030463 -342.520763)
			(xy 168.0227 -342.466773) (xy 166.539996 -342.466773) (xy 166.532234 -342.520761) (xy 166.516866 -342.573096)
			(xy 166.494207 -342.622711) (xy 166.464716 -342.668595) (xy 166.428996 -342.709816) (xy 166.387773 -342.745533)
			(xy 166.341886 -342.77502) (xy 166.29227 -342.797676) (xy 166.239934 -342.81304) (xy 166.185944 -342.820798)
			(xy 166.158672 -342.82126) (xy 165.295072 -342.82126) (xy 165.267804 -342.820776) (xy 165.213823 -342.813011)
			(xy 165.161496 -342.797643) (xy 165.11189 -342.774985) (xy 165.066012 -342.745498) (xy 165.024797 -342.709783)
			(xy 164.989085 -342.668566) (xy 164.959602 -342.622686) (xy 164.936947 -342.573077) (xy 164.921583 -342.52075)
			(xy 164.913822 -342.466768) (xy 144.196574 -342.466768) (xy 144.196574 -342.466769) (xy 144.188812 -342.520751)
			(xy 144.173447 -342.57308) (xy 144.150792 -342.622689) (xy 144.121307 -342.66857) (xy 144.085593 -342.709787)
			(xy 144.044376 -342.745502) (xy 143.998497 -342.774988) (xy 143.948888 -342.797645) (xy 143.896559 -342.81301)
			(xy 143.842577 -342.820773) (xy 143.815308 -342.82126) (xy 142.951708 -342.82126) (xy 142.924436 -342.820801)
			(xy 142.870448 -342.81304) (xy 142.818115 -342.797674) (xy 142.7685 -342.775017) (xy 142.722615 -342.745529)
			(xy 142.681394 -342.709812) (xy 142.645675 -342.668591) (xy 142.616187 -342.622707) (xy 142.593529 -342.573093)
			(xy 142.578162 -342.520759) (xy 142.5704 -342.466772) (xy 141.087573 -342.466772) (xy 141.079813 -342.520746)
			(xy 141.064451 -342.573072) (xy 141.041798 -342.622678) (xy 141.012317 -342.668557) (xy 140.976607 -342.709773)
			(xy 140.935395 -342.745488) (xy 140.88952 -342.774975) (xy 140.839917 -342.797634) (xy 140.787593 -342.813003)
			(xy 140.733615 -342.82077) (xy 140.706348 -342.82126) (xy 139.842748 -342.82126) (xy 139.815475 -342.820804)
			(xy 139.761482 -342.813047) (xy 139.709144 -342.797685) (xy 139.659524 -342.77503) (xy 139.613634 -342.745544)
			(xy 139.572408 -342.709826) (xy 139.536685 -342.668604) (xy 139.507193 -342.622718) (xy 139.484532 -342.573101)
			(xy 139.469163 -342.520765) (xy 139.4614 -342.466773) (xy 137.978696 -342.466773) (xy 137.970934 -342.520759)
			(xy 137.955567 -342.573092) (xy 137.932909 -342.622706) (xy 137.90342 -342.66859) (xy 137.867702 -342.70981)
			(xy 137.82648 -342.745528) (xy 137.780596 -342.775015) (xy 137.730981 -342.797671) (xy 137.678647 -342.813037)
			(xy 137.624659 -342.820797) (xy 137.597388 -342.82126) (xy 136.733788 -342.82126) (xy 136.706519 -342.820777)
			(xy 136.652536 -342.813014) (xy 136.600208 -342.797647) (xy 136.550599 -342.77499) (xy 136.50472 -342.745504)
			(xy 136.463503 -342.709788) (xy 136.427789 -342.668571) (xy 136.398304 -342.62269) (xy 136.375649 -342.573081)
			(xy 136.360284 -342.520752) (xy 136.352522 -342.466769) (xy 134.869674 -342.466769) (xy 134.861913 -342.520749)
			(xy 134.846549 -342.573076) (xy 134.823895 -342.622684) (xy 134.794412 -342.668563) (xy 134.7587 -342.70978)
			(xy 134.717486 -342.745495) (xy 134.671609 -342.774981) (xy 134.622002 -342.797639) (xy 134.569676 -342.813007)
			(xy 134.515696 -342.820772) (xy 134.488428 -342.82126) (xy 133.624828 -342.82126) (xy 133.597556 -342.820802)
			(xy 133.543565 -342.813043) (xy 133.491229 -342.79768) (xy 133.441612 -342.775023) (xy 133.395725 -342.745536)
			(xy 133.354501 -342.709819) (xy 133.31878 -342.668598) (xy 133.28929 -342.622712) (xy 133.26663 -342.573097)
			(xy 133.251262 -342.520762) (xy 133.2435 -342.466772) (xy 131.760796 -342.466772) (xy 131.753033 -342.520762)
			(xy 131.737666 -342.573097) (xy 131.715006 -342.622712) (xy 131.685515 -342.668597) (xy 131.649795 -342.709817)
			(xy 131.608571 -342.745535) (xy 131.562684 -342.775021) (xy 131.513067 -342.797677) (xy 131.46073 -342.81304)
			(xy 131.40674 -342.820799) (xy 131.379468 -342.82126) (xy 130.515868 -342.82126) (xy 130.4886 -342.820775)
			(xy 130.43462 -342.81301) (xy 130.382294 -342.797642) (xy 130.332687 -342.774984) (xy 130.28681 -342.745497)
			(xy 130.245596 -342.709781) (xy 130.209884 -342.668564) (xy 130.180401 -342.622685) (xy 130.157747 -342.573076)
			(xy 130.142383 -342.520749) (xy 130.134622 -342.466768) (xy 128.651774 -342.466768) (xy 128.651774 -342.466769)
			(xy 128.644012 -342.520751) (xy 128.628647 -342.57308) (xy 128.605992 -342.622689) (xy 128.576507 -342.66857)
			(xy 128.540793 -342.709787) (xy 128.499576 -342.745502) (xy 128.453697 -342.774988) (xy 128.404088 -342.797645)
			(xy 128.351759 -342.81301) (xy 128.297777 -342.820773) (xy 128.270508 -342.82126) (xy 127.406908 -342.82126)
			(xy 127.379636 -342.820801) (xy 127.325648 -342.81304) (xy 127.273315 -342.797674) (xy 127.2237 -342.775017)
			(xy 127.177815 -342.745529) (xy 127.136594 -342.709812) (xy 127.100875 -342.668591) (xy 127.071387 -342.622707)
			(xy 127.048729 -342.573093) (xy 127.033362 -342.520759) (xy 127.0256 -342.466772) (xy 125.542773 -342.466772)
			(xy 125.535013 -342.520746) (xy 125.519651 -342.573072) (xy 125.496998 -342.622678) (xy 125.467517 -342.668557)
			(xy 125.431807 -342.709773) (xy 125.390595 -342.745488) (xy 125.34472 -342.774975) (xy 125.295117 -342.797634)
			(xy 125.242793 -342.813003) (xy 125.188815 -342.82077) (xy 125.161548 -342.82126) (xy 124.297948 -342.82126)
			(xy 124.270675 -342.820804) (xy 124.216682 -342.813047) (xy 124.164344 -342.797685) (xy 124.114724 -342.77503)
			(xy 124.068834 -342.745544) (xy 124.027608 -342.709826) (xy 123.991885 -342.668604) (xy 123.962393 -342.622718)
			(xy 123.939732 -342.573101) (xy 123.924363 -342.520765) (xy 123.9166 -342.466773) (xy 122.433896 -342.466773)
			(xy 122.426134 -342.520759) (xy 122.410767 -342.573092) (xy 122.388109 -342.622706) (xy 122.35862 -342.66859)
			(xy 122.322902 -342.70981) (xy 122.28168 -342.745528) (xy 122.235796 -342.775015) (xy 122.186181 -342.797671)
			(xy 122.133847 -342.813037) (xy 122.079859 -342.820797) (xy 122.052588 -342.82126) (xy 121.188988 -342.82126)
			(xy 121.161719 -342.820777) (xy 121.107736 -342.813014) (xy 121.055408 -342.797647) (xy 121.005799 -342.77499)
			(xy 120.95992 -342.745504) (xy 120.918703 -342.709788) (xy 120.882989 -342.668571) (xy 120.853504 -342.62269)
			(xy 120.830849 -342.573081) (xy 120.815484 -342.520752) (xy 120.807722 -342.466769) (xy 119.324874 -342.466769)
			(xy 119.317113 -342.520749) (xy 119.301749 -342.573076) (xy 119.279095 -342.622684) (xy 119.249612 -342.668563)
			(xy 119.2139 -342.70978) (xy 119.172686 -342.745495) (xy 119.126809 -342.774981) (xy 119.077202 -342.797639)
			(xy 119.024876 -342.813007) (xy 118.970896 -342.820772) (xy 118.943628 -342.82126) (xy 118.080028 -342.82126)
			(xy 118.052756 -342.820802) (xy 117.998765 -342.813043) (xy 117.946429 -342.79768) (xy 117.896812 -342.775023)
			(xy 117.850925 -342.745536) (xy 117.809701 -342.709819) (xy 117.77398 -342.668598) (xy 117.74449 -342.622712)
			(xy 117.72183 -342.573097) (xy 117.706462 -342.520762) (xy 117.6987 -342.466772) (xy 116.215996 -342.466772)
			(xy 116.208233 -342.520762) (xy 116.192866 -342.573097) (xy 116.170206 -342.622712) (xy 116.140715 -342.668597)
			(xy 116.104995 -342.709817) (xy 116.063771 -342.745535) (xy 116.017884 -342.775021) (xy 115.968267 -342.797677)
			(xy 115.91593 -342.81304) (xy 115.86194 -342.820799) (xy 115.834668 -342.82126) (xy 114.971068 -342.82126)
			(xy 114.9438 -342.820775) (xy 114.88982 -342.81301) (xy 114.837494 -342.797642) (xy 114.787887 -342.774984)
			(xy 114.74201 -342.745497) (xy 114.700796 -342.709781) (xy 114.665084 -342.668564) (xy 114.635601 -342.622685)
			(xy 114.612947 -342.573076) (xy 114.597583 -342.520749) (xy 114.589822 -342.466768) (xy 113.106974 -342.466768)
			(xy 113.106974 -342.466769) (xy 113.099212 -342.520751) (xy 113.083847 -342.57308) (xy 113.061192 -342.622689)
			(xy 113.031707 -342.66857) (xy 112.995993 -342.709787) (xy 112.954776 -342.745502) (xy 112.908897 -342.774988)
			(xy 112.859288 -342.797645) (xy 112.806959 -342.81301) (xy 112.752977 -342.820773) (xy 112.725708 -342.82126)
			(xy 111.862108 -342.82126) (xy 111.834836 -342.820801) (xy 111.780848 -342.81304) (xy 111.728515 -342.797674)
			(xy 111.6789 -342.775017) (xy 111.633015 -342.745529) (xy 111.591794 -342.709812) (xy 111.556075 -342.668591)
			(xy 111.526587 -342.622707) (xy 111.503929 -342.573093) (xy 111.488562 -342.520759) (xy 111.4808 -342.466772)
			(xy 104.085479 -342.466772) (xy 104.10629 -342.517011) (xy 104.121803 -342.574906) (xy 104.129627 -342.634331)
			(xy 104.129627 -342.694269) (xy 104.121803 -342.753694) (xy 104.10629 -342.811589) (xy 104.083352 -342.866964)
			(xy 104.053383 -342.918871) (xy 104.016895 -342.966422) (xy 103.974512 -343.008804) (xy 103.926959 -343.045291)
			(xy 103.875051 -343.075259) (xy 103.819676 -343.098195) (xy 103.76178 -343.113706) (xy 103.702355 -343.121528)
			(xy 103.672386 -343.121996) (xy 102.808786 -343.121996) (xy 102.778818 -343.121529) (xy 102.719395 -343.113704)
			(xy 102.661502 -343.09819) (xy 102.60613 -343.075253) (xy 102.554224 -343.045284) (xy 102.506675 -343.008796)
			(xy 102.464294 -342.966415) (xy 102.427809 -342.918864) (xy 102.397841 -342.866958) (xy 102.374905 -342.811584)
			(xy 102.359393 -342.753691) (xy 102.35157 -342.694268) (xy 93.60914 -342.694268) (xy 93.595705 -342.709775)
			(xy 93.554492 -342.74549) (xy 93.508617 -342.774977) (xy 93.459012 -342.797635) (xy 93.406688 -342.813004)
			(xy 93.352709 -342.820771) (xy 93.325442 -342.82126) (xy 92.461842 -342.82126) (xy 92.434569 -342.820803)
			(xy 92.380577 -342.813046) (xy 92.328239 -342.797683) (xy 92.278621 -342.775028) (xy 92.232731 -342.745541)
			(xy 92.191506 -342.709824) (xy 92.155784 -342.668602) (xy 92.126292 -342.622716) (xy 92.103631 -342.5731)
			(xy 92.088263 -342.520764) (xy 92.0805 -342.466773) (xy 90.597796 -342.466773) (xy 90.590034 -342.52076)
			(xy 90.574667 -342.573094) (xy 90.552008 -342.622708) (xy 90.522519 -342.668592) (xy 90.4868 -342.709812)
			(xy 90.445578 -342.74553) (xy 90.399692 -342.775017) (xy 90.350077 -342.797673) (xy 90.297742 -342.813038)
			(xy 90.243754 -342.820798) (xy 90.216482 -342.82126) (xy 89.352882 -342.82126) (xy 89.325613 -342.820776)
			(xy 89.271631 -342.813013) (xy 89.219304 -342.797646) (xy 89.169696 -342.774988) (xy 89.123817 -342.745502)
			(xy 89.082601 -342.709786) (xy 89.046887 -342.668569) (xy 89.017403 -342.622689) (xy 88.994748 -342.573079)
			(xy 88.979384 -342.520751) (xy 88.971622 -342.466769) (xy 87.488774 -342.466769) (xy 87.481013 -342.52075)
			(xy 87.465648 -342.573077) (xy 87.442994 -342.622686) (xy 87.41351 -342.668565) (xy 87.377798 -342.709782)
			(xy 87.336583 -342.745497) (xy 87.290705 -342.774983) (xy 87.241098 -342.797641) (xy 87.188771 -342.813008)
			(xy 87.13479 -342.820772) (xy 87.107522 -342.82126) (xy 86.243922 -342.82126) (xy 86.21665 -342.820802)
			(xy 86.16266 -342.813042) (xy 86.110325 -342.797678) (xy 86.060709 -342.775021) (xy 86.014822 -342.745534)
			(xy 85.973599 -342.709817) (xy 85.937879 -342.668596) (xy 85.908389 -342.622711) (xy 85.88573 -342.573096)
			(xy 85.870362 -342.520761) (xy 85.8626 -342.466772) (xy 84.379896 -342.466772) (xy 84.379896 -342.466773)
			(xy 84.372133 -342.520763) (xy 84.356765 -342.573098) (xy 84.334105 -342.622713) (xy 84.304614 -342.668599)
			(xy 84.268893 -342.70982) (xy 84.227668 -342.745537) (xy 84.18178 -342.775023) (xy 84.132162 -342.797679)
			(xy 84.079825 -342.813041) (xy 84.025835 -342.820799) (xy 83.998562 -342.82126) (xy 83.134962 -342.82126)
			(xy 83.107694 -342.820775) (xy 83.053714 -342.813009) (xy 83.001389 -342.79764) (xy 82.951784 -342.774982)
			(xy 82.905907 -342.745495) (xy 82.864694 -342.709779) (xy 82.828983 -342.668562) (xy 82.7995 -342.622683)
			(xy 82.776847 -342.573075) (xy 82.761483 -342.520748) (xy 82.753722 -342.466768) (xy 81.270874 -342.466768)
			(xy 81.270874 -342.466769) (xy 81.263112 -342.520752) (xy 81.247747 -342.573081) (xy 81.225091 -342.622691)
			(xy 81.195605 -342.668572) (xy 81.159891 -342.709789) (xy 81.118673 -342.745504) (xy 81.072793 -342.77499)
			(xy 81.023183 -342.797646) (xy 80.970854 -342.813012) (xy 80.916871 -342.820773) (xy 80.889602 -342.82126)
			(xy 80.026002 -342.82126) (xy 79.998731 -342.820801) (xy 79.944743 -342.813039) (xy 79.89241 -342.797673)
			(xy 79.842797 -342.775015) (xy 79.796912 -342.745527) (xy 79.755692 -342.70981) (xy 79.719974 -342.668589)
			(xy 79.690486 -342.622705) (xy 79.667828 -342.573092) (xy 79.652462 -342.520759) (xy 79.644699 -342.466771)
			(xy 78.161873 -342.466771) (xy 78.154113 -342.520747) (xy 78.13875 -342.573073) (xy 78.116097 -342.62268)
			(xy 78.086615 -342.668559) (xy 78.050905 -342.709775) (xy 78.009692 -342.74549) (xy 77.963817 -342.774977)
			(xy 77.914212 -342.797635) (xy 77.861888 -342.813004) (xy 77.807909 -342.820771) (xy 77.780642 -342.82126)
			(xy 76.917042 -342.82126) (xy 76.889769 -342.820803) (xy 76.835777 -342.813046) (xy 76.783439 -342.797683)
			(xy 76.733821 -342.775028) (xy 76.687931 -342.745541) (xy 76.646706 -342.709824) (xy 76.610984 -342.668602)
			(xy 76.581492 -342.622716) (xy 76.558831 -342.5731) (xy 76.543463 -342.520764) (xy 76.5357 -342.466773)
			(xy 75.052996 -342.466773) (xy 75.045234 -342.52076) (xy 75.029867 -342.573094) (xy 75.007208 -342.622708)
			(xy 74.977719 -342.668592) (xy 74.942 -342.709812) (xy 74.900778 -342.74553) (xy 74.854892 -342.775017)
			(xy 74.805277 -342.797673) (xy 74.752942 -342.813038) (xy 74.698954 -342.820798) (xy 74.671682 -342.82126)
			(xy 73.808082 -342.82126) (xy 73.780813 -342.820776) (xy 73.726831 -342.813013) (xy 73.674504 -342.797646)
			(xy 73.624896 -342.774988) (xy 73.579017 -342.745502) (xy 73.537801 -342.709786) (xy 73.502087 -342.668569)
			(xy 73.472603 -342.622689) (xy 73.449948 -342.573079) (xy 73.434584 -342.520751) (xy 73.426822 -342.466769)
			(xy 71.943974 -342.466769) (xy 71.936213 -342.52075) (xy 71.920848 -342.573077) (xy 71.898194 -342.622686)
			(xy 71.86871 -342.668565) (xy 71.832998 -342.709782) (xy 71.791783 -342.745497) (xy 71.745905 -342.774983)
			(xy 71.696298 -342.797641) (xy 71.643971 -342.813008) (xy 71.58999 -342.820772) (xy 71.562722 -342.82126)
			(xy 70.699122 -342.82126) (xy 70.67185 -342.820802) (xy 70.61786 -342.813042) (xy 70.565525 -342.797678)
			(xy 70.515909 -342.775021) (xy 70.470022 -342.745534) (xy 70.428799 -342.709817) (xy 70.393079 -342.668596)
			(xy 70.363589 -342.622711) (xy 70.34093 -342.573096) (xy 70.325562 -342.520761) (xy 70.3178 -342.466772)
			(xy 68.835096 -342.466772) (xy 68.835096 -342.466773) (xy 68.827333 -342.520763) (xy 68.811965 -342.573098)
			(xy 68.789305 -342.622713) (xy 68.759814 -342.668599) (xy 68.724093 -342.70982) (xy 68.682868 -342.745537)
			(xy 68.63698 -342.775023) (xy 68.587362 -342.797679) (xy 68.535025 -342.813041) (xy 68.481035 -342.820799)
			(xy 68.453762 -342.82126) (xy 67.590162 -342.82126) (xy 67.562894 -342.820775) (xy 67.508914 -342.813009)
			(xy 67.456589 -342.79764) (xy 67.406984 -342.774982) (xy 67.361107 -342.745495) (xy 67.319894 -342.709779)
			(xy 67.284183 -342.668562) (xy 67.2547 -342.622683) (xy 67.232047 -342.573075) (xy 67.216683 -342.520748)
			(xy 67.208922 -342.466768) (xy 65.726074 -342.466768) (xy 65.726074 -342.466769) (xy 65.718312 -342.520752)
			(xy 65.702947 -342.573081) (xy 65.680291 -342.622691) (xy 65.650805 -342.668572) (xy 65.615091 -342.709789)
			(xy 65.573873 -342.745504) (xy 65.527993 -342.77499) (xy 65.478383 -342.797646) (xy 65.426054 -342.813012)
			(xy 65.372071 -342.820773) (xy 65.344802 -342.82126) (xy 64.481202 -342.82126) (xy 64.453931 -342.820801)
			(xy 64.399943 -342.813039) (xy 64.34761 -342.797673) (xy 64.297997 -342.775015) (xy 64.252112 -342.745527)
			(xy 64.210892 -342.70981) (xy 64.175174 -342.668589) (xy 64.145686 -342.622705) (xy 64.123028 -342.573092)
			(xy 64.107662 -342.520759) (xy 64.099899 -342.466771) (xy 62.617073 -342.466771) (xy 62.609313 -342.520747)
			(xy 62.59395 -342.573073) (xy 62.571297 -342.62268) (xy 62.541815 -342.668559) (xy 62.506105 -342.709775)
			(xy 62.464892 -342.74549) (xy 62.419017 -342.774977) (xy 62.369412 -342.797635) (xy 62.317088 -342.813004)
			(xy 62.263109 -342.820771) (xy 62.235842 -342.82126) (xy 61.372242 -342.82126) (xy 61.344969 -342.820803)
			(xy 61.290977 -342.813046) (xy 61.238639 -342.797683) (xy 61.189021 -342.775028) (xy 61.143131 -342.745541)
			(xy 61.101906 -342.709824) (xy 61.066184 -342.668602) (xy 61.036692 -342.622716) (xy 61.014031 -342.5731)
			(xy 60.998663 -342.520764) (xy 60.9909 -342.466773) (xy 51.666873 -342.466773) (xy 51.659113 -342.520746)
			(xy 51.643751 -342.573072) (xy 51.621098 -342.622678) (xy 51.591617 -342.668557) (xy 51.555907 -342.709773)
			(xy 51.514695 -342.745488) (xy 51.46882 -342.774975) (xy 51.419217 -342.797634) (xy 51.366893 -342.813003)
			(xy 51.312915 -342.82077) (xy 51.285648 -342.82126) (xy 50.422048 -342.82126) (xy 50.394775 -342.820804)
			(xy 50.340782 -342.813047) (xy 50.288444 -342.797685) (xy 50.238824 -342.77503) (xy 50.192934 -342.745544)
			(xy 50.151708 -342.709826) (xy 50.115985 -342.668604) (xy 50.086493 -342.622718) (xy 50.063832 -342.573101)
			(xy 50.048463 -342.520765) (xy 50.0407 -342.466773) (xy 48.557996 -342.466773) (xy 48.550234 -342.520759)
			(xy 48.534867 -342.573092) (xy 48.512209 -342.622706) (xy 48.48272 -342.66859) (xy 48.447002 -342.70981)
			(xy 48.40578 -342.745528) (xy 48.359896 -342.775015) (xy 48.310281 -342.797671) (xy 48.257947 -342.813037)
			(xy 48.203959 -342.820797) (xy 48.176688 -342.82126) (xy 47.313088 -342.82126) (xy 47.285819 -342.820777)
			(xy 47.231836 -342.813014) (xy 47.179508 -342.797647) (xy 47.129899 -342.77499) (xy 47.08402 -342.745504)
			(xy 47.042803 -342.709788) (xy 47.007089 -342.668571) (xy 46.977604 -342.62269) (xy 46.954949 -342.573081)
			(xy 46.939584 -342.520752) (xy 46.931822 -342.466769) (xy 45.448974 -342.466769) (xy 45.441213 -342.520749)
			(xy 45.425849 -342.573076) (xy 45.403195 -342.622684) (xy 45.373712 -342.668563) (xy 45.338 -342.70978)
			(xy 45.296786 -342.745495) (xy 45.250909 -342.774981) (xy 45.201302 -342.797639) (xy 45.148976 -342.813007)
			(xy 45.094996 -342.820772) (xy 45.067728 -342.82126) (xy 44.204128 -342.82126) (xy 44.176856 -342.820802)
			(xy 44.122865 -342.813043) (xy 44.070529 -342.79768) (xy 44.020912 -342.775023) (xy 43.975025 -342.745536)
			(xy 43.933801 -342.709819) (xy 43.89808 -342.668598) (xy 43.86859 -342.622712) (xy 43.84593 -342.573097)
			(xy 43.830562 -342.520762) (xy 43.8228 -342.466772) (xy 42.340096 -342.466772) (xy 42.332333 -342.520762)
			(xy 42.316966 -342.573097) (xy 42.294306 -342.622712) (xy 42.264815 -342.668597) (xy 42.229095 -342.709817)
			(xy 42.187871 -342.745535) (xy 42.141984 -342.775021) (xy 42.092367 -342.797677) (xy 42.04003 -342.81304)
			(xy 41.98604 -342.820799) (xy 41.958768 -342.82126) (xy 41.095168 -342.82126) (xy 41.0679 -342.820775)
			(xy 41.01392 -342.81301) (xy 40.961594 -342.797642) (xy 40.911987 -342.774984) (xy 40.86611 -342.745497)
			(xy 40.824896 -342.709781) (xy 40.789184 -342.668564) (xy 40.759701 -342.622685) (xy 40.737047 -342.573076)
			(xy 40.721683 -342.520749) (xy 40.713922 -342.466768) (xy 39.231074 -342.466768) (xy 39.231074 -342.466769)
			(xy 39.223312 -342.520751) (xy 39.207947 -342.57308) (xy 39.185292 -342.622689) (xy 39.155807 -342.66857)
			(xy 39.120093 -342.709787) (xy 39.078876 -342.745502) (xy 39.032997 -342.774988) (xy 38.983388 -342.797645)
			(xy 38.931059 -342.81301) (xy 38.877077 -342.820773) (xy 38.849808 -342.82126) (xy 37.986208 -342.82126)
			(xy 37.958936 -342.820801) (xy 37.904948 -342.81304) (xy 37.852615 -342.797674) (xy 37.803 -342.775017)
			(xy 37.757115 -342.745529) (xy 37.715894 -342.709812) (xy 37.680175 -342.668591) (xy 37.650687 -342.622707)
			(xy 37.628029 -342.573093) (xy 37.612662 -342.520759) (xy 37.6049 -342.466772) (xy 36.122073 -342.466772)
			(xy 36.114313 -342.520746) (xy 36.098951 -342.573072) (xy 36.076298 -342.622678) (xy 36.046817 -342.668557)
			(xy 36.011107 -342.709773) (xy 35.969895 -342.745488) (xy 35.92402 -342.774975) (xy 35.874417 -342.797634)
			(xy 35.822093 -342.813003) (xy 35.768115 -342.82077) (xy 35.740848 -342.82126) (xy 34.877248 -342.82126)
			(xy 34.849975 -342.820804) (xy 34.795982 -342.813047) (xy 34.743644 -342.797685) (xy 34.694024 -342.77503)
			(xy 34.648134 -342.745544) (xy 34.606908 -342.709826) (xy 34.571185 -342.668604) (xy 34.541693 -342.622718)
			(xy 34.519032 -342.573101) (xy 34.503663 -342.520765) (xy 34.4959 -342.466773) (xy 33.013196 -342.466773)
			(xy 33.005434 -342.520759) (xy 32.990067 -342.573092) (xy 32.967409 -342.622706) (xy 32.93792 -342.66859)
			(xy 32.902202 -342.70981) (xy 32.86098 -342.745528) (xy 32.815096 -342.775015) (xy 32.765481 -342.797671)
			(xy 32.713147 -342.813037) (xy 32.659159 -342.820797) (xy 32.631888 -342.82126) (xy 31.768288 -342.82126)
			(xy 31.741019 -342.820777) (xy 31.687036 -342.813014) (xy 31.634708 -342.797647) (xy 31.585099 -342.77499)
			(xy 31.53922 -342.745504) (xy 31.498003 -342.709788) (xy 31.462289 -342.668571) (xy 31.432804 -342.62269)
			(xy 31.410149 -342.573081) (xy 31.394784 -342.520752) (xy 31.387022 -342.466769) (xy 29.904174 -342.466769)
			(xy 29.896413 -342.520749) (xy 29.881049 -342.573076) (xy 29.858395 -342.622684) (xy 29.828912 -342.668563)
			(xy 29.7932 -342.70978) (xy 29.751986 -342.745495) (xy 29.706109 -342.774981) (xy 29.656502 -342.797639)
			(xy 29.604176 -342.813007) (xy 29.550196 -342.820772) (xy 29.522928 -342.82126) (xy 28.659328 -342.82126)
			(xy 28.632056 -342.820802) (xy 28.578065 -342.813043) (xy 28.525729 -342.79768) (xy 28.476112 -342.775023)
			(xy 28.430225 -342.745536) (xy 28.389001 -342.709819) (xy 28.35328 -342.668598) (xy 28.32379 -342.622712)
			(xy 28.30113 -342.573097) (xy 28.285762 -342.520762) (xy 28.278 -342.466772) (xy 26.795296 -342.466772)
			(xy 26.787533 -342.520762) (xy 26.772166 -342.573097) (xy 26.749506 -342.622712) (xy 26.720015 -342.668597)
			(xy 26.684295 -342.709817) (xy 26.643071 -342.745535) (xy 26.597184 -342.775021) (xy 26.547567 -342.797677)
			(xy 26.49523 -342.81304) (xy 26.44124 -342.820799) (xy 26.413968 -342.82126) (xy 25.550368 -342.82126)
			(xy 25.5231 -342.820775) (xy 25.46912 -342.81301) (xy 25.416794 -342.797642) (xy 25.367187 -342.774984)
			(xy 25.32131 -342.745497) (xy 25.280096 -342.709781) (xy 25.244384 -342.668564) (xy 25.214901 -342.622685)
			(xy 25.192247 -342.573076) (xy 25.176883 -342.520749) (xy 25.169122 -342.466768) (xy 23.686274 -342.466768)
			(xy 23.686274 -342.466769) (xy 23.678512 -342.520751) (xy 23.663147 -342.57308) (xy 23.640492 -342.622689)
			(xy 23.611007 -342.66857) (xy 23.575293 -342.709787) (xy 23.534076 -342.745502) (xy 23.488197 -342.774988)
			(xy 23.438588 -342.797645) (xy 23.386259 -342.81301) (xy 23.332277 -342.820773) (xy 23.305008 -342.82126)
			(xy 22.441408 -342.82126) (xy 22.414136 -342.820801) (xy 22.360148 -342.81304) (xy 22.307815 -342.797674)
			(xy 22.2582 -342.775017) (xy 22.212315 -342.745529) (xy 22.171094 -342.709812) (xy 22.135375 -342.668591)
			(xy 22.105887 -342.622707) (xy 22.083229 -342.573093) (xy 22.067862 -342.520759) (xy 22.0601 -342.466772)
			(xy 20.577347 -342.466772) (xy 20.569584 -342.520758) (xy 20.554218 -342.57309) (xy 20.53156 -342.622703)
			(xy 20.502073 -342.668587) (xy 20.466355 -342.709807) (xy 20.425135 -342.745524) (xy 20.379252 -342.775011)
			(xy 20.329638 -342.797669) (xy 20.277306 -342.813035) (xy 20.223319 -342.820797) (xy 20.196048 -342.82126)
			(xy 19.332448 -342.82126) (xy 19.305179 -342.820777) (xy 19.251195 -342.813015) (xy 19.198865 -342.79765)
			(xy 19.149255 -342.774993) (xy 19.103374 -342.745507) (xy 19.062157 -342.709792) (xy 19.026441 -342.668574)
			(xy 18.996956 -342.622693) (xy 18.974299 -342.573083) (xy 18.958934 -342.520753) (xy 18.951172 -342.466769)
			(xy 1.524 -342.466769) (xy 1.524 -345.49242) (xy 18.95117 -345.49242) (xy 18.95117 -345.43788) (xy 18.958932 -345.383896)
			(xy 18.974298 -345.331567) (xy 18.996954 -345.281956) (xy 19.02644 -345.236075) (xy 19.062155 -345.194857)
			(xy 19.103373 -345.159141) (xy 19.149254 -345.129655) (xy 19.198865 -345.106998) (xy 19.251194 -345.091633)
			(xy 19.305178 -345.083871) (xy 19.332448 -345.083384) (xy 20.196048 -345.083384) (xy 20.223319 -345.083855)
			(xy 20.277305 -345.091617) (xy 20.329638 -345.106983) (xy 20.379251 -345.12964) (xy 20.425134 -345.159128)
			(xy 20.466354 -345.194845) (xy 20.502071 -345.236064) (xy 20.531559 -345.281948) (xy 20.554216 -345.33156)
			(xy 20.569582 -345.383893) (xy 20.577345 -345.437879) (xy 20.577345 -345.49242) (xy 22.06013 -345.49242)
			(xy 22.06013 -345.43788) (xy 22.067892 -345.383896) (xy 22.083258 -345.331567) (xy 22.105914 -345.281956)
			(xy 22.1354 -345.236075) (xy 22.171115 -345.194857) (xy 22.212333 -345.159141) (xy 22.258214 -345.129655)
			(xy 22.307825 -345.106998) (xy 22.360154 -345.091633) (xy 22.414138 -345.083871) (xy 22.441408 -345.083384)
			(xy 23.305008 -345.083384) (xy 23.332279 -345.083855) (xy 23.386265 -345.091617) (xy 23.438598 -345.106983)
			(xy 23.488211 -345.12964) (xy 23.534094 -345.159128) (xy 23.575314 -345.194845) (xy 23.611031 -345.236064)
			(xy 23.640519 -345.281948) (xy 23.663176 -345.33156) (xy 23.678542 -345.383893) (xy 23.686305 -345.437879)
			(xy 23.686305 -345.492365) (xy 25.16917 -345.492365) (xy 25.16917 -345.437835) (xy 25.17693 -345.383861)
			(xy 25.192292 -345.33154) (xy 25.214943 -345.281938) (xy 25.244422 -345.236064) (xy 25.28013 -345.194853)
			(xy 25.321339 -345.159142) (xy 25.36721 -345.129658) (xy 25.41681 -345.107003) (xy 25.46913 -345.091637)
			(xy 25.523103 -345.083872) (xy 25.550368 -345.083384) (xy 26.413968 -345.083384) (xy 26.441244 -345.083753)
			(xy 26.495241 -345.091513) (xy 26.547583 -345.106878) (xy 26.597207 -345.129537) (xy 26.6431 -345.159027)
			(xy 26.684329 -345.194749) (xy 26.720054 -345.235975) (xy 26.749548 -345.281865) (xy 26.772211 -345.331487)
			(xy 26.78758 -345.383828) (xy 26.795344 -345.437824) (xy 26.795344 -345.492369) (xy 28.278047 -345.492369)
			(xy 28.278047 -345.437831) (xy 28.285809 -345.383848) (xy 28.301175 -345.33152) (xy 28.323832 -345.281911)
			(xy 28.353319 -345.236031) (xy 28.389035 -345.194815) (xy 28.430253 -345.159102) (xy 28.476135 -345.129619)
			(xy 28.525746 -345.106965) (xy 28.578076 -345.091603) (xy 28.632059 -345.083845) (xy 28.659328 -345.083384)
			(xy 29.522928 -345.083384) (xy 29.550199 -345.08378) (xy 29.604186 -345.091546) (xy 29.656519 -345.106916)
			(xy 29.706132 -345.129576) (xy 29.752014 -345.159067) (xy 29.793234 -345.194786) (xy 29.82895 -345.236008)
			(xy 29.858437 -345.281893) (xy 29.881094 -345.331507) (xy 29.89646 -345.383841) (xy 29.904222 -345.437829)
			(xy 29.904222 -345.492366) (xy 31.38707 -345.492366) (xy 31.38707 -345.437834) (xy 31.394831 -345.383858)
			(xy 31.410194 -345.331536) (xy 31.432846 -345.281933) (xy 31.462327 -345.236058) (xy 31.498037 -345.194846)
			(xy 31.539248 -345.159135) (xy 31.585122 -345.129652) (xy 31.634725 -345.106998) (xy 31.687047 -345.091633)
			(xy 31.741022 -345.083871) (xy 31.768288 -345.083384) (xy 32.631888 -345.083384) (xy 32.659163 -345.083755)
			(xy 32.713157 -345.091516) (xy 32.765498 -345.106884) (xy 32.815119 -345.129543) (xy 32.861009 -345.159034)
			(xy 32.902236 -345.194756) (xy 32.937959 -345.235981) (xy 32.967451 -345.281871) (xy 32.990112 -345.331491)
			(xy 33.005481 -345.383831) (xy 33.013244 -345.437825) (xy 33.013244 -345.49237) (xy 34.495948 -345.49237)
			(xy 34.495948 -345.43783) (xy 34.50371 -345.383846) (xy 34.519077 -345.331515) (xy 34.541735 -345.281905)
			(xy 34.571224 -345.236024) (xy 34.606942 -345.194808) (xy 34.648163 -345.159095) (xy 34.694047 -345.129612)
			(xy 34.74366 -345.10696) (xy 34.795992 -345.0916) (xy 34.849978 -345.083844) (xy 34.877248 -345.083384)
			(xy 35.740848 -345.083384) (xy 35.768118 -345.083782) (xy 35.822103 -345.09155) (xy 35.874433 -345.106921)
			(xy 35.924044 -345.129583) (xy 35.969924 -345.159074) (xy 36.011141 -345.194793) (xy 36.046855 -345.236015)
			(xy 36.07634 -345.281899) (xy 36.098995 -345.331512) (xy 36.11436 -345.383844) (xy 36.122122 -345.43783)
			(xy 36.122122 -345.492368) (xy 37.604947 -345.492368) (xy 37.604947 -345.437832) (xy 37.612709 -345.383851)
			(xy 37.628074 -345.331524) (xy 37.650729 -345.281916) (xy 37.680214 -345.236038) (xy 37.715928 -345.194822)
			(xy 37.757144 -345.159109) (xy 37.803023 -345.129625) (xy 37.852631 -345.106971) (xy 37.904959 -345.091607)
			(xy 37.95894 -345.083847) (xy 37.986208 -345.083384) (xy 38.849808 -345.083384) (xy 38.87708 -345.083779)
			(xy 38.93107 -345.091543) (xy 38.983404 -345.106911) (xy 39.03302 -345.12957) (xy 39.078905 -345.15906)
			(xy 39.120127 -345.194779) (xy 39.155845 -345.236001) (xy 39.185334 -345.281888) (xy 39.207992 -345.331503)
			(xy 39.223359 -345.383838) (xy 39.231121 -345.437828) (xy 39.231121 -345.492365) (xy 40.71397 -345.492365)
			(xy 40.71397 -345.437835) (xy 40.72173 -345.383861) (xy 40.737092 -345.33154) (xy 40.759743 -345.281938)
			(xy 40.789222 -345.236064) (xy 40.82493 -345.194853) (xy 40.866139 -345.159142) (xy 40.91201 -345.129658)
			(xy 40.96161 -345.107003) (xy 41.01393 -345.091637) (xy 41.067903 -345.083872) (xy 41.095168 -345.083384)
			(xy 41.958768 -345.083384) (xy 41.986044 -345.083753) (xy 42.040041 -345.091513) (xy 42.092383 -345.106878)
			(xy 42.142007 -345.129537) (xy 42.1879 -345.159027) (xy 42.229129 -345.194749) (xy 42.264854 -345.235975)
			(xy 42.294348 -345.281865) (xy 42.317011 -345.331487) (xy 42.33238 -345.383828) (xy 42.340144 -345.437824)
			(xy 42.340144 -345.492369) (xy 43.822847 -345.492369) (xy 43.822847 -345.437831) (xy 43.830609 -345.383848)
			(xy 43.845975 -345.33152) (xy 43.868632 -345.281911) (xy 43.898119 -345.236031) (xy 43.933835 -345.194815)
			(xy 43.975053 -345.159102) (xy 44.020935 -345.129619) (xy 44.070546 -345.106965) (xy 44.122876 -345.091603)
			(xy 44.176859 -345.083845) (xy 44.204128 -345.083384) (xy 45.067728 -345.083384) (xy 45.094999 -345.08378)
			(xy 45.148986 -345.091546) (xy 45.201319 -345.106916) (xy 45.250932 -345.129576) (xy 45.296814 -345.159067)
			(xy 45.338034 -345.194786) (xy 45.37375 -345.236008) (xy 45.403237 -345.281893) (xy 45.425894 -345.331507)
			(xy 45.44126 -345.383841) (xy 45.449022 -345.437829) (xy 45.449022 -345.492366) (xy 46.93187 -345.492366)
			(xy 46.93187 -345.437834) (xy 46.939631 -345.383858) (xy 46.954994 -345.331536) (xy 46.977646 -345.281933)
			(xy 47.007127 -345.236058) (xy 47.042837 -345.194846) (xy 47.084048 -345.159135) (xy 47.129922 -345.129652)
			(xy 47.179525 -345.106998) (xy 47.231847 -345.091633) (xy 47.285822 -345.083871) (xy 47.313088 -345.083384)
			(xy 48.176688 -345.083384) (xy 48.203963 -345.083755) (xy 48.257957 -345.091516) (xy 48.310298 -345.106884)
			(xy 48.359919 -345.129543) (xy 48.405809 -345.159034) (xy 48.447036 -345.194756) (xy 48.482759 -345.235981)
			(xy 48.512251 -345.281871) (xy 48.534912 -345.331491) (xy 48.550281 -345.383831) (xy 48.558044 -345.437825)
			(xy 48.558044 -345.49237) (xy 50.040748 -345.49237) (xy 50.040748 -345.43783) (xy 50.04851 -345.383846)
			(xy 50.063877 -345.331515) (xy 50.086535 -345.281905) (xy 50.116024 -345.236024) (xy 50.151742 -345.194808)
			(xy 50.192963 -345.159095) (xy 50.238847 -345.129612) (xy 50.28846 -345.10696) (xy 50.340792 -345.0916)
			(xy 50.394778 -345.083844) (xy 50.422048 -345.083384) (xy 51.285648 -345.083384) (xy 51.312918 -345.083782)
			(xy 51.366903 -345.09155) (xy 51.419233 -345.106921) (xy 51.468844 -345.129583) (xy 51.514724 -345.159074)
			(xy 51.555941 -345.194793) (xy 51.591655 -345.236015) (xy 51.62114 -345.281899) (xy 51.643795 -345.331512)
			(xy 51.65916 -345.383844) (xy 51.666922 -345.43783) (xy 51.666922 -345.49237) (xy 60.990948 -345.49237)
			(xy 60.990948 -345.43783) (xy 60.99871 -345.383846) (xy 61.014076 -345.331517) (xy 61.036734 -345.281907)
			(xy 61.066222 -345.236026) (xy 61.10194 -345.19481) (xy 61.14316 -345.159097) (xy 61.189044 -345.129614)
			(xy 61.238656 -345.106962) (xy 61.290987 -345.091601) (xy 61.344972 -345.083845) (xy 61.372242 -345.083384)
			(xy 62.235842 -345.083384) (xy 62.263113 -345.083781) (xy 62.317098 -345.091549) (xy 62.369429 -345.10692)
			(xy 62.41904 -345.129581) (xy 62.464921 -345.159072) (xy 62.506139 -345.194791) (xy 62.541854 -345.236013)
			(xy 62.571339 -345.281897) (xy 62.593995 -345.33151) (xy 62.60936 -345.383843) (xy 62.617122 -345.437829)
			(xy 62.617122 -345.492368) (xy 64.099947 -345.492368) (xy 64.099947 -345.437832) (xy 64.107709 -345.383852)
			(xy 64.123073 -345.331525) (xy 64.145728 -345.281918) (xy 64.175212 -345.23604) (xy 64.210926 -345.194824)
			(xy 64.252141 -345.159111) (xy 64.29802 -345.129627) (xy 64.347627 -345.106972) (xy 64.399954 -345.091608)
			(xy 64.453934 -345.083847) (xy 64.481202 -345.083384) (xy 65.344802 -345.083384) (xy 65.372075 -345.083779)
			(xy 65.426064 -345.091542) (xy 65.4784 -345.106909) (xy 65.528016 -345.129568) (xy 65.573902 -345.159057)
			(xy 65.615124 -345.194777) (xy 65.650844 -345.236) (xy 65.680333 -345.281886) (xy 65.702992 -345.331502)
			(xy 65.718359 -345.383838) (xy 65.726121 -345.437827) (xy 65.726121 -345.492364) (xy 67.20897 -345.492364)
			(xy 67.20897 -345.437836) (xy 67.21673 -345.383862) (xy 67.232092 -345.331542) (xy 67.254742 -345.28194)
			(xy 67.284221 -345.236066) (xy 67.319928 -345.194855) (xy 67.361136 -345.159144) (xy 67.407007 -345.12966)
			(xy 67.456606 -345.107005) (xy 67.508925 -345.091638) (xy 67.562898 -345.083873) (xy 67.590162 -345.083384)
			(xy 68.453762 -345.083384) (xy 68.481038 -345.083753) (xy 68.535036 -345.091512) (xy 68.587379 -345.106877)
			(xy 68.637003 -345.129535) (xy 68.682897 -345.159025) (xy 68.724127 -345.194747) (xy 68.759852 -345.235973)
			(xy 68.789347 -345.281864) (xy 68.81201 -345.331485) (xy 68.82738 -345.383827) (xy 68.835144 -345.437824)
			(xy 68.835144 -345.492369) (xy 70.317847 -345.492369) (xy 70.317847 -345.437831) (xy 70.325609 -345.383849)
			(xy 70.340975 -345.331521) (xy 70.363631 -345.281912) (xy 70.393117 -345.236033) (xy 70.428833 -345.194817)
			(xy 70.470051 -345.159104) (xy 70.515932 -345.129621) (xy 70.565541 -345.106967) (xy 70.617871 -345.091605)
			(xy 70.671853 -345.083846) (xy 70.699122 -345.083384) (xy 71.562722 -345.083384) (xy 71.589994 -345.08378)
			(xy 71.643981 -345.091545) (xy 71.696315 -345.106914) (xy 71.745928 -345.129574) (xy 71.791812 -345.159064)
			(xy 71.833032 -345.194784) (xy 71.868749 -345.236006) (xy 71.898236 -345.281891) (xy 71.920893 -345.331506)
			(xy 71.936259 -345.38384) (xy 71.944022 -345.437828) (xy 71.944022 -345.492365) (xy 73.42687 -345.492365)
			(xy 73.42687 -345.437835) (xy 73.434631 -345.383859) (xy 73.449993 -345.331537) (xy 73.472645 -345.281934)
			(xy 73.502126 -345.23606) (xy 73.537835 -345.194848) (xy 73.579045 -345.159137) (xy 73.624919 -345.129654)
			(xy 73.674521 -345.106999) (xy 73.726842 -345.091634) (xy 73.780817 -345.083872) (xy 73.808082 -345.083384)
			(xy 74.671682 -345.083384) (xy 74.698957 -345.083754) (xy 74.752952 -345.091515) (xy 74.805294 -345.106882)
			(xy 74.854915 -345.129541) (xy 74.900806 -345.159032) (xy 74.942034 -345.194754) (xy 74.977757 -345.235979)
			(xy 75.00725 -345.281869) (xy 75.029912 -345.33149) (xy 75.045281 -345.38383) (xy 75.053044 -345.437825)
			(xy 75.053044 -345.49237) (xy 76.535748 -345.49237) (xy 76.535748 -345.43783) (xy 76.54351 -345.383846)
			(xy 76.558876 -345.331517) (xy 76.581534 -345.281907) (xy 76.611022 -345.236026) (xy 76.64674 -345.19481)
			(xy 76.68796 -345.159097) (xy 76.733844 -345.129614) (xy 76.783456 -345.106962) (xy 76.835787 -345.091601)
			(xy 76.889772 -345.083845) (xy 76.917042 -345.083384) (xy 77.780642 -345.083384) (xy 77.807913 -345.083781)
			(xy 77.861898 -345.091549) (xy 77.914229 -345.10692) (xy 77.96384 -345.129581) (xy 78.009721 -345.159072)
			(xy 78.050939 -345.194791) (xy 78.086654 -345.236013) (xy 78.116139 -345.281897) (xy 78.138795 -345.33151)
			(xy 78.15416 -345.383843) (xy 78.161922 -345.437829) (xy 78.161922 -345.492368) (xy 79.644747 -345.492368)
			(xy 79.644747 -345.437832) (xy 79.652509 -345.383852) (xy 79.667873 -345.331525) (xy 79.690528 -345.281918)
			(xy 79.720012 -345.23604) (xy 79.755726 -345.194824) (xy 79.796941 -345.159111) (xy 79.84282 -345.129627)
			(xy 79.892427 -345.106972) (xy 79.944754 -345.091608) (xy 79.998734 -345.083847) (xy 80.026002 -345.083384)
			(xy 80.889602 -345.083384) (xy 80.916875 -345.083779) (xy 80.970864 -345.091542) (xy 81.0232 -345.106909)
			(xy 81.072816 -345.129568) (xy 81.118702 -345.159057) (xy 81.159924 -345.194777) (xy 81.195644 -345.236)
			(xy 81.225133 -345.281886) (xy 81.247792 -345.331502) (xy 81.263159 -345.383838) (xy 81.270921 -345.437827)
			(xy 81.270921 -345.492364) (xy 82.75377 -345.492364) (xy 82.75377 -345.437836) (xy 82.76153 -345.383862)
			(xy 82.776892 -345.331542) (xy 82.799542 -345.28194) (xy 82.829021 -345.236066) (xy 82.864728 -345.194855)
			(xy 82.905936 -345.159144) (xy 82.951807 -345.12966) (xy 83.001406 -345.107005) (xy 83.053725 -345.091638)
			(xy 83.107698 -345.083873) (xy 83.134962 -345.083384) (xy 83.998562 -345.083384) (xy 84.025838 -345.083753)
			(xy 84.079836 -345.091512) (xy 84.132179 -345.106877) (xy 84.181803 -345.129535) (xy 84.227697 -345.159025)
			(xy 84.268927 -345.194747) (xy 84.304652 -345.235973) (xy 84.334147 -345.281864) (xy 84.35681 -345.331485)
			(xy 84.37218 -345.383827) (xy 84.379944 -345.437824) (xy 84.379944 -345.492369) (xy 85.862647 -345.492369)
			(xy 85.862647 -345.437831) (xy 85.870409 -345.383849) (xy 85.885775 -345.331521) (xy 85.908431 -345.281912)
			(xy 85.937917 -345.236033) (xy 85.973633 -345.194817) (xy 86.014851 -345.159104) (xy 86.060732 -345.129621)
			(xy 86.110341 -345.106967) (xy 86.162671 -345.091605) (xy 86.216653 -345.083846) (xy 86.243922 -345.083384)
			(xy 87.107522 -345.083384) (xy 87.134794 -345.08378) (xy 87.188781 -345.091545) (xy 87.241115 -345.106914)
			(xy 87.290728 -345.129574) (xy 87.336612 -345.159064) (xy 87.377832 -345.194784) (xy 87.413549 -345.236006)
			(xy 87.443036 -345.281891) (xy 87.465693 -345.331506) (xy 87.481059 -345.38384) (xy 87.488822 -345.437828)
			(xy 87.488822 -345.492365) (xy 88.97167 -345.492365) (xy 88.97167 -345.437835) (xy 88.979431 -345.383859)
			(xy 88.994793 -345.331537) (xy 89.017445 -345.281934) (xy 89.046926 -345.23606) (xy 89.082635 -345.194848)
			(xy 89.123845 -345.159137) (xy 89.169719 -345.129654) (xy 89.219321 -345.106999) (xy 89.271642 -345.091634)
			(xy 89.325617 -345.083872) (xy 89.352882 -345.083384) (xy 90.216482 -345.083384) (xy 90.243757 -345.083754)
			(xy 90.297752 -345.091515) (xy 90.350094 -345.106882) (xy 90.399715 -345.129541) (xy 90.445606 -345.159032)
			(xy 90.486834 -345.194754) (xy 90.522557 -345.235979) (xy 90.55205 -345.281869) (xy 90.574712 -345.33149)
			(xy 90.590081 -345.38383) (xy 90.597844 -345.437825) (xy 90.597844 -345.49237) (xy 92.080548 -345.49237)
			(xy 92.080548 -345.43783) (xy 92.08831 -345.383846) (xy 92.103676 -345.331517) (xy 92.126334 -345.281907)
			(xy 92.155822 -345.236026) (xy 92.19154 -345.19481) (xy 92.23276 -345.159097) (xy 92.278644 -345.129614)
			(xy 92.328256 -345.106962) (xy 92.380587 -345.091601) (xy 92.434572 -345.083845) (xy 92.461842 -345.083384)
			(xy 93.325442 -345.083384) (xy 93.352713 -345.083781) (xy 93.406698 -345.091549) (xy 93.459029 -345.10692)
			(xy 93.50864 -345.129581) (xy 93.554521 -345.159072) (xy 93.595739 -345.194791) (xy 93.631454 -345.236013)
			(xy 93.660939 -345.281897) (xy 93.683595 -345.33151) (xy 93.69896 -345.383843) (xy 93.706722 -345.437829)
			(xy 93.706722 -345.492368) (xy 111.480847 -345.492368) (xy 111.480847 -345.437832) (xy 111.488609 -345.383851)
			(xy 111.503974 -345.331524) (xy 111.526629 -345.281916) (xy 111.556114 -345.236038) (xy 111.591828 -345.194822)
			(xy 111.633044 -345.159109) (xy 111.678923 -345.129625) (xy 111.728531 -345.106971) (xy 111.780859 -345.091607)
			(xy 111.83484 -345.083847) (xy 111.862108 -345.083384) (xy 112.725708 -345.083384) (xy 112.75298 -345.083779)
			(xy 112.80697 -345.091543) (xy 112.859304 -345.106911) (xy 112.90892 -345.12957) (xy 112.954805 -345.15906)
			(xy 112.996027 -345.194779) (xy 113.031745 -345.236001) (xy 113.061234 -345.281888) (xy 113.083892 -345.331503)
			(xy 113.099259 -345.383838) (xy 113.107021 -345.437828) (xy 113.107021 -345.492365) (xy 114.58987 -345.492365)
			(xy 114.58987 -345.437835) (xy 114.59763 -345.383861) (xy 114.612992 -345.33154) (xy 114.635643 -345.281938)
			(xy 114.665122 -345.236064) (xy 114.70083 -345.194853) (xy 114.742039 -345.159142) (xy 114.78791 -345.129658)
			(xy 114.83751 -345.107003) (xy 114.88983 -345.091637) (xy 114.943803 -345.083872) (xy 114.971068 -345.083384)
			(xy 115.834668 -345.083384) (xy 115.861944 -345.083753) (xy 115.915941 -345.091513) (xy 115.968283 -345.106878)
			(xy 116.017907 -345.129537) (xy 116.0638 -345.159027) (xy 116.105029 -345.194749) (xy 116.140754 -345.235975)
			(xy 116.170248 -345.281865) (xy 116.192911 -345.331487) (xy 116.20828 -345.383828) (xy 116.216044 -345.437824)
			(xy 116.216044 -345.492369) (xy 117.698747 -345.492369) (xy 117.698747 -345.437831) (xy 117.706509 -345.383848)
			(xy 117.721875 -345.33152) (xy 117.744532 -345.281911) (xy 117.774019 -345.236031) (xy 117.809735 -345.194815)
			(xy 117.850953 -345.159102) (xy 117.896835 -345.129619) (xy 117.946446 -345.106965) (xy 117.998776 -345.091603)
			(xy 118.052759 -345.083845) (xy 118.080028 -345.083384) (xy 118.943628 -345.083384) (xy 118.970899 -345.08378)
			(xy 119.024886 -345.091546) (xy 119.077219 -345.106916) (xy 119.126832 -345.129576) (xy 119.172714 -345.159067)
			(xy 119.213934 -345.194786) (xy 119.24965 -345.236008) (xy 119.279137 -345.281893) (xy 119.301794 -345.331507)
			(xy 119.31716 -345.383841) (xy 119.324922 -345.437829) (xy 119.324922 -345.492366) (xy 120.80777 -345.492366)
			(xy 120.80777 -345.437834) (xy 120.815531 -345.383858) (xy 120.830894 -345.331536) (xy 120.853546 -345.281933)
			(xy 120.883027 -345.236058) (xy 120.918737 -345.194846) (xy 120.959948 -345.159135) (xy 121.005822 -345.129652)
			(xy 121.055425 -345.106998) (xy 121.107747 -345.091633) (xy 121.161722 -345.083871) (xy 121.188988 -345.083384)
			(xy 122.052588 -345.083384) (xy 122.079863 -345.083755) (xy 122.133857 -345.091516) (xy 122.186198 -345.106884)
			(xy 122.235819 -345.129543) (xy 122.281709 -345.159034) (xy 122.322936 -345.194756) (xy 122.358659 -345.235981)
			(xy 122.388151 -345.281871) (xy 122.410812 -345.331491) (xy 122.426181 -345.383831) (xy 122.433944 -345.437825)
			(xy 122.433944 -345.49237) (xy 123.916648 -345.49237) (xy 123.916648 -345.43783) (xy 123.92441 -345.383846)
			(xy 123.939777 -345.331515) (xy 123.962435 -345.281905) (xy 123.991924 -345.236024) (xy 124.027642 -345.194808)
			(xy 124.068863 -345.159095) (xy 124.114747 -345.129612) (xy 124.16436 -345.10696) (xy 124.216692 -345.0916)
			(xy 124.270678 -345.083844) (xy 124.297948 -345.083384) (xy 125.161548 -345.083384) (xy 125.188818 -345.083782)
			(xy 125.242803 -345.09155) (xy 125.295133 -345.106921) (xy 125.344744 -345.129583) (xy 125.390624 -345.159074)
			(xy 125.431841 -345.194793) (xy 125.467555 -345.236015) (xy 125.49704 -345.281899) (xy 125.519695 -345.331512)
			(xy 125.53506 -345.383844) (xy 125.542822 -345.43783) (xy 125.542822 -345.492368) (xy 127.025647 -345.492368)
			(xy 127.025647 -345.437832) (xy 127.033409 -345.383851) (xy 127.048774 -345.331524) (xy 127.071429 -345.281916)
			(xy 127.100914 -345.236038) (xy 127.136628 -345.194822) (xy 127.177844 -345.159109) (xy 127.223723 -345.129625)
			(xy 127.273331 -345.106971) (xy 127.325659 -345.091607) (xy 127.37964 -345.083847) (xy 127.406908 -345.083384)
			(xy 128.270508 -345.083384) (xy 128.29778 -345.083779) (xy 128.35177 -345.091543) (xy 128.404104 -345.106911)
			(xy 128.45372 -345.12957) (xy 128.499605 -345.15906) (xy 128.540827 -345.194779) (xy 128.576545 -345.236001)
			(xy 128.606034 -345.281888) (xy 128.628692 -345.331503) (xy 128.644059 -345.383838) (xy 128.651821 -345.437828)
			(xy 128.651821 -345.492365) (xy 130.13467 -345.492365) (xy 130.13467 -345.437835) (xy 130.14243 -345.383861)
			(xy 130.157792 -345.33154) (xy 130.180443 -345.281938) (xy 130.209922 -345.236064) (xy 130.24563 -345.194853)
			(xy 130.286839 -345.159142) (xy 130.33271 -345.129658) (xy 130.38231 -345.107003) (xy 130.43463 -345.091637)
			(xy 130.488603 -345.083872) (xy 130.515868 -345.083384) (xy 131.379468 -345.083384) (xy 131.406744 -345.083753)
			(xy 131.460741 -345.091513) (xy 131.513083 -345.106878) (xy 131.562707 -345.129537) (xy 131.6086 -345.159027)
			(xy 131.649829 -345.194749) (xy 131.685554 -345.235975) (xy 131.715048 -345.281865) (xy 131.737711 -345.331487)
			(xy 131.75308 -345.383828) (xy 131.760844 -345.437824) (xy 131.760844 -345.492369) (xy 133.243547 -345.492369)
			(xy 133.243547 -345.437831) (xy 133.251309 -345.383848) (xy 133.266675 -345.33152) (xy 133.289332 -345.281911)
			(xy 133.318819 -345.236031) (xy 133.354535 -345.194815) (xy 133.395753 -345.159102) (xy 133.441635 -345.129619)
			(xy 133.491246 -345.106965) (xy 133.543576 -345.091603) (xy 133.597559 -345.083845) (xy 133.624828 -345.083384)
			(xy 134.488428 -345.083384) (xy 134.515699 -345.08378) (xy 134.569686 -345.091546) (xy 134.622019 -345.106916)
			(xy 134.671632 -345.129576) (xy 134.717514 -345.159067) (xy 134.758734 -345.194786) (xy 134.79445 -345.236008)
			(xy 134.823937 -345.281893) (xy 134.846594 -345.331507) (xy 134.86196 -345.383841) (xy 134.869722 -345.437829)
			(xy 134.869722 -345.492366) (xy 136.35257 -345.492366) (xy 136.35257 -345.437834) (xy 136.360331 -345.383858)
			(xy 136.375694 -345.331536) (xy 136.398346 -345.281933) (xy 136.427827 -345.236058) (xy 136.463537 -345.194846)
			(xy 136.504748 -345.159135) (xy 136.550622 -345.129652) (xy 136.600225 -345.106998) (xy 136.652547 -345.091633)
			(xy 136.706522 -345.083871) (xy 136.733788 -345.083384) (xy 137.597388 -345.083384) (xy 137.624663 -345.083755)
			(xy 137.678657 -345.091516) (xy 137.730998 -345.106884) (xy 137.780619 -345.129543) (xy 137.826509 -345.159034)
			(xy 137.867736 -345.194756) (xy 137.903459 -345.235981) (xy 137.932951 -345.281871) (xy 137.955612 -345.331491)
			(xy 137.970981 -345.383831) (xy 137.978744 -345.437825) (xy 137.978744 -345.49237) (xy 139.461448 -345.49237)
			(xy 139.461448 -345.43783) (xy 139.46921 -345.383846) (xy 139.484577 -345.331515) (xy 139.507235 -345.281905)
			(xy 139.536724 -345.236024) (xy 139.572442 -345.194808) (xy 139.613663 -345.159095) (xy 139.659547 -345.129612)
			(xy 139.70916 -345.10696) (xy 139.761492 -345.0916) (xy 139.815478 -345.083844) (xy 139.842748 -345.083384)
			(xy 140.706348 -345.083384) (xy 140.733618 -345.083782) (xy 140.787603 -345.09155) (xy 140.839933 -345.106921)
			(xy 140.889544 -345.129583) (xy 140.935424 -345.159074) (xy 140.976641 -345.194793) (xy 141.012355 -345.236015)
			(xy 141.04184 -345.281899) (xy 141.064495 -345.331512) (xy 141.07986 -345.383844) (xy 141.087622 -345.43783)
			(xy 141.087622 -345.492368) (xy 142.570447 -345.492368) (xy 142.570447 -345.437832) (xy 142.578209 -345.383851)
			(xy 142.593574 -345.331524) (xy 142.616229 -345.281916) (xy 142.645714 -345.236038) (xy 142.681428 -345.194822)
			(xy 142.722644 -345.159109) (xy 142.768523 -345.129625) (xy 142.818131 -345.106971) (xy 142.870459 -345.091607)
			(xy 142.92444 -345.083847) (xy 142.951708 -345.083384) (xy 143.815308 -345.083384) (xy 143.84258 -345.083779)
			(xy 143.89657 -345.091543) (xy 143.948904 -345.106911) (xy 143.99852 -345.12957) (xy 144.044405 -345.15906)
			(xy 144.085627 -345.194779) (xy 144.121345 -345.236001) (xy 144.150834 -345.281888) (xy 144.173492 -345.331503)
			(xy 144.188859 -345.383838) (xy 144.196621 -345.437828) (xy 144.196621 -345.492365) (xy 164.91387 -345.492365)
			(xy 164.91387 -345.437835) (xy 164.92163 -345.383861) (xy 164.936992 -345.33154) (xy 164.959644 -345.281937)
			(xy 164.989123 -345.236063) (xy 165.024831 -345.194851) (xy 165.066041 -345.15914) (xy 165.111913 -345.129657)
			(xy 165.161513 -345.107002) (xy 165.213833 -345.091636) (xy 165.267807 -345.083872) (xy 165.295072 -345.083384)
			(xy 166.158672 -345.083384) (xy 166.185948 -345.083754) (xy 166.239944 -345.091514) (xy 166.292286 -345.106879)
			(xy 166.341909 -345.129538) (xy 166.387802 -345.159028) (xy 166.42903 -345.19475) (xy 166.464755 -345.235976)
			(xy 166.494249 -345.281866) (xy 166.516911 -345.331487) (xy 166.532281 -345.383829) (xy 166.540044 -345.437824)
			(xy 166.540044 -345.492369) (xy 168.022747 -345.492369) (xy 168.022747 -345.437831) (xy 168.03051 -345.383848)
			(xy 168.045876 -345.331519) (xy 168.068533 -345.281909) (xy 168.09802 -345.23603) (xy 168.133736 -345.194814)
			(xy 168.174955 -345.159101) (xy 168.220838 -345.129617) (xy 168.270449 -345.106964) (xy 168.322779 -345.091603)
			(xy 168.376763 -345.083845) (xy 168.404032 -345.083384) (xy 169.267632 -345.083384) (xy 169.294903 -345.083781)
			(xy 169.34889 -345.091547) (xy 169.401222 -345.106917) (xy 169.450834 -345.129578) (xy 169.496716 -345.159068)
			(xy 169.537935 -345.194788) (xy 169.573651 -345.236009) (xy 169.603138 -345.281894) (xy 169.625794 -345.331508)
			(xy 169.64116 -345.383842) (xy 169.648922 -345.437829) (xy 169.648922 -345.492366) (xy 171.13177 -345.492366)
			(xy 171.13177 -345.437834) (xy 171.139531 -345.383858) (xy 171.154894 -345.331535) (xy 171.177547 -345.281932)
			(xy 171.207028 -345.236057) (xy 171.242738 -345.194844) (xy 171.28395 -345.159133) (xy 171.329825 -345.129651)
			(xy 171.379428 -345.106997) (xy 171.43175 -345.091633) (xy 171.485726 -345.083871) (xy 171.512992 -345.083384)
			(xy 172.376592 -345.083384) (xy 172.403867 -345.083755) (xy 172.457861 -345.091517) (xy 172.510201 -345.106885)
			(xy 172.559821 -345.129544) (xy 172.605711 -345.159035) (xy 172.646937 -345.194757) (xy 172.68266 -345.235982)
			(xy 172.712152 -345.281872) (xy 172.734813 -345.331492) (xy 172.750181 -345.383831) (xy 172.757944 -345.437825)
			(xy 172.757944 -345.492364) (xy 174.24077 -345.492364) (xy 174.24077 -345.437836) (xy 174.24853 -345.383863)
			(xy 174.263891 -345.331544) (xy 174.286541 -345.281943) (xy 174.316019 -345.23607) (xy 174.351724 -345.194858)
			(xy 174.392931 -345.159147) (xy 174.438801 -345.129664) (xy 174.488399 -345.107008) (xy 174.540716 -345.09164)
			(xy 174.594688 -345.083874) (xy 174.621952 -345.083384) (xy 175.485552 -345.083384) (xy 175.512829 -345.083752)
			(xy 175.566827 -345.09151) (xy 175.619172 -345.106874) (xy 175.668797 -345.129531) (xy 175.714692 -345.159021)
			(xy 175.755923 -345.194743) (xy 175.79165 -345.235969) (xy 175.821146 -345.281861) (xy 175.843809 -345.331483)
			(xy 175.85918 -345.383826) (xy 175.866944 -345.437824) (xy 175.866944 -345.492368) (xy 177.349647 -345.492368)
			(xy 177.349647 -345.437832) (xy 177.357409 -345.38385) (xy 177.372774 -345.331523) (xy 177.39543 -345.281915)
			(xy 177.424915 -345.236036) (xy 177.460629 -345.194821) (xy 177.501846 -345.159108) (xy 177.547726 -345.129624)
			(xy 177.597334 -345.10697) (xy 177.649662 -345.091606) (xy 177.703644 -345.083847) (xy 177.730912 -345.083384)
			(xy 178.594512 -345.083384) (xy 178.621784 -345.083779) (xy 178.675773 -345.091543) (xy 178.728107 -345.106912)
			(xy 178.777722 -345.129571) (xy 178.823607 -345.159061) (xy 178.864828 -345.194781) (xy 178.900546 -345.236003)
			(xy 178.930035 -345.281889) (xy 178.952693 -345.331504) (xy 178.968059 -345.383839) (xy 178.975821 -345.437828)
			(xy 178.975821 -345.492365) (xy 180.45867 -345.492365) (xy 180.45867 -345.437835) (xy 180.46643 -345.383861)
			(xy 180.481792 -345.33154) (xy 180.504444 -345.281937) (xy 180.533923 -345.236063) (xy 180.569631 -345.194851)
			(xy 180.610841 -345.15914) (xy 180.656713 -345.129657) (xy 180.706313 -345.107002) (xy 180.758633 -345.091636)
			(xy 180.812607 -345.083872) (xy 180.839872 -345.083384) (xy 181.703472 -345.083384) (xy 181.730748 -345.083754)
			(xy 181.784744 -345.091514) (xy 181.837086 -345.106879) (xy 181.886709 -345.129538) (xy 181.932602 -345.159028)
			(xy 181.97383 -345.19475) (xy 182.009555 -345.235976) (xy 182.039049 -345.281866) (xy 182.061711 -345.331487)
			(xy 182.077081 -345.383829) (xy 182.084844 -345.437824) (xy 182.084844 -345.492369) (xy 183.567547 -345.492369)
			(xy 183.567547 -345.437831) (xy 183.57531 -345.383848) (xy 183.590676 -345.331519) (xy 183.613333 -345.281909)
			(xy 183.64282 -345.23603) (xy 183.678536 -345.194814) (xy 183.719755 -345.159101) (xy 183.765638 -345.129617)
			(xy 183.815249 -345.106964) (xy 183.867579 -345.091603) (xy 183.921563 -345.083845) (xy 183.948832 -345.083384)
			(xy 184.812432 -345.083384) (xy 184.839703 -345.083781) (xy 184.89369 -345.091547) (xy 184.946022 -345.106917)
			(xy 184.995634 -345.129578) (xy 185.041516 -345.159068) (xy 185.082735 -345.194788) (xy 185.118451 -345.236009)
			(xy 185.147938 -345.281894) (xy 185.170594 -345.331508) (xy 185.18596 -345.383842) (xy 185.193722 -345.437829)
			(xy 185.193722 -345.492366) (xy 186.67657 -345.492366) (xy 186.67657 -345.437834) (xy 186.684331 -345.383858)
			(xy 186.699694 -345.331535) (xy 186.722347 -345.281932) (xy 186.751828 -345.236057) (xy 186.787538 -345.194844)
			(xy 186.82875 -345.159133) (xy 186.874625 -345.129651) (xy 186.924228 -345.106997) (xy 186.97655 -345.091633)
			(xy 187.030526 -345.083871) (xy 187.057792 -345.083384) (xy 187.921392 -345.083384) (xy 187.948667 -345.083755)
			(xy 188.002661 -345.091517) (xy 188.055001 -345.106885) (xy 188.104621 -345.129544) (xy 188.150511 -345.159035)
			(xy 188.191737 -345.194757) (xy 188.22746 -345.235982) (xy 188.256952 -345.281872) (xy 188.279613 -345.331492)
			(xy 188.294981 -345.383831) (xy 188.302744 -345.437825) (xy 188.302744 -345.492364) (xy 189.78557 -345.492364)
			(xy 189.78557 -345.437836) (xy 189.79333 -345.383863) (xy 189.808691 -345.331544) (xy 189.831341 -345.281943)
			(xy 189.860819 -345.23607) (xy 189.896524 -345.194858) (xy 189.937731 -345.159147) (xy 189.983601 -345.129664)
			(xy 190.033199 -345.107008) (xy 190.085516 -345.09164) (xy 190.139488 -345.083874) (xy 190.166752 -345.083384)
			(xy 191.030352 -345.083384) (xy 191.057629 -345.083752) (xy 191.111627 -345.09151) (xy 191.163972 -345.106874)
			(xy 191.213597 -345.129531) (xy 191.259492 -345.159021) (xy 191.300723 -345.194743) (xy 191.33645 -345.235969)
			(xy 191.365946 -345.281861) (xy 191.388609 -345.331483) (xy 191.40398 -345.383826) (xy 191.411744 -345.437824)
			(xy 191.411744 -345.492368) (xy 192.894447 -345.492368) (xy 192.894447 -345.437832) (xy 192.902209 -345.38385)
			(xy 192.917574 -345.331523) (xy 192.94023 -345.281915) (xy 192.969715 -345.236036) (xy 193.005429 -345.194821)
			(xy 193.046646 -345.159108) (xy 193.092526 -345.129624) (xy 193.142134 -345.10697) (xy 193.194462 -345.091606)
			(xy 193.248444 -345.083847) (xy 193.275712 -345.083384) (xy 194.139312 -345.083384) (xy 194.166584 -345.083779)
			(xy 194.220573 -345.091543) (xy 194.272907 -345.106912) (xy 194.322522 -345.129571) (xy 194.368407 -345.159061)
			(xy 194.409628 -345.194781) (xy 194.445346 -345.236003) (xy 194.474835 -345.281889) (xy 194.497493 -345.331504)
			(xy 194.512859 -345.383839) (xy 194.520621 -345.437828) (xy 194.520621 -345.492365) (xy 196.00347 -345.492365)
			(xy 196.00347 -345.437835) (xy 196.01123 -345.383861) (xy 196.026592 -345.33154) (xy 196.049244 -345.281937)
			(xy 196.078723 -345.236063) (xy 196.114431 -345.194851) (xy 196.155641 -345.15914) (xy 196.201513 -345.129657)
			(xy 196.251113 -345.107002) (xy 196.303433 -345.091636) (xy 196.357407 -345.083872) (xy 196.384672 -345.083384)
			(xy 197.248272 -345.083384) (xy 197.275548 -345.083754) (xy 197.329544 -345.091514) (xy 197.381886 -345.106879)
			(xy 197.431509 -345.129538) (xy 197.477402 -345.159028) (xy 197.51863 -345.19475) (xy 197.554355 -345.235976)
			(xy 197.583849 -345.281866) (xy 197.606511 -345.331487) (xy 197.621881 -345.383829) (xy 197.629644 -345.437824)
			(xy 197.629644 -345.492376) (xy 197.621881 -345.546371) (xy 197.606511 -345.598713) (xy 197.583849 -345.648334)
			(xy 197.554355 -345.694224) (xy 197.51863 -345.73545) (xy 197.477402 -345.771172) (xy 197.431509 -345.800662)
			(xy 197.381886 -345.823321) (xy 197.329544 -345.838686) (xy 197.275548 -345.846446) (xy 197.248272 -345.846908)
			(xy 196.384672 -345.846908) (xy 196.357407 -345.846328) (xy 196.303433 -345.838564) (xy 196.251113 -345.823198)
			(xy 196.201513 -345.800543) (xy 196.155641 -345.77106) (xy 196.114431 -345.735349) (xy 196.078723 -345.694137)
			(xy 196.049244 -345.648263) (xy 196.026592 -345.59866) (xy 196.01123 -345.546339) (xy 196.00347 -345.492365)
			(xy 194.520621 -345.492365) (xy 194.520621 -345.492372) (xy 194.512859 -345.546361) (xy 194.497493 -345.598696)
			(xy 194.474835 -345.648311) (xy 194.445346 -345.694197) (xy 194.409628 -345.735419) (xy 194.368407 -345.771139)
			(xy 194.322522 -345.800629) (xy 194.272907 -345.823288) (xy 194.220573 -345.838657) (xy 194.166584 -345.846421)
			(xy 194.139312 -345.846908) (xy 193.275712 -345.846908) (xy 193.248444 -345.846353) (xy 193.194462 -345.838594)
			(xy 193.142134 -345.82323) (xy 193.092526 -345.800576) (xy 193.046646 -345.771092) (xy 193.005429 -345.735379)
			(xy 192.969715 -345.694164) (xy 192.94023 -345.648285) (xy 192.917574 -345.598677) (xy 192.902209 -345.54635)
			(xy 192.894447 -345.492368) (xy 191.411744 -345.492368) (xy 191.411744 -345.492376) (xy 191.40398 -345.546374)
			(xy 191.388609 -345.598717) (xy 191.365946 -345.648339) (xy 191.33645 -345.694231) (xy 191.300723 -345.735457)
			(xy 191.259492 -345.771179) (xy 191.213597 -345.800669) (xy 191.163972 -345.823326) (xy 191.111627 -345.83869)
			(xy 191.057629 -345.846448) (xy 191.030352 -345.846908) (xy 190.166752 -345.846908) (xy 190.139488 -345.846326)
			(xy 190.085516 -345.83856) (xy 190.033199 -345.823192) (xy 189.983601 -345.800536) (xy 189.937731 -345.771053)
			(xy 189.896524 -345.735342) (xy 189.860819 -345.69413) (xy 189.831341 -345.648257) (xy 189.808691 -345.598656)
			(xy 189.79333 -345.546337) (xy 189.78557 -345.492364) (xy 188.302744 -345.492364) (xy 188.302744 -345.492375)
			(xy 188.294981 -345.546369) (xy 188.279613 -345.598708) (xy 188.256952 -345.648328) (xy 188.22746 -345.694218)
			(xy 188.191737 -345.735443) (xy 188.150511 -345.771165) (xy 188.104621 -345.800656) (xy 188.055001 -345.823315)
			(xy 188.002661 -345.838683) (xy 187.948667 -345.846445) (xy 187.921392 -345.846908) (xy 187.057792 -345.846908)
			(xy 187.030526 -345.846329) (xy 186.97655 -345.838567) (xy 186.924228 -345.823203) (xy 186.874625 -345.800549)
			(xy 186.82875 -345.771067) (xy 186.787538 -345.735356) (xy 186.751828 -345.694143) (xy 186.722347 -345.648268)
			(xy 186.699694 -345.598665) (xy 186.684331 -345.546342) (xy 186.67657 -345.492366) (xy 185.193722 -345.492366)
			(xy 185.193722 -345.492371) (xy 185.18596 -345.546358) (xy 185.170594 -345.598692) (xy 185.147938 -345.648306)
			(xy 185.118451 -345.694191) (xy 185.082735 -345.735412) (xy 185.041516 -345.771132) (xy 184.995634 -345.800622)
			(xy 184.946022 -345.823283) (xy 184.89369 -345.838653) (xy 184.839703 -345.846419) (xy 184.812432 -345.846908)
			(xy 183.948832 -345.846908) (xy 183.921563 -345.846355) (xy 183.867579 -345.838597) (xy 183.815249 -345.823236)
			(xy 183.765638 -345.800583) (xy 183.719755 -345.771099) (xy 183.678536 -345.735386) (xy 183.64282 -345.69417)
			(xy 183.613333 -345.648291) (xy 183.590676 -345.598681) (xy 183.57531 -345.546352) (xy 183.567547 -345.492369)
			(xy 182.084844 -345.492369) (xy 182.084844 -345.492376) (xy 182.077081 -345.546371) (xy 182.061711 -345.598713)
			(xy 182.039049 -345.648334) (xy 182.009555 -345.694224) (xy 181.97383 -345.73545) (xy 181.932602 -345.771172)
			(xy 181.886709 -345.800662) (xy 181.837086 -345.823321) (xy 181.784744 -345.838686) (xy 181.730748 -345.846446)
			(xy 181.703472 -345.846908) (xy 180.839872 -345.846908) (xy 180.812607 -345.846328) (xy 180.758633 -345.838564)
			(xy 180.706313 -345.823198) (xy 180.656713 -345.800543) (xy 180.610841 -345.77106) (xy 180.569631 -345.735349)
			(xy 180.533923 -345.694137) (xy 180.504444 -345.648263) (xy 180.481792 -345.59866) (xy 180.46643 -345.546339)
			(xy 180.45867 -345.492365) (xy 178.975821 -345.492365) (xy 178.975821 -345.492372) (xy 178.968059 -345.546361)
			(xy 178.952693 -345.598696) (xy 178.930035 -345.648311) (xy 178.900546 -345.694197) (xy 178.864828 -345.735419)
			(xy 178.823607 -345.771139) (xy 178.777722 -345.800629) (xy 178.728107 -345.823288) (xy 178.675773 -345.838657)
			(xy 178.621784 -345.846421) (xy 178.594512 -345.846908) (xy 177.730912 -345.846908) (xy 177.703644 -345.846353)
			(xy 177.649662 -345.838594) (xy 177.597334 -345.82323) (xy 177.547726 -345.800576) (xy 177.501846 -345.771092)
			(xy 177.460629 -345.735379) (xy 177.424915 -345.694164) (xy 177.39543 -345.648285) (xy 177.372774 -345.598677)
			(xy 177.357409 -345.54635) (xy 177.349647 -345.492368) (xy 175.866944 -345.492368) (xy 175.866944 -345.492376)
			(xy 175.85918 -345.546374) (xy 175.843809 -345.598717) (xy 175.821146 -345.648339) (xy 175.79165 -345.694231)
			(xy 175.755923 -345.735457) (xy 175.714692 -345.771179) (xy 175.668797 -345.800669) (xy 175.619172 -345.823326)
			(xy 175.566827 -345.83869) (xy 175.512829 -345.846448) (xy 175.485552 -345.846908) (xy 174.621952 -345.846908)
			(xy 174.594688 -345.846326) (xy 174.540716 -345.83856) (xy 174.488399 -345.823192) (xy 174.438801 -345.800536)
			(xy 174.392931 -345.771053) (xy 174.351724 -345.735342) (xy 174.316019 -345.69413) (xy 174.286541 -345.648257)
			(xy 174.263891 -345.598656) (xy 174.24853 -345.546337) (xy 174.24077 -345.492364) (xy 172.757944 -345.492364)
			(xy 172.757944 -345.492375) (xy 172.750181 -345.546369) (xy 172.734813 -345.598708) (xy 172.712152 -345.648328)
			(xy 172.68266 -345.694218) (xy 172.646937 -345.735443) (xy 172.605711 -345.771165) (xy 172.559821 -345.800656)
			(xy 172.510201 -345.823315) (xy 172.457861 -345.838683) (xy 172.403867 -345.846445) (xy 172.376592 -345.846908)
			(xy 171.512992 -345.846908) (xy 171.485726 -345.846329) (xy 171.43175 -345.838567) (xy 171.379428 -345.823203)
			(xy 171.329825 -345.800549) (xy 171.28395 -345.771067) (xy 171.242738 -345.735356) (xy 171.207028 -345.694143)
			(xy 171.177547 -345.648268) (xy 171.154894 -345.598665) (xy 171.139531 -345.546342) (xy 171.13177 -345.492366)
			(xy 169.648922 -345.492366) (xy 169.648922 -345.492371) (xy 169.64116 -345.546358) (xy 169.625794 -345.598692)
			(xy 169.603138 -345.648306) (xy 169.573651 -345.694191) (xy 169.537935 -345.735412) (xy 169.496716 -345.771132)
			(xy 169.450834 -345.800622) (xy 169.401222 -345.823283) (xy 169.34889 -345.838653) (xy 169.294903 -345.846419)
			(xy 169.267632 -345.846908) (xy 168.404032 -345.846908) (xy 168.376763 -345.846355) (xy 168.322779 -345.838597)
			(xy 168.270449 -345.823236) (xy 168.220838 -345.800583) (xy 168.174955 -345.771099) (xy 168.133736 -345.735386)
			(xy 168.09802 -345.69417) (xy 168.068533 -345.648291) (xy 168.045876 -345.598681) (xy 168.03051 -345.546352)
			(xy 168.022747 -345.492369) (xy 166.540044 -345.492369) (xy 166.540044 -345.492376) (xy 166.532281 -345.546371)
			(xy 166.516911 -345.598713) (xy 166.494249 -345.648334) (xy 166.464755 -345.694224) (xy 166.42903 -345.73545)
			(xy 166.387802 -345.771172) (xy 166.341909 -345.800662) (xy 166.292286 -345.823321) (xy 166.239944 -345.838686)
			(xy 166.185948 -345.846446) (xy 166.158672 -345.846908) (xy 165.295072 -345.846908) (xy 165.267807 -345.846328)
			(xy 165.213833 -345.838564) (xy 165.161513 -345.823198) (xy 165.111913 -345.800543) (xy 165.066041 -345.77106)
			(xy 165.024831 -345.735349) (xy 164.989123 -345.694137) (xy 164.959644 -345.648263) (xy 164.936992 -345.59866)
			(xy 164.92163 -345.546339) (xy 164.91387 -345.492365) (xy 144.196621 -345.492365) (xy 144.196621 -345.492372)
			(xy 144.188859 -345.546362) (xy 144.173492 -345.598697) (xy 144.150834 -345.648312) (xy 144.121345 -345.694199)
			(xy 144.085627 -345.735421) (xy 144.044405 -345.77114) (xy 143.99852 -345.80063) (xy 143.948904 -345.82329)
			(xy 143.89657 -345.838657) (xy 143.84258 -345.846421) (xy 143.815308 -345.846908) (xy 142.951708 -345.846908)
			(xy 142.92444 -345.846353) (xy 142.870459 -345.838593) (xy 142.818131 -345.823229) (xy 142.768523 -345.800575)
			(xy 142.722644 -345.771091) (xy 142.681428 -345.735378) (xy 142.645714 -345.694162) (xy 142.616229 -345.648284)
			(xy 142.593574 -345.598676) (xy 142.578209 -345.546349) (xy 142.570447 -345.492368) (xy 141.087622 -345.492368)
			(xy 141.087622 -345.49237) (xy 141.07986 -345.546356) (xy 141.064495 -345.598688) (xy 141.04184 -345.648301)
			(xy 141.012355 -345.694185) (xy 140.976641 -345.735407) (xy 140.935424 -345.771126) (xy 140.889543 -345.800617)
			(xy 140.839933 -345.823279) (xy 140.787603 -345.83865) (xy 140.733618 -345.846418) (xy 140.706348 -345.846908)
			(xy 139.842748 -345.846908) (xy 139.815478 -345.846356) (xy 139.761492 -345.8386) (xy 139.70916 -345.82324)
			(xy 139.659547 -345.800588) (xy 139.613663 -345.771105) (xy 139.572442 -345.735392) (xy 139.536724 -345.694176)
			(xy 139.507235 -345.648295) (xy 139.484577 -345.598685) (xy 139.46921 -345.546354) (xy 139.461448 -345.49237)
			(xy 137.978744 -345.49237) (xy 137.978744 -345.492375) (xy 137.970981 -345.546369) (xy 137.955612 -345.598709)
			(xy 137.932951 -345.648329) (xy 137.903459 -345.694219) (xy 137.867736 -345.735444) (xy 137.826509 -345.771166)
			(xy 137.780619 -345.800657) (xy 137.730998 -345.823316) (xy 137.678658 -345.838684) (xy 137.624663 -345.846445)
			(xy 137.597388 -345.846908) (xy 136.733788 -345.846908) (xy 136.706522 -345.846329) (xy 136.652547 -345.838567)
			(xy 136.600225 -345.823202) (xy 136.550622 -345.800548) (xy 136.504748 -345.771065) (xy 136.463537 -345.735354)
			(xy 136.427827 -345.694142) (xy 136.398346 -345.648267) (xy 136.375694 -345.598664) (xy 136.360331 -345.546342)
			(xy 136.35257 -345.492366) (xy 134.869722 -345.492366) (xy 134.869722 -345.492371) (xy 134.86196 -345.546359)
			(xy 134.846594 -345.598693) (xy 134.823937 -345.648307) (xy 134.79445 -345.694192) (xy 134.758734 -345.735414)
			(xy 134.717514 -345.771133) (xy 134.671632 -345.800624) (xy 134.622019 -345.823284) (xy 134.569686 -345.838654)
			(xy 134.515699 -345.84642) (xy 134.488428 -345.846908) (xy 133.624828 -345.846908) (xy 133.597559 -345.846355)
			(xy 133.543576 -345.838597) (xy 133.491246 -345.823235) (xy 133.441635 -345.800581) (xy 133.395753 -345.771098)
			(xy 133.354535 -345.735385) (xy 133.318819 -345.694169) (xy 133.289332 -345.648289) (xy 133.266675 -345.59868)
			(xy 133.251309 -345.546352) (xy 133.243547 -345.492369) (xy 131.760844 -345.492369) (xy 131.760844 -345.492376)
			(xy 131.75308 -345.546372) (xy 131.737711 -345.598713) (xy 131.715048 -345.648335) (xy 131.685554 -345.694225)
			(xy 131.649829 -345.735451) (xy 131.6086 -345.771173) (xy 131.562707 -345.800663) (xy 131.513083 -345.823322)
			(xy 131.460741 -345.838687) (xy 131.406744 -345.846447) (xy 131.379468 -345.846908) (xy 130.515868 -345.846908)
			(xy 130.488603 -345.846328) (xy 130.43463 -345.838563) (xy 130.38231 -345.823197) (xy 130.33271 -345.800542)
			(xy 130.286839 -345.771058) (xy 130.24563 -345.735347) (xy 130.209922 -345.694136) (xy 130.180443 -345.648262)
			(xy 130.157792 -345.59866) (xy 130.14243 -345.546339) (xy 130.13467 -345.492365) (xy 128.651821 -345.492365)
			(xy 128.651821 -345.492372) (xy 128.644059 -345.546362) (xy 128.628692 -345.598697) (xy 128.606034 -345.648312)
			(xy 128.576545 -345.694199) (xy 128.540827 -345.735421) (xy 128.499605 -345.77114) (xy 128.45372 -345.80063)
			(xy 128.404104 -345.82329) (xy 128.35177 -345.838657) (xy 128.29778 -345.846421) (xy 128.270508 -345.846908)
			(xy 127.406908 -345.846908) (xy 127.37964 -345.846353) (xy 127.325659 -345.838593) (xy 127.273331 -345.823229)
			(xy 127.223723 -345.800575) (xy 127.177844 -345.771091) (xy 127.136628 -345.735378) (xy 127.100914 -345.694162)
			(xy 127.071429 -345.648284) (xy 127.048774 -345.598676) (xy 127.033409 -345.546349) (xy 127.025647 -345.492368)
			(xy 125.542822 -345.492368) (xy 125.542822 -345.49237) (xy 125.53506 -345.546356) (xy 125.519695 -345.598688)
			(xy 125.49704 -345.648301) (xy 125.467555 -345.694185) (xy 125.431841 -345.735407) (xy 125.390624 -345.771126)
			(xy 125.344743 -345.800617) (xy 125.295133 -345.823279) (xy 125.242803 -345.83865) (xy 125.188818 -345.846418)
			(xy 125.161548 -345.846908) (xy 124.297948 -345.846908) (xy 124.270678 -345.846356) (xy 124.216692 -345.8386)
			(xy 124.16436 -345.82324) (xy 124.114747 -345.800588) (xy 124.068863 -345.771105) (xy 124.027642 -345.735392)
			(xy 123.991924 -345.694176) (xy 123.962435 -345.648295) (xy 123.939777 -345.598685) (xy 123.92441 -345.546354)
			(xy 123.916648 -345.49237) (xy 122.433944 -345.49237) (xy 122.433944 -345.492375) (xy 122.426181 -345.546369)
			(xy 122.410812 -345.598709) (xy 122.388151 -345.648329) (xy 122.358659 -345.694219) (xy 122.322936 -345.735444)
			(xy 122.281709 -345.771166) (xy 122.235819 -345.800657) (xy 122.186198 -345.823316) (xy 122.133858 -345.838684)
			(xy 122.079863 -345.846445) (xy 122.052588 -345.846908) (xy 121.188988 -345.846908) (xy 121.161722 -345.846329)
			(xy 121.107747 -345.838567) (xy 121.055425 -345.823202) (xy 121.005822 -345.800548) (xy 120.959948 -345.771065)
			(xy 120.918737 -345.735354) (xy 120.883027 -345.694142) (xy 120.853546 -345.648267) (xy 120.830894 -345.598664)
			(xy 120.815531 -345.546342) (xy 120.80777 -345.492366) (xy 119.324922 -345.492366) (xy 119.324922 -345.492371)
			(xy 119.31716 -345.546359) (xy 119.301794 -345.598693) (xy 119.279137 -345.648307) (xy 119.24965 -345.694192)
			(xy 119.213934 -345.735414) (xy 119.172714 -345.771133) (xy 119.126832 -345.800624) (xy 119.077219 -345.823284)
			(xy 119.024886 -345.838654) (xy 118.970899 -345.84642) (xy 118.943628 -345.846908) (xy 118.080028 -345.846908)
			(xy 118.052759 -345.846355) (xy 117.998776 -345.838597) (xy 117.946446 -345.823235) (xy 117.896835 -345.800581)
			(xy 117.850953 -345.771098) (xy 117.809735 -345.735385) (xy 117.774019 -345.694169) (xy 117.744532 -345.648289)
			(xy 117.721875 -345.59868) (xy 117.706509 -345.546352) (xy 117.698747 -345.492369) (xy 116.216044 -345.492369)
			(xy 116.216044 -345.492376) (xy 116.20828 -345.546372) (xy 116.192911 -345.598713) (xy 116.170248 -345.648335)
			(xy 116.140754 -345.694225) (xy 116.105029 -345.735451) (xy 116.0638 -345.771173) (xy 116.017907 -345.800663)
			(xy 115.968283 -345.823322) (xy 115.915941 -345.838687) (xy 115.861944 -345.846447) (xy 115.834668 -345.846908)
			(xy 114.971068 -345.846908) (xy 114.943803 -345.846328) (xy 114.88983 -345.838563) (xy 114.83751 -345.823197)
			(xy 114.78791 -345.800542) (xy 114.742039 -345.771058) (xy 114.70083 -345.735347) (xy 114.665122 -345.694136)
			(xy 114.635643 -345.648262) (xy 114.612992 -345.59866) (xy 114.59763 -345.546339) (xy 114.58987 -345.492365)
			(xy 113.107021 -345.492365) (xy 113.107021 -345.492372) (xy 113.099259 -345.546362) (xy 113.083892 -345.598697)
			(xy 113.061234 -345.648312) (xy 113.031745 -345.694199) (xy 112.996027 -345.735421) (xy 112.954805 -345.77114)
			(xy 112.90892 -345.80063) (xy 112.859304 -345.82329) (xy 112.80697 -345.838657) (xy 112.75298 -345.846421)
			(xy 112.725708 -345.846908) (xy 111.862108 -345.846908) (xy 111.83484 -345.846353) (xy 111.780859 -345.838593)
			(xy 111.728531 -345.823229) (xy 111.678923 -345.800575) (xy 111.633044 -345.771091) (xy 111.591828 -345.735378)
			(xy 111.556114 -345.694162) (xy 111.526629 -345.648284) (xy 111.503974 -345.598676) (xy 111.488609 -345.546349)
			(xy 111.480847 -345.492368) (xy 93.706722 -345.492368) (xy 93.706722 -345.492371) (xy 93.69896 -345.546357)
			(xy 93.683595 -345.59869) (xy 93.660939 -345.648303) (xy 93.631454 -345.694187) (xy 93.595739 -345.735409)
			(xy 93.554521 -345.771128) (xy 93.50864 -345.800619) (xy 93.459029 -345.82328) (xy 93.406698 -345.838651)
			(xy 93.352713 -345.846419) (xy 93.325442 -345.846908) (xy 92.461842 -345.846908) (xy 92.434572 -345.846355)
			(xy 92.380587 -345.838599) (xy 92.328256 -345.823238) (xy 92.278643 -345.800586) (xy 92.23276 -345.771103)
			(xy 92.19154 -345.73539) (xy 92.155822 -345.694174) (xy 92.126334 -345.648293) (xy 92.103676 -345.598683)
			(xy 92.08831 -345.546354) (xy 92.080548 -345.49237) (xy 90.597844 -345.49237) (xy 90.597844 -345.492375)
			(xy 90.590081 -345.54637) (xy 90.574712 -345.59871) (xy 90.55205 -345.648331) (xy 90.522557 -345.694221)
			(xy 90.486834 -345.735446) (xy 90.445606 -345.771168) (xy 90.399715 -345.800659) (xy 90.350094 -345.823318)
			(xy 90.297752 -345.838685) (xy 90.243757 -345.846446) (xy 90.216482 -345.846908) (xy 89.352882 -345.846908)
			(xy 89.325617 -345.846328) (xy 89.271642 -345.838566) (xy 89.219321 -345.823201) (xy 89.169719 -345.800546)
			(xy 89.123845 -345.771063) (xy 89.082635 -345.735352) (xy 89.046926 -345.69414) (xy 89.017445 -345.648266)
			(xy 88.994793 -345.598663) (xy 88.979431 -345.546341) (xy 88.97167 -345.492365) (xy 87.488822 -345.492365)
			(xy 87.488822 -345.492372) (xy 87.481059 -345.54636) (xy 87.465693 -345.598694) (xy 87.443036 -345.648309)
			(xy 87.413549 -345.694194) (xy 87.377832 -345.735416) (xy 87.336612 -345.771136) (xy 87.290728 -345.800626)
			(xy 87.241115 -345.823286) (xy 87.188781 -345.838655) (xy 87.134794 -345.84642) (xy 87.107522 -345.846908)
			(xy 86.243922 -345.846908) (xy 86.216653 -345.846354) (xy 86.16267 -345.838595) (xy 86.110341 -345.823233)
			(xy 86.060732 -345.800579) (xy 86.014851 -345.771096) (xy 85.973633 -345.735383) (xy 85.937917 -345.694167)
			(xy 85.908431 -345.648288) (xy 85.885775 -345.598679) (xy 85.870409 -345.546351) (xy 85.862647 -345.492369)
			(xy 84.379944 -345.492369) (xy 84.379944 -345.492376) (xy 84.37218 -345.546373) (xy 84.35681 -345.598715)
			(xy 84.334147 -345.648336) (xy 84.304652 -345.694227) (xy 84.268927 -345.735453) (xy 84.227697 -345.771175)
			(xy 84.181803 -345.800665) (xy 84.132179 -345.823323) (xy 84.079836 -345.838688) (xy 84.025838 -345.846447)
			(xy 83.998562 -345.846908) (xy 83.134962 -345.846908) (xy 83.107698 -345.846327) (xy 83.053725 -345.838562)
			(xy 83.001406 -345.823195) (xy 82.951807 -345.80054) (xy 82.905936 -345.771056) (xy 82.864728 -345.735345)
			(xy 82.829021 -345.694134) (xy 82.799542 -345.64826) (xy 82.776892 -345.598658) (xy 82.76153 -345.546338)
			(xy 82.75377 -345.492364) (xy 81.270921 -345.492364) (xy 81.270921 -345.492373) (xy 81.263159 -345.546362)
			(xy 81.247792 -345.598698) (xy 81.225133 -345.648314) (xy 81.195644 -345.6942) (xy 81.159924 -345.735423)
			(xy 81.118702 -345.771143) (xy 81.072816 -345.800632) (xy 81.0232 -345.823291) (xy 80.970864 -345.838658)
			(xy 80.916875 -345.846421) (xy 80.889602 -345.846908) (xy 80.026002 -345.846908) (xy 79.998734 -345.846353)
			(xy 79.944754 -345.838592) (xy 79.892427 -345.823228) (xy 79.84282 -345.800573) (xy 79.796941 -345.771089)
			(xy 79.755726 -345.735376) (xy 79.720012 -345.69416) (xy 79.690528 -345.648282) (xy 79.667873 -345.598675)
			(xy 79.652509 -345.546348) (xy 79.644747 -345.492368) (xy 78.161922 -345.492368) (xy 78.161922 -345.492371)
			(xy 78.15416 -345.546357) (xy 78.138795 -345.59869) (xy 78.116139 -345.648303) (xy 78.086654 -345.694187)
			(xy 78.050939 -345.735409) (xy 78.009721 -345.771128) (xy 77.96384 -345.800619) (xy 77.914229 -345.82328)
			(xy 77.861898 -345.838651) (xy 77.807913 -345.846419) (xy 77.780642 -345.846908) (xy 76.917042 -345.846908)
			(xy 76.889772 -345.846355) (xy 76.835787 -345.838599) (xy 76.783456 -345.823238) (xy 76.733843 -345.800586)
			(xy 76.68796 -345.771103) (xy 76.64674 -345.73539) (xy 76.611022 -345.694174) (xy 76.581534 -345.648293)
			(xy 76.558876 -345.598683) (xy 76.54351 -345.546354) (xy 76.535748 -345.49237) (xy 75.053044 -345.49237)
			(xy 75.053044 -345.492375) (xy 75.045281 -345.54637) (xy 75.029912 -345.59871) (xy 75.00725 -345.648331)
			(xy 74.977757 -345.694221) (xy 74.942034 -345.735446) (xy 74.900806 -345.771168) (xy 74.854915 -345.800659)
			(xy 74.805294 -345.823318) (xy 74.752952 -345.838685) (xy 74.698957 -345.846446) (xy 74.671682 -345.846908)
			(xy 73.808082 -345.846908) (xy 73.780817 -345.846328) (xy 73.726842 -345.838566) (xy 73.674521 -345.823201)
			(xy 73.624919 -345.800546) (xy 73.579045 -345.771063) (xy 73.537835 -345.735352) (xy 73.502126 -345.69414)
			(xy 73.472645 -345.648266) (xy 73.449993 -345.598663) (xy 73.434631 -345.546341) (xy 73.42687 -345.492365)
			(xy 71.944022 -345.492365) (xy 71.944022 -345.492372) (xy 71.936259 -345.54636) (xy 71.920893 -345.598694)
			(xy 71.898236 -345.648309) (xy 71.868749 -345.694194) (xy 71.833032 -345.735416) (xy 71.791812 -345.771136)
			(xy 71.745928 -345.800626) (xy 71.696315 -345.823286) (xy 71.643981 -345.838655) (xy 71.589994 -345.84642)
			(xy 71.562722 -345.846908) (xy 70.699122 -345.846908) (xy 70.671853 -345.846354) (xy 70.61787 -345.838595)
			(xy 70.565541 -345.823233) (xy 70.515932 -345.800579) (xy 70.470051 -345.771096) (xy 70.428833 -345.735383)
			(xy 70.393117 -345.694167) (xy 70.363631 -345.648288) (xy 70.340975 -345.598679) (xy 70.325609 -345.546351)
			(xy 70.317847 -345.492369) (xy 68.835144 -345.492369) (xy 68.835144 -345.492376) (xy 68.82738 -345.546373)
			(xy 68.81201 -345.598715) (xy 68.789347 -345.648336) (xy 68.759852 -345.694227) (xy 68.724127 -345.735453)
			(xy 68.682897 -345.771175) (xy 68.637003 -345.800665) (xy 68.587379 -345.823323) (xy 68.535036 -345.838688)
			(xy 68.481038 -345.846447) (xy 68.453762 -345.846908) (xy 67.590162 -345.846908) (xy 67.562898 -345.846327)
			(xy 67.508925 -345.838562) (xy 67.456606 -345.823195) (xy 67.407007 -345.80054) (xy 67.361136 -345.771056)
			(xy 67.319928 -345.735345) (xy 67.284221 -345.694134) (xy 67.254742 -345.64826) (xy 67.232092 -345.598658)
			(xy 67.21673 -345.546338) (xy 67.20897 -345.492364) (xy 65.726121 -345.492364) (xy 65.726121 -345.492373)
			(xy 65.718359 -345.546362) (xy 65.702992 -345.598698) (xy 65.680333 -345.648314) (xy 65.650844 -345.6942)
			(xy 65.615124 -345.735423) (xy 65.573902 -345.771143) (xy 65.528016 -345.800632) (xy 65.4784 -345.823291)
			(xy 65.426064 -345.838658) (xy 65.372075 -345.846421) (xy 65.344802 -345.846908) (xy 64.481202 -345.846908)
			(xy 64.453934 -345.846353) (xy 64.399954 -345.838592) (xy 64.347627 -345.823228) (xy 64.29802 -345.800573)
			(xy 64.252141 -345.771089) (xy 64.210926 -345.735376) (xy 64.175212 -345.69416) (xy 64.145728 -345.648282)
			(xy 64.123073 -345.598675) (xy 64.107709 -345.546348) (xy 64.099947 -345.492368) (xy 62.617122 -345.492368)
			(xy 62.617122 -345.492371) (xy 62.60936 -345.546357) (xy 62.593995 -345.59869) (xy 62.571339 -345.648303)
			(xy 62.541854 -345.694187) (xy 62.506139 -345.735409) (xy 62.464921 -345.771128) (xy 62.41904 -345.800619)
			(xy 62.369429 -345.82328) (xy 62.317098 -345.838651) (xy 62.263113 -345.846419) (xy 62.235842 -345.846908)
			(xy 61.372242 -345.846908) (xy 61.344972 -345.846355) (xy 61.290987 -345.838599) (xy 61.238656 -345.823238)
			(xy 61.189043 -345.800586) (xy 61.14316 -345.771103) (xy 61.10194 -345.73539) (xy 61.066222 -345.694174)
			(xy 61.036734 -345.648293) (xy 61.014076 -345.598683) (xy 60.99871 -345.546354) (xy 60.990948 -345.49237)
			(xy 51.666922 -345.49237) (xy 51.65916 -345.546356) (xy 51.643795 -345.598688) (xy 51.62114 -345.648301)
			(xy 51.591655 -345.694185) (xy 51.555941 -345.735407) (xy 51.514724 -345.771126) (xy 51.468843 -345.800617)
			(xy 51.419233 -345.823279) (xy 51.366903 -345.83865) (xy 51.312918 -345.846418) (xy 51.285648 -345.846908)
			(xy 50.422048 -345.846908) (xy 50.394778 -345.846356) (xy 50.340792 -345.8386) (xy 50.28846 -345.82324)
			(xy 50.238847 -345.800588) (xy 50.192963 -345.771105) (xy 50.151742 -345.735392) (xy 50.116024 -345.694176)
			(xy 50.086535 -345.648295) (xy 50.063877 -345.598685) (xy 50.04851 -345.546354) (xy 50.040748 -345.49237)
			(xy 48.558044 -345.49237) (xy 48.558044 -345.492375) (xy 48.550281 -345.546369) (xy 48.534912 -345.598709)
			(xy 48.512251 -345.648329) (xy 48.482759 -345.694219) (xy 48.447036 -345.735444) (xy 48.405809 -345.771166)
			(xy 48.359919 -345.800657) (xy 48.310298 -345.823316) (xy 48.257958 -345.838684) (xy 48.203963 -345.846445)
			(xy 48.176688 -345.846908) (xy 47.313088 -345.846908) (xy 47.285822 -345.846329) (xy 47.231847 -345.838567)
			(xy 47.179525 -345.823202) (xy 47.129922 -345.800548) (xy 47.084048 -345.771065) (xy 47.042837 -345.735354)
			(xy 47.007127 -345.694142) (xy 46.977646 -345.648267) (xy 46.954994 -345.598664) (xy 46.939631 -345.546342)
			(xy 46.93187 -345.492366) (xy 45.449022 -345.492366) (xy 45.449022 -345.492371) (xy 45.44126 -345.546359)
			(xy 45.425894 -345.598693) (xy 45.403237 -345.648307) (xy 45.37375 -345.694192) (xy 45.338034 -345.735414)
			(xy 45.296814 -345.771133) (xy 45.250932 -345.800624) (xy 45.201319 -345.823284) (xy 45.148986 -345.838654)
			(xy 45.094999 -345.84642) (xy 45.067728 -345.846908) (xy 44.204128 -345.846908) (xy 44.176859 -345.846355)
			(xy 44.122876 -345.838597) (xy 44.070546 -345.823235) (xy 44.020935 -345.800581) (xy 43.975053 -345.771098)
			(xy 43.933835 -345.735385) (xy 43.898119 -345.694169) (xy 43.868632 -345.648289) (xy 43.845975 -345.59868)
			(xy 43.830609 -345.546352) (xy 43.822847 -345.492369) (xy 42.340144 -345.492369) (xy 42.340144 -345.492376)
			(xy 42.33238 -345.546372) (xy 42.317011 -345.598713) (xy 42.294348 -345.648335) (xy 42.264854 -345.694225)
			(xy 42.229129 -345.735451) (xy 42.1879 -345.771173) (xy 42.142007 -345.800663) (xy 42.092383 -345.823322)
			(xy 42.040041 -345.838687) (xy 41.986044 -345.846447) (xy 41.958768 -345.846908) (xy 41.095168 -345.846908)
			(xy 41.067903 -345.846328) (xy 41.01393 -345.838563) (xy 40.96161 -345.823197) (xy 40.91201 -345.800542)
			(xy 40.866139 -345.771058) (xy 40.82493 -345.735347) (xy 40.789222 -345.694136) (xy 40.759743 -345.648262)
			(xy 40.737092 -345.59866) (xy 40.72173 -345.546339) (xy 40.71397 -345.492365) (xy 39.231121 -345.492365)
			(xy 39.231121 -345.492372) (xy 39.223359 -345.546362) (xy 39.207992 -345.598697) (xy 39.185334 -345.648312)
			(xy 39.155845 -345.694199) (xy 39.120127 -345.735421) (xy 39.078905 -345.77114) (xy 39.03302 -345.80063)
			(xy 38.983404 -345.82329) (xy 38.93107 -345.838657) (xy 38.87708 -345.846421) (xy 38.849808 -345.846908)
			(xy 37.986208 -345.846908) (xy 37.95894 -345.846353) (xy 37.904959 -345.838593) (xy 37.852631 -345.823229)
			(xy 37.803023 -345.800575) (xy 37.757144 -345.771091) (xy 37.715928 -345.735378) (xy 37.680214 -345.694162)
			(xy 37.650729 -345.648284) (xy 37.628074 -345.598676) (xy 37.612709 -345.546349) (xy 37.604947 -345.492368)
			(xy 36.122122 -345.492368) (xy 36.122122 -345.49237) (xy 36.11436 -345.546356) (xy 36.098995 -345.598688)
			(xy 36.07634 -345.648301) (xy 36.046855 -345.694185) (xy 36.011141 -345.735407) (xy 35.969924 -345.771126)
			(xy 35.924043 -345.800617) (xy 35.874433 -345.823279) (xy 35.822103 -345.83865) (xy 35.768118 -345.846418)
			(xy 35.740848 -345.846908) (xy 34.877248 -345.846908) (xy 34.849978 -345.846356) (xy 34.795992 -345.8386)
			(xy 34.74366 -345.82324) (xy 34.694047 -345.800588) (xy 34.648163 -345.771105) (xy 34.606942 -345.735392)
			(xy 34.571224 -345.694176) (xy 34.541735 -345.648295) (xy 34.519077 -345.598685) (xy 34.50371 -345.546354)
			(xy 34.495948 -345.49237) (xy 33.013244 -345.49237) (xy 33.013244 -345.492375) (xy 33.005481 -345.546369)
			(xy 32.990112 -345.598709) (xy 32.967451 -345.648329) (xy 32.937959 -345.694219) (xy 32.902236 -345.735444)
			(xy 32.861009 -345.771166) (xy 32.815119 -345.800657) (xy 32.765498 -345.823316) (xy 32.713158 -345.838684)
			(xy 32.659163 -345.846445) (xy 32.631888 -345.846908) (xy 31.768288 -345.846908) (xy 31.741022 -345.846329)
			(xy 31.687047 -345.838567) (xy 31.634725 -345.823202) (xy 31.585122 -345.800548) (xy 31.539248 -345.771065)
			(xy 31.498037 -345.735354) (xy 31.462327 -345.694142) (xy 31.432846 -345.648267) (xy 31.410194 -345.598664)
			(xy 31.394831 -345.546342) (xy 31.38707 -345.492366) (xy 29.904222 -345.492366) (xy 29.904222 -345.492371)
			(xy 29.89646 -345.546359) (xy 29.881094 -345.598693) (xy 29.858437 -345.648307) (xy 29.82895 -345.694192)
			(xy 29.793234 -345.735414) (xy 29.752014 -345.771133) (xy 29.706132 -345.800624) (xy 29.656519 -345.823284)
			(xy 29.604186 -345.838654) (xy 29.550199 -345.84642) (xy 29.522928 -345.846908) (xy 28.659328 -345.846908)
			(xy 28.632059 -345.846355) (xy 28.578076 -345.838597) (xy 28.525746 -345.823235) (xy 28.476135 -345.800581)
			(xy 28.430253 -345.771098) (xy 28.389035 -345.735385) (xy 28.353319 -345.694169) (xy 28.323832 -345.648289)
			(xy 28.301175 -345.59868) (xy 28.285809 -345.546352) (xy 28.278047 -345.492369) (xy 26.795344 -345.492369)
			(xy 26.795344 -345.492376) (xy 26.78758 -345.546372) (xy 26.772211 -345.598713) (xy 26.749548 -345.648335)
			(xy 26.720054 -345.694225) (xy 26.684329 -345.735451) (xy 26.6431 -345.771173) (xy 26.597207 -345.800663)
			(xy 26.547583 -345.823322) (xy 26.495241 -345.838687) (xy 26.441244 -345.846447) (xy 26.413968 -345.846908)
			(xy 25.550368 -345.846908) (xy 25.523103 -345.846328) (xy 25.46913 -345.838563) (xy 25.41681 -345.823197)
			(xy 25.36721 -345.800542) (xy 25.321339 -345.771058) (xy 25.28013 -345.735347) (xy 25.244422 -345.694136)
			(xy 25.214943 -345.648262) (xy 25.192292 -345.59866) (xy 25.17693 -345.546339) (xy 25.16917 -345.492365)
			(xy 23.686305 -345.492365) (xy 23.686305 -345.492421) (xy 23.678542 -345.546407) (xy 23.663176 -345.59874)
			(xy 23.640519 -345.648352) (xy 23.611031 -345.694236) (xy 23.575314 -345.735455) (xy 23.534094 -345.771172)
			(xy 23.488211 -345.80066) (xy 23.438598 -345.823317) (xy 23.386265 -345.838683) (xy 23.332279 -345.846445)
			(xy 23.305008 -345.846908) (xy 22.441408 -345.846908) (xy 22.414138 -345.846429) (xy 22.360154 -345.838667)
			(xy 22.307825 -345.823302) (xy 22.258214 -345.800645) (xy 22.212333 -345.771159) (xy 22.171115 -345.735443)
			(xy 22.1354 -345.694225) (xy 22.105914 -345.648344) (xy 22.083258 -345.598733) (xy 22.067892 -345.546404)
			(xy 22.06013 -345.49242) (xy 20.577345 -345.49242) (xy 20.577345 -345.492421) (xy 20.569582 -345.546407)
			(xy 20.554216 -345.59874) (xy 20.531559 -345.648352) (xy 20.502071 -345.694236) (xy 20.466354 -345.735455)
			(xy 20.425134 -345.771172) (xy 20.379251 -345.80066) (xy 20.329638 -345.823317) (xy 20.277305 -345.838683)
			(xy 20.223319 -345.846445) (xy 20.196048 -345.846908) (xy 19.332448 -345.846908) (xy 19.305178 -345.846429)
			(xy 19.251194 -345.838667) (xy 19.198865 -345.823302) (xy 19.149254 -345.800645) (xy 19.103373 -345.771159)
			(xy 19.062155 -345.735443) (xy 19.02644 -345.694225) (xy 18.996954 -345.648344) (xy 18.974298 -345.598733)
			(xy 18.958932 -345.546404) (xy 18.95117 -345.49242) (xy 1.524 -345.49242) (xy 1.524 -348.976496)
			(xy 4.708641 -348.976496) (xy 4.708641 -348.847356) (xy 4.716591 -348.718461) (xy 4.732461 -348.590301)
			(xy 4.75619 -348.46336) (xy 4.787689 -348.338121) (xy 4.826838 -348.215058) (xy 4.873489 -348.094639)
			(xy 4.927464 -347.97732) (xy 4.988559 -347.863546) (xy 5.056542 -347.753749) (xy 5.131156 -347.648346)
			(xy 5.212117 -347.547736) (xy 5.299117 -347.452301) (xy 5.391828 -347.362402) (xy 5.489898 -347.278381)
			(xy 5.592953 -347.200557) (xy 5.700604 -347.129225) (xy 5.812443 -347.064655) (xy 5.928044 -347.007093)
			(xy 6.046969 -346.956756) (xy 6.168768 -346.913836) (xy 6.292978 -346.878495) (xy 6.419127 -346.850868)
			(xy 6.546739 -346.831059) (xy 6.675328 -346.819143) (xy 6.804406 -346.815167) (xy 6.933484 -346.819143)
			(xy 7.062073 -346.831059) (xy 7.189685 -346.850868) (xy 7.315834 -346.878495) (xy 7.440044 -346.913836)
			(xy 7.561843 -346.956756) (xy 7.680768 -347.007093) (xy 7.796369 -347.064655) (xy 7.908208 -347.129225)
			(xy 8.015859 -347.200557) (xy 8.118914 -347.278381) (xy 8.216984 -347.362402) (xy 8.25588 -347.400118)
			(xy 211.503015 -347.400118) (xy 211.507009 -347.215797) (xy 211.518984 -347.031821) (xy 211.538917 -346.848538)
			(xy 211.566771 -346.666289) (xy 211.602494 -346.485419) (xy 211.646018 -346.306266) (xy 211.697263 -346.129166)
			(xy 211.756131 -345.954452) (xy 211.822512 -345.782453) (xy 211.896281 -345.61349) (xy 211.977301 -345.447882)
			(xy 212.065418 -345.285938) (xy 212.160468 -345.127964) (xy 212.262272 -344.974256) (xy 212.370638 -344.825102)
			(xy 212.485365 -344.680782) (xy 212.606235 -344.541568) (xy 212.733022 -344.40772) (xy 212.865489 -344.27949)
			(xy 213.003386 -344.157119) (xy 213.146454 -344.040836) (xy 213.294425 -343.93086) (xy 213.447022 -343.827397)
			(xy 213.603957 -343.730641) (xy 213.764936 -343.640775) (xy 213.929657 -343.557966) (xy 214.097811 -343.48237)
			(xy 214.269081 -343.41413) (xy 214.443147 -343.353373) (xy 214.619681 -343.300213) (xy 214.798352 -343.254751)
			(xy 214.978825 -343.217071) (xy 215.160761 -343.187244) (xy 215.343818 -343.165326) (xy 215.527653 -343.151359)
			(xy 215.71192 -343.145368) (xy 215.896274 -343.147365) (xy 216.080368 -343.157347) (xy 216.263857 -343.175293)
			(xy 216.446396 -343.201172) (xy 216.627643 -343.234933) (xy 216.807258 -343.276514) (xy 216.984902 -343.325837)
			(xy 217.160243 -343.382809) (xy 217.332952 -343.447323) (xy 217.502703 -343.519257) (xy 217.66918 -343.598478)
			(xy 217.832068 -343.684836) (xy 217.991063 -343.778169) (xy 218.145865 -343.878302) (xy 218.296184 -343.985046)
			(xy 218.441738 -344.098202) (xy 218.582254 -344.217558) (xy 218.717467 -344.342888) (xy 218.847124 -344.473957)
			(xy 218.970982 -344.61052) (xy 219.088808 -344.752321) (xy 219.200381 -344.899092) (xy 219.305491 -345.050559)
			(xy 219.403941 -345.206437) (xy 219.495546 -345.366433) (xy 219.560575 -345.492368) (xy 267.515847 -345.492368)
			(xy 267.515847 -345.437832) (xy 267.523609 -345.383852) (xy 267.538973 -345.331525) (xy 267.561628 -345.281918)
			(xy 267.591112 -345.23604) (xy 267.626826 -345.194824) (xy 267.668041 -345.159111) (xy 267.71392 -345.129627)
			(xy 267.763527 -345.106972) (xy 267.815854 -345.091608) (xy 267.869834 -345.083847) (xy 267.897102 -345.083384)
			(xy 268.760702 -345.083384) (xy 268.787975 -345.083779) (xy 268.841964 -345.091542) (xy 268.8943 -345.106909)
			(xy 268.943916 -345.129568) (xy 268.989802 -345.159057) (xy 269.031024 -345.194777) (xy 269.066744 -345.236)
			(xy 269.096233 -345.281886) (xy 269.118892 -345.331502) (xy 269.134259 -345.383838) (xy 269.142021 -345.437827)
			(xy 269.142021 -345.492364) (xy 270.62487 -345.492364) (xy 270.62487 -345.437836) (xy 270.63263 -345.383862)
			(xy 270.647992 -345.331542) (xy 270.670642 -345.28194) (xy 270.700121 -345.236066) (xy 270.735828 -345.194855)
			(xy 270.777036 -345.159144) (xy 270.822907 -345.12966) (xy 270.872506 -345.107005) (xy 270.924825 -345.091638)
			(xy 270.978798 -345.083873) (xy 271.006062 -345.083384) (xy 271.869662 -345.083384) (xy 271.896938 -345.083753)
			(xy 271.950936 -345.091512) (xy 272.003279 -345.106877) (xy 272.052903 -345.129535) (xy 272.098797 -345.159025)
			(xy 272.140027 -345.194747) (xy 272.175752 -345.235973) (xy 272.205247 -345.281864) (xy 272.22791 -345.331485)
			(xy 272.24328 -345.383827) (xy 272.251044 -345.437824) (xy 272.251044 -345.492369) (xy 273.733747 -345.492369)
			(xy 273.733747 -345.437831) (xy 273.741509 -345.383849) (xy 273.756875 -345.331521) (xy 273.779531 -345.281912)
			(xy 273.809017 -345.236033) (xy 273.844733 -345.194817) (xy 273.885951 -345.159104) (xy 273.931832 -345.129621)
			(xy 273.981441 -345.106967) (xy 274.033771 -345.091605) (xy 274.087753 -345.083846) (xy 274.115022 -345.083384)
			(xy 274.978622 -345.083384) (xy 275.005894 -345.08378) (xy 275.059881 -345.091545) (xy 275.112215 -345.106914)
			(xy 275.161828 -345.129574) (xy 275.207712 -345.159064) (xy 275.248932 -345.194784) (xy 275.284649 -345.236006)
			(xy 275.314136 -345.281891) (xy 275.336793 -345.331506) (xy 275.352159 -345.38384) (xy 275.359922 -345.437828)
			(xy 275.359922 -345.492365) (xy 276.84277 -345.492365) (xy 276.84277 -345.437835) (xy 276.850531 -345.383859)
			(xy 276.865893 -345.331537) (xy 276.888545 -345.281934) (xy 276.918026 -345.23606) (xy 276.953735 -345.194848)
			(xy 276.994945 -345.159137) (xy 277.040819 -345.129654) (xy 277.090421 -345.106999) (xy 277.142742 -345.091634)
			(xy 277.196717 -345.083872) (xy 277.223982 -345.083384) (xy 278.087582 -345.083384) (xy 278.114857 -345.083754)
			(xy 278.168852 -345.091515) (xy 278.221194 -345.106882) (xy 278.270815 -345.129541) (xy 278.316706 -345.159032)
			(xy 278.357934 -345.194754) (xy 278.393657 -345.235979) (xy 278.42315 -345.281869) (xy 278.445812 -345.33149)
			(xy 278.461181 -345.38383) (xy 278.468944 -345.437825) (xy 278.468944 -345.49237) (xy 279.951648 -345.49237)
			(xy 279.951648 -345.43783) (xy 279.95941 -345.383846) (xy 279.974776 -345.331517) (xy 279.997434 -345.281907)
			(xy 280.026922 -345.236026) (xy 280.06264 -345.19481) (xy 280.10386 -345.159097) (xy 280.149744 -345.129614)
			(xy 280.199356 -345.106962) (xy 280.251687 -345.091601) (xy 280.305672 -345.083845) (xy 280.332942 -345.083384)
			(xy 281.196542 -345.083384) (xy 281.223813 -345.083781) (xy 281.277798 -345.091549) (xy 281.330129 -345.10692)
			(xy 281.37974 -345.129581) (xy 281.425621 -345.159072) (xy 281.466839 -345.194791) (xy 281.502554 -345.236013)
			(xy 281.532039 -345.281897) (xy 281.554695 -345.33151) (xy 281.57006 -345.383843) (xy 281.577822 -345.437829)
			(xy 281.577822 -345.492368) (xy 283.060647 -345.492368) (xy 283.060647 -345.437832) (xy 283.068409 -345.383852)
			(xy 283.083773 -345.331525) (xy 283.106428 -345.281918) (xy 283.135912 -345.23604) (xy 283.171626 -345.194824)
			(xy 283.212841 -345.159111) (xy 283.25872 -345.129627) (xy 283.308327 -345.106972) (xy 283.360654 -345.091608)
			(xy 283.414634 -345.083847) (xy 283.441902 -345.083384) (xy 284.305502 -345.083384) (xy 284.332775 -345.083779)
			(xy 284.386764 -345.091542) (xy 284.4391 -345.106909) (xy 284.488716 -345.129568) (xy 284.534602 -345.159057)
			(xy 284.575824 -345.194777) (xy 284.611544 -345.236) (xy 284.641033 -345.281886) (xy 284.663692 -345.331502)
			(xy 284.679059 -345.383838) (xy 284.686821 -345.437827) (xy 284.686821 -345.492364) (xy 286.16967 -345.492364)
			(xy 286.16967 -345.437836) (xy 286.17743 -345.383862) (xy 286.192792 -345.331542) (xy 286.215442 -345.28194)
			(xy 286.244921 -345.236066) (xy 286.280628 -345.194855) (xy 286.321836 -345.159144) (xy 286.367707 -345.12966)
			(xy 286.417306 -345.107005) (xy 286.469625 -345.091638) (xy 286.523598 -345.083873) (xy 286.550862 -345.083384)
			(xy 287.414462 -345.083384) (xy 287.441738 -345.083753) (xy 287.495736 -345.091512) (xy 287.548079 -345.106877)
			(xy 287.597703 -345.129535) (xy 287.643597 -345.159025) (xy 287.684827 -345.194747) (xy 287.720552 -345.235973)
			(xy 287.750047 -345.281864) (xy 287.77271 -345.331485) (xy 287.78808 -345.383827) (xy 287.795844 -345.437824)
			(xy 287.795844 -345.492369) (xy 289.278547 -345.492369) (xy 289.278547 -345.437831) (xy 289.286309 -345.383849)
			(xy 289.301675 -345.331521) (xy 289.324331 -345.281912) (xy 289.353817 -345.236033) (xy 289.389533 -345.194817)
			(xy 289.430751 -345.159104) (xy 289.476632 -345.129621) (xy 289.526241 -345.106967) (xy 289.578571 -345.091605)
			(xy 289.632553 -345.083846) (xy 289.659822 -345.083384) (xy 290.523422 -345.083384) (xy 290.550694 -345.08378)
			(xy 290.604681 -345.091545) (xy 290.657015 -345.106914) (xy 290.706628 -345.129574) (xy 290.752512 -345.159064)
			(xy 290.793732 -345.194784) (xy 290.829449 -345.236006) (xy 290.858936 -345.281891) (xy 290.881593 -345.331506)
			(xy 290.896959 -345.38384) (xy 290.904722 -345.437828) (xy 290.904722 -345.492365) (xy 292.38757 -345.492365)
			(xy 292.38757 -345.437835) (xy 292.395331 -345.383859) (xy 292.410693 -345.331537) (xy 292.433345 -345.281934)
			(xy 292.462826 -345.23606) (xy 292.498535 -345.194848) (xy 292.539745 -345.159137) (xy 292.585619 -345.129654)
			(xy 292.635221 -345.106999) (xy 292.687542 -345.091634) (xy 292.741517 -345.083872) (xy 292.768782 -345.083384)
			(xy 293.632382 -345.083384) (xy 293.659657 -345.083754) (xy 293.713652 -345.091515) (xy 293.765994 -345.106882)
			(xy 293.815615 -345.129541) (xy 293.861506 -345.159032) (xy 293.902734 -345.194754) (xy 293.938457 -345.235979)
			(xy 293.96795 -345.281869) (xy 293.990612 -345.33149) (xy 294.005981 -345.38383) (xy 294.013744 -345.437825)
			(xy 294.013744 -345.49237) (xy 295.496448 -345.49237) (xy 295.496448 -345.43783) (xy 295.50421 -345.383846)
			(xy 295.519576 -345.331517) (xy 295.542234 -345.281907) (xy 295.571722 -345.236026) (xy 295.60744 -345.19481)
			(xy 295.64866 -345.159097) (xy 295.694544 -345.129614) (xy 295.744156 -345.106962) (xy 295.796487 -345.091601)
			(xy 295.850472 -345.083845) (xy 295.877742 -345.083384) (xy 296.741342 -345.083384) (xy 296.768613 -345.083781)
			(xy 296.822598 -345.091549) (xy 296.874929 -345.10692) (xy 296.92454 -345.129581) (xy 296.970421 -345.159072)
			(xy 297.011639 -345.194791) (xy 297.047354 -345.236013) (xy 297.076839 -345.281897) (xy 297.099495 -345.33151)
			(xy 297.11486 -345.383843) (xy 297.122622 -345.437829) (xy 297.122622 -345.492368) (xy 298.605447 -345.492368)
			(xy 298.605447 -345.437832) (xy 298.613209 -345.383852) (xy 298.628573 -345.331525) (xy 298.651228 -345.281918)
			(xy 298.680712 -345.23604) (xy 298.716426 -345.194824) (xy 298.757641 -345.159111) (xy 298.80352 -345.129627)
			(xy 298.853127 -345.106972) (xy 298.905454 -345.091608) (xy 298.959434 -345.083847) (xy 298.986702 -345.083384)
			(xy 299.850302 -345.083384) (xy 299.877575 -345.083779) (xy 299.931564 -345.091542) (xy 299.9839 -345.106909)
			(xy 300.033516 -345.129568) (xy 300.079402 -345.159057) (xy 300.120624 -345.194777) (xy 300.156344 -345.236)
			(xy 300.185833 -345.281886) (xy 300.208492 -345.331502) (xy 300.223859 -345.383838) (xy 300.231621 -345.437827)
			(xy 300.231621 -345.492368) (xy 312.121547 -345.492368) (xy 312.121547 -345.437832) (xy 312.129309 -345.383851)
			(xy 312.144673 -345.331525) (xy 312.167328 -345.281917) (xy 312.196813 -345.236039) (xy 312.232526 -345.194824)
			(xy 312.273742 -345.159111) (xy 312.319621 -345.129627) (xy 312.369228 -345.106972) (xy 312.421555 -345.091608)
			(xy 312.475536 -345.083847) (xy 312.502804 -345.083384) (xy 313.366404 -345.083384) (xy 313.393676 -345.083779)
			(xy 313.447666 -345.091542) (xy 313.500001 -345.106909) (xy 313.549617 -345.129569) (xy 313.595503 -345.159058)
			(xy 313.636725 -345.194778) (xy 313.672444 -345.236) (xy 313.701933 -345.281886) (xy 313.724592 -345.331502)
			(xy 313.739959 -345.383838) (xy 313.747721 -345.437828) (xy 313.747721 -345.492364) (xy 315.23057 -345.492364)
			(xy 315.23057 -345.437836) (xy 315.23833 -345.383862) (xy 315.253692 -345.331541) (xy 315.276343 -345.281939)
			(xy 315.305821 -345.236066) (xy 315.341529 -345.194854) (xy 315.382737 -345.159143) (xy 315.428608 -345.12966)
			(xy 315.478207 -345.107004) (xy 315.530526 -345.091638) (xy 315.5845 -345.083873) (xy 315.611764 -345.083384)
			(xy 316.475364 -345.083384) (xy 316.50264 -345.083753) (xy 316.556637 -345.091512) (xy 316.608981 -345.106877)
			(xy 316.658604 -345.129535) (xy 316.704498 -345.159026) (xy 316.745727 -345.194747) (xy 316.781453 -345.235973)
			(xy 316.810947 -345.281864) (xy 316.83361 -345.331486) (xy 316.84898 -345.383828) (xy 316.856744 -345.437824)
			(xy 316.856744 -345.492369) (xy 318.339447 -345.492369) (xy 318.339447 -345.437831) (xy 318.347209 -345.383849)
			(xy 318.362575 -345.33152) (xy 318.385231 -345.281912) (xy 318.414718 -345.236032) (xy 318.450434 -345.194817)
			(xy 318.491652 -345.159103) (xy 318.537533 -345.12962) (xy 318.587143 -345.106966) (xy 318.639472 -345.091604)
			(xy 318.693455 -345.083846) (xy 318.720724 -345.083384) (xy 319.584324 -345.083384) (xy 319.611596 -345.08378)
			(xy 319.665583 -345.091546) (xy 319.717916 -345.106915) (xy 319.767529 -345.129575) (xy 319.813413 -345.159065)
			(xy 319.854632 -345.194785) (xy 319.890349 -345.236007) (xy 319.919836 -345.281892) (xy 319.942494 -345.331507)
			(xy 319.95786 -345.38384) (xy 319.965622 -345.437828) (xy 319.965622 -345.492365) (xy 321.44847 -345.492365)
			(xy 321.44847 -345.437835) (xy 321.456231 -345.383859) (xy 321.471593 -345.331537) (xy 321.494246 -345.281934)
			(xy 321.523726 -345.236059) (xy 321.559436 -345.194847) (xy 321.600646 -345.159136) (xy 321.64652 -345.129653)
			(xy 321.696122 -345.106999) (xy 321.748443 -345.091634) (xy 321.802419 -345.083871) (xy 321.829684 -345.083384)
			(xy 322.693284 -345.083384) (xy 322.720559 -345.083755) (xy 322.774554 -345.091516) (xy 322.826895 -345.106882)
			(xy 322.876516 -345.129542) (xy 322.922407 -345.159033) (xy 322.963634 -345.194754) (xy 322.999358 -345.23598)
			(xy 323.02885 -345.28187) (xy 323.051512 -345.33149) (xy 323.066881 -345.38383) (xy 323.074644 -345.437825)
			(xy 323.074644 -345.49237) (xy 324.557348 -345.49237) (xy 324.557348 -345.43783) (xy 324.56511 -345.383846)
			(xy 324.580476 -345.331516) (xy 324.603135 -345.281906) (xy 324.632623 -345.236026) (xy 324.668341 -345.194809)
			(xy 324.709561 -345.159096) (xy 324.755445 -345.129613) (xy 324.805057 -345.106961) (xy 324.857389 -345.0916)
			(xy 324.911374 -345.083844) (xy 324.938644 -345.083384) (xy 325.802244 -345.083384) (xy 325.829515 -345.083782)
			(xy 325.8835 -345.091549) (xy 325.93583 -345.10692) (xy 325.985441 -345.129582) (xy 326.031322 -345.159072)
			(xy 326.072539 -345.194792) (xy 326.108254 -345.236013) (xy 326.137739 -345.281898) (xy 326.160395 -345.331511)
			(xy 326.17576 -345.383843) (xy 326.183522 -345.437829) (xy 326.183522 -345.492368) (xy 327.666347 -345.492368)
			(xy 327.666347 -345.437832) (xy 327.674109 -345.383851) (xy 327.689473 -345.331525) (xy 327.712128 -345.281917)
			(xy 327.741613 -345.236039) (xy 327.777326 -345.194824) (xy 327.818542 -345.159111) (xy 327.864421 -345.129627)
			(xy 327.914028 -345.106972) (xy 327.966355 -345.091608) (xy 328.020336 -345.083847) (xy 328.047604 -345.083384)
			(xy 328.911204 -345.083384) (xy 328.938476 -345.083779) (xy 328.992466 -345.091542) (xy 329.044801 -345.106909)
			(xy 329.094417 -345.129569) (xy 329.140303 -345.159058) (xy 329.181525 -345.194778) (xy 329.217244 -345.236)
			(xy 329.246733 -345.281886) (xy 329.269392 -345.331502) (xy 329.284759 -345.383838) (xy 329.292521 -345.437828)
			(xy 329.292521 -345.492364) (xy 330.77537 -345.492364) (xy 330.77537 -345.437836) (xy 330.78313 -345.383862)
			(xy 330.798492 -345.331541) (xy 330.821143 -345.281939) (xy 330.850621 -345.236066) (xy 330.886329 -345.194854)
			(xy 330.927537 -345.159143) (xy 330.973408 -345.12966) (xy 331.023007 -345.107004) (xy 331.075326 -345.091638)
			(xy 331.1293 -345.083873) (xy 331.156564 -345.083384) (xy 332.020164 -345.083384) (xy 332.04744 -345.083753)
			(xy 332.101437 -345.091512) (xy 332.153781 -345.106877) (xy 332.203404 -345.129535) (xy 332.249298 -345.159026)
			(xy 332.290527 -345.194747) (xy 332.326253 -345.235973) (xy 332.355747 -345.281864) (xy 332.37841 -345.331486)
			(xy 332.39378 -345.383828) (xy 332.401544 -345.437824) (xy 332.401544 -345.492369) (xy 333.884247 -345.492369)
			(xy 333.884247 -345.437831) (xy 333.892009 -345.383849) (xy 333.907375 -345.33152) (xy 333.930031 -345.281912)
			(xy 333.959518 -345.236032) (xy 333.995234 -345.194817) (xy 334.036452 -345.159103) (xy 334.082333 -345.12962)
			(xy 334.131943 -345.106966) (xy 334.184272 -345.091604) (xy 334.238255 -345.083846) (xy 334.265524 -345.083384)
			(xy 335.129124 -345.083384) (xy 335.156396 -345.08378) (xy 335.210383 -345.091546) (xy 335.262716 -345.106915)
			(xy 335.312329 -345.129575) (xy 335.358213 -345.159065) (xy 335.399432 -345.194785) (xy 335.435149 -345.236007)
			(xy 335.464636 -345.281892) (xy 335.487294 -345.331507) (xy 335.50266 -345.38384) (xy 335.510422 -345.437828)
			(xy 335.510422 -345.492365) (xy 336.99327 -345.492365) (xy 336.99327 -345.437835) (xy 337.001031 -345.383859)
			(xy 337.016393 -345.331537) (xy 337.039046 -345.281934) (xy 337.068526 -345.236059) (xy 337.104236 -345.194847)
			(xy 337.145446 -345.159136) (xy 337.19132 -345.129653) (xy 337.240922 -345.106999) (xy 337.293243 -345.091634)
			(xy 337.347219 -345.083871) (xy 337.374484 -345.083384) (xy 338.238084 -345.083384) (xy 338.265359 -345.083755)
			(xy 338.319354 -345.091516) (xy 338.371695 -345.106882) (xy 338.421316 -345.129542) (xy 338.467207 -345.159033)
			(xy 338.508434 -345.194754) (xy 338.544158 -345.23598) (xy 338.57365 -345.28187) (xy 338.596312 -345.33149)
			(xy 338.611681 -345.38383) (xy 338.619444 -345.437825) (xy 338.619444 -345.49237) (xy 340.102148 -345.49237)
			(xy 340.102148 -345.43783) (xy 340.10991 -345.383846) (xy 340.125276 -345.331516) (xy 340.147935 -345.281906)
			(xy 340.177423 -345.236026) (xy 340.213141 -345.194809) (xy 340.254361 -345.159096) (xy 340.300245 -345.129613)
			(xy 340.349857 -345.106961) (xy 340.402189 -345.0916) (xy 340.456174 -345.083844) (xy 340.483444 -345.083384)
			(xy 341.347044 -345.083384) (xy 341.374315 -345.083782) (xy 341.4283 -345.091549) (xy 341.48063 -345.10692)
			(xy 341.530241 -345.129582) (xy 341.576122 -345.159072) (xy 341.617339 -345.194792) (xy 341.653054 -345.236013)
			(xy 341.682539 -345.281898) (xy 341.705195 -345.331511) (xy 341.72056 -345.383843) (xy 341.728322 -345.437829)
			(xy 341.728322 -345.492368) (xy 343.211147 -345.492368) (xy 343.211147 -345.437832) (xy 343.218909 -345.383851)
			(xy 343.234273 -345.331525) (xy 343.256928 -345.281917) (xy 343.286413 -345.236039) (xy 343.322126 -345.194824)
			(xy 343.363342 -345.159111) (xy 343.409221 -345.129627) (xy 343.458828 -345.106972) (xy 343.511155 -345.091608)
			(xy 343.565136 -345.083847) (xy 343.592404 -345.083384) (xy 344.456004 -345.083384) (xy 344.483276 -345.083779)
			(xy 344.537266 -345.091542) (xy 344.589601 -345.106909) (xy 344.639217 -345.129569) (xy 344.685103 -345.159058)
			(xy 344.726325 -345.194778) (xy 344.762044 -345.236) (xy 344.791533 -345.281886) (xy 344.814192 -345.331502)
			(xy 344.829559 -345.383838) (xy 344.837321 -345.437828) (xy 344.837321 -345.492365) (xy 370.80677 -345.492365)
			(xy 370.80677 -345.437835) (xy 370.81453 -345.383859) (xy 370.829893 -345.331538) (xy 370.852545 -345.281935)
			(xy 370.882025 -345.236061) (xy 370.917734 -345.194848) (xy 370.958945 -345.159137) (xy 371.004817 -345.129655)
			(xy 371.054419 -345.107) (xy 371.10674 -345.091635) (xy 371.160715 -345.083872) (xy 371.18798 -345.083384)
			(xy 372.05158 -345.083384) (xy 372.078855 -345.083754) (xy 372.132851 -345.091515) (xy 372.185192 -345.106881)
			(xy 372.234814 -345.129541) (xy 372.280705 -345.159031) (xy 372.321933 -345.194753) (xy 372.357657 -345.235978)
			(xy 372.38715 -345.281869) (xy 372.409812 -345.331489) (xy 372.425181 -345.38383) (xy 372.432944 -345.437825)
			(xy 372.432944 -345.49237) (xy 373.915647 -345.49237) (xy 373.915647 -345.43783) (xy 373.92341 -345.383847)
			(xy 373.938776 -345.331517) (xy 373.961434 -345.281907) (xy 373.990922 -345.236027) (xy 374.026639 -345.194811)
			(xy 374.067859 -345.159098) (xy 374.113742 -345.129615) (xy 374.163355 -345.106962) (xy 374.215686 -345.091601)
			(xy 374.26967 -345.083845) (xy 374.29694 -345.083384) (xy 375.16054 -345.083384) (xy 375.187811 -345.083781)
			(xy 375.241797 -345.091549) (xy 375.294128 -345.106919) (xy 375.343739 -345.12958) (xy 375.38962 -345.159071)
			(xy 375.430838 -345.19479) (xy 375.466553 -345.236012) (xy 375.496039 -345.281896) (xy 375.518695 -345.33151)
			(xy 375.53406 -345.383843) (xy 375.541822 -345.437829) (xy 375.541822 -345.492366) (xy 377.02467 -345.492366)
			(xy 377.02467 -345.437834) (xy 377.032431 -345.383857) (xy 377.047795 -345.331534) (xy 377.070448 -345.281929)
			(xy 377.09993 -345.236054) (xy 377.135641 -345.194841) (xy 377.176854 -345.15913) (xy 377.222729 -345.129648)
			(xy 377.272334 -345.106995) (xy 377.324657 -345.091631) (xy 377.378634 -345.08387) (xy 377.4059 -345.083384)
			(xy 378.2695 -345.083384) (xy 378.296773 -345.083779) (xy 378.350763 -345.091541) (xy 378.403099 -345.106908)
			(xy 378.452715 -345.129567) (xy 378.498601 -345.159057) (xy 378.539824 -345.194776) (xy 378.575543 -345.235999)
			(xy 378.605033 -345.281885) (xy 378.627692 -345.331501) (xy 378.643059 -345.383837) (xy 378.650821 -345.437827)
			(xy 378.650821 -345.492364) (xy 380.13367 -345.492364) (xy 380.13367 -345.437836) (xy 380.14143 -345.383862)
			(xy 380.156791 -345.331542) (xy 380.179442 -345.281941) (xy 380.208921 -345.236067) (xy 380.244627 -345.194855)
			(xy 380.285835 -345.159145) (xy 380.331705 -345.129661) (xy 380.381305 -345.107005) (xy 380.433623 -345.091638)
			(xy 380.487596 -345.083873) (xy 380.51486 -345.083384) (xy 381.37846 -345.083384) (xy 381.405736 -345.083753)
			(xy 381.459734 -345.091511) (xy 381.512078 -345.106876) (xy 381.561702 -345.129534) (xy 381.607596 -345.159024)
			(xy 381.648826 -345.194746) (xy 381.684552 -345.235972) (xy 381.714047 -345.281863) (xy 381.73671 -345.331485)
			(xy 381.75208 -345.383827) (xy 381.759844 -345.437824) (xy 381.759844 -345.492369) (xy 383.242547 -345.492369)
			(xy 383.242547 -345.437831) (xy 383.250309 -345.383849) (xy 383.265675 -345.331521) (xy 383.288331 -345.281913)
			(xy 383.317817 -345.236034) (xy 383.353532 -345.194818) (xy 383.39475 -345.159105) (xy 383.44063 -345.129621)
			(xy 383.49024 -345.106968) (xy 383.542569 -345.091605) (xy 383.596551 -345.083846) (xy 383.62382 -345.083384)
			(xy 384.48742 -345.083384) (xy 384.514692 -345.08378) (xy 384.56868 -345.091545) (xy 384.621013 -345.106914)
			(xy 384.670627 -345.129574) (xy 384.716511 -345.159064) (xy 384.757731 -345.194783) (xy 384.793448 -345.236005)
			(xy 384.822936 -345.281891) (xy 384.845593 -345.331506) (xy 384.860959 -345.38384) (xy 384.868722 -345.437828)
			(xy 384.868722 -345.492365) (xy 386.35157 -345.492365) (xy 386.35157 -345.437835) (xy 386.35933 -345.383859)
			(xy 386.374693 -345.331538) (xy 386.397345 -345.281935) (xy 386.426825 -345.236061) (xy 386.462534 -345.194848)
			(xy 386.503745 -345.159137) (xy 386.549617 -345.129655) (xy 386.599219 -345.107) (xy 386.65154 -345.091635)
			(xy 386.705515 -345.083872) (xy 386.73278 -345.083384) (xy 387.59638 -345.083384) (xy 387.623655 -345.083754)
			(xy 387.677651 -345.091515) (xy 387.729992 -345.106881) (xy 387.779614 -345.129541) (xy 387.825505 -345.159031)
			(xy 387.866733 -345.194753) (xy 387.902457 -345.235978) (xy 387.93195 -345.281869) (xy 387.954612 -345.331489)
			(xy 387.969981 -345.38383) (xy 387.977744 -345.437825) (xy 387.977744 -345.49237) (xy 389.460447 -345.49237)
			(xy 389.460447 -345.43783) (xy 389.46821 -345.383847) (xy 389.483576 -345.331517) (xy 389.506234 -345.281907)
			(xy 389.535722 -345.236027) (xy 389.571439 -345.194811) (xy 389.612659 -345.159098) (xy 389.658542 -345.129615)
			(xy 389.708155 -345.106962) (xy 389.760486 -345.091601) (xy 389.81447 -345.083845) (xy 389.84174 -345.083384)
			(xy 390.70534 -345.083384) (xy 390.732611 -345.083781) (xy 390.786597 -345.091549) (xy 390.838928 -345.106919)
			(xy 390.888539 -345.12958) (xy 390.93442 -345.159071) (xy 390.975638 -345.19479) (xy 391.011353 -345.236012)
			(xy 391.040839 -345.281896) (xy 391.063495 -345.33151) (xy 391.07886 -345.383843) (xy 391.086622 -345.437829)
			(xy 391.086622 -345.492366) (xy 392.56947 -345.492366) (xy 392.56947 -345.437834) (xy 392.577231 -345.383857)
			(xy 392.592595 -345.331534) (xy 392.615248 -345.281929) (xy 392.64473 -345.236054) (xy 392.680441 -345.194841)
			(xy 392.721654 -345.15913) (xy 392.767529 -345.129648) (xy 392.817134 -345.106995) (xy 392.869457 -345.091631)
			(xy 392.923434 -345.08387) (xy 392.9507 -345.083384) (xy 393.8143 -345.083384) (xy 393.841573 -345.083779)
			(xy 393.895563 -345.091541) (xy 393.947899 -345.106908) (xy 393.997515 -345.129567) (xy 394.043401 -345.159057)
			(xy 394.084624 -345.194776) (xy 394.120343 -345.235999) (xy 394.149833 -345.281885) (xy 394.172492 -345.331501)
			(xy 394.187859 -345.383837) (xy 394.195621 -345.437827) (xy 394.195621 -345.492364) (xy 395.67847 -345.492364)
			(xy 395.67847 -345.437836) (xy 395.68623 -345.383862) (xy 395.701591 -345.331542) (xy 395.724242 -345.281941)
			(xy 395.753721 -345.236067) (xy 395.789427 -345.194855) (xy 395.830635 -345.159145) (xy 395.876505 -345.129661)
			(xy 395.926105 -345.107005) (xy 395.978423 -345.091638) (xy 396.032396 -345.083873) (xy 396.05966 -345.083384)
			(xy 396.92326 -345.083384) (xy 396.950536 -345.083753) (xy 397.004534 -345.091511) (xy 397.056878 -345.106876)
			(xy 397.106502 -345.129534) (xy 397.152396 -345.159024) (xy 397.193626 -345.194746) (xy 397.229352 -345.235972)
			(xy 397.258847 -345.281863) (xy 397.28151 -345.331485) (xy 397.29688 -345.383827) (xy 397.304644 -345.437824)
			(xy 397.304644 -345.492369) (xy 398.787347 -345.492369) (xy 398.787347 -345.437831) (xy 398.795109 -345.383849)
			(xy 398.810475 -345.331521) (xy 398.833131 -345.281913) (xy 398.862617 -345.236034) (xy 398.898332 -345.194818)
			(xy 398.93955 -345.159105) (xy 398.98543 -345.129621) (xy 399.03504 -345.106968) (xy 399.087369 -345.091605)
			(xy 399.141351 -345.083846) (xy 399.16862 -345.083384) (xy 400.03222 -345.083384) (xy 400.059492 -345.08378)
			(xy 400.11348 -345.091545) (xy 400.165813 -345.106914) (xy 400.215427 -345.129574) (xy 400.261311 -345.159064)
			(xy 400.302531 -345.194783) (xy 400.338248 -345.236005) (xy 400.367736 -345.281891) (xy 400.390393 -345.331506)
			(xy 400.405759 -345.38384) (xy 400.413522 -345.437828) (xy 400.413522 -345.492365) (xy 401.89637 -345.492365)
			(xy 401.89637 -345.437835) (xy 401.90413 -345.383859) (xy 401.919493 -345.331538) (xy 401.942145 -345.281935)
			(xy 401.971625 -345.236061) (xy 402.007334 -345.194848) (xy 402.048545 -345.159137) (xy 402.094417 -345.129655)
			(xy 402.144019 -345.107) (xy 402.19634 -345.091635) (xy 402.250315 -345.083872) (xy 402.27758 -345.083384)
			(xy 403.14118 -345.083384) (xy 403.168455 -345.083754) (xy 403.222451 -345.091515) (xy 403.274792 -345.106881)
			(xy 403.324414 -345.129541) (xy 403.370305 -345.159031) (xy 403.411533 -345.194753) (xy 403.447257 -345.235978)
			(xy 403.47675 -345.281869) (xy 403.499412 -345.331489) (xy 403.514781 -345.38383) (xy 403.522544 -345.437825)
			(xy 403.522544 -345.492366) (xy 408.91387 -345.492366) (xy 408.91387 -345.437834) (xy 408.921631 -345.383858)
			(xy 408.936994 -345.331535) (xy 408.959647 -345.281932) (xy 408.989128 -345.236057) (xy 409.024838 -345.194844)
			(xy 409.06605 -345.159133) (xy 409.111925 -345.129651) (xy 409.161528 -345.106997) (xy 409.21385 -345.091633)
			(xy 409.267826 -345.083871) (xy 409.295092 -345.083384) (xy 410.158692 -345.083384) (xy 410.185967 -345.083755)
			(xy 410.239961 -345.091517) (xy 410.292301 -345.106885) (xy 410.341921 -345.129544) (xy 410.387811 -345.159035)
			(xy 410.429037 -345.194757) (xy 410.46476 -345.235982) (xy 410.494252 -345.281872) (xy 410.516913 -345.331492)
			(xy 410.532281 -345.383831) (xy 410.540044 -345.437825) (xy 410.540044 -345.492364) (xy 412.02287 -345.492364)
			(xy 412.02287 -345.437836) (xy 412.03063 -345.383863) (xy 412.045991 -345.331544) (xy 412.068641 -345.281943)
			(xy 412.098119 -345.23607) (xy 412.133824 -345.194858) (xy 412.175031 -345.159147) (xy 412.220901 -345.129664)
			(xy 412.270499 -345.107008) (xy 412.322816 -345.09164) (xy 412.376788 -345.083874) (xy 412.404052 -345.083384)
			(xy 413.267652 -345.083384) (xy 413.294929 -345.083752) (xy 413.348927 -345.09151) (xy 413.401272 -345.106874)
			(xy 413.450897 -345.129531) (xy 413.496792 -345.159021) (xy 413.538023 -345.194743) (xy 413.57375 -345.235969)
			(xy 413.603246 -345.281861) (xy 413.625909 -345.331483) (xy 413.64128 -345.383826) (xy 413.649044 -345.437824)
			(xy 413.649044 -345.492368) (xy 415.131747 -345.492368) (xy 415.131747 -345.437832) (xy 415.139509 -345.38385)
			(xy 415.154874 -345.331523) (xy 415.17753 -345.281915) (xy 415.207015 -345.236036) (xy 415.242729 -345.194821)
			(xy 415.283946 -345.159108) (xy 415.329826 -345.129624) (xy 415.379434 -345.10697) (xy 415.431762 -345.091606)
			(xy 415.485744 -345.083847) (xy 415.513012 -345.083384) (xy 416.376612 -345.083384) (xy 416.403884 -345.083779)
			(xy 416.457873 -345.091543) (xy 416.510207 -345.106912) (xy 416.559822 -345.129571) (xy 416.605707 -345.159061)
			(xy 416.646928 -345.194781) (xy 416.682646 -345.236003) (xy 416.712135 -345.281889) (xy 416.734793 -345.331504)
			(xy 416.750159 -345.383839) (xy 416.757921 -345.437828) (xy 416.757921 -345.492365) (xy 418.24077 -345.492365)
			(xy 418.24077 -345.437835) (xy 418.24853 -345.383861) (xy 418.263892 -345.33154) (xy 418.286544 -345.281937)
			(xy 418.316023 -345.236063) (xy 418.351731 -345.194851) (xy 418.392941 -345.15914) (xy 418.438813 -345.129657)
			(xy 418.488413 -345.107002) (xy 418.540733 -345.091636) (xy 418.594707 -345.083872) (xy 418.621972 -345.083384)
			(xy 419.485572 -345.083384) (xy 419.512848 -345.083754) (xy 419.566844 -345.091514) (xy 419.619186 -345.106879)
			(xy 419.668809 -345.129538) (xy 419.714702 -345.159028) (xy 419.75593 -345.19475) (xy 419.791655 -345.235976)
			(xy 419.821149 -345.281866) (xy 419.843811 -345.331487) (xy 419.859181 -345.383829) (xy 419.866944 -345.437824)
			(xy 419.866944 -345.492369) (xy 421.349647 -345.492369) (xy 421.349647 -345.437831) (xy 421.35741 -345.383848)
			(xy 421.372776 -345.331519) (xy 421.395433 -345.281909) (xy 421.42492 -345.23603) (xy 421.460636 -345.194814)
			(xy 421.501855 -345.159101) (xy 421.547738 -345.129617) (xy 421.597349 -345.106964) (xy 421.649679 -345.091603)
			(xy 421.703663 -345.083845) (xy 421.730932 -345.083384) (xy 422.594532 -345.083384) (xy 422.621803 -345.083781)
			(xy 422.67579 -345.091547) (xy 422.728122 -345.106917) (xy 422.777734 -345.129578) (xy 422.823616 -345.159068)
			(xy 422.864835 -345.194788) (xy 422.900551 -345.236009) (xy 422.930038 -345.281894) (xy 422.952694 -345.331508)
			(xy 422.96806 -345.383842) (xy 422.975822 -345.437829) (xy 422.975822 -345.492366) (xy 424.45867 -345.492366)
			(xy 424.45867 -345.437834) (xy 424.466431 -345.383858) (xy 424.481794 -345.331535) (xy 424.504447 -345.281932)
			(xy 424.533928 -345.236057) (xy 424.569638 -345.194844) (xy 424.61085 -345.159133) (xy 424.656725 -345.129651)
			(xy 424.706328 -345.106997) (xy 424.75865 -345.091633) (xy 424.812626 -345.083871) (xy 424.839892 -345.083384)
			(xy 425.703492 -345.083384) (xy 425.730767 -345.083755) (xy 425.784761 -345.091517) (xy 425.837101 -345.106885)
			(xy 425.886721 -345.129544) (xy 425.932611 -345.159035) (xy 425.973837 -345.194757) (xy 426.00956 -345.235982)
			(xy 426.039052 -345.281872) (xy 426.061713 -345.331492) (xy 426.077081 -345.383831) (xy 426.084844 -345.437825)
			(xy 426.084844 -345.492364) (xy 427.56767 -345.492364) (xy 427.56767 -345.437836) (xy 427.57543 -345.383863)
			(xy 427.590791 -345.331544) (xy 427.613441 -345.281943) (xy 427.642919 -345.23607) (xy 427.678624 -345.194858)
			(xy 427.719831 -345.159147) (xy 427.765701 -345.129664) (xy 427.815299 -345.107008) (xy 427.867616 -345.09164)
			(xy 427.921588 -345.083874) (xy 427.948852 -345.083384) (xy 428.812452 -345.083384) (xy 428.839729 -345.083752)
			(xy 428.893727 -345.09151) (xy 428.946072 -345.106874) (xy 428.995697 -345.129531) (xy 429.041592 -345.159021)
			(xy 429.082823 -345.194743) (xy 429.11855 -345.235969) (xy 429.148046 -345.281861) (xy 429.170709 -345.331483)
			(xy 429.18608 -345.383826) (xy 429.193844 -345.437824) (xy 429.193844 -345.492368) (xy 430.676547 -345.492368)
			(xy 430.676547 -345.437832) (xy 430.684309 -345.38385) (xy 430.699674 -345.331523) (xy 430.72233 -345.281915)
			(xy 430.751815 -345.236036) (xy 430.787529 -345.194821) (xy 430.828746 -345.159108) (xy 430.874626 -345.129624)
			(xy 430.924234 -345.10697) (xy 430.976562 -345.091606) (xy 431.030544 -345.083847) (xy 431.057812 -345.083384)
			(xy 431.921412 -345.083384) (xy 431.948684 -345.083779) (xy 432.002673 -345.091543) (xy 432.055007 -345.106912)
			(xy 432.104622 -345.129571) (xy 432.150507 -345.159061) (xy 432.191728 -345.194781) (xy 432.227446 -345.236003)
			(xy 432.256935 -345.281889) (xy 432.279593 -345.331504) (xy 432.294959 -345.383839) (xy 432.302721 -345.437828)
			(xy 432.302721 -345.492365) (xy 433.78557 -345.492365) (xy 433.78557 -345.437835) (xy 433.79333 -345.383861)
			(xy 433.808692 -345.33154) (xy 433.831344 -345.281937) (xy 433.860823 -345.236063) (xy 433.896531 -345.194851)
			(xy 433.937741 -345.15914) (xy 433.983613 -345.129657) (xy 434.033213 -345.107002) (xy 434.085533 -345.091636)
			(xy 434.139507 -345.083872) (xy 434.166772 -345.083384) (xy 435.030372 -345.083384) (xy 435.057648 -345.083754)
			(xy 435.111644 -345.091514) (xy 435.163986 -345.106879) (xy 435.213609 -345.129538) (xy 435.259502 -345.159028)
			(xy 435.30073 -345.19475) (xy 435.336455 -345.235976) (xy 435.365949 -345.281866) (xy 435.388611 -345.331487)
			(xy 435.403981 -345.383829) (xy 435.411744 -345.437824) (xy 435.411744 -345.492369) (xy 436.894447 -345.492369)
			(xy 436.894447 -345.437831) (xy 436.90221 -345.383848) (xy 436.917576 -345.331519) (xy 436.940233 -345.281909)
			(xy 436.96972 -345.23603) (xy 437.005436 -345.194814) (xy 437.046655 -345.159101) (xy 437.092538 -345.129617)
			(xy 437.142149 -345.106964) (xy 437.194479 -345.091603) (xy 437.248463 -345.083845) (xy 437.275732 -345.083384)
			(xy 438.139332 -345.083384) (xy 438.166603 -345.083781) (xy 438.22059 -345.091547) (xy 438.272922 -345.106917)
			(xy 438.322534 -345.129578) (xy 438.368416 -345.159068) (xy 438.409635 -345.194788) (xy 438.445351 -345.236009)
			(xy 438.474838 -345.281894) (xy 438.497494 -345.331508) (xy 438.51286 -345.383842) (xy 438.520622 -345.437829)
			(xy 438.520622 -345.492366) (xy 440.00347 -345.492366) (xy 440.00347 -345.437834) (xy 440.011231 -345.383858)
			(xy 440.026594 -345.331535) (xy 440.049247 -345.281932) (xy 440.078728 -345.236057) (xy 440.114438 -345.194844)
			(xy 440.15565 -345.159133) (xy 440.201525 -345.129651) (xy 440.251128 -345.106997) (xy 440.30345 -345.091633)
			(xy 440.357426 -345.083871) (xy 440.384692 -345.083384) (xy 441.248292 -345.083384) (xy 441.275567 -345.083755)
			(xy 441.329561 -345.091517) (xy 441.381901 -345.106885) (xy 441.431521 -345.129544) (xy 441.477411 -345.159035)
			(xy 441.518637 -345.194757) (xy 441.55436 -345.235982) (xy 441.583852 -345.281872) (xy 441.606513 -345.331492)
			(xy 441.621881 -345.383831) (xy 441.629644 -345.437825) (xy 441.629644 -345.492375) (xy 441.621881 -345.546369)
			(xy 441.606513 -345.598708) (xy 441.583852 -345.648328) (xy 441.55436 -345.694218) (xy 441.518637 -345.735443)
			(xy 441.477411 -345.771165) (xy 441.431521 -345.800656) (xy 441.381901 -345.823315) (xy 441.329561 -345.838683)
			(xy 441.275567 -345.846445) (xy 441.248292 -345.846908) (xy 440.384692 -345.846908) (xy 440.357426 -345.846329)
			(xy 440.30345 -345.838567) (xy 440.251128 -345.823203) (xy 440.201525 -345.800549) (xy 440.15565 -345.771067)
			(xy 440.114438 -345.735356) (xy 440.078728 -345.694143) (xy 440.049247 -345.648268) (xy 440.026594 -345.598665)
			(xy 440.011231 -345.546342) (xy 440.00347 -345.492366) (xy 438.520622 -345.492366) (xy 438.520622 -345.492371)
			(xy 438.51286 -345.546358) (xy 438.497494 -345.598692) (xy 438.474838 -345.648306) (xy 438.445351 -345.694191)
			(xy 438.409635 -345.735412) (xy 438.368416 -345.771132) (xy 438.322534 -345.800622) (xy 438.272922 -345.823283)
			(xy 438.22059 -345.838653) (xy 438.166603 -345.846419) (xy 438.139332 -345.846908) (xy 437.275732 -345.846908)
			(xy 437.248463 -345.846355) (xy 437.194479 -345.838597) (xy 437.142149 -345.823236) (xy 437.092538 -345.800583)
			(xy 437.046655 -345.771099) (xy 437.005436 -345.735386) (xy 436.96972 -345.69417) (xy 436.940233 -345.648291)
			(xy 436.917576 -345.598681) (xy 436.90221 -345.546352) (xy 436.894447 -345.492369) (xy 435.411744 -345.492369)
			(xy 435.411744 -345.492376) (xy 435.403981 -345.546371) (xy 435.388611 -345.598713) (xy 435.365949 -345.648334)
			(xy 435.336455 -345.694224) (xy 435.30073 -345.73545) (xy 435.259502 -345.771172) (xy 435.213609 -345.800662)
			(xy 435.163986 -345.823321) (xy 435.111644 -345.838686) (xy 435.057648 -345.846446) (xy 435.030372 -345.846908)
			(xy 434.166772 -345.846908) (xy 434.139507 -345.846328) (xy 434.085533 -345.838564) (xy 434.033213 -345.823198)
			(xy 433.983613 -345.800543) (xy 433.937741 -345.77106) (xy 433.896531 -345.735349) (xy 433.860823 -345.694137)
			(xy 433.831344 -345.648263) (xy 433.808692 -345.59866) (xy 433.79333 -345.546339) (xy 433.78557 -345.492365)
			(xy 432.302721 -345.492365) (xy 432.302721 -345.492372) (xy 432.294959 -345.546361) (xy 432.279593 -345.598696)
			(xy 432.256935 -345.648311) (xy 432.227446 -345.694197) (xy 432.191728 -345.735419) (xy 432.150507 -345.771139)
			(xy 432.104622 -345.800629) (xy 432.055007 -345.823288) (xy 432.002673 -345.838657) (xy 431.948684 -345.846421)
			(xy 431.921412 -345.846908) (xy 431.057812 -345.846908) (xy 431.030544 -345.846353) (xy 430.976562 -345.838594)
			(xy 430.924234 -345.82323) (xy 430.874626 -345.800576) (xy 430.828746 -345.771092) (xy 430.787529 -345.735379)
			(xy 430.751815 -345.694164) (xy 430.72233 -345.648285) (xy 430.699674 -345.598677) (xy 430.684309 -345.54635)
			(xy 430.676547 -345.492368) (xy 429.193844 -345.492368) (xy 429.193844 -345.492376) (xy 429.18608 -345.546374)
			(xy 429.170709 -345.598717) (xy 429.148046 -345.648339) (xy 429.11855 -345.694231) (xy 429.082823 -345.735457)
			(xy 429.041592 -345.771179) (xy 428.995697 -345.800669) (xy 428.946072 -345.823326) (xy 428.893727 -345.83869)
			(xy 428.839729 -345.846448) (xy 428.812452 -345.846908) (xy 427.948852 -345.846908) (xy 427.921588 -345.846326)
			(xy 427.867616 -345.83856) (xy 427.815299 -345.823192) (xy 427.765701 -345.800536) (xy 427.719831 -345.771053)
			(xy 427.678624 -345.735342) (xy 427.642919 -345.69413) (xy 427.613441 -345.648257) (xy 427.590791 -345.598656)
			(xy 427.57543 -345.546337) (xy 427.56767 -345.492364) (xy 426.084844 -345.492364) (xy 426.084844 -345.492375)
			(xy 426.077081 -345.546369) (xy 426.061713 -345.598708) (xy 426.039052 -345.648328) (xy 426.00956 -345.694218)
			(xy 425.973837 -345.735443) (xy 425.932611 -345.771165) (xy 425.886721 -345.800656) (xy 425.837101 -345.823315)
			(xy 425.784761 -345.838683) (xy 425.730767 -345.846445) (xy 425.703492 -345.846908) (xy 424.839892 -345.846908)
			(xy 424.812626 -345.846329) (xy 424.75865 -345.838567) (xy 424.706328 -345.823203) (xy 424.656725 -345.800549)
			(xy 424.61085 -345.771067) (xy 424.569638 -345.735356) (xy 424.533928 -345.694143) (xy 424.504447 -345.648268)
			(xy 424.481794 -345.598665) (xy 424.466431 -345.546342) (xy 424.45867 -345.492366) (xy 422.975822 -345.492366)
			(xy 422.975822 -345.492371) (xy 422.96806 -345.546358) (xy 422.952694 -345.598692) (xy 422.930038 -345.648306)
			(xy 422.900551 -345.694191) (xy 422.864835 -345.735412) (xy 422.823616 -345.771132) (xy 422.777734 -345.800622)
			(xy 422.728122 -345.823283) (xy 422.67579 -345.838653) (xy 422.621803 -345.846419) (xy 422.594532 -345.846908)
			(xy 421.730932 -345.846908) (xy 421.703663 -345.846355) (xy 421.649679 -345.838597) (xy 421.597349 -345.823236)
			(xy 421.547738 -345.800583) (xy 421.501855 -345.771099) (xy 421.460636 -345.735386) (xy 421.42492 -345.69417)
			(xy 421.395433 -345.648291) (xy 421.372776 -345.598681) (xy 421.35741 -345.546352) (xy 421.349647 -345.492369)
			(xy 419.866944 -345.492369) (xy 419.866944 -345.492376) (xy 419.859181 -345.546371) (xy 419.843811 -345.598713)
			(xy 419.821149 -345.648334) (xy 419.791655 -345.694224) (xy 419.75593 -345.73545) (xy 419.714702 -345.771172)
			(xy 419.668809 -345.800662) (xy 419.619186 -345.823321) (xy 419.566844 -345.838686) (xy 419.512848 -345.846446)
			(xy 419.485572 -345.846908) (xy 418.621972 -345.846908) (xy 418.594707 -345.846328) (xy 418.540733 -345.838564)
			(xy 418.488413 -345.823198) (xy 418.438813 -345.800543) (xy 418.392941 -345.77106) (xy 418.351731 -345.735349)
			(xy 418.316023 -345.694137) (xy 418.286544 -345.648263) (xy 418.263892 -345.59866) (xy 418.24853 -345.546339)
			(xy 418.24077 -345.492365) (xy 416.757921 -345.492365) (xy 416.757921 -345.492372) (xy 416.750159 -345.546361)
			(xy 416.734793 -345.598696) (xy 416.712135 -345.648311) (xy 416.682646 -345.694197) (xy 416.646928 -345.735419)
			(xy 416.605707 -345.771139) (xy 416.559822 -345.800629) (xy 416.510207 -345.823288) (xy 416.457873 -345.838657)
			(xy 416.403884 -345.846421) (xy 416.376612 -345.846908) (xy 415.513012 -345.846908) (xy 415.485744 -345.846353)
			(xy 415.431762 -345.838594) (xy 415.379434 -345.82323) (xy 415.329826 -345.800576) (xy 415.283946 -345.771092)
			(xy 415.242729 -345.735379) (xy 415.207015 -345.694164) (xy 415.17753 -345.648285) (xy 415.154874 -345.598677)
			(xy 415.139509 -345.54635) (xy 415.131747 -345.492368) (xy 413.649044 -345.492368) (xy 413.649044 -345.492376)
			(xy 413.64128 -345.546374) (xy 413.625909 -345.598717) (xy 413.603246 -345.648339) (xy 413.57375 -345.694231)
			(xy 413.538023 -345.735457) (xy 413.496792 -345.771179) (xy 413.450897 -345.800669) (xy 413.401272 -345.823326)
			(xy 413.348927 -345.83869) (xy 413.294929 -345.846448) (xy 413.267652 -345.846908) (xy 412.404052 -345.846908)
			(xy 412.376788 -345.846326) (xy 412.322816 -345.83856) (xy 412.270499 -345.823192) (xy 412.220901 -345.800536)
			(xy 412.175031 -345.771053) (xy 412.133824 -345.735342) (xy 412.098119 -345.69413) (xy 412.068641 -345.648257)
			(xy 412.045991 -345.598656) (xy 412.03063 -345.546337) (xy 412.02287 -345.492364) (xy 410.540044 -345.492364)
			(xy 410.540044 -345.492375) (xy 410.532281 -345.546369) (xy 410.516913 -345.598708) (xy 410.494252 -345.648328)
			(xy 410.46476 -345.694218) (xy 410.429037 -345.735443) (xy 410.387811 -345.771165) (xy 410.341921 -345.800656)
			(xy 410.292301 -345.823315) (xy 410.239961 -345.838683) (xy 410.185967 -345.846445) (xy 410.158692 -345.846908)
			(xy 409.295092 -345.846908) (xy 409.267826 -345.846329) (xy 409.21385 -345.838567) (xy 409.161528 -345.823203)
			(xy 409.111925 -345.800549) (xy 409.06605 -345.771067) (xy 409.024838 -345.735356) (xy 408.989128 -345.694143)
			(xy 408.959647 -345.648268) (xy 408.936994 -345.598665) (xy 408.921631 -345.546342) (xy 408.91387 -345.492366)
			(xy 403.522544 -345.492366) (xy 403.522544 -345.492375) (xy 403.514781 -345.54637) (xy 403.499412 -345.598711)
			(xy 403.47675 -345.648331) (xy 403.447257 -345.694221) (xy 403.411533 -345.735447) (xy 403.370305 -345.771169)
			(xy 403.324414 -345.800659) (xy 403.274792 -345.823319) (xy 403.222451 -345.838685) (xy 403.168455 -345.846446)
			(xy 403.14118 -345.846908) (xy 402.27758 -345.846908) (xy 402.250315 -345.846328) (xy 402.19634 -345.838565)
			(xy 402.144019 -345.8232) (xy 402.094417 -345.800545) (xy 402.048545 -345.771063) (xy 402.007334 -345.735352)
			(xy 401.971625 -345.694139) (xy 401.942145 -345.648265) (xy 401.919493 -345.598662) (xy 401.90413 -345.546341)
			(xy 401.89637 -345.492365) (xy 400.413522 -345.492365) (xy 400.413522 -345.492372) (xy 400.405759 -345.54636)
			(xy 400.390393 -345.598694) (xy 400.367736 -345.648309) (xy 400.338248 -345.694195) (xy 400.302531 -345.735417)
			(xy 400.261311 -345.771136) (xy 400.215427 -345.800626) (xy 400.165813 -345.823286) (xy 400.11348 -345.838655)
			(xy 400.059492 -345.84642) (xy 400.03222 -345.846908) (xy 399.16862 -345.846908) (xy 399.141351 -345.846354)
			(xy 399.087369 -345.838595) (xy 399.03504 -345.823232) (xy 398.98543 -345.800579) (xy 398.93955 -345.771095)
			(xy 398.898332 -345.735382) (xy 398.862617 -345.694166) (xy 398.833131 -345.648287) (xy 398.810475 -345.598679)
			(xy 398.795109 -345.546351) (xy 398.787347 -345.492369) (xy 397.304644 -345.492369) (xy 397.304644 -345.492376)
			(xy 397.29688 -345.546373) (xy 397.28151 -345.598715) (xy 397.258847 -345.648337) (xy 397.229352 -345.694228)
			(xy 397.193626 -345.735454) (xy 397.152396 -345.771176) (xy 397.106502 -345.800666) (xy 397.056878 -345.823324)
			(xy 397.004534 -345.838689) (xy 396.950536 -345.846447) (xy 396.92326 -345.846908) (xy 396.05966 -345.846908)
			(xy 396.032396 -345.846327) (xy 395.978423 -345.838562) (xy 395.926105 -345.823195) (xy 395.876505 -345.800539)
			(xy 395.830635 -345.771055) (xy 395.789427 -345.735345) (xy 395.753721 -345.694133) (xy 395.724242 -345.648259)
			(xy 395.701591 -345.598658) (xy 395.68623 -345.546338) (xy 395.67847 -345.492364) (xy 394.195621 -345.492364)
			(xy 394.195621 -345.492373) (xy 394.187859 -345.546363) (xy 394.172492 -345.598699) (xy 394.149833 -345.648315)
			(xy 394.120343 -345.694201) (xy 394.084624 -345.735424) (xy 394.043401 -345.771143) (xy 393.997515 -345.800633)
			(xy 393.947899 -345.823292) (xy 393.895563 -345.838659) (xy 393.841573 -345.846421) (xy 393.8143 -345.846908)
			(xy 392.9507 -345.846908) (xy 392.923434 -345.84633) (xy 392.869457 -345.838569) (xy 392.817134 -345.823205)
			(xy 392.767529 -345.800552) (xy 392.721654 -345.77107) (xy 392.680441 -345.735359) (xy 392.64473 -345.694146)
			(xy 392.615248 -345.648271) (xy 392.592595 -345.598666) (xy 392.577231 -345.546343) (xy 392.56947 -345.492366)
			(xy 391.086622 -345.492366) (xy 391.086622 -345.492371) (xy 391.07886 -345.546357) (xy 391.063495 -345.59869)
			(xy 391.040839 -345.648304) (xy 391.011353 -345.694188) (xy 390.975638 -345.73541) (xy 390.93442 -345.771129)
			(xy 390.888539 -345.80062) (xy 390.838928 -345.823281) (xy 390.786597 -345.838651) (xy 390.732611 -345.846419)
			(xy 390.70534 -345.846908) (xy 389.84174 -345.846908) (xy 389.81447 -345.846355) (xy 389.760486 -345.838599)
			(xy 389.708155 -345.823238) (xy 389.658542 -345.800585) (xy 389.612659 -345.771102) (xy 389.571439 -345.735389)
			(xy 389.535722 -345.694173) (xy 389.506234 -345.648293) (xy 389.483576 -345.598683) (xy 389.46821 -345.546353)
			(xy 389.460447 -345.49237) (xy 387.977744 -345.49237) (xy 387.977744 -345.492375) (xy 387.969981 -345.54637)
			(xy 387.954612 -345.598711) (xy 387.93195 -345.648331) (xy 387.902457 -345.694221) (xy 387.866733 -345.735447)
			(xy 387.825505 -345.771169) (xy 387.779614 -345.800659) (xy 387.729992 -345.823319) (xy 387.677651 -345.838685)
			(xy 387.623655 -345.846446) (xy 387.59638 -345.846908) (xy 386.73278 -345.846908) (xy 386.705515 -345.846328)
			(xy 386.65154 -345.838565) (xy 386.599219 -345.8232) (xy 386.549617 -345.800545) (xy 386.503745 -345.771063)
			(xy 386.462534 -345.735352) (xy 386.426825 -345.694139) (xy 386.397345 -345.648265) (xy 386.374693 -345.598662)
			(xy 386.35933 -345.546341) (xy 386.35157 -345.492365) (xy 384.868722 -345.492365) (xy 384.868722 -345.492372)
			(xy 384.860959 -345.54636) (xy 384.845593 -345.598694) (xy 384.822936 -345.648309) (xy 384.793448 -345.694195)
			(xy 384.757731 -345.735417) (xy 384.716511 -345.771136) (xy 384.670627 -345.800626) (xy 384.621013 -345.823286)
			(xy 384.56868 -345.838655) (xy 384.514692 -345.84642) (xy 384.48742 -345.846908) (xy 383.62382 -345.846908)
			(xy 383.596551 -345.846354) (xy 383.542569 -345.838595) (xy 383.49024 -345.823232) (xy 383.44063 -345.800579)
			(xy 383.39475 -345.771095) (xy 383.353532 -345.735382) (xy 383.317817 -345.694166) (xy 383.288331 -345.648287)
			(xy 383.265675 -345.598679) (xy 383.250309 -345.546351) (xy 383.242547 -345.492369) (xy 381.759844 -345.492369)
			(xy 381.759844 -345.492376) (xy 381.75208 -345.546373) (xy 381.73671 -345.598715) (xy 381.714047 -345.648337)
			(xy 381.684552 -345.694228) (xy 381.648826 -345.735454) (xy 381.607596 -345.771176) (xy 381.561702 -345.800666)
			(xy 381.512078 -345.823324) (xy 381.459734 -345.838689) (xy 381.405736 -345.846447) (xy 381.37846 -345.846908)
			(xy 380.51486 -345.846908) (xy 380.487596 -345.846327) (xy 380.433623 -345.838562) (xy 380.381305 -345.823195)
			(xy 380.331705 -345.800539) (xy 380.285835 -345.771055) (xy 380.244627 -345.735345) (xy 380.208921 -345.694133)
			(xy 380.179442 -345.648259) (xy 380.156791 -345.598658) (xy 380.14143 -345.546338) (xy 380.13367 -345.492364)
			(xy 378.650821 -345.492364) (xy 378.650821 -345.492373) (xy 378.643059 -345.546363) (xy 378.627692 -345.598699)
			(xy 378.605033 -345.648315) (xy 378.575543 -345.694201) (xy 378.539824 -345.735424) (xy 378.498601 -345.771143)
			(xy 378.452715 -345.800633) (xy 378.403099 -345.823292) (xy 378.350763 -345.838659) (xy 378.296773 -345.846421)
			(xy 378.2695 -345.846908) (xy 377.4059 -345.846908) (xy 377.378634 -345.84633) (xy 377.324657 -345.838569)
			(xy 377.272334 -345.823205) (xy 377.222729 -345.800552) (xy 377.176854 -345.77107) (xy 377.135641 -345.735359)
			(xy 377.09993 -345.694146) (xy 377.070448 -345.648271) (xy 377.047795 -345.598666) (xy 377.032431 -345.546343)
			(xy 377.02467 -345.492366) (xy 375.541822 -345.492366) (xy 375.541822 -345.492371) (xy 375.53406 -345.546357)
			(xy 375.518695 -345.59869) (xy 375.496039 -345.648304) (xy 375.466553 -345.694188) (xy 375.430838 -345.73541)
			(xy 375.38962 -345.771129) (xy 375.343739 -345.80062) (xy 375.294128 -345.823281) (xy 375.241797 -345.838651)
			(xy 375.187811 -345.846419) (xy 375.16054 -345.846908) (xy 374.29694 -345.846908) (xy 374.26967 -345.846355)
			(xy 374.215686 -345.838599) (xy 374.163355 -345.823238) (xy 374.113742 -345.800585) (xy 374.067859 -345.771102)
			(xy 374.026639 -345.735389) (xy 373.990922 -345.694173) (xy 373.961434 -345.648293) (xy 373.938776 -345.598683)
			(xy 373.92341 -345.546353) (xy 373.915647 -345.49237) (xy 372.432944 -345.49237) (xy 372.432944 -345.492375)
			(xy 372.425181 -345.54637) (xy 372.409812 -345.598711) (xy 372.38715 -345.648331) (xy 372.357657 -345.694221)
			(xy 372.321933 -345.735447) (xy 372.280705 -345.771169) (xy 372.234814 -345.800659) (xy 372.185192 -345.823319)
			(xy 372.132851 -345.838685) (xy 372.078855 -345.846446) (xy 372.05158 -345.846908) (xy 371.18798 -345.846908)
			(xy 371.160715 -345.846328) (xy 371.10674 -345.838565) (xy 371.054419 -345.8232) (xy 371.004817 -345.800545)
			(xy 370.958945 -345.771063) (xy 370.917734 -345.735352) (xy 370.882025 -345.694139) (xy 370.852545 -345.648265)
			(xy 370.829893 -345.598662) (xy 370.81453 -345.546341) (xy 370.80677 -345.492365) (xy 344.837321 -345.492365)
			(xy 344.837321 -345.492372) (xy 344.829559 -345.546362) (xy 344.814192 -345.598698) (xy 344.791533 -345.648314)
			(xy 344.762044 -345.6942) (xy 344.726325 -345.735422) (xy 344.685103 -345.771142) (xy 344.639217 -345.800631)
			(xy 344.589601 -345.823291) (xy 344.537266 -345.838658) (xy 344.483276 -345.846421) (xy 344.456004 -345.846908)
			(xy 343.592404 -345.846908) (xy 343.565136 -345.846353) (xy 343.511155 -345.838592) (xy 343.458828 -345.823228)
			(xy 343.409221 -345.800573) (xy 343.363342 -345.771089) (xy 343.322126 -345.735376) (xy 343.286413 -345.694161)
			(xy 343.256928 -345.648283) (xy 343.234273 -345.598675) (xy 343.218909 -345.546349) (xy 343.211147 -345.492368)
			(xy 341.728322 -345.492368) (xy 341.728322 -345.492371) (xy 341.72056 -345.546357) (xy 341.705195 -345.598689)
			(xy 341.682539 -345.648302) (xy 341.653054 -345.694187) (xy 341.617339 -345.735408) (xy 341.576122 -345.771128)
			(xy 341.530241 -345.800618) (xy 341.48063 -345.82328) (xy 341.4283 -345.838651) (xy 341.374315 -345.846418)
			(xy 341.347044 -345.846908) (xy 340.483444 -345.846908) (xy 340.456174 -345.846356) (xy 340.402189 -345.8386)
			(xy 340.349857 -345.823239) (xy 340.300245 -345.800587) (xy 340.254361 -345.771104) (xy 340.213141 -345.735391)
			(xy 340.177423 -345.694174) (xy 340.147935 -345.648294) (xy 340.125276 -345.598684) (xy 340.10991 -345.546354)
			(xy 340.102148 -345.49237) (xy 338.619444 -345.49237) (xy 338.619444 -345.492375) (xy 338.611681 -345.54637)
			(xy 338.596312 -345.59871) (xy 338.57365 -345.64833) (xy 338.544158 -345.69422) (xy 338.508434 -345.735446)
			(xy 338.467207 -345.771167) (xy 338.421316 -345.800658) (xy 338.371695 -345.823318) (xy 338.319354 -345.838684)
			(xy 338.265359 -345.846445) (xy 338.238084 -345.846908) (xy 337.374484 -345.846908) (xy 337.347219 -345.846329)
			(xy 337.293243 -345.838566) (xy 337.240922 -345.823201) (xy 337.19132 -345.800547) (xy 337.145446 -345.771064)
			(xy 337.104236 -345.735353) (xy 337.068526 -345.694141) (xy 337.039046 -345.648266) (xy 337.016393 -345.598663)
			(xy 337.001031 -345.546341) (xy 336.99327 -345.492365) (xy 335.510422 -345.492365) (xy 335.510422 -345.492372)
			(xy 335.50266 -345.54636) (xy 335.487294 -345.598693) (xy 335.464636 -345.648308) (xy 335.435149 -345.694193)
			(xy 335.399432 -345.735415) (xy 335.358213 -345.771135) (xy 335.312329 -345.800625) (xy 335.262716 -345.823285)
			(xy 335.210383 -345.838654) (xy 335.156396 -345.84642) (xy 335.129124 -345.846908) (xy 334.265524 -345.846908)
			(xy 334.238255 -345.846354) (xy 334.184272 -345.838596) (xy 334.131943 -345.823234) (xy 334.082333 -345.80058)
			(xy 334.036452 -345.771097) (xy 333.995234 -345.735383) (xy 333.959518 -345.694168) (xy 333.930031 -345.648288)
			(xy 333.907375 -345.59868) (xy 333.892009 -345.546351) (xy 333.884247 -345.492369) (xy 332.401544 -345.492369)
			(xy 332.401544 -345.492376) (xy 332.39378 -345.546372) (xy 332.37841 -345.598714) (xy 332.355747 -345.648336)
			(xy 332.326253 -345.694227) (xy 332.290527 -345.735453) (xy 332.249298 -345.771174) (xy 332.203404 -345.800665)
			(xy 332.153781 -345.823323) (xy 332.101437 -345.838688) (xy 332.04744 -345.846447) (xy 332.020164 -345.846908)
			(xy 331.156564 -345.846908) (xy 331.1293 -345.846327) (xy 331.075326 -345.838562) (xy 331.023007 -345.823196)
			(xy 330.973408 -345.80054) (xy 330.927537 -345.771057) (xy 330.886329 -345.735346) (xy 330.850622 -345.694134)
			(xy 330.821143 -345.648261) (xy 330.798492 -345.598659) (xy 330.78313 -345.546338) (xy 330.77537 -345.492364)
			(xy 329.292521 -345.492364) (xy 329.292521 -345.492372) (xy 329.284759 -345.546362) (xy 329.269392 -345.598698)
			(xy 329.246733 -345.648314) (xy 329.217244 -345.6942) (xy 329.181525 -345.735422) (xy 329.140303 -345.771142)
			(xy 329.094417 -345.800631) (xy 329.044801 -345.823291) (xy 328.992466 -345.838658) (xy 328.938476 -345.846421)
			(xy 328.911204 -345.846908) (xy 328.047604 -345.846908) (xy 328.020336 -345.846353) (xy 327.966355 -345.838592)
			(xy 327.914028 -345.823228) (xy 327.864421 -345.800573) (xy 327.818542 -345.771089) (xy 327.777326 -345.735376)
			(xy 327.741613 -345.694161) (xy 327.712128 -345.648283) (xy 327.689473 -345.598675) (xy 327.674109 -345.546349)
			(xy 327.666347 -345.492368) (xy 326.183522 -345.492368) (xy 326.183522 -345.492371) (xy 326.17576 -345.546357)
			(xy 326.160395 -345.598689) (xy 326.137739 -345.648302) (xy 326.108254 -345.694187) (xy 326.072539 -345.735408)
			(xy 326.031322 -345.771128) (xy 325.985441 -345.800618) (xy 325.93583 -345.82328) (xy 325.8835 -345.838651)
			(xy 325.829515 -345.846418) (xy 325.802244 -345.846908) (xy 324.938644 -345.846908) (xy 324.911374 -345.846356)
			(xy 324.857389 -345.8386) (xy 324.805057 -345.823239) (xy 324.755445 -345.800587) (xy 324.709561 -345.771104)
			(xy 324.668341 -345.735391) (xy 324.632623 -345.694174) (xy 324.603135 -345.648294) (xy 324.580476 -345.598684)
			(xy 324.56511 -345.546354) (xy 324.557348 -345.49237) (xy 323.074644 -345.49237) (xy 323.074644 -345.492375)
			(xy 323.066881 -345.54637) (xy 323.051512 -345.59871) (xy 323.02885 -345.64833) (xy 322.999358 -345.69422)
			(xy 322.963634 -345.735446) (xy 322.922407 -345.771167) (xy 322.876516 -345.800658) (xy 322.826895 -345.823318)
			(xy 322.774554 -345.838684) (xy 322.720559 -345.846445) (xy 322.693284 -345.846908) (xy 321.829684 -345.846908)
			(xy 321.802419 -345.846329) (xy 321.748443 -345.838566) (xy 321.696122 -345.823201) (xy 321.64652 -345.800547)
			(xy 321.600646 -345.771064) (xy 321.559436 -345.735353) (xy 321.523726 -345.694141) (xy 321.494246 -345.648266)
			(xy 321.471593 -345.598663) (xy 321.456231 -345.546341) (xy 321.44847 -345.492365) (xy 319.965622 -345.492365)
			(xy 319.965622 -345.492372) (xy 319.95786 -345.54636) (xy 319.942494 -345.598693) (xy 319.919836 -345.648308)
			(xy 319.890349 -345.694193) (xy 319.854632 -345.735415) (xy 319.813413 -345.771135) (xy 319.767529 -345.800625)
			(xy 319.717916 -345.823285) (xy 319.665583 -345.838654) (xy 319.611596 -345.84642) (xy 319.584324 -345.846908)
			(xy 318.720724 -345.846908) (xy 318.693455 -345.846354) (xy 318.639472 -345.838596) (xy 318.587143 -345.823234)
			(xy 318.537533 -345.80058) (xy 318.491652 -345.771097) (xy 318.450434 -345.735383) (xy 318.414718 -345.694168)
			(xy 318.385231 -345.648288) (xy 318.362575 -345.59868) (xy 318.347209 -345.546351) (xy 318.339447 -345.492369)
			(xy 316.856744 -345.492369) (xy 316.856744 -345.492376) (xy 316.84898 -345.546372) (xy 316.83361 -345.598714)
			(xy 316.810947 -345.648336) (xy 316.781453 -345.694227) (xy 316.745727 -345.735453) (xy 316.704498 -345.771174)
			(xy 316.658604 -345.800665) (xy 316.608981 -345.823323) (xy 316.556637 -345.838688) (xy 316.50264 -345.846447)
			(xy 316.475364 -345.846908) (xy 315.611764 -345.846908) (xy 315.5845 -345.846327) (xy 315.530526 -345.838562)
			(xy 315.478207 -345.823196) (xy 315.428608 -345.80054) (xy 315.382737 -345.771057) (xy 315.341529 -345.735346)
			(xy 315.305822 -345.694134) (xy 315.276343 -345.648261) (xy 315.253692 -345.598659) (xy 315.23833 -345.546338)
			(xy 315.23057 -345.492364) (xy 313.747721 -345.492364) (xy 313.747721 -345.492372) (xy 313.739959 -345.546362)
			(xy 313.724592 -345.598698) (xy 313.701933 -345.648314) (xy 313.672444 -345.6942) (xy 313.636725 -345.735422)
			(xy 313.595503 -345.771142) (xy 313.549617 -345.800631) (xy 313.500001 -345.823291) (xy 313.447666 -345.838658)
			(xy 313.393676 -345.846421) (xy 313.366404 -345.846908) (xy 312.502804 -345.846908) (xy 312.475536 -345.846353)
			(xy 312.421555 -345.838592) (xy 312.369228 -345.823228) (xy 312.319621 -345.800573) (xy 312.273742 -345.771089)
			(xy 312.232526 -345.735376) (xy 312.196813 -345.694161) (xy 312.167328 -345.648283) (xy 312.144673 -345.598675)
			(xy 312.129309 -345.546349) (xy 312.121547 -345.492368) (xy 300.231621 -345.492368) (xy 300.231621 -345.492373)
			(xy 300.223859 -345.546362) (xy 300.208492 -345.598698) (xy 300.185833 -345.648314) (xy 300.156344 -345.6942)
			(xy 300.120624 -345.735423) (xy 300.079402 -345.771143) (xy 300.033516 -345.800632) (xy 299.9839 -345.823291)
			(xy 299.931564 -345.838658) (xy 299.877575 -345.846421) (xy 299.850302 -345.846908) (xy 298.986702 -345.846908)
			(xy 298.959434 -345.846353) (xy 298.905454 -345.838592) (xy 298.853127 -345.823228) (xy 298.80352 -345.800573)
			(xy 298.757641 -345.771089) (xy 298.716426 -345.735376) (xy 298.680712 -345.69416) (xy 298.651228 -345.648282)
			(xy 298.628573 -345.598675) (xy 298.613209 -345.546348) (xy 298.605447 -345.492368) (xy 297.122622 -345.492368)
			(xy 297.122622 -345.492371) (xy 297.11486 -345.546357) (xy 297.099495 -345.59869) (xy 297.076839 -345.648303)
			(xy 297.047354 -345.694187) (xy 297.011639 -345.735409) (xy 296.970421 -345.771128) (xy 296.92454 -345.800619)
			(xy 296.874929 -345.82328) (xy 296.822598 -345.838651) (xy 296.768613 -345.846419) (xy 296.741342 -345.846908)
			(xy 295.877742 -345.846908) (xy 295.850472 -345.846355) (xy 295.796487 -345.838599) (xy 295.744156 -345.823238)
			(xy 295.694543 -345.800586) (xy 295.64866 -345.771103) (xy 295.60744 -345.73539) (xy 295.571722 -345.694174)
			(xy 295.542234 -345.648293) (xy 295.519576 -345.598683) (xy 295.50421 -345.546354) (xy 295.496448 -345.49237)
			(xy 294.013744 -345.49237) (xy 294.013744 -345.492375) (xy 294.005981 -345.54637) (xy 293.990612 -345.59871)
			(xy 293.96795 -345.648331) (xy 293.938457 -345.694221) (xy 293.902734 -345.735446) (xy 293.861506 -345.771168)
			(xy 293.815615 -345.800659) (xy 293.765994 -345.823318) (xy 293.713652 -345.838685) (xy 293.659657 -345.846446)
			(xy 293.632382 -345.846908) (xy 292.768782 -345.846908) (xy 292.741517 -345.846328) (xy 292.687542 -345.838566)
			(xy 292.635221 -345.823201) (xy 292.585619 -345.800546) (xy 292.539745 -345.771063) (xy 292.498535 -345.735352)
			(xy 292.462826 -345.69414) (xy 292.433345 -345.648266) (xy 292.410693 -345.598663) (xy 292.395331 -345.546341)
			(xy 292.38757 -345.492365) (xy 290.904722 -345.492365) (xy 290.904722 -345.492372) (xy 290.896959 -345.54636)
			(xy 290.881593 -345.598694) (xy 290.858936 -345.648309) (xy 290.829449 -345.694194) (xy 290.793732 -345.735416)
			(xy 290.752512 -345.771136) (xy 290.706628 -345.800626) (xy 290.657015 -345.823286) (xy 290.604681 -345.838655)
			(xy 290.550694 -345.84642) (xy 290.523422 -345.846908) (xy 289.659822 -345.846908) (xy 289.632553 -345.846354)
			(xy 289.57857 -345.838595) (xy 289.526241 -345.823233) (xy 289.476632 -345.800579) (xy 289.430751 -345.771096)
			(xy 289.389533 -345.735383) (xy 289.353817 -345.694167) (xy 289.324331 -345.648288) (xy 289.301675 -345.598679)
			(xy 289.286309 -345.546351) (xy 289.278547 -345.492369) (xy 287.795844 -345.492369) (xy 287.795844 -345.492376)
			(xy 287.78808 -345.546373) (xy 287.77271 -345.598715) (xy 287.750047 -345.648336) (xy 287.720552 -345.694227)
			(xy 287.684827 -345.735453) (xy 287.643597 -345.771175) (xy 287.597703 -345.800665) (xy 287.548079 -345.823323)
			(xy 287.495736 -345.838688) (xy 287.441738 -345.846447) (xy 287.414462 -345.846908) (xy 286.550862 -345.846908)
			(xy 286.523598 -345.846327) (xy 286.469625 -345.838562) (xy 286.417306 -345.823195) (xy 286.367707 -345.80054)
			(xy 286.321836 -345.771056) (xy 286.280628 -345.735345) (xy 286.244921 -345.694134) (xy 286.215442 -345.64826)
			(xy 286.192792 -345.598658) (xy 286.17743 -345.546338) (xy 286.16967 -345.492364) (xy 284.686821 -345.492364)
			(xy 284.686821 -345.492373) (xy 284.679059 -345.546362) (xy 284.663692 -345.598698) (xy 284.641033 -345.648314)
			(xy 284.611544 -345.6942) (xy 284.575824 -345.735423) (xy 284.534602 -345.771143) (xy 284.488716 -345.800632)
			(xy 284.4391 -345.823291) (xy 284.386764 -345.838658) (xy 284.332775 -345.846421) (xy 284.305502 -345.846908)
			(xy 283.441902 -345.846908) (xy 283.414634 -345.846353) (xy 283.360654 -345.838592) (xy 283.308327 -345.823228)
			(xy 283.25872 -345.800573) (xy 283.212841 -345.771089) (xy 283.171626 -345.735376) (xy 283.135912 -345.69416)
			(xy 283.106428 -345.648282) (xy 283.083773 -345.598675) (xy 283.068409 -345.546348) (xy 283.060647 -345.492368)
			(xy 281.577822 -345.492368) (xy 281.577822 -345.492371) (xy 281.57006 -345.546357) (xy 281.554695 -345.59869)
			(xy 281.532039 -345.648303) (xy 281.502554 -345.694187) (xy 281.466839 -345.735409) (xy 281.425621 -345.771128)
			(xy 281.37974 -345.800619) (xy 281.330129 -345.82328) (xy 281.277798 -345.838651) (xy 281.223813 -345.846419)
			(xy 281.196542 -345.846908) (xy 280.332942 -345.846908) (xy 280.305672 -345.846355) (xy 280.251687 -345.838599)
			(xy 280.199356 -345.823238) (xy 280.149743 -345.800586) (xy 280.10386 -345.771103) (xy 280.06264 -345.73539)
			(xy 280.026922 -345.694174) (xy 279.997434 -345.648293) (xy 279.974776 -345.598683) (xy 279.95941 -345.546354)
			(xy 279.951648 -345.49237) (xy 278.468944 -345.49237) (xy 278.468944 -345.492375) (xy 278.461181 -345.54637)
			(xy 278.445812 -345.59871) (xy 278.42315 -345.648331) (xy 278.393657 -345.694221) (xy 278.357934 -345.735446)
			(xy 278.316706 -345.771168) (xy 278.270815 -345.800659) (xy 278.221194 -345.823318) (xy 278.168852 -345.838685)
			(xy 278.114857 -345.846446) (xy 278.087582 -345.846908) (xy 277.223982 -345.846908) (xy 277.196717 -345.846328)
			(xy 277.142742 -345.838566) (xy 277.090421 -345.823201) (xy 277.040819 -345.800546) (xy 276.994945 -345.771063)
			(xy 276.953735 -345.735352) (xy 276.918026 -345.69414) (xy 276.888545 -345.648266) (xy 276.865893 -345.598663)
			(xy 276.850531 -345.546341) (xy 276.84277 -345.492365) (xy 275.359922 -345.492365) (xy 275.359922 -345.492372)
			(xy 275.352159 -345.54636) (xy 275.336793 -345.598694) (xy 275.314136 -345.648309) (xy 275.284649 -345.694194)
			(xy 275.248932 -345.735416) (xy 275.207712 -345.771136) (xy 275.161828 -345.800626) (xy 275.112215 -345.823286)
			(xy 275.059881 -345.838655) (xy 275.005894 -345.84642) (xy 274.978622 -345.846908) (xy 274.115022 -345.846908)
			(xy 274.087753 -345.846354) (xy 274.03377 -345.838595) (xy 273.981441 -345.823233) (xy 273.931832 -345.800579)
			(xy 273.885951 -345.771096) (xy 273.844733 -345.735383) (xy 273.809017 -345.694167) (xy 273.779531 -345.648288)
			(xy 273.756875 -345.598679) (xy 273.741509 -345.546351) (xy 273.733747 -345.492369) (xy 272.251044 -345.492369)
			(xy 272.251044 -345.492376) (xy 272.24328 -345.546373) (xy 272.22791 -345.598715) (xy 272.205247 -345.648336)
			(xy 272.175752 -345.694227) (xy 272.140027 -345.735453) (xy 272.098797 -345.771175) (xy 272.052903 -345.800665)
			(xy 272.003279 -345.823323) (xy 271.950936 -345.838688) (xy 271.896938 -345.846447) (xy 271.869662 -345.846908)
			(xy 271.006062 -345.846908) (xy 270.978798 -345.846327) (xy 270.924825 -345.838562) (xy 270.872506 -345.823195)
			(xy 270.822907 -345.80054) (xy 270.777036 -345.771056) (xy 270.735828 -345.735345) (xy 270.700121 -345.694134)
			(xy 270.670642 -345.64826) (xy 270.647992 -345.598658) (xy 270.63263 -345.546338) (xy 270.62487 -345.492364)
			(xy 269.142021 -345.492364) (xy 269.142021 -345.492373) (xy 269.134259 -345.546362) (xy 269.118892 -345.598698)
			(xy 269.096233 -345.648314) (xy 269.066744 -345.6942) (xy 269.031024 -345.735423) (xy 268.989802 -345.771143)
			(xy 268.943916 -345.800632) (xy 268.8943 -345.823291) (xy 268.841964 -345.838658) (xy 268.787975 -345.846421)
			(xy 268.760702 -345.846908) (xy 267.897102 -345.846908) (xy 267.869834 -345.846353) (xy 267.815854 -345.838592)
			(xy 267.763527 -345.823228) (xy 267.71392 -345.800573) (xy 267.668041 -345.771089) (xy 267.626826 -345.735376)
			(xy 267.591112 -345.69416) (xy 267.561628 -345.648282) (xy 267.538973 -345.598675) (xy 267.523609 -345.546348)
			(xy 267.515847 -345.492368) (xy 219.560575 -345.492368) (xy 219.580134 -345.530247) (xy 219.657547 -345.697572)
			(xy 219.727639 -345.868093) (xy 219.790278 -346.04149) (xy 219.845347 -346.217438) (xy 219.892742 -346.395606)
			(xy 219.932375 -346.575661) (xy 219.964171 -346.757263) (xy 219.98518 -346.917956) (xy 245.50903 -346.917956)
			(xy 245.50903 -346.83326) (xy 245.517081 -346.748946) (xy 245.53311 -346.66578) (xy 245.556971 -346.584513)
			(xy 245.58845 -346.505883) (xy 245.627261 -346.430602) (xy 245.673051 -346.35935) (xy 245.725407 -346.292774)
			(xy 245.783855 -346.231476) (xy 245.847865 -346.176011) (xy 245.916857 -346.126882) (xy 245.990207 -346.084533)
			(xy 246.06725 -346.049349) (xy 246.147289 -346.021647) (xy 246.229598 -346.001679) (xy 246.313433 -345.989626)
			(xy 246.398034 -345.985596) (xy 246.482635 -345.989626) (xy 246.56647 -346.001679) (xy 246.648779 -346.021647)
			(xy 246.728818 -346.049349) (xy 246.805861 -346.084533) (xy 246.879211 -346.126882) (xy 246.948203 -346.176011)
			(xy 247.012213 -346.231476) (xy 247.070661 -346.292774) (xy 247.123017 -346.35935) (xy 247.168807 -346.430602)
			(xy 247.207618 -346.505883) (xy 247.239097 -346.584513) (xy 247.262958 -346.66578) (xy 247.278987 -346.748946)
			(xy 247.287038 -346.83326) (xy 247.287542 -346.875608) (xy 247.287038 -346.917956) (xy 247.278987 -347.00227)
			(xy 247.262958 -347.085436) (xy 247.239097 -347.166703) (xy 247.207618 -347.245333) (xy 247.168807 -347.320614)
			(xy 247.123017 -347.391866) (xy 247.070661 -347.458442) (xy 247.012213 -347.51974) (xy 246.948203 -347.575205)
			(xy 246.879211 -347.624334) (xy 246.805861 -347.666683) (xy 246.728818 -347.701867) (xy 246.648779 -347.729569)
			(xy 246.56647 -347.749537) (xy 246.482635 -347.76159) (xy 246.398034 -347.765621) (xy 246.313433 -347.76159)
			(xy 246.229598 -347.749537) (xy 246.147289 -347.729569) (xy 246.06725 -347.701867) (xy 245.990207 -347.666683)
			(xy 245.916857 -347.624334) (xy 245.847865 -347.575205) (xy 245.783855 -347.51974) (xy 245.725407 -347.458442)
			(xy 245.673051 -347.391866) (xy 245.627261 -347.320614) (xy 245.58845 -347.245333) (xy 245.556971 -347.166703)
			(xy 245.53311 -347.085436) (xy 245.517081 -347.00227) (xy 245.50903 -346.917956) (xy 219.98518 -346.917956)
			(xy 219.988071 -346.940072) (xy 220.004028 -347.123744) (xy 220.012015 -347.307936) (xy 220.012514 -347.400118)
			(xy 220.012015 -347.4923) (xy 220.004028 -347.676492) (xy 219.988071 -347.860164) (xy 219.964171 -348.042973)
			(xy 219.932375 -348.224575) (xy 219.892742 -348.40463) (xy 219.845347 -348.582798) (xy 219.835872 -348.613072)
			(xy 267.515792 -348.613072) (xy 267.515792 -348.558528) (xy 267.523554 -348.50454) (xy 267.538921 -348.452206)
			(xy 267.561579 -348.402591) (xy 267.591068 -348.356706) (xy 267.626786 -348.315485) (xy 267.668008 -348.279766)
			(xy 267.713893 -348.250278) (xy 267.763507 -348.22762) (xy 267.815842 -348.212253) (xy 267.86983 -348.204491)
			(xy 267.897102 -348.204028) (xy 268.760702 -348.204028) (xy 268.787971 -348.204535) (xy 268.841953 -348.212296)
			(xy 268.89428 -348.227661) (xy 268.943889 -348.250317) (xy 268.989769 -348.279802) (xy 269.030985 -348.315517)
			(xy 269.066699 -348.356733) (xy 269.096184 -348.402613) (xy 269.118839 -348.452221) (xy 269.134204 -348.504549)
			(xy 269.141966 -348.558531) (xy 269.141966 -348.613068) (xy 270.624814 -348.613068) (xy 270.624814 -348.558532)
			(xy 270.632575 -348.50455) (xy 270.647939 -348.452222) (xy 270.670593 -348.402613) (xy 270.700076 -348.356733)
			(xy 270.735788 -348.315515) (xy 270.777002 -348.279799) (xy 270.82288 -348.250311) (xy 270.872486 -348.227652)
			(xy 270.924813 -348.212283) (xy 270.978794 -348.204517) (xy 271.006062 -348.204028) (xy 271.869662 -348.204028)
			(xy 271.896934 -348.204509) (xy 271.950924 -348.212266) (xy 272.00326 -348.227629) (xy 272.052876 -348.250284)
			(xy 272.098763 -348.27977) (xy 272.139987 -348.315486) (xy 272.175708 -348.356706) (xy 272.205198 -348.40259)
			(xy 272.227858 -348.452205) (xy 272.243226 -348.504539) (xy 272.250988 -348.558528) (xy 272.250988 -348.613072)
			(xy 272.250988 -348.613073) (xy 273.733692 -348.613073) (xy 273.733692 -348.558527) (xy 273.741454 -348.504537)
			(xy 273.756822 -348.452201) (xy 273.779482 -348.402585) (xy 273.808972 -348.356699) (xy 273.844693 -348.315478)
			(xy 273.885917 -348.279759) (xy 273.931805 -348.250271) (xy 273.981422 -348.227615) (xy 274.033759 -348.21225)
			(xy 274.087749 -348.20449) (xy 274.115022 -348.204028) (xy 274.978622 -348.204028) (xy 275.00589 -348.204536)
			(xy 275.059869 -348.2123) (xy 275.112195 -348.227667) (xy 275.161801 -348.250324) (xy 275.207678 -348.279809)
			(xy 275.248892 -348.315524) (xy 275.284604 -348.35674) (xy 275.314087 -348.402618) (xy 275.336741 -348.452226)
			(xy 275.352105 -348.504552) (xy 275.359866 -348.558532) (xy 275.359866 -348.613068) (xy 275.359866 -348.613069)
			(xy 276.842714 -348.613069) (xy 276.842714 -348.558531) (xy 276.850476 -348.504547) (xy 276.865841 -348.452218)
			(xy 276.888496 -348.402608) (xy 276.917981 -348.356726) (xy 276.953695 -348.315508) (xy 276.994912 -348.279792)
			(xy 277.040792 -348.250305) (xy 277.090401 -348.227647) (xy 277.14273 -348.21228) (xy 277.196713 -348.204516)
			(xy 277.223982 -348.204028) (xy 278.087582 -348.204028) (xy 278.114853 -348.20451) (xy 278.168841 -348.21227)
			(xy 278.221174 -348.227634) (xy 278.270788 -348.25029) (xy 278.316673 -348.279777) (xy 278.357894 -348.315493)
			(xy 278.393612 -348.356713) (xy 278.423101 -348.402596) (xy 278.445759 -348.452209) (xy 278.461126 -348.504542)
			(xy 278.468888 -348.558529) (xy 278.468888 -348.613071) (xy 278.468888 -348.613074) (xy 279.951592 -348.613074)
			(xy 279.951592 -348.558526) (xy 279.959355 -348.504534) (xy 279.974724 -348.452197) (xy 279.997385 -348.40258)
			(xy 280.026877 -348.356693) (xy 280.0626 -348.315471) (xy 280.103827 -348.279752) (xy 280.149717 -348.250265)
			(xy 280.199336 -348.227609) (xy 280.251676 -348.212246) (xy 280.305668 -348.204489) (xy 280.332942 -348.204028)
			(xy 281.196542 -348.204028) (xy 281.223809 -348.204537) (xy 281.277786 -348.212304) (xy 281.330109 -348.227672)
			(xy 281.379713 -348.25033) (xy 281.425587 -348.279816) (xy 281.466799 -348.315531) (xy 281.502509 -348.356746)
			(xy 281.53199 -348.402624) (xy 281.554643 -348.45223) (xy 281.570005 -348.504555) (xy 281.577766 -348.558533)
			(xy 281.577766 -348.613067) (xy 281.577765 -348.613072) (xy 283.060592 -348.613072) (xy 283.060592 -348.558528)
			(xy 283.068354 -348.50454) (xy 283.083721 -348.452206) (xy 283.106379 -348.402591) (xy 283.135868 -348.356706)
			(xy 283.171586 -348.315485) (xy 283.212808 -348.279766) (xy 283.258693 -348.250278) (xy 283.308307 -348.22762)
			(xy 283.360642 -348.212253) (xy 283.41463 -348.204491) (xy 283.441902 -348.204028) (xy 284.305502 -348.204028)
			(xy 284.332771 -348.204535) (xy 284.386753 -348.212296) (xy 284.43908 -348.227661) (xy 284.488689 -348.250317)
			(xy 284.534569 -348.279802) (xy 284.575785 -348.315517) (xy 284.611499 -348.356733) (xy 284.640984 -348.402613)
			(xy 284.663639 -348.452221) (xy 284.679004 -348.504549) (xy 284.686766 -348.558531) (xy 284.686766 -348.613068)
			(xy 286.169614 -348.613068) (xy 286.169614 -348.558532) (xy 286.177375 -348.50455) (xy 286.192739 -348.452222)
			(xy 286.215393 -348.402613) (xy 286.244876 -348.356733) (xy 286.280588 -348.315515) (xy 286.321802 -348.279799)
			(xy 286.36768 -348.250311) (xy 286.417286 -348.227652) (xy 286.469613 -348.212283) (xy 286.523594 -348.204517)
			(xy 286.550862 -348.204028) (xy 287.414462 -348.204028) (xy 287.441734 -348.204509) (xy 287.495724 -348.212266)
			(xy 287.54806 -348.227629) (xy 287.597676 -348.250284) (xy 287.643563 -348.27977) (xy 287.684787 -348.315486)
			(xy 287.720508 -348.356706) (xy 287.749998 -348.40259) (xy 287.772658 -348.452205) (xy 287.788026 -348.504539)
			(xy 287.795788 -348.558528) (xy 287.795788 -348.613072) (xy 287.795788 -348.613073) (xy 289.278492 -348.613073)
			(xy 289.278492 -348.558527) (xy 289.286254 -348.504537) (xy 289.301622 -348.452201) (xy 289.324282 -348.402585)
			(xy 289.353772 -348.356699) (xy 289.389493 -348.315478) (xy 289.430717 -348.279759) (xy 289.476605 -348.250271)
			(xy 289.526222 -348.227615) (xy 289.578559 -348.21225) (xy 289.632549 -348.20449) (xy 289.659822 -348.204028)
			(xy 290.523422 -348.204028) (xy 290.55069 -348.204536) (xy 290.604669 -348.2123) (xy 290.656995 -348.227667)
			(xy 290.706601 -348.250324) (xy 290.752478 -348.279809) (xy 290.793692 -348.315524) (xy 290.829404 -348.35674)
			(xy 290.858887 -348.402618) (xy 290.881541 -348.452226) (xy 290.896905 -348.504552) (xy 290.904666 -348.558532)
			(xy 290.904666 -348.613068) (xy 290.904666 -348.613069) (xy 292.387514 -348.613069) (xy 292.387514 -348.558531)
			(xy 292.395276 -348.504547) (xy 292.410641 -348.452218) (xy 292.433296 -348.402608) (xy 292.462781 -348.356726)
			(xy 292.498495 -348.315508) (xy 292.539712 -348.279792) (xy 292.585592 -348.250305) (xy 292.635201 -348.227647)
			(xy 292.68753 -348.21228) (xy 292.741513 -348.204516) (xy 292.768782 -348.204028) (xy 293.632382 -348.204028)
			(xy 293.659653 -348.20451) (xy 293.713641 -348.21227) (xy 293.765974 -348.227634) (xy 293.815588 -348.25029)
			(xy 293.861473 -348.279777) (xy 293.902694 -348.315493) (xy 293.938412 -348.356713) (xy 293.967901 -348.402596)
			(xy 293.990559 -348.452209) (xy 294.005926 -348.504542) (xy 294.013688 -348.558529) (xy 294.013688 -348.613071)
			(xy 294.013688 -348.613074) (xy 295.496392 -348.613074) (xy 295.496392 -348.558526) (xy 295.504155 -348.504534)
			(xy 295.519524 -348.452197) (xy 295.542185 -348.40258) (xy 295.571677 -348.356693) (xy 295.6074 -348.315471)
			(xy 295.648627 -348.279752) (xy 295.694517 -348.250265) (xy 295.744136 -348.227609) (xy 295.796476 -348.212246)
			(xy 295.850468 -348.204489) (xy 295.877742 -348.204028) (xy 296.741342 -348.204028) (xy 296.768609 -348.204537)
			(xy 296.822586 -348.212304) (xy 296.874909 -348.227672) (xy 296.924513 -348.25033) (xy 296.970387 -348.279816)
			(xy 297.011599 -348.315531) (xy 297.047309 -348.356746) (xy 297.07679 -348.402624) (xy 297.099443 -348.45223)
			(xy 297.114805 -348.504555) (xy 297.122566 -348.558533) (xy 297.122566 -348.613067) (xy 297.122565 -348.613072)
			(xy 298.605392 -348.613072) (xy 298.605392 -348.558528) (xy 298.613154 -348.50454) (xy 298.628521 -348.452206)
			(xy 298.651179 -348.402591) (xy 298.680668 -348.356706) (xy 298.716386 -348.315485) (xy 298.757608 -348.279766)
			(xy 298.803493 -348.250278) (xy 298.853107 -348.22762) (xy 298.905442 -348.212253) (xy 298.95943 -348.204491)
			(xy 298.986702 -348.204028) (xy 299.850302 -348.204028) (xy 299.877571 -348.204535) (xy 299.931553 -348.212296)
			(xy 299.98388 -348.227661) (xy 300.033489 -348.250317) (xy 300.079369 -348.279802) (xy 300.120585 -348.315517)
			(xy 300.156299 -348.356733) (xy 300.185784 -348.402613) (xy 300.208439 -348.452221) (xy 300.223804 -348.504549)
			(xy 300.231566 -348.558531) (xy 300.231566 -348.613069) (xy 300.231566 -348.613072) (xy 312.121492 -348.613072)
			(xy 312.121492 -348.558528) (xy 312.129254 -348.504539) (xy 312.144621 -348.452205) (xy 312.167279 -348.40259)
			(xy 312.196768 -348.356705) (xy 312.232487 -348.315484) (xy 312.273709 -348.279766) (xy 312.319594 -348.250277)
			(xy 312.369209 -348.227619) (xy 312.421543 -348.212253) (xy 312.475532 -348.204491) (xy 312.502804 -348.204028)
			(xy 313.366404 -348.204028) (xy 313.393672 -348.204535) (xy 313.447654 -348.212297) (xy 313.499982 -348.227662)
			(xy 313.54959 -348.250318) (xy 313.595469 -348.279803) (xy 313.636686 -348.315517) (xy 313.672399 -348.356734)
			(xy 313.701884 -348.402613) (xy 313.72454 -348.452222) (xy 313.739904 -348.50455) (xy 313.747666 -348.558532)
			(xy 313.747666 -348.613068) (xy 315.230514 -348.613068) (xy 315.230514 -348.558532) (xy 315.238275 -348.50455)
			(xy 315.253639 -348.452222) (xy 315.276293 -348.402613) (xy 315.305777 -348.356732) (xy 315.341489 -348.315514)
			(xy 315.382703 -348.279798) (xy 315.428581 -348.250311) (xy 315.478188 -348.227652) (xy 315.530514 -348.212283)
			(xy 315.584496 -348.204517) (xy 315.611764 -348.204028) (xy 316.475364 -348.204028) (xy 316.502636 -348.204509)
			(xy 316.556625 -348.212267) (xy 316.608961 -348.22763) (xy 316.658577 -348.250284) (xy 316.704464 -348.27977)
			(xy 316.745688 -348.315487) (xy 316.781408 -348.356707) (xy 316.810898 -348.402591) (xy 316.833558 -348.452205)
			(xy 316.848926 -348.504539) (xy 316.856688 -348.558528) (xy 316.856688 -348.613072) (xy 316.856688 -348.613073)
			(xy 318.339392 -348.613073) (xy 318.339392 -348.558527) (xy 318.347155 -348.504537) (xy 318.362522 -348.452201)
			(xy 318.385182 -348.402585) (xy 318.414673 -348.356699) (xy 318.450394 -348.315477) (xy 318.491618 -348.279759)
			(xy 318.537506 -348.250271) (xy 318.587123 -348.227614) (xy 318.63946 -348.212249) (xy 318.693451 -348.20449)
			(xy 318.720724 -348.204028) (xy 319.584324 -348.204028) (xy 319.611592 -348.204536) (xy 319.665571 -348.2123)
			(xy 319.717896 -348.227667) (xy 319.767502 -348.250324) (xy 319.813379 -348.27981) (xy 319.854593 -348.315524)
			(xy 319.890304 -348.35674) (xy 319.919787 -348.402619) (xy 319.942441 -348.452226) (xy 319.957805 -348.504552)
			(xy 319.965566 -348.558532) (xy 319.965566 -348.613068) (xy 319.965566 -348.613069) (xy 321.448414 -348.613069)
			(xy 321.448414 -348.558531) (xy 321.456176 -348.504547) (xy 321.471541 -348.452217) (xy 321.494196 -348.402607)
			(xy 321.523682 -348.356726) (xy 321.559396 -348.315507) (xy 321.600613 -348.279791) (xy 321.646493 -348.250304)
			(xy 321.696102 -348.227646) (xy 321.748431 -348.212279) (xy 321.802415 -348.204516) (xy 321.829684 -348.204028)
			(xy 322.693284 -348.204028) (xy 322.720555 -348.20451) (xy 322.774542 -348.21227) (xy 322.826875 -348.227635)
			(xy 322.876489 -348.250291) (xy 322.922374 -348.279777) (xy 322.963595 -348.315494) (xy 322.999313 -348.356713)
			(xy 323.028801 -348.402597) (xy 323.051459 -348.45221) (xy 323.066826 -348.504542) (xy 323.074588 -348.558529)
			(xy 323.074588 -348.613071) (xy 323.074588 -348.613074) (xy 324.557292 -348.613074) (xy 324.557292 -348.558526)
			(xy 324.565055 -348.504534) (xy 324.580424 -348.452197) (xy 324.603085 -348.402579) (xy 324.632578 -348.356692)
			(xy 324.668301 -348.31547) (xy 324.709527 -348.279751) (xy 324.755418 -348.250264) (xy 324.805038 -348.227609)
			(xy 324.857377 -348.212246) (xy 324.91137 -348.204489) (xy 324.938644 -348.204028) (xy 325.802244 -348.204028)
			(xy 325.829511 -348.204537) (xy 325.883488 -348.212304) (xy 325.935811 -348.227673) (xy 325.985414 -348.250331)
			(xy 326.031288 -348.279817) (xy 326.0725 -348.315531) (xy 326.108209 -348.356747) (xy 326.13769 -348.402624)
			(xy 326.160343 -348.45223) (xy 326.175705 -348.504555) (xy 326.183466 -348.558533) (xy 326.183466 -348.613067)
			(xy 326.183465 -348.613072) (xy 327.666292 -348.613072) (xy 327.666292 -348.558528) (xy 327.674054 -348.504539)
			(xy 327.689421 -348.452205) (xy 327.712079 -348.40259) (xy 327.741568 -348.356705) (xy 327.777287 -348.315484)
			(xy 327.818509 -348.279766) (xy 327.864394 -348.250277) (xy 327.914009 -348.227619) (xy 327.966343 -348.212253)
			(xy 328.020332 -348.204491) (xy 328.047604 -348.204028) (xy 328.911204 -348.204028) (xy 328.938472 -348.204535)
			(xy 328.992454 -348.212297) (xy 329.044782 -348.227662) (xy 329.09439 -348.250318) (xy 329.140269 -348.279803)
			(xy 329.181486 -348.315517) (xy 329.217199 -348.356734) (xy 329.246684 -348.402613) (xy 329.26934 -348.452222)
			(xy 329.284704 -348.50455) (xy 329.292466 -348.558532) (xy 329.292466 -348.613068) (xy 330.775314 -348.613068)
			(xy 330.775314 -348.558532) (xy 330.783075 -348.50455) (xy 330.798439 -348.452222) (xy 330.821093 -348.402613)
			(xy 330.850577 -348.356732) (xy 330.886289 -348.315514) (xy 330.927503 -348.279798) (xy 330.973381 -348.250311)
			(xy 331.022988 -348.227652) (xy 331.075314 -348.212283) (xy 331.129296 -348.204517) (xy 331.156564 -348.204028)
			(xy 332.020164 -348.204028) (xy 332.047436 -348.204509) (xy 332.101425 -348.212267) (xy 332.153761 -348.22763)
			(xy 332.203377 -348.250284) (xy 332.249264 -348.27977) (xy 332.290488 -348.315487) (xy 332.326208 -348.356707)
			(xy 332.355698 -348.402591) (xy 332.378358 -348.452205) (xy 332.393726 -348.504539) (xy 332.401488 -348.558528)
			(xy 332.401488 -348.613072) (xy 332.401488 -348.613073) (xy 333.884192 -348.613073) (xy 333.884192 -348.558527)
			(xy 333.891955 -348.504537) (xy 333.907322 -348.452201) (xy 333.929982 -348.402585) (xy 333.959473 -348.356699)
			(xy 333.995194 -348.315477) (xy 334.036418 -348.279759) (xy 334.082306 -348.250271) (xy 334.131923 -348.227614)
			(xy 334.18426 -348.212249) (xy 334.238251 -348.20449) (xy 334.265524 -348.204028) (xy 335.129124 -348.204028)
			(xy 335.156392 -348.204536) (xy 335.210371 -348.2123) (xy 335.262696 -348.227667) (xy 335.312302 -348.250324)
			(xy 335.358179 -348.27981) (xy 335.399393 -348.315524) (xy 335.435104 -348.35674) (xy 335.464587 -348.402619)
			(xy 335.487241 -348.452226) (xy 335.502605 -348.504552) (xy 335.510366 -348.558532) (xy 335.510366 -348.613068)
			(xy 335.510366 -348.613069) (xy 336.993214 -348.613069) (xy 336.993214 -348.558531) (xy 337.000976 -348.504547)
			(xy 337.016341 -348.452217) (xy 337.038996 -348.402607) (xy 337.068482 -348.356726) (xy 337.104196 -348.315507)
			(xy 337.145413 -348.279791) (xy 337.191293 -348.250304) (xy 337.240902 -348.227646) (xy 337.293231 -348.212279)
			(xy 337.347215 -348.204516) (xy 337.374484 -348.204028) (xy 338.238084 -348.204028) (xy 338.265355 -348.20451)
			(xy 338.319342 -348.21227) (xy 338.371675 -348.227635) (xy 338.421289 -348.250291) (xy 338.467174 -348.279777)
			(xy 338.508395 -348.315494) (xy 338.544113 -348.356713) (xy 338.573601 -348.402597) (xy 338.596259 -348.45221)
			(xy 338.611626 -348.504542) (xy 338.619388 -348.558529) (xy 338.619388 -348.613071) (xy 338.619388 -348.613074)
			(xy 340.102092 -348.613074) (xy 340.102092 -348.558526) (xy 340.109855 -348.504534) (xy 340.125224 -348.452197)
			(xy 340.147885 -348.402579) (xy 340.177378 -348.356692) (xy 340.213101 -348.31547) (xy 340.254327 -348.279751)
			(xy 340.300218 -348.250264) (xy 340.349838 -348.227609) (xy 340.402177 -348.212246) (xy 340.45617 -348.204489)
			(xy 340.483444 -348.204028) (xy 341.347044 -348.204028) (xy 341.374311 -348.204537) (xy 341.428288 -348.212304)
			(xy 341.480611 -348.227673) (xy 341.530214 -348.250331) (xy 341.576088 -348.279817) (xy 341.6173 -348.315531)
			(xy 341.653009 -348.356747) (xy 341.68249 -348.402624) (xy 341.705143 -348.45223) (xy 341.720505 -348.504555)
			(xy 341.728266 -348.558533) (xy 341.728266 -348.613067) (xy 341.728265 -348.613072) (xy 343.211092 -348.613072)
			(xy 343.211092 -348.558528) (xy 343.218854 -348.504539) (xy 343.234221 -348.452205) (xy 343.256879 -348.40259)
			(xy 343.286368 -348.356705) (xy 343.322087 -348.315484) (xy 343.363309 -348.279766) (xy 343.409194 -348.250277)
			(xy 343.458809 -348.227619) (xy 343.511143 -348.212253) (xy 343.565132 -348.204491) (xy 343.592404 -348.204028)
			(xy 344.456004 -348.204028) (xy 344.483272 -348.204535) (xy 344.537254 -348.212297) (xy 344.589582 -348.227662)
			(xy 344.63919 -348.250318) (xy 344.685069 -348.279803) (xy 344.726286 -348.315517) (xy 344.761999 -348.356734)
			(xy 344.791484 -348.402613) (xy 344.81414 -348.452222) (xy 344.829504 -348.50455) (xy 344.837266 -348.558532)
			(xy 344.837266 -348.613068) (xy 344.837266 -348.613069) (xy 370.806714 -348.613069) (xy 370.806714 -348.558531)
			(xy 370.814476 -348.504548) (xy 370.82984 -348.452218) (xy 370.852496 -348.402608) (xy 370.881981 -348.356727)
			(xy 370.917695 -348.315509) (xy 370.958911 -348.279793) (xy 371.004791 -348.250305) (xy 371.054399 -348.227647)
			(xy 371.106728 -348.21228) (xy 371.160711 -348.204516) (xy 371.18798 -348.204028) (xy 372.05158 -348.204028)
			(xy 372.078851 -348.20451) (xy 372.132839 -348.21227) (xy 372.185173 -348.227634) (xy 372.234787 -348.25029)
			(xy 372.280672 -348.279776) (xy 372.321893 -348.315493) (xy 372.357612 -348.356712) (xy 372.387101 -348.402595)
			(xy 372.409759 -348.452209) (xy 372.425126 -348.504542) (xy 372.432888 -348.558529) (xy 372.432888 -348.613071)
			(xy 372.432888 -348.613074) (xy 373.915592 -348.613074) (xy 373.915592 -348.558526) (xy 373.923355 -348.504535)
			(xy 373.938724 -348.452197) (xy 373.961385 -348.40258) (xy 373.990877 -348.356694) (xy 374.0266 -348.315471)
			(xy 374.067826 -348.279753) (xy 374.113715 -348.250266) (xy 374.163335 -348.22761) (xy 374.215674 -348.212246)
			(xy 374.269666 -348.204489) (xy 374.29694 -348.204028) (xy 375.16054 -348.204028) (xy 375.187807 -348.204537)
			(xy 375.241785 -348.212303) (xy 375.294108 -348.227672) (xy 375.343712 -348.25033) (xy 375.389587 -348.279816)
			(xy 375.430798 -348.31553) (xy 375.466508 -348.356746) (xy 375.49599 -348.402623) (xy 375.518642 -348.45223)
			(xy 375.534005 -348.504554) (xy 375.541766 -348.558533) (xy 375.541766 -348.613067) (xy 375.541766 -348.61307)
			(xy 377.024614 -348.61307) (xy 377.024614 -348.55853) (xy 377.032376 -348.504545) (xy 377.047742 -348.452214)
			(xy 377.070399 -348.402603) (xy 377.099886 -348.35672) (xy 377.135602 -348.315502) (xy 377.17682 -348.279786)
			(xy 377.222703 -348.250299) (xy 377.272314 -348.227642) (xy 377.324645 -348.212276) (xy 377.37863 -348.204514)
			(xy 377.4059 -348.204028) (xy 378.2695 -348.204028) (xy 378.296769 -348.204534) (xy 378.350751 -348.212296)
			(xy 378.403079 -348.227661) (xy 378.452688 -348.250316) (xy 378.498568 -348.279802) (xy 378.539784 -348.315516)
			(xy 378.575498 -348.356732) (xy 378.604984 -348.402612) (xy 378.627639 -348.452221) (xy 378.643004 -348.504549)
			(xy 378.650766 -348.558531) (xy 378.650766 -348.613068) (xy 380.133614 -348.613068) (xy 380.133614 -348.558532)
			(xy 380.141375 -348.50455) (xy 380.156739 -348.452223) (xy 380.179393 -348.402614) (xy 380.208876 -348.356734)
			(xy 380.244588 -348.315516) (xy 380.285801 -348.2798) (xy 380.331679 -348.250312) (xy 380.381285 -348.227653)
			(xy 380.433611 -348.212284) (xy 380.487592 -348.204517) (xy 380.51486 -348.204028) (xy 381.37846 -348.204028)
			(xy 381.405732 -348.204509) (xy 381.459722 -348.212266) (xy 381.512058 -348.227628) (xy 381.561675 -348.250283)
			(xy 381.607562 -348.279769) (xy 381.648786 -348.315485) (xy 381.684507 -348.356706) (xy 381.713998 -348.40259)
			(xy 381.736658 -348.452204) (xy 381.752025 -348.504539) (xy 381.759788 -348.558528) (xy 381.759788 -348.613072)
			(xy 381.759788 -348.613073) (xy 383.242492 -348.613073) (xy 383.242492 -348.558527) (xy 383.250254 -348.504537)
			(xy 383.265622 -348.452202) (xy 383.288282 -348.402586) (xy 383.317772 -348.3567) (xy 383.353493 -348.315478)
			(xy 383.394716 -348.27976) (xy 383.440603 -348.250272) (xy 383.49022 -348.227615) (xy 383.542557 -348.21225)
			(xy 383.596547 -348.20449) (xy 383.62382 -348.204028) (xy 384.48742 -348.204028) (xy 384.514688 -348.204536)
			(xy 384.568668 -348.2123) (xy 384.620994 -348.227666) (xy 384.6706 -348.250323) (xy 384.716477 -348.279809)
			(xy 384.757691 -348.315523) (xy 384.793403 -348.356739) (xy 384.822887 -348.402618) (xy 384.845541 -348.452225)
			(xy 384.860905 -348.504552) (xy 384.868666 -348.558532) (xy 384.868666 -348.613068) (xy 384.868666 -348.613069)
			(xy 386.351514 -348.613069) (xy 386.351514 -348.558531) (xy 386.359276 -348.504548) (xy 386.37464 -348.452218)
			(xy 386.397296 -348.402608) (xy 386.426781 -348.356727) (xy 386.462495 -348.315509) (xy 386.503711 -348.279793)
			(xy 386.549591 -348.250305) (xy 386.599199 -348.227647) (xy 386.651528 -348.21228) (xy 386.705511 -348.204516)
			(xy 386.73278 -348.204028) (xy 387.59638 -348.204028) (xy 387.623651 -348.20451) (xy 387.677639 -348.21227)
			(xy 387.729973 -348.227634) (xy 387.779587 -348.25029) (xy 387.825472 -348.279776) (xy 387.866693 -348.315493)
			(xy 387.902412 -348.356712) (xy 387.931901 -348.402595) (xy 387.954559 -348.452209) (xy 387.969926 -348.504542)
			(xy 387.977688 -348.558529) (xy 387.977688 -348.613071) (xy 387.977688 -348.613074) (xy 389.460392 -348.613074)
			(xy 389.460392 -348.558526) (xy 389.468155 -348.504535) (xy 389.483524 -348.452197) (xy 389.506185 -348.40258)
			(xy 389.535677 -348.356694) (xy 389.5714 -348.315471) (xy 389.612626 -348.279753) (xy 389.658515 -348.250266)
			(xy 389.708135 -348.22761) (xy 389.760474 -348.212246) (xy 389.814466 -348.204489) (xy 389.84174 -348.204028)
			(xy 390.70534 -348.204028) (xy 390.732607 -348.204537) (xy 390.786585 -348.212303) (xy 390.838908 -348.227672)
			(xy 390.888512 -348.25033) (xy 390.934387 -348.279816) (xy 390.975598 -348.31553) (xy 391.011308 -348.356746)
			(xy 391.04079 -348.402623) (xy 391.063442 -348.45223) (xy 391.078805 -348.504554) (xy 391.086566 -348.558533)
			(xy 391.086566 -348.613067) (xy 391.086566 -348.61307) (xy 392.569414 -348.61307) (xy 392.569414 -348.55853)
			(xy 392.577176 -348.504545) (xy 392.592542 -348.452214) (xy 392.615199 -348.402603) (xy 392.644686 -348.35672)
			(xy 392.680402 -348.315502) (xy 392.72162 -348.279786) (xy 392.767503 -348.250299) (xy 392.817114 -348.227642)
			(xy 392.869445 -348.212276) (xy 392.92343 -348.204514) (xy 392.9507 -348.204028) (xy 393.8143 -348.204028)
			(xy 393.841569 -348.204534) (xy 393.895551 -348.212296) (xy 393.947879 -348.227661) (xy 393.997488 -348.250316)
			(xy 394.043368 -348.279802) (xy 394.084584 -348.315516) (xy 394.120298 -348.356732) (xy 394.149784 -348.402612)
			(xy 394.172439 -348.452221) (xy 394.187804 -348.504549) (xy 394.195566 -348.558531) (xy 394.195566 -348.613068)
			(xy 395.678414 -348.613068) (xy 395.678414 -348.558532) (xy 395.686175 -348.50455) (xy 395.701539 -348.452223)
			(xy 395.724193 -348.402614) (xy 395.753676 -348.356734) (xy 395.789388 -348.315516) (xy 395.830601 -348.2798)
			(xy 395.876479 -348.250312) (xy 395.926085 -348.227653) (xy 395.978411 -348.212284) (xy 396.032392 -348.204517)
			(xy 396.05966 -348.204028) (xy 396.92326 -348.204028) (xy 396.950532 -348.204509) (xy 397.004522 -348.212266)
			(xy 397.056858 -348.227628) (xy 397.106475 -348.250283) (xy 397.152362 -348.279769) (xy 397.193586 -348.315485)
			(xy 397.229307 -348.356706) (xy 397.258798 -348.40259) (xy 397.281458 -348.452204) (xy 397.296825 -348.504539)
			(xy 397.304588 -348.558528) (xy 397.304588 -348.613072) (xy 397.304588 -348.613073) (xy 398.787292 -348.613073)
			(xy 398.787292 -348.558527) (xy 398.795054 -348.504537) (xy 398.810422 -348.452202) (xy 398.833082 -348.402586)
			(xy 398.862572 -348.3567) (xy 398.898293 -348.315478) (xy 398.939516 -348.27976) (xy 398.985403 -348.250272)
			(xy 399.03502 -348.227615) (xy 399.087357 -348.21225) (xy 399.141347 -348.20449) (xy 399.16862 -348.204028)
			(xy 400.03222 -348.204028) (xy 400.059488 -348.204536) (xy 400.113468 -348.2123) (xy 400.165794 -348.227666)
			(xy 400.2154 -348.250323) (xy 400.261277 -348.279809) (xy 400.302491 -348.315523) (xy 400.338203 -348.356739)
			(xy 400.367687 -348.402618) (xy 400.390341 -348.452225) (xy 400.405705 -348.504552) (xy 400.413466 -348.558532)
			(xy 400.413466 -348.613068) (xy 400.413466 -348.613069) (xy 401.896314 -348.613069) (xy 401.896314 -348.558531)
			(xy 401.904076 -348.504548) (xy 401.91944 -348.452218) (xy 401.942096 -348.402608) (xy 401.971581 -348.356727)
			(xy 402.007295 -348.315509) (xy 402.048511 -348.279793) (xy 402.094391 -348.250305) (xy 402.143999 -348.227647)
			(xy 402.196328 -348.21228) (xy 402.250311 -348.204516) (xy 402.27758 -348.204028) (xy 403.14118 -348.204028)
			(xy 403.168451 -348.20451) (xy 403.222439 -348.21227) (xy 403.274773 -348.227634) (xy 403.324387 -348.25029)
			(xy 403.370272 -348.279776) (xy 403.411493 -348.315493) (xy 403.447212 -348.356712) (xy 403.476701 -348.402595)
			(xy 403.499359 -348.452209) (xy 403.514726 -348.504542) (xy 403.522488 -348.558529) (xy 403.522488 -348.61307)
			(xy 408.913814 -348.61307) (xy 408.913814 -348.55853) (xy 408.921576 -348.504546) (xy 408.936941 -348.452216)
			(xy 408.959598 -348.402605) (xy 408.989084 -348.356723) (xy 409.024799 -348.315505) (xy 409.066017 -348.279788)
			(xy 409.111898 -348.250301) (xy 409.161508 -348.227644) (xy 409.213838 -348.212278) (xy 409.267822 -348.204515)
			(xy 409.295092 -348.204028) (xy 410.158692 -348.204028) (xy 410.185963 -348.204511) (xy 410.239949 -348.212272)
			(xy 410.292281 -348.227637) (xy 410.341894 -348.250294) (xy 410.387778 -348.27978) (xy 410.428998 -348.315497)
			(xy 410.464715 -348.356716) (xy 410.494203 -348.402599) (xy 410.51686 -348.452211) (xy 410.532226 -348.504543)
			(xy 410.539989 -348.558529) (xy 410.539989 -348.613068) (xy 412.022814 -348.613068) (xy 412.022814 -348.558532)
			(xy 412.030575 -348.504551) (xy 412.045938 -348.452224) (xy 412.068592 -348.402616) (xy 412.098074 -348.356736)
			(xy 412.133785 -348.315519) (xy 412.174998 -348.279803) (xy 412.220874 -348.250315) (xy 412.270479 -348.227655)
			(xy 412.322804 -348.212285) (xy 412.376784 -348.204518) (xy 412.404052 -348.204028) (xy 413.267652 -348.204028)
			(xy 413.294925 -348.204508) (xy 413.348915 -348.212265) (xy 413.401252 -348.227626) (xy 413.45087 -348.250281)
			(xy 413.496759 -348.279766) (xy 413.537983 -348.315483) (xy 413.573705 -348.356703) (xy 413.603196 -348.402588)
			(xy 413.625857 -348.452203) (xy 413.641225 -348.504538) (xy 413.648988 -348.558528) (xy 413.648988 -348.613072)
			(xy 415.131692 -348.613072) (xy 415.131692 -348.558528) (xy 415.139454 -348.504538) (xy 415.154821 -348.452203)
			(xy 415.177481 -348.402588) (xy 415.20697 -348.356703) (xy 415.24269 -348.315481) (xy 415.283912 -348.279763)
			(xy 415.329799 -348.250275) (xy 415.379415 -348.227617) (xy 415.43175 -348.212252) (xy 415.48574 -348.204491)
			(xy 415.513012 -348.204028) (xy 416.376612 -348.204028) (xy 416.40388 -348.204535) (xy 416.457861 -348.212298)
			(xy 416.510188 -348.227664) (xy 416.559795 -348.25032) (xy 416.605673 -348.279806) (xy 416.646888 -348.31552)
			(xy 416.682601 -348.356736) (xy 416.712085 -348.402615) (xy 416.73474 -348.452224) (xy 416.750104 -348.504551)
			(xy 416.757866 -348.558532) (xy 416.757866 -348.613068) (xy 416.757866 -348.613069) (xy 418.240714 -348.613069)
			(xy 418.240714 -348.558531) (xy 418.248476 -348.504549) (xy 418.26384 -348.45222) (xy 418.286495 -348.40261)
			(xy 418.315979 -348.35673) (xy 418.351692 -348.315512) (xy 418.392907 -348.279795) (xy 418.438786 -348.250308)
			(xy 418.488394 -348.22765) (xy 418.540721 -348.212281) (xy 418.594703 -348.204516) (xy 418.621972 -348.204028)
			(xy 419.485572 -348.204028) (xy 419.512844 -348.20451) (xy 419.566832 -348.212268) (xy 419.619167 -348.227632)
			(xy 419.668782 -348.250287) (xy 419.714668 -348.279773) (xy 419.75589 -348.31549) (xy 419.79161 -348.356709)
			(xy 419.821099 -348.402593) (xy 419.843759 -348.452207) (xy 419.859126 -348.504541) (xy 419.866888 -348.558528)
			(xy 419.866888 -348.613072) (xy 419.866888 -348.613073) (xy 421.349592 -348.613073) (xy 421.349592 -348.558527)
			(xy 421.357355 -348.504536) (xy 421.372723 -348.452199) (xy 421.395384 -348.402583) (xy 421.424875 -348.356696)
			(xy 421.460597 -348.315474) (xy 421.501822 -348.279756) (xy 421.547711 -348.250268) (xy 421.597329 -348.227612)
			(xy 421.649667 -348.212248) (xy 421.703659 -348.204489) (xy 421.730932 -348.204028) (xy 422.594532 -348.204028)
			(xy 422.621799 -348.204537) (xy 422.675778 -348.212302) (xy 422.728102 -348.227669) (xy 422.777707 -348.250327)
			(xy 422.823583 -348.279813) (xy 422.864795 -348.315527) (xy 422.900506 -348.356743) (xy 422.929988 -348.402621)
			(xy 422.952642 -348.452228) (xy 422.968005 -348.504553) (xy 422.975766 -348.558533) (xy 422.975766 -348.613067)
			(xy 422.975766 -348.61307) (xy 424.458614 -348.61307) (xy 424.458614 -348.55853) (xy 424.466376 -348.504546)
			(xy 424.481741 -348.452216) (xy 424.504398 -348.402605) (xy 424.533884 -348.356723) (xy 424.569599 -348.315505)
			(xy 424.610817 -348.279788) (xy 424.656698 -348.250301) (xy 424.706308 -348.227644) (xy 424.758638 -348.212278)
			(xy 424.812622 -348.204515) (xy 424.839892 -348.204028) (xy 425.703492 -348.204028) (xy 425.730763 -348.204511)
			(xy 425.784749 -348.212272) (xy 425.837081 -348.227637) (xy 425.886694 -348.250294) (xy 425.932578 -348.27978)
			(xy 425.973798 -348.315497) (xy 426.009515 -348.356716) (xy 426.039003 -348.402599) (xy 426.06166 -348.452211)
			(xy 426.077026 -348.504543) (xy 426.084789 -348.558529) (xy 426.084789 -348.613068) (xy 427.567614 -348.613068)
			(xy 427.567614 -348.558532) (xy 427.575375 -348.504551) (xy 427.590738 -348.452224) (xy 427.613392 -348.402616)
			(xy 427.642874 -348.356736) (xy 427.678585 -348.315519) (xy 427.719798 -348.279803) (xy 427.765674 -348.250315)
			(xy 427.815279 -348.227655) (xy 427.867604 -348.212285) (xy 427.921584 -348.204518) (xy 427.948852 -348.204028)
			(xy 428.812452 -348.204028) (xy 428.839725 -348.204508) (xy 428.893715 -348.212265) (xy 428.946052 -348.227626)
			(xy 428.99567 -348.250281) (xy 429.041559 -348.279766) (xy 429.082783 -348.315483) (xy 429.118505 -348.356703)
			(xy 429.147996 -348.402588) (xy 429.170657 -348.452203) (xy 429.186025 -348.504538) (xy 429.193788 -348.558528)
			(xy 429.193788 -348.613072) (xy 430.676492 -348.613072) (xy 430.676492 -348.558528) (xy 430.684254 -348.504538)
			(xy 430.699621 -348.452203) (xy 430.722281 -348.402588) (xy 430.75177 -348.356703) (xy 430.78749 -348.315481)
			(xy 430.828712 -348.279763) (xy 430.874599 -348.250275) (xy 430.924215 -348.227617) (xy 430.97655 -348.212252)
			(xy 431.03054 -348.204491) (xy 431.057812 -348.204028) (xy 431.921412 -348.204028) (xy 431.94868 -348.204535)
			(xy 432.002661 -348.212298) (xy 432.054988 -348.227664) (xy 432.104595 -348.25032) (xy 432.150473 -348.279806)
			(xy 432.191688 -348.31552) (xy 432.227401 -348.356736) (xy 432.256885 -348.402615) (xy 432.27954 -348.452224)
			(xy 432.294904 -348.504551) (xy 432.302666 -348.558532) (xy 432.302666 -348.613068) (xy 432.302666 -348.613069)
			(xy 433.785514 -348.613069) (xy 433.785514 -348.558531) (xy 433.793276 -348.504549) (xy 433.80864 -348.45222)
			(xy 433.831295 -348.40261) (xy 433.860779 -348.35673) (xy 433.896492 -348.315512) (xy 433.937707 -348.279795)
			(xy 433.983586 -348.250308) (xy 434.033194 -348.22765) (xy 434.085521 -348.212281) (xy 434.139503 -348.204516)
			(xy 434.166772 -348.204028) (xy 435.030372 -348.204028) (xy 435.057644 -348.20451) (xy 435.111632 -348.212268)
			(xy 435.163967 -348.227632) (xy 435.213582 -348.250287) (xy 435.259468 -348.279773) (xy 435.30069 -348.31549)
			(xy 435.33641 -348.356709) (xy 435.365899 -348.402593) (xy 435.388559 -348.452207) (xy 435.403926 -348.504541)
			(xy 435.411688 -348.558528) (xy 435.411688 -348.613072) (xy 435.411688 -348.613073) (xy 436.894392 -348.613073)
			(xy 436.894392 -348.558527) (xy 436.902155 -348.504536) (xy 436.917523 -348.452199) (xy 436.940184 -348.402583)
			(xy 436.969675 -348.356696) (xy 437.005397 -348.315474) (xy 437.046622 -348.279756) (xy 437.092511 -348.250268)
			(xy 437.142129 -348.227612) (xy 437.194467 -348.212248) (xy 437.248459 -348.204489) (xy 437.275732 -348.204028)
			(xy 438.139332 -348.204028) (xy 438.166599 -348.204537) (xy 438.220578 -348.212302) (xy 438.272902 -348.227669)
			(xy 438.322507 -348.250327) (xy 438.368383 -348.279813) (xy 438.409595 -348.315527) (xy 438.445306 -348.356743)
			(xy 438.474788 -348.402621) (xy 438.497442 -348.452228) (xy 438.512805 -348.504553) (xy 438.520566 -348.558533)
			(xy 438.520566 -348.613067) (xy 438.520566 -348.61307) (xy 440.003414 -348.61307) (xy 440.003414 -348.55853)
			(xy 440.011176 -348.504546) (xy 440.026541 -348.452216) (xy 440.049198 -348.402605) (xy 440.078684 -348.356723)
			(xy 440.114399 -348.315505) (xy 440.155617 -348.279788) (xy 440.201498 -348.250301) (xy 440.251108 -348.227644)
			(xy 440.303438 -348.212278) (xy 440.357422 -348.204515) (xy 440.384692 -348.204028) (xy 441.248292 -348.204028)
			(xy 441.275563 -348.204511) (xy 441.329549 -348.212272) (xy 441.381881 -348.227637) (xy 441.431494 -348.250294)
			(xy 441.477378 -348.27978) (xy 441.518598 -348.315497) (xy 441.554315 -348.356716) (xy 441.583803 -348.402599)
			(xy 441.60646 -348.452211) (xy 441.621826 -348.504543) (xy 441.629589 -348.558529) (xy 441.629589 -348.613071)
			(xy 441.621826 -348.667057) (xy 441.60646 -348.719389) (xy 441.583803 -348.769001) (xy 441.554315 -348.814884)
			(xy 441.518598 -348.856103) (xy 441.477378 -348.89182) (xy 441.431494 -348.921306) (xy 441.381881 -348.943963)
			(xy 441.329549 -348.959328) (xy 441.275563 -348.967089) (xy 441.248292 -348.967552) (xy 440.384692 -348.967552)
			(xy 440.357422 -348.967085) (xy 440.303438 -348.959322) (xy 440.251108 -348.943956) (xy 440.201498 -348.921299)
			(xy 440.155617 -348.891812) (xy 440.114399 -348.856095) (xy 440.078684 -348.814877) (xy 440.049198 -348.768995)
			(xy 440.026541 -348.719384) (xy 440.011176 -348.667054) (xy 440.003414 -348.61307) (xy 438.520566 -348.61307)
			(xy 438.512805 -348.667047) (xy 438.497442 -348.719372) (xy 438.474788 -348.768979) (xy 438.445306 -348.814857)
			(xy 438.409595 -348.856073) (xy 438.368383 -348.891787) (xy 438.322507 -348.921273) (xy 438.272902 -348.943931)
			(xy 438.220578 -348.959298) (xy 438.166599 -348.967063) (xy 438.139332 -348.967552) (xy 437.275732 -348.967552)
			(xy 437.248459 -348.967111) (xy 437.194467 -348.959352) (xy 437.142129 -348.943988) (xy 437.092511 -348.921332)
			(xy 437.046622 -348.891844) (xy 437.005397 -348.856126) (xy 436.969675 -348.814904) (xy 436.940184 -348.769017)
			(xy 436.917523 -348.719401) (xy 436.902155 -348.667064) (xy 436.894392 -348.613073) (xy 435.411688 -348.613073)
			(xy 435.403926 -348.667059) (xy 435.388559 -348.719393) (xy 435.365899 -348.769007) (xy 435.33641 -348.814891)
			(xy 435.30069 -348.85611) (xy 435.259468 -348.891827) (xy 435.213582 -348.921313) (xy 435.163967 -348.943968)
			(xy 435.111632 -348.959332) (xy 435.057644 -348.96709) (xy 435.030372 -348.967552) (xy 434.166772 -348.967552)
			(xy 434.139503 -348.967084) (xy 434.085521 -348.959319) (xy 434.033194 -348.94395) (xy 433.983586 -348.921292)
			(xy 433.937707 -348.891805) (xy 433.896492 -348.856088) (xy 433.860779 -348.81487) (xy 433.831295 -348.76899)
			(xy 433.80864 -348.71938) (xy 433.793276 -348.667051) (xy 433.785514 -348.613069) (xy 432.302666 -348.613069)
			(xy 432.294904 -348.667049) (xy 432.27954 -348.719376) (xy 432.256885 -348.768985) (xy 432.227401 -348.814864)
			(xy 432.191688 -348.85608) (xy 432.150473 -348.891794) (xy 432.104595 -348.92128) (xy 432.054988 -348.943936)
			(xy 432.002661 -348.959302) (xy 431.94868 -348.967065) (xy 431.921412 -348.967552) (xy 431.057812 -348.967552)
			(xy 431.03054 -348.967109) (xy 430.97655 -348.959348) (xy 430.924215 -348.943983) (xy 430.874599 -348.921325)
			(xy 430.828712 -348.891837) (xy 430.78749 -348.856119) (xy 430.75177 -348.814897) (xy 430.722281 -348.769012)
			(xy 430.699621 -348.719397) (xy 430.684254 -348.667062) (xy 430.676492 -348.613072) (xy 429.193788 -348.613072)
			(xy 429.186025 -348.667062) (xy 429.170657 -348.719397) (xy 429.147996 -348.769012) (xy 429.118505 -348.814897)
			(xy 429.082783 -348.856117) (xy 429.041559 -348.891834) (xy 428.99567 -348.921319) (xy 428.946052 -348.943974)
			(xy 428.893715 -348.959335) (xy 428.839725 -348.967092) (xy 428.812452 -348.967552) (xy 427.948852 -348.967552)
			(xy 427.921584 -348.967082) (xy 427.867604 -348.959315) (xy 427.815279 -348.943945) (xy 427.765674 -348.921285)
			(xy 427.719798 -348.891797) (xy 427.678585 -348.856081) (xy 427.642874 -348.814864) (xy 427.613392 -348.768984)
			(xy 427.590738 -348.719376) (xy 427.575375 -348.667049) (xy 427.567614 -348.613068) (xy 426.084789 -348.613068)
			(xy 426.084789 -348.613071) (xy 426.077026 -348.667057) (xy 426.06166 -348.719389) (xy 426.039003 -348.769001)
			(xy 426.009515 -348.814884) (xy 425.973798 -348.856103) (xy 425.932578 -348.89182) (xy 425.886694 -348.921306)
			(xy 425.837081 -348.943963) (xy 425.784749 -348.959328) (xy 425.730763 -348.967089) (xy 425.703492 -348.967552)
			(xy 424.839892 -348.967552) (xy 424.812622 -348.967085) (xy 424.758638 -348.959322) (xy 424.706308 -348.943956)
			(xy 424.656698 -348.921299) (xy 424.610817 -348.891812) (xy 424.569599 -348.856095) (xy 424.533884 -348.814877)
			(xy 424.504398 -348.768995) (xy 424.481741 -348.719384) (xy 424.466376 -348.667054) (xy 424.458614 -348.61307)
			(xy 422.975766 -348.61307) (xy 422.968005 -348.667047) (xy 422.952642 -348.719372) (xy 422.929988 -348.768979)
			(xy 422.900506 -348.814857) (xy 422.864795 -348.856073) (xy 422.823583 -348.891787) (xy 422.777707 -348.921273)
			(xy 422.728102 -348.943931) (xy 422.675778 -348.959298) (xy 422.621799 -348.967063) (xy 422.594532 -348.967552)
			(xy 421.730932 -348.967552) (xy 421.703659 -348.967111) (xy 421.649667 -348.959352) (xy 421.597329 -348.943988)
			(xy 421.547711 -348.921332) (xy 421.501822 -348.891844) (xy 421.460597 -348.856126) (xy 421.424875 -348.814904)
			(xy 421.395384 -348.769017) (xy 421.372723 -348.719401) (xy 421.357355 -348.667064) (xy 421.349592 -348.613073)
			(xy 419.866888 -348.613073) (xy 419.859126 -348.667059) (xy 419.843759 -348.719393) (xy 419.821099 -348.769007)
			(xy 419.79161 -348.814891) (xy 419.75589 -348.85611) (xy 419.714668 -348.891827) (xy 419.668782 -348.921313)
			(xy 419.619167 -348.943968) (xy 419.566832 -348.959332) (xy 419.512844 -348.96709) (xy 419.485572 -348.967552)
			(xy 418.621972 -348.967552) (xy 418.594703 -348.967084) (xy 418.540721 -348.959319) (xy 418.488394 -348.94395)
			(xy 418.438786 -348.921292) (xy 418.392907 -348.891805) (xy 418.351692 -348.856088) (xy 418.315979 -348.81487)
			(xy 418.286495 -348.76899) (xy 418.26384 -348.71938) (xy 418.248476 -348.667051) (xy 418.240714 -348.613069)
			(xy 416.757866 -348.613069) (xy 416.750104 -348.667049) (xy 416.73474 -348.719376) (xy 416.712085 -348.768985)
			(xy 416.682601 -348.814864) (xy 416.646888 -348.85608) (xy 416.605673 -348.891794) (xy 416.559795 -348.92128)
			(xy 416.510188 -348.943936) (xy 416.457861 -348.959302) (xy 416.40388 -348.967065) (xy 416.376612 -348.967552)
			(xy 415.513012 -348.967552) (xy 415.48574 -348.967109) (xy 415.43175 -348.959348) (xy 415.379415 -348.943983)
			(xy 415.329799 -348.921325) (xy 415.283912 -348.891837) (xy 415.24269 -348.856119) (xy 415.20697 -348.814897)
			(xy 415.177481 -348.769012) (xy 415.154821 -348.719397) (xy 415.139454 -348.667062) (xy 415.131692 -348.613072)
			(xy 413.648988 -348.613072) (xy 413.641225 -348.667062) (xy 413.625857 -348.719397) (xy 413.603196 -348.769012)
			(xy 413.573705 -348.814897) (xy 413.537983 -348.856117) (xy 413.496759 -348.891834) (xy 413.45087 -348.921319)
			(xy 413.401252 -348.943974) (xy 413.348915 -348.959335) (xy 413.294925 -348.967092) (xy 413.267652 -348.967552)
			(xy 412.404052 -348.967552) (xy 412.376784 -348.967082) (xy 412.322804 -348.959315) (xy 412.270479 -348.943945)
			(xy 412.220874 -348.921285) (xy 412.174998 -348.891797) (xy 412.133785 -348.856081) (xy 412.098074 -348.814864)
			(xy 412.068592 -348.768984) (xy 412.045938 -348.719376) (xy 412.030575 -348.667049) (xy 412.022814 -348.613068)
			(xy 410.539989 -348.613068) (xy 410.539989 -348.613071) (xy 410.532226 -348.667057) (xy 410.51686 -348.719389)
			(xy 410.494203 -348.769001) (xy 410.464715 -348.814884) (xy 410.428998 -348.856103) (xy 410.387778 -348.89182)
			(xy 410.341894 -348.921306) (xy 410.292281 -348.943963) (xy 410.239949 -348.959328) (xy 410.185963 -348.967089)
			(xy 410.158692 -348.967552) (xy 409.295092 -348.967552) (xy 409.267822 -348.967085) (xy 409.213838 -348.959322)
			(xy 409.161508 -348.943956) (xy 409.111898 -348.921299) (xy 409.066017 -348.891812) (xy 409.024799 -348.856095)
			(xy 408.989084 -348.814877) (xy 408.959598 -348.768995) (xy 408.936941 -348.719384) (xy 408.921576 -348.667054)
			(xy 408.913814 -348.61307) (xy 403.522488 -348.61307) (xy 403.522488 -348.613071) (xy 403.514726 -348.667058)
			(xy 403.499359 -348.719391) (xy 403.476701 -348.769005) (xy 403.447212 -348.814888) (xy 403.411493 -348.856107)
			(xy 403.370272 -348.891824) (xy 403.324387 -348.92131) (xy 403.274773 -348.943966) (xy 403.222439 -348.95933)
			(xy 403.168451 -348.96709) (xy 403.14118 -348.967552) (xy 402.27758 -348.967552) (xy 402.250311 -348.967084)
			(xy 402.196328 -348.95932) (xy 402.143999 -348.943953) (xy 402.094391 -348.921295) (xy 402.048511 -348.891807)
			(xy 402.007295 -348.856091) (xy 401.971581 -348.814873) (xy 401.942096 -348.768992) (xy 401.91944 -348.719382)
			(xy 401.904076 -348.667052) (xy 401.896314 -348.613069) (xy 400.413466 -348.613069) (xy 400.405705 -348.667048)
			(xy 400.390341 -348.719375) (xy 400.367687 -348.768982) (xy 400.338203 -348.814861) (xy 400.302491 -348.856077)
			(xy 400.261277 -348.891791) (xy 400.2154 -348.921277) (xy 400.165794 -348.943934) (xy 400.113468 -348.9593)
			(xy 400.059488 -348.967064) (xy 400.03222 -348.967552) (xy 399.16862 -348.967552) (xy 399.141347 -348.96711)
			(xy 399.087357 -348.95935) (xy 399.03502 -348.943985) (xy 398.985403 -348.921328) (xy 398.939516 -348.89184)
			(xy 398.898293 -348.856122) (xy 398.862572 -348.8149) (xy 398.833082 -348.769014) (xy 398.810422 -348.719398)
			(xy 398.795054 -348.667063) (xy 398.787292 -348.613073) (xy 397.304588 -348.613073) (xy 397.296825 -348.667061)
			(xy 397.281458 -348.719396) (xy 397.258798 -348.76901) (xy 397.229307 -348.814894) (xy 397.193586 -348.856115)
			(xy 397.152362 -348.891831) (xy 397.106475 -348.921317) (xy 397.056858 -348.943972) (xy 397.004522 -348.959334)
			(xy 396.950532 -348.967091) (xy 396.92326 -348.967552) (xy 396.05966 -348.967552) (xy 396.032392 -348.967083)
			(xy 395.978411 -348.959316) (xy 395.926085 -348.943947) (xy 395.876479 -348.921288) (xy 395.830601 -348.8918)
			(xy 395.789388 -348.856084) (xy 395.753676 -348.814866) (xy 395.724193 -348.768986) (xy 395.701539 -348.719377)
			(xy 395.686175 -348.66705) (xy 395.678414 -348.613068) (xy 394.195566 -348.613068) (xy 394.195566 -348.613069)
			(xy 394.187804 -348.667051) (xy 394.172439 -348.719379) (xy 394.149784 -348.768988) (xy 394.120298 -348.814868)
			(xy 394.084584 -348.856084) (xy 394.043368 -348.891798) (xy 393.997488 -348.921284) (xy 393.947879 -348.943939)
			(xy 393.895551 -348.959304) (xy 393.841569 -348.967066) (xy 393.8143 -348.967552) (xy 392.9507 -348.967552)
			(xy 392.92343 -348.967086) (xy 392.869445 -348.959324) (xy 392.817114 -348.943958) (xy 392.767503 -348.921301)
			(xy 392.72162 -348.891814) (xy 392.680402 -348.856098) (xy 392.644686 -348.81488) (xy 392.615199 -348.768997)
			(xy 392.592542 -348.719386) (xy 392.577176 -348.667055) (xy 392.569414 -348.61307) (xy 391.086566 -348.61307)
			(xy 391.078805 -348.667046) (xy 391.063442 -348.71937) (xy 391.04079 -348.768977) (xy 391.011308 -348.814854)
			(xy 390.975598 -348.85607) (xy 390.934387 -348.891784) (xy 390.888512 -348.92127) (xy 390.838908 -348.943928)
			(xy 390.786585 -348.959297) (xy 390.732607 -348.967063) (xy 390.70534 -348.967552) (xy 389.84174 -348.967552)
			(xy 389.814466 -348.967111) (xy 389.760474 -348.959354) (xy 389.708135 -348.94399) (xy 389.658515 -348.921334)
			(xy 389.612626 -348.891847) (xy 389.5714 -348.856129) (xy 389.535677 -348.814906) (xy 389.506185 -348.76902)
			(xy 389.483524 -348.719403) (xy 389.468155 -348.667065) (xy 389.460392 -348.613074) (xy 387.977688 -348.613074)
			(xy 387.969926 -348.667058) (xy 387.954559 -348.719391) (xy 387.931901 -348.769005) (xy 387.902412 -348.814888)
			(xy 387.866693 -348.856107) (xy 387.825472 -348.891824) (xy 387.779587 -348.92131) (xy 387.729973 -348.943966)
			(xy 387.677639 -348.95933) (xy 387.623651 -348.96709) (xy 387.59638 -348.967552) (xy 386.73278 -348.967552)
			(xy 386.705511 -348.967084) (xy 386.651528 -348.95932) (xy 386.599199 -348.943953) (xy 386.549591 -348.921295)
			(xy 386.503711 -348.891807) (xy 386.462495 -348.856091) (xy 386.426781 -348.814873) (xy 386.397296 -348.768992)
			(xy 386.37464 -348.719382) (xy 386.359276 -348.667052) (xy 386.351514 -348.613069) (xy 384.868666 -348.613069)
			(xy 384.860905 -348.667048) (xy 384.845541 -348.719375) (xy 384.822887 -348.768982) (xy 384.793403 -348.814861)
			(xy 384.757691 -348.856077) (xy 384.716477 -348.891791) (xy 384.6706 -348.921277) (xy 384.620994 -348.943934)
			(xy 384.568668 -348.9593) (xy 384.514688 -348.967064) (xy 384.48742 -348.967552) (xy 383.62382 -348.967552)
			(xy 383.596547 -348.96711) (xy 383.542557 -348.95935) (xy 383.49022 -348.943985) (xy 383.440603 -348.921328)
			(xy 383.394716 -348.89184) (xy 383.353493 -348.856122) (xy 383.317772 -348.8149) (xy 383.288282 -348.769014)
			(xy 383.265622 -348.719398) (xy 383.250254 -348.667063) (xy 383.242492 -348.613073) (xy 381.759788 -348.613073)
			(xy 381.752025 -348.667061) (xy 381.736658 -348.719396) (xy 381.713998 -348.76901) (xy 381.684507 -348.814894)
			(xy 381.648786 -348.856115) (xy 381.607562 -348.891831) (xy 381.561675 -348.921317) (xy 381.512058 -348.943972)
			(xy 381.459722 -348.959334) (xy 381.405732 -348.967091) (xy 381.37846 -348.967552) (xy 380.51486 -348.967552)
			(xy 380.487592 -348.967083) (xy 380.433611 -348.959316) (xy 380.381285 -348.943947) (xy 380.331679 -348.921288)
			(xy 380.285801 -348.8918) (xy 380.244588 -348.856084) (xy 380.208876 -348.814866) (xy 380.179393 -348.768986)
			(xy 380.156739 -348.719377) (xy 380.141375 -348.66705) (xy 380.133614 -348.613068) (xy 378.650766 -348.613068)
			(xy 378.650766 -348.613069) (xy 378.643004 -348.667051) (xy 378.627639 -348.719379) (xy 378.604984 -348.768988)
			(xy 378.575498 -348.814868) (xy 378.539784 -348.856084) (xy 378.498568 -348.891798) (xy 378.452688 -348.921284)
			(xy 378.403079 -348.943939) (xy 378.350751 -348.959304) (xy 378.296769 -348.967066) (xy 378.2695 -348.967552)
			(xy 377.4059 -348.967552) (xy 377.37863 -348.967086) (xy 377.324645 -348.959324) (xy 377.272314 -348.943958)
			(xy 377.222703 -348.921301) (xy 377.17682 -348.891814) (xy 377.135602 -348.856098) (xy 377.099886 -348.81488)
			(xy 377.070399 -348.768997) (xy 377.047742 -348.719386) (xy 377.032376 -348.667055) (xy 377.024614 -348.61307)
			(xy 375.541766 -348.61307) (xy 375.534005 -348.667046) (xy 375.518642 -348.71937) (xy 375.49599 -348.768977)
			(xy 375.466508 -348.814854) (xy 375.430798 -348.85607) (xy 375.389587 -348.891784) (xy 375.343712 -348.92127)
			(xy 375.294108 -348.943928) (xy 375.241785 -348.959297) (xy 375.187807 -348.967063) (xy 375.16054 -348.967552)
			(xy 374.29694 -348.967552) (xy 374.269666 -348.967111) (xy 374.215674 -348.959354) (xy 374.163335 -348.94399)
			(xy 374.113715 -348.921334) (xy 374.067826 -348.891847) (xy 374.0266 -348.856129) (xy 373.990877 -348.814906)
			(xy 373.961385 -348.76902) (xy 373.938724 -348.719403) (xy 373.923355 -348.667065) (xy 373.915592 -348.613074)
			(xy 372.432888 -348.613074) (xy 372.425126 -348.667058) (xy 372.409759 -348.719391) (xy 372.387101 -348.769005)
			(xy 372.357612 -348.814888) (xy 372.321893 -348.856107) (xy 372.280672 -348.891824) (xy 372.234787 -348.92131)
			(xy 372.185173 -348.943966) (xy 372.132839 -348.95933) (xy 372.078851 -348.96709) (xy 372.05158 -348.967552)
			(xy 371.18798 -348.967552) (xy 371.160711 -348.967084) (xy 371.106728 -348.95932) (xy 371.054399 -348.943953)
			(xy 371.004791 -348.921295) (xy 370.958911 -348.891807) (xy 370.917695 -348.856091) (xy 370.881981 -348.814873)
			(xy 370.852496 -348.768992) (xy 370.82984 -348.719382) (xy 370.814476 -348.667052) (xy 370.806714 -348.613069)
			(xy 344.837266 -348.613069) (xy 344.829504 -348.66705) (xy 344.81414 -348.719378) (xy 344.791484 -348.768987)
			(xy 344.761999 -348.814866) (xy 344.726286 -348.856083) (xy 344.685069 -348.891797) (xy 344.63919 -348.921282)
			(xy 344.589582 -348.943938) (xy 344.537254 -348.959303) (xy 344.483272 -348.967065) (xy 344.456004 -348.967552)
			(xy 343.592404 -348.967552) (xy 343.565132 -348.967109) (xy 343.511143 -348.959347) (xy 343.458809 -348.943981)
			(xy 343.409194 -348.921323) (xy 343.363309 -348.891834) (xy 343.322087 -348.856116) (xy 343.286368 -348.814895)
			(xy 343.256879 -348.76901) (xy 343.234221 -348.719395) (xy 343.218854 -348.667061) (xy 343.211092 -348.613072)
			(xy 341.728265 -348.613072) (xy 341.720505 -348.667045) (xy 341.705143 -348.71937) (xy 341.68249 -348.768976)
			(xy 341.653009 -348.814853) (xy 341.6173 -348.856069) (xy 341.576088 -348.891783) (xy 341.530214 -348.921269)
			(xy 341.480611 -348.943927) (xy 341.428288 -348.959296) (xy 341.374311 -348.967063) (xy 341.347044 -348.967552)
			(xy 340.483444 -348.967552) (xy 340.45617 -348.967111) (xy 340.402177 -348.959354) (xy 340.349838 -348.943991)
			(xy 340.300218 -348.921336) (xy 340.254327 -348.891849) (xy 340.213101 -348.85613) (xy 340.177378 -348.814908)
			(xy 340.147885 -348.769021) (xy 340.125224 -348.719403) (xy 340.109855 -348.667066) (xy 340.102092 -348.613074)
			(xy 338.619388 -348.613074) (xy 338.611626 -348.667058) (xy 338.596259 -348.71939) (xy 338.573601 -348.769003)
			(xy 338.544113 -348.814887) (xy 338.508395 -348.856106) (xy 338.467174 -348.891823) (xy 338.421289 -348.921309)
			(xy 338.371675 -348.943965) (xy 338.319342 -348.95933) (xy 338.265355 -348.96709) (xy 338.238084 -348.967552)
			(xy 337.374484 -348.967552) (xy 337.347215 -348.967084) (xy 337.293231 -348.959321) (xy 337.240902 -348.943954)
			(xy 337.191293 -348.921296) (xy 337.145413 -348.891809) (xy 337.104196 -348.856093) (xy 337.068482 -348.814874)
			(xy 337.038996 -348.768993) (xy 337.016341 -348.719383) (xy 337.000976 -348.667053) (xy 336.993214 -348.613069)
			(xy 335.510366 -348.613069) (xy 335.502605 -348.667048) (xy 335.487241 -348.719374) (xy 335.464587 -348.768981)
			(xy 335.435104 -348.81486) (xy 335.399393 -348.856076) (xy 335.358179 -348.89179) (xy 335.312302 -348.921276)
			(xy 335.262696 -348.943933) (xy 335.210371 -348.9593) (xy 335.156392 -348.967064) (xy 335.129124 -348.967552)
			(xy 334.265524 -348.967552) (xy 334.238251 -348.96711) (xy 334.18426 -348.959351) (xy 334.131923 -348.943986)
			(xy 334.082306 -348.921329) (xy 334.036418 -348.891841) (xy 333.995194 -348.856123) (xy 333.959473 -348.814901)
			(xy 333.929982 -348.769015) (xy 333.907322 -348.719399) (xy 333.891955 -348.667063) (xy 333.884192 -348.613073)
			(xy 332.401488 -348.613073) (xy 332.393726 -348.667061) (xy 332.378358 -348.719395) (xy 332.355698 -348.769009)
			(xy 332.326208 -348.814893) (xy 332.290488 -348.856113) (xy 332.249264 -348.89183) (xy 332.203377 -348.921316)
			(xy 332.153761 -348.94397) (xy 332.101425 -348.959333) (xy 332.047436 -348.967091) (xy 332.020164 -348.967552)
			(xy 331.156564 -348.967552) (xy 331.129296 -348.967083) (xy 331.075314 -348.959317) (xy 331.022988 -348.943948)
			(xy 330.973381 -348.921289) (xy 330.927503 -348.891802) (xy 330.886289 -348.856086) (xy 330.850577 -348.814868)
			(xy 330.821093 -348.768987) (xy 330.798439 -348.719378) (xy 330.783075 -348.66705) (xy 330.775314 -348.613068)
			(xy 329.292466 -348.613068) (xy 329.284704 -348.66705) (xy 329.26934 -348.719378) (xy 329.246684 -348.768987)
			(xy 329.217199 -348.814866) (xy 329.181486 -348.856083) (xy 329.140269 -348.891797) (xy 329.09439 -348.921282)
			(xy 329.044782 -348.943938) (xy 328.992454 -348.959303) (xy 328.938472 -348.967065) (xy 328.911204 -348.967552)
			(xy 328.047604 -348.967552) (xy 328.020332 -348.967109) (xy 327.966343 -348.959347) (xy 327.914009 -348.943981)
			(xy 327.864394 -348.921323) (xy 327.818509 -348.891834) (xy 327.777287 -348.856116) (xy 327.741568 -348.814895)
			(xy 327.712079 -348.76901) (xy 327.689421 -348.719395) (xy 327.674054 -348.667061) (xy 327.666292 -348.613072)
			(xy 326.183465 -348.613072) (xy 326.175705 -348.667045) (xy 326.160343 -348.71937) (xy 326.13769 -348.768976)
			(xy 326.108209 -348.814853) (xy 326.0725 -348.856069) (xy 326.031288 -348.891783) (xy 325.985414 -348.921269)
			(xy 325.935811 -348.943927) (xy 325.883488 -348.959296) (xy 325.829511 -348.967063) (xy 325.802244 -348.967552)
			(xy 324.938644 -348.967552) (xy 324.91137 -348.967111) (xy 324.857377 -348.959354) (xy 324.805038 -348.943991)
			(xy 324.755418 -348.921336) (xy 324.709527 -348.891849) (xy 324.668301 -348.85613) (xy 324.632578 -348.814908)
			(xy 324.603085 -348.769021) (xy 324.580424 -348.719403) (xy 324.565055 -348.667066) (xy 324.557292 -348.613074)
			(xy 323.074588 -348.613074) (xy 323.066826 -348.667058) (xy 323.051459 -348.71939) (xy 323.028801 -348.769003)
			(xy 322.999313 -348.814887) (xy 322.963595 -348.856106) (xy 322.922374 -348.891823) (xy 322.876489 -348.921309)
			(xy 322.826875 -348.943965) (xy 322.774542 -348.95933) (xy 322.720555 -348.96709) (xy 322.693284 -348.967552)
			(xy 321.829684 -348.967552) (xy 321.802415 -348.967084) (xy 321.748431 -348.959321) (xy 321.696102 -348.943954)
			(xy 321.646493 -348.921296) (xy 321.600613 -348.891809) (xy 321.559396 -348.856093) (xy 321.523682 -348.814874)
			(xy 321.494196 -348.768993) (xy 321.471541 -348.719383) (xy 321.456176 -348.667053) (xy 321.448414 -348.613069)
			(xy 319.965566 -348.613069) (xy 319.957805 -348.667048) (xy 319.942441 -348.719374) (xy 319.919787 -348.768981)
			(xy 319.890304 -348.81486) (xy 319.854593 -348.856076) (xy 319.813379 -348.89179) (xy 319.767502 -348.921276)
			(xy 319.717896 -348.943933) (xy 319.665571 -348.9593) (xy 319.611592 -348.967064) (xy 319.584324 -348.967552)
			(xy 318.720724 -348.967552) (xy 318.693451 -348.96711) (xy 318.63946 -348.959351) (xy 318.587123 -348.943986)
			(xy 318.537506 -348.921329) (xy 318.491618 -348.891841) (xy 318.450394 -348.856123) (xy 318.414673 -348.814901)
			(xy 318.385182 -348.769015) (xy 318.362522 -348.719399) (xy 318.347155 -348.667063) (xy 318.339392 -348.613073)
			(xy 316.856688 -348.613073) (xy 316.848926 -348.667061) (xy 316.833558 -348.719395) (xy 316.810898 -348.769009)
			(xy 316.781408 -348.814893) (xy 316.745688 -348.856113) (xy 316.704464 -348.89183) (xy 316.658577 -348.921316)
			(xy 316.608961 -348.94397) (xy 316.556625 -348.959333) (xy 316.502636 -348.967091) (xy 316.475364 -348.967552)
			(xy 315.611764 -348.967552) (xy 315.584496 -348.967083) (xy 315.530514 -348.959317) (xy 315.478188 -348.943948)
			(xy 315.428581 -348.921289) (xy 315.382703 -348.891802) (xy 315.341489 -348.856086) (xy 315.305777 -348.814868)
			(xy 315.276293 -348.768987) (xy 315.253639 -348.719378) (xy 315.238275 -348.66705) (xy 315.230514 -348.613068)
			(xy 313.747666 -348.613068) (xy 313.739904 -348.66705) (xy 313.72454 -348.719378) (xy 313.701884 -348.768987)
			(xy 313.672399 -348.814866) (xy 313.636686 -348.856083) (xy 313.595469 -348.891797) (xy 313.54959 -348.921282)
			(xy 313.499982 -348.943938) (xy 313.447654 -348.959303) (xy 313.393672 -348.967065) (xy 313.366404 -348.967552)
			(xy 312.502804 -348.967552) (xy 312.475532 -348.967109) (xy 312.421543 -348.959347) (xy 312.369209 -348.943981)
			(xy 312.319594 -348.921323) (xy 312.273709 -348.891834) (xy 312.232487 -348.856116) (xy 312.196768 -348.814895)
			(xy 312.167279 -348.76901) (xy 312.144621 -348.719395) (xy 312.129254 -348.667061) (xy 312.121492 -348.613072)
			(xy 300.231566 -348.613072) (xy 300.223804 -348.667051) (xy 300.208439 -348.719379) (xy 300.185784 -348.768987)
			(xy 300.156299 -348.814867) (xy 300.120585 -348.856083) (xy 300.079369 -348.891798) (xy 300.033489 -348.921283)
			(xy 299.98388 -348.943939) (xy 299.931553 -348.959304) (xy 299.877571 -348.967065) (xy 299.850302 -348.967552)
			(xy 298.986702 -348.967552) (xy 298.95943 -348.967109) (xy 298.905442 -348.959347) (xy 298.853107 -348.94398)
			(xy 298.803493 -348.921322) (xy 298.757608 -348.891834) (xy 298.716386 -348.856115) (xy 298.680668 -348.814894)
			(xy 298.651179 -348.769009) (xy 298.628521 -348.719394) (xy 298.613154 -348.66706) (xy 298.605392 -348.613072)
			(xy 297.122565 -348.613072) (xy 297.114805 -348.667045) (xy 297.099443 -348.71937) (xy 297.07679 -348.768976)
			(xy 297.047309 -348.814854) (xy 297.011599 -348.856069) (xy 296.970387 -348.891784) (xy 296.924513 -348.92127)
			(xy 296.874909 -348.943928) (xy 296.822586 -348.959296) (xy 296.768609 -348.967063) (xy 296.741342 -348.967552)
			(xy 295.877742 -348.967552) (xy 295.850468 -348.967111) (xy 295.796476 -348.959354) (xy 295.744136 -348.943991)
			(xy 295.694517 -348.921335) (xy 295.648627 -348.891848) (xy 295.6074 -348.856129) (xy 295.571677 -348.814907)
			(xy 295.542185 -348.76902) (xy 295.519524 -348.719403) (xy 295.504155 -348.667066) (xy 295.496392 -348.613074)
			(xy 294.013688 -348.613074) (xy 294.005926 -348.667058) (xy 293.990559 -348.719391) (xy 293.967901 -348.769004)
			(xy 293.938412 -348.814887) (xy 293.902694 -348.856107) (xy 293.861473 -348.891823) (xy 293.815588 -348.92131)
			(xy 293.765974 -348.943966) (xy 293.713641 -348.95933) (xy 293.659653 -348.96709) (xy 293.632382 -348.967552)
			(xy 292.768782 -348.967552) (xy 292.741513 -348.967084) (xy 292.68753 -348.95932) (xy 292.635201 -348.943953)
			(xy 292.585592 -348.921295) (xy 292.539712 -348.891808) (xy 292.498495 -348.856092) (xy 292.462781 -348.814874)
			(xy 292.433296 -348.768992) (xy 292.410641 -348.719382) (xy 292.395276 -348.667053) (xy 292.387514 -348.613069)
			(xy 290.904666 -348.613069) (xy 290.896905 -348.667048) (xy 290.881541 -348.719374) (xy 290.858887 -348.768982)
			(xy 290.829404 -348.81486) (xy 290.793692 -348.856076) (xy 290.752478 -348.891791) (xy 290.706601 -348.921276)
			(xy 290.656995 -348.943933) (xy 290.604669 -348.9593) (xy 290.55069 -348.967064) (xy 290.523422 -348.967552)
			(xy 289.659822 -348.967552) (xy 289.632549 -348.96711) (xy 289.578559 -348.95935) (xy 289.526222 -348.943985)
			(xy 289.476605 -348.921329) (xy 289.430717 -348.891841) (xy 289.389493 -348.856122) (xy 289.353772 -348.814901)
			(xy 289.324282 -348.769015) (xy 289.301622 -348.719399) (xy 289.286254 -348.667063) (xy 289.278492 -348.613073)
			(xy 287.795788 -348.613073) (xy 287.788026 -348.667061) (xy 287.772658 -348.719395) (xy 287.749998 -348.76901)
			(xy 287.720508 -348.814894) (xy 287.684787 -348.856114) (xy 287.643563 -348.89183) (xy 287.597676 -348.921316)
			(xy 287.54806 -348.943971) (xy 287.495724 -348.959334) (xy 287.441734 -348.967091) (xy 287.414462 -348.967552)
			(xy 286.550862 -348.967552) (xy 286.523594 -348.967083) (xy 286.469613 -348.959317) (xy 286.417286 -348.943948)
			(xy 286.36768 -348.921289) (xy 286.321802 -348.891801) (xy 286.280588 -348.856085) (xy 286.244876 -348.814867)
			(xy 286.215393 -348.768987) (xy 286.192739 -348.719378) (xy 286.177375 -348.66705) (xy 286.169614 -348.613068)
			(xy 284.686766 -348.613068) (xy 284.686766 -348.613069) (xy 284.679004 -348.667051) (xy 284.663639 -348.719379)
			(xy 284.640984 -348.768987) (xy 284.611499 -348.814867) (xy 284.575785 -348.856083) (xy 284.534569 -348.891798)
			(xy 284.488689 -348.921283) (xy 284.43908 -348.943939) (xy 284.386753 -348.959304) (xy 284.332771 -348.967065)
			(xy 284.305502 -348.967552) (xy 283.441902 -348.967552) (xy 283.41463 -348.967109) (xy 283.360642 -348.959347)
			(xy 283.308307 -348.94398) (xy 283.258693 -348.921322) (xy 283.212808 -348.891834) (xy 283.171586 -348.856115)
			(xy 283.135868 -348.814894) (xy 283.106379 -348.769009) (xy 283.083721 -348.719394) (xy 283.068354 -348.66706)
			(xy 283.060592 -348.613072) (xy 281.577765 -348.613072) (xy 281.570005 -348.667045) (xy 281.554643 -348.71937)
			(xy 281.53199 -348.768976) (xy 281.502509 -348.814854) (xy 281.466799 -348.856069) (xy 281.425587 -348.891784)
			(xy 281.379713 -348.92127) (xy 281.330109 -348.943928) (xy 281.277786 -348.959296) (xy 281.223809 -348.967063)
			(xy 281.196542 -348.967552) (xy 280.332942 -348.967552) (xy 280.305668 -348.967111) (xy 280.251676 -348.959354)
			(xy 280.199336 -348.943991) (xy 280.149717 -348.921335) (xy 280.103827 -348.891848) (xy 280.0626 -348.856129)
			(xy 280.026877 -348.814907) (xy 279.997385 -348.76902) (xy 279.974724 -348.719403) (xy 279.959355 -348.667066)
			(xy 279.951592 -348.613074) (xy 278.468888 -348.613074) (xy 278.461126 -348.667058) (xy 278.445759 -348.719391)
			(xy 278.423101 -348.769004) (xy 278.393612 -348.814887) (xy 278.357894 -348.856107) (xy 278.316673 -348.891823)
			(xy 278.270788 -348.92131) (xy 278.221174 -348.943966) (xy 278.168841 -348.95933) (xy 278.114853 -348.96709)
			(xy 278.087582 -348.967552) (xy 277.223982 -348.967552) (xy 277.196713 -348.967084) (xy 277.14273 -348.95932)
			(xy 277.090401 -348.943953) (xy 277.040792 -348.921295) (xy 276.994912 -348.891808) (xy 276.953695 -348.856092)
			(xy 276.917981 -348.814874) (xy 276.888496 -348.768992) (xy 276.865841 -348.719382) (xy 276.850476 -348.667053)
			(xy 276.842714 -348.613069) (xy 275.359866 -348.613069) (xy 275.352105 -348.667048) (xy 275.336741 -348.719374)
			(xy 275.314087 -348.768982) (xy 275.284604 -348.81486) (xy 275.248892 -348.856076) (xy 275.207678 -348.891791)
			(xy 275.161801 -348.921276) (xy 275.112195 -348.943933) (xy 275.059869 -348.9593) (xy 275.00589 -348.967064)
			(xy 274.978622 -348.967552) (xy 274.115022 -348.967552) (xy 274.087749 -348.96711) (xy 274.033759 -348.95935)
			(xy 273.981422 -348.943985) (xy 273.931805 -348.921329) (xy 273.885917 -348.891841) (xy 273.844693 -348.856122)
			(xy 273.808972 -348.814901) (xy 273.779482 -348.769015) (xy 273.756822 -348.719399) (xy 273.741454 -348.667063)
			(xy 273.733692 -348.613073) (xy 272.250988 -348.613073) (xy 272.243226 -348.667061) (xy 272.227858 -348.719395)
			(xy 272.205198 -348.76901) (xy 272.175708 -348.814894) (xy 272.139987 -348.856114) (xy 272.098763 -348.89183)
			(xy 272.052876 -348.921316) (xy 272.00326 -348.943971) (xy 271.950924 -348.959334) (xy 271.896934 -348.967091)
			(xy 271.869662 -348.967552) (xy 271.006062 -348.967552) (xy 270.978794 -348.967083) (xy 270.924813 -348.959317)
			(xy 270.872486 -348.943948) (xy 270.82288 -348.921289) (xy 270.777002 -348.891801) (xy 270.735788 -348.856085)
			(xy 270.700076 -348.814867) (xy 270.670593 -348.768987) (xy 270.647939 -348.719378) (xy 270.632575 -348.66705)
			(xy 270.624814 -348.613068) (xy 269.141966 -348.613068) (xy 269.141966 -348.613069) (xy 269.134204 -348.667051)
			(xy 269.118839 -348.719379) (xy 269.096184 -348.768987) (xy 269.066699 -348.814867) (xy 269.030985 -348.856083)
			(xy 268.989769 -348.891798) (xy 268.943889 -348.921283) (xy 268.89428 -348.943939) (xy 268.841953 -348.959304)
			(xy 268.787971 -348.967065) (xy 268.760702 -348.967552) (xy 267.897102 -348.967552) (xy 267.86983 -348.967109)
			(xy 267.815842 -348.959347) (xy 267.763507 -348.94398) (xy 267.713893 -348.921322) (xy 267.668008 -348.891834)
			(xy 267.626786 -348.856115) (xy 267.591068 -348.814894) (xy 267.561579 -348.769009) (xy 267.538921 -348.719394)
			(xy 267.523554 -348.66706) (xy 267.515792 -348.613072) (xy 219.835872 -348.613072) (xy 219.790278 -348.758746)
			(xy 219.727639 -348.932143) (xy 219.657547 -349.102664) (xy 219.580134 -349.269989) (xy 219.495546 -349.433803)
			(xy 219.403941 -349.593799) (xy 219.305491 -349.749677) (xy 219.200381 -349.901144) (xy 219.088808 -350.047915)
			(xy 218.970982 -350.189716) (xy 218.847124 -350.326279) (xy 218.717467 -350.457348) (xy 218.582254 -350.582678)
			(xy 218.441738 -350.702034) (xy 218.296184 -350.81519) (xy 218.145865 -350.921934) (xy 217.991063 -351.022067)
			(xy 217.832068 -351.1154) (xy 217.66918 -351.201758) (xy 217.502703 -351.280979) (xy 217.332952 -351.352913)
			(xy 217.160243 -351.417427) (xy 216.984902 -351.474399) (xy 216.807258 -351.523722) (xy 216.627643 -351.565303)
			(xy 216.446396 -351.599064) (xy 216.263857 -351.624943) (xy 216.123526 -351.638668) (xy 267.515839 -351.638668)
			(xy 267.515839 -351.584132) (xy 267.523601 -351.53015) (xy 267.538966 -351.477822) (xy 267.561621 -351.428214)
			(xy 267.591106 -351.382335) (xy 267.62682 -351.341119) (xy 267.668036 -351.305405) (xy 267.713916 -351.27592)
			(xy 267.763524 -351.253265) (xy 267.815852 -351.2379) (xy 267.869834 -351.230139) (xy 267.897102 -351.229676)
			(xy 268.760702 -351.229676) (xy 268.787974 -351.230087) (xy 268.841963 -351.237849) (xy 268.894297 -351.253216)
			(xy 268.943912 -351.275875) (xy 268.989797 -351.305364) (xy 269.031019 -351.341083) (xy 269.066737 -351.382304)
			(xy 269.096226 -351.42819) (xy 269.118884 -351.477805) (xy 269.134251 -351.530139) (xy 269.142013 -351.584128)
			(xy 269.142013 -351.638665) (xy 270.624862 -351.638665) (xy 270.624862 -351.584135) (xy 270.632622 -351.53016)
			(xy 270.647984 -351.477839) (xy 270.670635 -351.428236) (xy 270.700115 -351.382362) (xy 270.735822 -351.341149)
			(xy 270.777031 -351.305437) (xy 270.822903 -351.275953) (xy 270.872503 -351.253297) (xy 270.924823 -351.23793)
			(xy 270.978797 -351.230165) (xy 271.006062 -351.229676) (xy 271.869662 -351.229676) (xy 271.896937 -351.230061)
			(xy 271.950934 -351.23782) (xy 272.003276 -351.253184) (xy 272.052899 -351.275842) (xy 272.098792 -351.305331)
			(xy 272.140021 -351.341052) (xy 272.175746 -351.382277) (xy 272.20524 -351.428167) (xy 272.227903 -351.477788)
			(xy 272.243272 -351.530129) (xy 272.251036 -351.584125) (xy 272.251036 -351.638669) (xy 273.733739 -351.638669)
			(xy 273.733739 -351.584131) (xy 273.741501 -351.530147) (xy 273.756867 -351.477818) (xy 273.779524 -351.428208)
			(xy 273.809011 -351.382328) (xy 273.844727 -351.341112) (xy 273.885946 -351.305398) (xy 273.931828 -351.275914)
			(xy 273.981439 -351.25326) (xy 274.033769 -351.237897) (xy 274.087753 -351.230138) (xy 274.115022 -351.229676)
			(xy 274.978622 -351.229676) (xy 275.005893 -351.230088) (xy 275.05988 -351.237853) (xy 275.112212 -351.253222)
			(xy 275.161824 -351.275881) (xy 275.207707 -351.305371) (xy 275.248926 -351.34109) (xy 275.284642 -351.382311)
			(xy 275.314129 -351.428195) (xy 275.336786 -351.477809) (xy 275.352152 -351.530142) (xy 275.359914 -351.584129)
			(xy 275.359914 -351.638666) (xy 276.842762 -351.638666) (xy 276.842762 -351.584134) (xy 276.850523 -351.530158)
			(xy 276.865886 -351.477835) (xy 276.888538 -351.428231) (xy 276.91802 -351.382355) (xy 276.953729 -351.341142)
			(xy 276.994941 -351.30543) (xy 277.040815 -351.275947) (xy 277.090418 -351.253292) (xy 277.14274 -351.237927)
			(xy 277.196716 -351.230164) (xy 277.223982 -351.229676) (xy 278.087582 -351.229676) (xy 278.114857 -351.230062)
			(xy 278.168851 -351.237823) (xy 278.221191 -351.253189) (xy 278.270811 -351.275848) (xy 278.316702 -351.305338)
			(xy 278.357928 -351.341059) (xy 278.393651 -351.382284) (xy 278.423143 -351.428173) (xy 278.445804 -351.477792)
			(xy 278.461173 -351.530132) (xy 278.468936 -351.584125) (xy 278.468936 -351.63867) (xy 279.95164 -351.63867)
			(xy 279.95164 -351.58413) (xy 279.959402 -351.530145) (xy 279.974769 -351.477814) (xy 279.997427 -351.428203)
			(xy 280.026916 -351.382322) (xy 280.062634 -351.341105) (xy 280.103855 -351.305391) (xy 280.14974 -351.275907)
			(xy 280.199353 -351.253254) (xy 280.251686 -351.237893) (xy 280.305672 -351.230137) (xy 280.332942 -351.229676)
			(xy 281.196542 -351.229676) (xy 281.223812 -351.230089) (xy 281.277797 -351.237857) (xy 281.330126 -351.253227)
			(xy 281.379736 -351.275888) (xy 281.425616 -351.305378) (xy 281.466833 -351.341097) (xy 281.502547 -351.382317)
			(xy 281.532032 -351.428201) (xy 281.554688 -351.477813) (xy 281.570052 -351.530145) (xy 281.577814 -351.58413)
			(xy 281.577814 -351.638668) (xy 283.060639 -351.638668) (xy 283.060639 -351.584132) (xy 283.068401 -351.53015)
			(xy 283.083766 -351.477822) (xy 283.106421 -351.428214) (xy 283.135906 -351.382335) (xy 283.17162 -351.341119)
			(xy 283.212836 -351.305405) (xy 283.258716 -351.27592) (xy 283.308324 -351.253265) (xy 283.360652 -351.2379)
			(xy 283.414634 -351.230139) (xy 283.441902 -351.229676) (xy 284.305502 -351.229676) (xy 284.332774 -351.230087)
			(xy 284.386763 -351.237849) (xy 284.439097 -351.253216) (xy 284.488712 -351.275875) (xy 284.534597 -351.305364)
			(xy 284.575819 -351.341083) (xy 284.611537 -351.382304) (xy 284.641026 -351.42819) (xy 284.663684 -351.477805)
			(xy 284.679051 -351.530139) (xy 284.686813 -351.584128) (xy 284.686813 -351.638665) (xy 286.169662 -351.638665)
			(xy 286.169662 -351.584135) (xy 286.177422 -351.53016) (xy 286.192784 -351.477839) (xy 286.215435 -351.428236)
			(xy 286.244915 -351.382362) (xy 286.280622 -351.341149) (xy 286.321831 -351.305437) (xy 286.367703 -351.275953)
			(xy 286.417303 -351.253297) (xy 286.469623 -351.23793) (xy 286.523597 -351.230165) (xy 286.550862 -351.229676)
			(xy 287.414462 -351.229676) (xy 287.441737 -351.230061) (xy 287.495734 -351.23782) (xy 287.548076 -351.253184)
			(xy 287.597699 -351.275842) (xy 287.643592 -351.305331) (xy 287.684821 -351.341052) (xy 287.720546 -351.382277)
			(xy 287.75004 -351.428167) (xy 287.772703 -351.477788) (xy 287.788072 -351.530129) (xy 287.795836 -351.584125)
			(xy 287.795836 -351.638669) (xy 289.278539 -351.638669) (xy 289.278539 -351.584131) (xy 289.286301 -351.530147)
			(xy 289.301667 -351.477818) (xy 289.324324 -351.428208) (xy 289.353811 -351.382328) (xy 289.389527 -351.341112)
			(xy 289.430746 -351.305398) (xy 289.476628 -351.275914) (xy 289.526239 -351.25326) (xy 289.578569 -351.237897)
			(xy 289.632553 -351.230138) (xy 289.659822 -351.229676) (xy 290.523422 -351.229676) (xy 290.550693 -351.230088)
			(xy 290.60468 -351.237853) (xy 290.657012 -351.253222) (xy 290.706624 -351.275881) (xy 290.752507 -351.305371)
			(xy 290.793726 -351.34109) (xy 290.829442 -351.382311) (xy 290.858929 -351.428195) (xy 290.881586 -351.477809)
			(xy 290.896952 -351.530142) (xy 290.904714 -351.584129) (xy 290.904714 -351.638666) (xy 292.387562 -351.638666)
			(xy 292.387562 -351.584134) (xy 292.395323 -351.530158) (xy 292.410686 -351.477835) (xy 292.433338 -351.428231)
			(xy 292.46282 -351.382355) (xy 292.498529 -351.341142) (xy 292.539741 -351.30543) (xy 292.585615 -351.275947)
			(xy 292.635218 -351.253292) (xy 292.68754 -351.237927) (xy 292.741516 -351.230164) (xy 292.768782 -351.229676)
			(xy 293.632382 -351.229676) (xy 293.659657 -351.230062) (xy 293.713651 -351.237823) (xy 293.765991 -351.253189)
			(xy 293.815611 -351.275848) (xy 293.861502 -351.305338) (xy 293.902728 -351.341059) (xy 293.938451 -351.382284)
			(xy 293.967943 -351.428173) (xy 293.990604 -351.477792) (xy 294.005973 -351.530132) (xy 294.013736 -351.584125)
			(xy 294.013736 -351.63867) (xy 295.49644 -351.63867) (xy 295.49644 -351.58413) (xy 295.504202 -351.530145)
			(xy 295.519569 -351.477814) (xy 295.542227 -351.428203) (xy 295.571716 -351.382322) (xy 295.607434 -351.341105)
			(xy 295.648655 -351.305391) (xy 295.69454 -351.275907) (xy 295.744153 -351.253254) (xy 295.796486 -351.237893)
			(xy 295.850472 -351.230137) (xy 295.877742 -351.229676) (xy 296.741342 -351.229676) (xy 296.768612 -351.230089)
			(xy 296.822597 -351.237857) (xy 296.874926 -351.253227) (xy 296.924536 -351.275888) (xy 296.970416 -351.305378)
			(xy 297.011633 -351.341097) (xy 297.047347 -351.382317) (xy 297.076832 -351.428201) (xy 297.099488 -351.477813)
			(xy 297.114852 -351.530145) (xy 297.122614 -351.58413) (xy 297.122614 -351.638668) (xy 298.605439 -351.638668)
			(xy 298.605439 -351.584132) (xy 298.613201 -351.53015) (xy 298.628566 -351.477822) (xy 298.651221 -351.428214)
			(xy 298.680706 -351.382335) (xy 298.71642 -351.341119) (xy 298.757636 -351.305405) (xy 298.803516 -351.27592)
			(xy 298.853124 -351.253265) (xy 298.905452 -351.2379) (xy 298.959434 -351.230139) (xy 298.986702 -351.229676)
			(xy 299.850302 -351.229676) (xy 299.877574 -351.230087) (xy 299.931563 -351.237849) (xy 299.983897 -351.253216)
			(xy 300.033512 -351.275875) (xy 300.079397 -351.305364) (xy 300.120619 -351.341083) (xy 300.156337 -351.382304)
			(xy 300.185826 -351.42819) (xy 300.208484 -351.477805) (xy 300.223851 -351.530139) (xy 300.231613 -351.584128)
			(xy 300.231613 -351.638668) (xy 312.121539 -351.638668) (xy 312.121539 -351.584132) (xy 312.129301 -351.53015)
			(xy 312.144666 -351.477822) (xy 312.167321 -351.428213) (xy 312.196807 -351.382334) (xy 312.232521 -351.341118)
			(xy 312.273737 -351.305404) (xy 312.319617 -351.27592) (xy 312.369226 -351.253264) (xy 312.421554 -351.2379)
			(xy 312.475536 -351.230139) (xy 312.502804 -351.229676) (xy 313.366404 -351.229676) (xy 313.393676 -351.230087)
			(xy 313.447664 -351.23785) (xy 313.499999 -351.253217) (xy 313.549613 -351.275876) (xy 313.595498 -351.305365)
			(xy 313.63672 -351.341083) (xy 313.672438 -351.382305) (xy 313.701926 -351.42819) (xy 313.724584 -351.477805)
			(xy 313.739951 -351.530139) (xy 313.747713 -351.584128) (xy 313.747713 -351.638665) (xy 315.230562 -351.638665)
			(xy 315.230562 -351.584135) (xy 315.238322 -351.53016) (xy 315.253684 -351.477838) (xy 315.276335 -351.428236)
			(xy 315.305815 -351.382361) (xy 315.341523 -351.341148) (xy 315.382732 -351.305437) (xy 315.428604 -351.275953)
			(xy 315.478205 -351.253297) (xy 315.530525 -351.23793) (xy 315.584499 -351.230165) (xy 315.611764 -351.229676)
			(xy 316.475364 -351.229676) (xy 316.502639 -351.230061) (xy 316.556636 -351.23782) (xy 316.608978 -351.253185)
			(xy 316.6586 -351.275842) (xy 316.704493 -351.305332) (xy 316.745722 -351.341053) (xy 316.781446 -351.382278)
			(xy 316.81094 -351.428168) (xy 316.833603 -351.477788) (xy 316.848972 -351.530129) (xy 316.856736 -351.584125)
			(xy 316.856736 -351.638669) (xy 318.339439 -351.638669) (xy 318.339439 -351.584131) (xy 318.347201 -351.530147)
			(xy 318.362567 -351.477818) (xy 318.385224 -351.428208) (xy 318.414711 -351.382328) (xy 318.450428 -351.341111)
			(xy 318.491647 -351.305397) (xy 318.537529 -351.275913) (xy 318.58714 -351.253259) (xy 318.63947 -351.237896)
			(xy 318.693455 -351.230138) (xy 318.720724 -351.229676) (xy 319.584324 -351.229676) (xy 319.611595 -351.230088)
			(xy 319.665581 -351.237853) (xy 319.717913 -351.253222) (xy 319.767525 -351.275882) (xy 319.813408 -351.305372)
			(xy 319.854627 -351.34109) (xy 319.890343 -351.382312) (xy 319.919829 -351.428196) (xy 319.942486 -351.477809)
			(xy 319.957852 -351.530142) (xy 319.965614 -351.584129) (xy 319.965614 -351.638666) (xy 321.448462 -351.638666)
			(xy 321.448462 -351.584134) (xy 321.456223 -351.530157) (xy 321.471586 -351.477834) (xy 321.494239 -351.42823)
			(xy 321.52372 -351.382354) (xy 321.55943 -351.341141) (xy 321.600642 -351.30543) (xy 321.646516 -351.275946)
			(xy 321.696119 -351.253291) (xy 321.748442 -351.237926) (xy 321.802418 -351.230163) (xy 321.829684 -351.229676)
			(xy 322.693284 -351.229676) (xy 322.720558 -351.230062) (xy 322.774552 -351.237824) (xy 322.826892 -351.25319)
			(xy 322.876512 -351.275849) (xy 322.922403 -351.305339) (xy 322.963629 -351.34106) (xy 322.999351 -351.382285)
			(xy 323.028843 -351.428174) (xy 323.051504 -351.477793) (xy 323.066873 -351.530132) (xy 323.074636 -351.584126)
			(xy 323.074636 -351.63867) (xy 324.55734 -351.63867) (xy 324.55734 -351.58413) (xy 324.565102 -351.530144)
			(xy 324.580469 -351.477813) (xy 324.603128 -351.428202) (xy 324.632616 -351.382321) (xy 324.668335 -351.341104)
			(xy 324.709556 -351.30539) (xy 324.755441 -351.275906) (xy 324.805055 -351.253254) (xy 324.857387 -351.237893)
			(xy 324.911374 -351.230136) (xy 324.938644 -351.229676) (xy 325.802244 -351.229676) (xy 325.829514 -351.23009)
			(xy 325.883498 -351.237857) (xy 325.935828 -351.253228) (xy 325.985437 -351.275889) (xy 326.031317 -351.305379)
			(xy 326.072534 -351.341097) (xy 326.108248 -351.382318) (xy 326.137732 -351.428201) (xy 326.160388 -351.477814)
			(xy 326.175752 -351.530145) (xy 326.183514 -351.58413) (xy 326.183514 -351.638668) (xy 327.666339 -351.638668)
			(xy 327.666339 -351.584132) (xy 327.674101 -351.53015) (xy 327.689466 -351.477822) (xy 327.712121 -351.428213)
			(xy 327.741607 -351.382334) (xy 327.777321 -351.341118) (xy 327.818537 -351.305404) (xy 327.864417 -351.27592)
			(xy 327.914026 -351.253264) (xy 327.966354 -351.2379) (xy 328.020336 -351.230139) (xy 328.047604 -351.229676)
			(xy 328.911204 -351.229676) (xy 328.938476 -351.230087) (xy 328.992464 -351.23785) (xy 329.044799 -351.253217)
			(xy 329.094413 -351.275876) (xy 329.140298 -351.305365) (xy 329.18152 -351.341083) (xy 329.217238 -351.382305)
			(xy 329.246726 -351.42819) (xy 329.269384 -351.477805) (xy 329.284751 -351.530139) (xy 329.292513 -351.584128)
			(xy 329.292513 -351.638665) (xy 330.775362 -351.638665) (xy 330.775362 -351.584135) (xy 330.783122 -351.53016)
			(xy 330.798484 -351.477838) (xy 330.821135 -351.428236) (xy 330.850615 -351.382361) (xy 330.886323 -351.341148)
			(xy 330.927532 -351.305437) (xy 330.973404 -351.275953) (xy 331.023005 -351.253297) (xy 331.075325 -351.23793)
			(xy 331.129299 -351.230165) (xy 331.156564 -351.229676) (xy 332.020164 -351.229676) (xy 332.047439 -351.230061)
			(xy 332.101436 -351.23782) (xy 332.153778 -351.253185) (xy 332.2034 -351.275842) (xy 332.249293 -351.305332)
			(xy 332.290522 -351.341053) (xy 332.326246 -351.382278) (xy 332.35574 -351.428168) (xy 332.378403 -351.477788)
			(xy 332.393772 -351.530129) (xy 332.401536 -351.584125) (xy 332.401536 -351.638669) (xy 333.884239 -351.638669)
			(xy 333.884239 -351.584131) (xy 333.892001 -351.530147) (xy 333.907367 -351.477818) (xy 333.930024 -351.428208)
			(xy 333.959511 -351.382328) (xy 333.995228 -351.341111) (xy 334.036447 -351.305397) (xy 334.082329 -351.275913)
			(xy 334.13194 -351.253259) (xy 334.18427 -351.237896) (xy 334.238255 -351.230138) (xy 334.265524 -351.229676)
			(xy 335.129124 -351.229676) (xy 335.156395 -351.230088) (xy 335.210381 -351.237853) (xy 335.262713 -351.253222)
			(xy 335.312325 -351.275882) (xy 335.358208 -351.305372) (xy 335.399427 -351.34109) (xy 335.435143 -351.382312)
			(xy 335.464629 -351.428196) (xy 335.487286 -351.477809) (xy 335.502652 -351.530142) (xy 335.510414 -351.584129)
			(xy 335.510414 -351.638666) (xy 336.993262 -351.638666) (xy 336.993262 -351.584134) (xy 337.001023 -351.530157)
			(xy 337.016386 -351.477834) (xy 337.039039 -351.42823) (xy 337.06852 -351.382354) (xy 337.10423 -351.341141)
			(xy 337.145442 -351.30543) (xy 337.191316 -351.275946) (xy 337.240919 -351.253291) (xy 337.293242 -351.237926)
			(xy 337.347218 -351.230163) (xy 337.374484 -351.229676) (xy 338.238084 -351.229676) (xy 338.265358 -351.230062)
			(xy 338.319352 -351.237824) (xy 338.371692 -351.25319) (xy 338.421312 -351.275849) (xy 338.467203 -351.305339)
			(xy 338.508429 -351.34106) (xy 338.544151 -351.382285) (xy 338.573643 -351.428174) (xy 338.596304 -351.477793)
			(xy 338.611673 -351.530132) (xy 338.619436 -351.584126) (xy 338.619436 -351.63867) (xy 340.10214 -351.63867)
			(xy 340.10214 -351.58413) (xy 340.109902 -351.530144) (xy 340.125269 -351.477813) (xy 340.147928 -351.428202)
			(xy 340.177416 -351.382321) (xy 340.213135 -351.341104) (xy 340.254356 -351.30539) (xy 340.300241 -351.275906)
			(xy 340.349855 -351.253254) (xy 340.402187 -351.237893) (xy 340.456174 -351.230136) (xy 340.483444 -351.229676)
			(xy 341.347044 -351.229676) (xy 341.374314 -351.23009) (xy 341.428298 -351.237857) (xy 341.480628 -351.253228)
			(xy 341.530237 -351.275889) (xy 341.576117 -351.305379) (xy 341.617334 -351.341097) (xy 341.653048 -351.382318)
			(xy 341.682532 -351.428201) (xy 341.705188 -351.477814) (xy 341.720552 -351.530145) (xy 341.728314 -351.58413)
			(xy 341.728314 -351.638668) (xy 343.211139 -351.638668) (xy 343.211139 -351.584132) (xy 343.218901 -351.53015)
			(xy 343.234266 -351.477822) (xy 343.256921 -351.428213) (xy 343.286407 -351.382334) (xy 343.322121 -351.341118)
			(xy 343.363337 -351.305404) (xy 343.409217 -351.27592) (xy 343.458826 -351.253264) (xy 343.511154 -351.2379)
			(xy 343.565136 -351.230139) (xy 343.592404 -351.229676) (xy 344.456004 -351.229676) (xy 344.483276 -351.230087)
			(xy 344.537264 -351.23785) (xy 344.589599 -351.253217) (xy 344.639213 -351.275876) (xy 344.685098 -351.305365)
			(xy 344.72632 -351.341083) (xy 344.762038 -351.382305) (xy 344.791526 -351.42819) (xy 344.814184 -351.477805)
			(xy 344.829551 -351.530139) (xy 344.837313 -351.584128) (xy 344.837313 -351.638666) (xy 370.806762 -351.638666)
			(xy 370.806762 -351.584134) (xy 370.814523 -351.530158) (xy 370.829885 -351.477835) (xy 370.852538 -351.428231)
			(xy 370.882019 -351.382356) (xy 370.917729 -351.341143) (xy 370.95894 -351.305431) (xy 371.004814 -351.275948)
			(xy 371.054416 -351.253292) (xy 371.106738 -351.237927) (xy 371.160714 -351.230164) (xy 371.18798 -351.229676)
			(xy 372.05158 -351.229676) (xy 372.078855 -351.230062) (xy 372.132849 -351.237823) (xy 372.185189 -351.253189)
			(xy 372.23481 -351.275848) (xy 372.280701 -351.305338) (xy 372.321927 -351.341059) (xy 372.35765 -351.382283)
			(xy 372.387143 -351.428172) (xy 372.409804 -351.477792) (xy 372.425173 -351.530131) (xy 372.432936 -351.584125)
			(xy 372.432936 -351.63867) (xy 373.91564 -351.63867) (xy 373.91564 -351.58413) (xy 373.923402 -351.530145)
			(xy 373.938769 -351.477814) (xy 373.961427 -351.428203) (xy 373.990915 -351.382322) (xy 374.026634 -351.341105)
			(xy 374.067854 -351.305391) (xy 374.113738 -351.275908) (xy 374.163352 -351.253255) (xy 374.215684 -351.237893)
			(xy 374.26967 -351.230137) (xy 374.29694 -351.229676) (xy 375.16054 -351.229676) (xy 375.18781 -351.230089)
			(xy 375.241795 -351.237856) (xy 375.294125 -351.253227) (xy 375.343735 -351.275887) (xy 375.389615 -351.305377)
			(xy 375.430832 -351.341096) (xy 375.466547 -351.382317) (xy 375.496032 -351.4282) (xy 375.518687 -351.477813)
			(xy 375.534052 -351.530144) (xy 375.541814 -351.58413) (xy 375.541814 -351.638667) (xy 377.024662 -351.638667)
			(xy 377.024662 -351.584133) (xy 377.032423 -351.530155) (xy 377.047787 -351.477831) (xy 377.070441 -351.428226)
			(xy 377.099924 -351.382349) (xy 377.135636 -351.341136) (xy 377.176849 -351.305424) (xy 377.222726 -351.275941)
			(xy 377.272331 -351.253287) (xy 377.324655 -351.237923) (xy 377.378633 -351.230162) (xy 377.4059 -351.229676)
			(xy 378.2695 -351.229676) (xy 378.296772 -351.230087) (xy 378.350761 -351.237849) (xy 378.403096 -351.253216)
			(xy 378.452711 -351.275874) (xy 378.498596 -351.305363) (xy 378.539818 -351.341082) (xy 378.575537 -351.382304)
			(xy 378.605026 -351.428189) (xy 378.627684 -351.477804) (xy 378.643051 -351.530139) (xy 378.650813 -351.584128)
			(xy 378.650813 -351.638665) (xy 380.133662 -351.638665) (xy 380.133662 -351.584135) (xy 380.141422 -351.53016)
			(xy 380.156784 -351.477839) (xy 380.179435 -351.428237) (xy 380.208914 -351.382362) (xy 380.244621 -351.34115)
			(xy 380.28583 -351.305438) (xy 380.331702 -351.275954) (xy 380.381302 -351.253298) (xy 380.433621 -351.237931)
			(xy 380.487595 -351.230165) (xy 380.51486 -351.229676) (xy 381.37846 -351.229676) (xy 381.405736 -351.230061)
			(xy 381.459732 -351.237819) (xy 381.512075 -351.253183) (xy 381.561698 -351.275841) (xy 381.607591 -351.30533)
			(xy 381.64882 -351.341051) (xy 381.684546 -351.382277) (xy 381.71404 -351.428167) (xy 381.736703 -351.477788)
			(xy 381.752072 -351.530129) (xy 381.759836 -351.584124) (xy 381.759836 -351.638669) (xy 383.242539 -351.638669)
			(xy 383.242539 -351.584131) (xy 383.250301 -351.530148) (xy 383.265667 -351.477818) (xy 383.288324 -351.428209)
			(xy 383.31781 -351.382329) (xy 383.353526 -351.341112) (xy 383.394745 -351.305398) (xy 383.440626 -351.275914)
			(xy 383.490237 -351.25326) (xy 383.542567 -351.237897) (xy 383.596551 -351.230138) (xy 383.62382 -351.229676)
			(xy 384.48742 -351.229676) (xy 384.514691 -351.230088) (xy 384.568678 -351.237853) (xy 384.62101 -351.253221)
			(xy 384.670623 -351.275881) (xy 384.716506 -351.30537) (xy 384.757725 -351.341089) (xy 384.793442 -351.38231)
			(xy 384.822929 -351.428195) (xy 384.845586 -351.477808) (xy 384.860952 -351.530142) (xy 384.868714 -351.584129)
			(xy 384.868714 -351.638666) (xy 386.351562 -351.638666) (xy 386.351562 -351.584134) (xy 386.359323 -351.530158)
			(xy 386.374685 -351.477835) (xy 386.397338 -351.428231) (xy 386.426819 -351.382356) (xy 386.462529 -351.341143)
			(xy 386.50374 -351.305431) (xy 386.549614 -351.275948) (xy 386.599216 -351.253292) (xy 386.651538 -351.237927)
			(xy 386.705514 -351.230164) (xy 386.73278 -351.229676) (xy 387.59638 -351.229676) (xy 387.623655 -351.230062)
			(xy 387.677649 -351.237823) (xy 387.729989 -351.253189) (xy 387.77961 -351.275848) (xy 387.825501 -351.305338)
			(xy 387.866727 -351.341059) (xy 387.90245 -351.382283) (xy 387.931943 -351.428172) (xy 387.954604 -351.477792)
			(xy 387.969973 -351.530131) (xy 387.977736 -351.584125) (xy 387.977736 -351.63867) (xy 389.46044 -351.63867)
			(xy 389.46044 -351.58413) (xy 389.468202 -351.530145) (xy 389.483569 -351.477814) (xy 389.506227 -351.428203)
			(xy 389.535715 -351.382322) (xy 389.571434 -351.341105) (xy 389.612654 -351.305391) (xy 389.658538 -351.275908)
			(xy 389.708152 -351.253255) (xy 389.760484 -351.237893) (xy 389.81447 -351.230137) (xy 389.84174 -351.229676)
			(xy 390.70534 -351.229676) (xy 390.73261 -351.230089) (xy 390.786595 -351.237856) (xy 390.838925 -351.253227)
			(xy 390.888535 -351.275887) (xy 390.934415 -351.305377) (xy 390.975632 -351.341096) (xy 391.011347 -351.382317)
			(xy 391.040832 -351.4282) (xy 391.063487 -351.477813) (xy 391.078852 -351.530144) (xy 391.086614 -351.58413)
			(xy 391.086614 -351.638667) (xy 392.569462 -351.638667) (xy 392.569462 -351.584133) (xy 392.577223 -351.530155)
			(xy 392.592587 -351.477831) (xy 392.615241 -351.428226) (xy 392.644724 -351.382349) (xy 392.680436 -351.341136)
			(xy 392.721649 -351.305424) (xy 392.767526 -351.275941) (xy 392.817131 -351.253287) (xy 392.869455 -351.237923)
			(xy 392.923433 -351.230162) (xy 392.9507 -351.229676) (xy 393.8143 -351.229676) (xy 393.841572 -351.230087)
			(xy 393.895561 -351.237849) (xy 393.947896 -351.253216) (xy 393.997511 -351.275874) (xy 394.043396 -351.305363)
			(xy 394.084618 -351.341082) (xy 394.120337 -351.382304) (xy 394.149826 -351.428189) (xy 394.172484 -351.477804)
			(xy 394.187851 -351.530139) (xy 394.195613 -351.584128) (xy 394.195613 -351.638665) (xy 395.678462 -351.638665)
			(xy 395.678462 -351.584135) (xy 395.686222 -351.53016) (xy 395.701584 -351.477839) (xy 395.724235 -351.428237)
			(xy 395.753714 -351.382362) (xy 395.789421 -351.34115) (xy 395.83063 -351.305438) (xy 395.876502 -351.275954)
			(xy 395.926102 -351.253298) (xy 395.978421 -351.237931) (xy 396.032395 -351.230165) (xy 396.05966 -351.229676)
			(xy 396.92326 -351.229676) (xy 396.950536 -351.230061) (xy 397.004532 -351.237819) (xy 397.056875 -351.253183)
			(xy 397.106498 -351.275841) (xy 397.152391 -351.30533) (xy 397.19362 -351.341051) (xy 397.229346 -351.382277)
			(xy 397.25884 -351.428167) (xy 397.281503 -351.477788) (xy 397.296872 -351.530129) (xy 397.304636 -351.584124)
			(xy 397.304636 -351.638669) (xy 398.787339 -351.638669) (xy 398.787339 -351.584131) (xy 398.795101 -351.530148)
			(xy 398.810467 -351.477818) (xy 398.833124 -351.428209) (xy 398.86261 -351.382329) (xy 398.898326 -351.341112)
			(xy 398.939545 -351.305398) (xy 398.985426 -351.275914) (xy 399.035037 -351.25326) (xy 399.087367 -351.237897)
			(xy 399.141351 -351.230138) (xy 399.16862 -351.229676) (xy 400.03222 -351.229676) (xy 400.059491 -351.230088)
			(xy 400.113478 -351.237853) (xy 400.16581 -351.253221) (xy 400.215423 -351.275881) (xy 400.261306 -351.30537)
			(xy 400.302525 -351.341089) (xy 400.338242 -351.38231) (xy 400.367729 -351.428195) (xy 400.390386 -351.477808)
			(xy 400.405752 -351.530142) (xy 400.413514 -351.584129) (xy 400.413514 -351.638666) (xy 401.896362 -351.638666)
			(xy 401.896362 -351.584134) (xy 401.904123 -351.530158) (xy 401.919485 -351.477835) (xy 401.942138 -351.428231)
			(xy 401.971619 -351.382356) (xy 402.007329 -351.341143) (xy 402.04854 -351.305431) (xy 402.094414 -351.275948)
			(xy 402.144016 -351.253292) (xy 402.196338 -351.237927) (xy 402.250314 -351.230164) (xy 402.27758 -351.229676)
			(xy 403.14118 -351.229676) (xy 403.168455 -351.230062) (xy 403.222449 -351.237823) (xy 403.274789 -351.253189)
			(xy 403.32441 -351.275848) (xy 403.370301 -351.305338) (xy 403.411527 -351.341059) (xy 403.44725 -351.382283)
			(xy 403.476743 -351.428172) (xy 403.499404 -351.477792) (xy 403.514773 -351.530131) (xy 403.522536 -351.584125)
			(xy 403.522536 -351.638666) (xy 408.913862 -351.638666) (xy 408.913862 -351.584134) (xy 408.921623 -351.530156)
			(xy 408.936986 -351.477832) (xy 408.95964 -351.428228) (xy 408.989122 -351.382352) (xy 409.024833 -351.341138)
			(xy 409.066045 -351.305427) (xy 409.111921 -351.275944) (xy 409.161525 -351.253289) (xy 409.213848 -351.237925)
			(xy 409.267826 -351.230163) (xy 409.295092 -351.229676) (xy 410.158692 -351.229676) (xy 410.185966 -351.230063)
			(xy 410.239959 -351.237825) (xy 410.292298 -351.253192) (xy 410.341917 -351.275851) (xy 410.387806 -351.305342)
			(xy 410.429032 -351.341063) (xy 410.464753 -351.382287) (xy 410.494245 -351.428176) (xy 410.516905 -351.477794)
			(xy 410.532273 -351.530133) (xy 410.540036 -351.584126) (xy 410.540036 -351.638664) (xy 412.022862 -351.638664)
			(xy 412.022862 -351.584136) (xy 412.030622 -351.530162) (xy 412.045983 -351.477841) (xy 412.068634 -351.428239)
			(xy 412.098112 -351.382365) (xy 412.133819 -351.341153) (xy 412.175026 -351.305441) (xy 412.220897 -351.275957)
			(xy 412.270496 -351.2533) (xy 412.322815 -351.237932) (xy 412.376788 -351.230166) (xy 412.404052 -351.229676)
			(xy 413.267652 -351.229676) (xy 413.294928 -351.23006) (xy 413.348925 -351.237818) (xy 413.401269 -351.253181)
			(xy 413.450893 -351.275838) (xy 413.496787 -351.305328) (xy 413.538017 -351.341049) (xy 413.573744 -351.382274)
			(xy 413.603239 -351.428165) (xy 413.625902 -351.477786) (xy 413.641272 -351.530128) (xy 413.649036 -351.584124)
			(xy 413.649036 -351.638669) (xy 415.131739 -351.638669) (xy 415.131739 -351.584131) (xy 415.139501 -351.530149)
			(xy 415.154866 -351.47782) (xy 415.177523 -351.428211) (xy 415.207008 -351.382331) (xy 415.242724 -351.341115)
			(xy 415.283941 -351.305401) (xy 415.329822 -351.275917) (xy 415.379431 -351.253262) (xy 415.43176 -351.237899)
			(xy 415.485743 -351.230139) (xy 415.513012 -351.229676) (xy 416.376612 -351.229676) (xy 416.403884 -351.230087)
			(xy 416.457871 -351.237851) (xy 416.510204 -351.253219) (xy 416.559818 -351.275878) (xy 416.605702 -351.305367)
			(xy 416.646922 -351.341086) (xy 416.68264 -351.382308) (xy 416.712128 -351.428192) (xy 416.734785 -351.477807)
			(xy 416.750151 -351.530141) (xy 416.757914 -351.584128) (xy 416.757914 -351.638665) (xy 418.240762 -351.638665)
			(xy 418.240762 -351.584135) (xy 418.248522 -351.530159) (xy 418.263885 -351.477837) (xy 418.286537 -351.428233)
			(xy 418.316017 -351.382358) (xy 418.351726 -351.341146) (xy 418.392936 -351.305434) (xy 418.438809 -351.27595)
			(xy 418.48841 -351.253295) (xy 418.540731 -351.237928) (xy 418.594707 -351.230164) (xy 418.621972 -351.229676)
			(xy 419.485572 -351.229676) (xy 419.512847 -351.230062) (xy 419.566842 -351.237821) (xy 419.619184 -351.253187)
			(xy 419.668805 -351.275845) (xy 419.714697 -351.305335) (xy 419.755924 -351.341056) (xy 419.791648 -351.382281)
			(xy 419.821142 -351.42817) (xy 419.843803 -351.47779) (xy 419.859173 -351.53013) (xy 419.866936 -351.584125)
			(xy 419.866936 -351.63867) (xy 421.349639 -351.63867) (xy 421.349639 -351.58413) (xy 421.357402 -351.530146)
			(xy 421.372768 -351.477816) (xy 421.395426 -351.428206) (xy 421.424913 -351.382325) (xy 421.460631 -351.341108)
			(xy 421.501851 -351.305394) (xy 421.547734 -351.27591) (xy 421.597346 -351.253257) (xy 421.649677 -351.237895)
			(xy 421.703662 -351.230137) (xy 421.730932 -351.229676) (xy 422.594532 -351.229676) (xy 422.621803 -351.230089)
			(xy 422.675788 -351.237855) (xy 422.728119 -351.253224) (xy 422.77773 -351.275885) (xy 422.823612 -351.305374)
			(xy 422.864829 -351.341093) (xy 422.900545 -351.382314) (xy 422.930031 -351.428198) (xy 422.952687 -351.477811)
			(xy 422.968052 -351.530143) (xy 422.975814 -351.584129) (xy 422.975814 -351.638666) (xy 424.458662 -351.638666)
			(xy 424.458662 -351.584134) (xy 424.466423 -351.530156) (xy 424.481786 -351.477832) (xy 424.50444 -351.428228)
			(xy 424.533922 -351.382352) (xy 424.569633 -351.341138) (xy 424.610845 -351.305427) (xy 424.656721 -351.275944)
			(xy 424.706325 -351.253289) (xy 424.758648 -351.237925) (xy 424.812626 -351.230163) (xy 424.839892 -351.229676)
			(xy 425.703492 -351.229676) (xy 425.730766 -351.230063) (xy 425.784759 -351.237825) (xy 425.837098 -351.253192)
			(xy 425.886717 -351.275851) (xy 425.932606 -351.305342) (xy 425.973832 -351.341063) (xy 426.009553 -351.382287)
			(xy 426.039045 -351.428176) (xy 426.061705 -351.477794) (xy 426.077073 -351.530133) (xy 426.084836 -351.584126)
			(xy 426.084836 -351.638664) (xy 427.567662 -351.638664) (xy 427.567662 -351.584136) (xy 427.575422 -351.530162)
			(xy 427.590783 -351.477841) (xy 427.613434 -351.428239) (xy 427.642912 -351.382365) (xy 427.678619 -351.341153)
			(xy 427.719826 -351.305441) (xy 427.765697 -351.275957) (xy 427.815296 -351.2533) (xy 427.867615 -351.237932)
			(xy 427.921588 -351.230166) (xy 427.948852 -351.229676) (xy 428.812452 -351.229676) (xy 428.839728 -351.23006)
			(xy 428.893725 -351.237818) (xy 428.946069 -351.253181) (xy 428.995693 -351.275838) (xy 429.041587 -351.305328)
			(xy 429.082817 -351.341049) (xy 429.118544 -351.382274) (xy 429.148039 -351.428165) (xy 429.170702 -351.477786)
			(xy 429.186072 -351.530128) (xy 429.193836 -351.584124) (xy 429.193836 -351.638669) (xy 430.676539 -351.638669)
			(xy 430.676539 -351.584131) (xy 430.684301 -351.530149) (xy 430.699666 -351.47782) (xy 430.722323 -351.428211)
			(xy 430.751808 -351.382331) (xy 430.787524 -351.341115) (xy 430.828741 -351.305401) (xy 430.874622 -351.275917)
			(xy 430.924231 -351.253262) (xy 430.97656 -351.237899) (xy 431.030543 -351.230139) (xy 431.057812 -351.229676)
			(xy 431.921412 -351.229676) (xy 431.948684 -351.230087) (xy 432.002671 -351.237851) (xy 432.055004 -351.253219)
			(xy 432.104618 -351.275878) (xy 432.150502 -351.305367) (xy 432.191722 -351.341086) (xy 432.22744 -351.382308)
			(xy 432.256928 -351.428192) (xy 432.279585 -351.477807) (xy 432.294951 -351.530141) (xy 432.302714 -351.584128)
			(xy 432.302714 -351.638665) (xy 433.785562 -351.638665) (xy 433.785562 -351.584135) (xy 433.793322 -351.530159)
			(xy 433.808685 -351.477837) (xy 433.831337 -351.428233) (xy 433.860817 -351.382358) (xy 433.896526 -351.341146)
			(xy 433.937736 -351.305434) (xy 433.983609 -351.27595) (xy 434.03321 -351.253295) (xy 434.085531 -351.237928)
			(xy 434.139507 -351.230164) (xy 434.166772 -351.229676) (xy 435.030372 -351.229676) (xy 435.057647 -351.230062)
			(xy 435.111642 -351.237821) (xy 435.163984 -351.253187) (xy 435.213605 -351.275845) (xy 435.259497 -351.305335)
			(xy 435.300724 -351.341056) (xy 435.336448 -351.382281) (xy 435.365942 -351.42817) (xy 435.388603 -351.47779)
			(xy 435.403973 -351.53013) (xy 435.411736 -351.584125) (xy 435.411736 -351.63867) (xy 436.894439 -351.63867)
			(xy 436.894439 -351.58413) (xy 436.902202 -351.530146) (xy 436.917568 -351.477816) (xy 436.940226 -351.428206)
			(xy 436.969713 -351.382325) (xy 437.005431 -351.341108) (xy 437.046651 -351.305394) (xy 437.092534 -351.27591)
			(xy 437.142146 -351.253257) (xy 437.194477 -351.237895) (xy 437.248462 -351.230137) (xy 437.275732 -351.229676)
			(xy 438.139332 -351.229676) (xy 438.166603 -351.230089) (xy 438.220588 -351.237855) (xy 438.272919 -351.253224)
			(xy 438.32253 -351.275885) (xy 438.368412 -351.305374) (xy 438.409629 -351.341093) (xy 438.445345 -351.382314)
			(xy 438.474831 -351.428198) (xy 438.497487 -351.477811) (xy 438.512852 -351.530143) (xy 438.520614 -351.584129)
			(xy 438.520614 -351.638666) (xy 440.003462 -351.638666) (xy 440.003462 -351.584134) (xy 440.011223 -351.530156)
			(xy 440.026586 -351.477832) (xy 440.04924 -351.428228) (xy 440.078722 -351.382352) (xy 440.114433 -351.341138)
			(xy 440.155645 -351.305427) (xy 440.201521 -351.275944) (xy 440.251125 -351.253289) (xy 440.303448 -351.237925)
			(xy 440.357426 -351.230163) (xy 440.384692 -351.229676) (xy 441.248292 -351.229676) (xy 441.275566 -351.230063)
			(xy 441.329559 -351.237825) (xy 441.381898 -351.253192) (xy 441.431517 -351.275851) (xy 441.477406 -351.305342)
			(xy 441.518632 -351.341063) (xy 441.554353 -351.382287) (xy 441.583845 -351.428176) (xy 441.606505 -351.477794)
			(xy 441.621873 -351.530133) (xy 441.629636 -351.584126) (xy 441.629636 -351.638674) (xy 441.621873 -351.692667)
			(xy 441.606505 -351.745006) (xy 441.583845 -351.794624) (xy 441.554353 -351.840513) (xy 441.518632 -351.881737)
			(xy 441.477406 -351.917458) (xy 441.431517 -351.946949) (xy 441.381898 -351.969608) (xy 441.329559 -351.984975)
			(xy 441.275566 -351.992737) (xy 441.248292 -351.9932) (xy 440.384692 -351.9932) (xy 440.357426 -351.992637)
			(xy 440.303448 -351.984875) (xy 440.251125 -351.969511) (xy 440.201521 -351.946856) (xy 440.155645 -351.917373)
			(xy 440.114433 -351.881662) (xy 440.078722 -351.840448) (xy 440.04924 -351.794572) (xy 440.026586 -351.744968)
			(xy 440.011223 -351.692644) (xy 440.003462 -351.638666) (xy 438.520614 -351.638666) (xy 438.520614 -351.638671)
			(xy 438.512852 -351.692657) (xy 438.497487 -351.744989) (xy 438.474831 -351.794602) (xy 438.445345 -351.840486)
			(xy 438.409629 -351.881707) (xy 438.368412 -351.917426) (xy 438.32253 -351.946915) (xy 438.272919 -351.969576)
			(xy 438.220588 -351.984945) (xy 438.166603 -351.992711) (xy 438.139332 -351.9932) (xy 437.275732 -351.9932)
			(xy 437.248462 -351.992663) (xy 437.194477 -351.984905) (xy 437.142146 -351.969543) (xy 437.092534 -351.94689)
			(xy 437.046651 -351.917406) (xy 437.005431 -351.881692) (xy 436.969713 -351.840475) (xy 436.940226 -351.794594)
			(xy 436.917568 -351.744984) (xy 436.902202 -351.692654) (xy 436.894439 -351.63867) (xy 435.411736 -351.63867)
			(xy 435.411736 -351.638675) (xy 435.403973 -351.69267) (xy 435.388603 -351.74501) (xy 435.365942 -351.79463)
			(xy 435.336448 -351.840519) (xy 435.300724 -351.881744) (xy 435.259497 -351.917465) (xy 435.213605 -351.946955)
			(xy 435.163984 -351.969613) (xy 435.111642 -351.984979) (xy 435.057647 -351.992738) (xy 435.030372 -351.9932)
			(xy 434.166772 -351.9932) (xy 434.139507 -351.992636) (xy 434.085531 -351.984872) (xy 434.03321 -351.969505)
			(xy 433.983609 -351.94685) (xy 433.937736 -351.917366) (xy 433.896526 -351.881654) (xy 433.860817 -351.840442)
			(xy 433.831337 -351.794567) (xy 433.808685 -351.744963) (xy 433.793322 -351.692641) (xy 433.785562 -351.638665)
			(xy 432.302714 -351.638665) (xy 432.302714 -351.638672) (xy 432.294951 -351.692659) (xy 432.279585 -351.744993)
			(xy 432.256928 -351.794608) (xy 432.22744 -351.840492) (xy 432.191722 -351.881714) (xy 432.150502 -351.917433)
			(xy 432.104618 -351.946922) (xy 432.055004 -351.969581) (xy 432.002671 -351.984949) (xy 431.948684 -351.992713)
			(xy 431.921412 -351.9932) (xy 431.057812 -351.9932) (xy 431.030543 -351.992661) (xy 430.97656 -351.984901)
			(xy 430.924231 -351.969538) (xy 430.874622 -351.946883) (xy 430.828741 -351.917399) (xy 430.787524 -351.881685)
			(xy 430.751808 -351.840469) (xy 430.722323 -351.794589) (xy 430.699666 -351.74498) (xy 430.684301 -351.692651)
			(xy 430.676539 -351.638669) (xy 429.193836 -351.638669) (xy 429.193836 -351.638676) (xy 429.186072 -351.692672)
			(xy 429.170702 -351.745014) (xy 429.148039 -351.794635) (xy 429.118544 -351.840526) (xy 429.082817 -351.881751)
			(xy 429.041587 -351.917472) (xy 428.995693 -351.946962) (xy 428.946069 -351.969619) (xy 428.893725 -351.984982)
			(xy 428.839728 -351.99274) (xy 428.812452 -351.9932) (xy 427.948852 -351.9932) (xy 427.921588 -351.992634)
			(xy 427.867615 -351.984868) (xy 427.815296 -351.9695) (xy 427.765697 -351.946843) (xy 427.719826 -351.917359)
			(xy 427.678619 -351.881647) (xy 427.642912 -351.840435) (xy 427.613434 -351.794561) (xy 427.590783 -351.744959)
			(xy 427.575422 -351.692639) (xy 427.567662 -351.638664) (xy 426.084836 -351.638664) (xy 426.084836 -351.638674)
			(xy 426.077073 -351.692667) (xy 426.061705 -351.745006) (xy 426.039045 -351.794624) (xy 426.009553 -351.840513)
			(xy 425.973832 -351.881737) (xy 425.932606 -351.917458) (xy 425.886717 -351.946949) (xy 425.837098 -351.969608)
			(xy 425.784759 -351.984975) (xy 425.730766 -351.992737) (xy 425.703492 -351.9932) (xy 424.839892 -351.9932)
			(xy 424.812626 -351.992637) (xy 424.758648 -351.984875) (xy 424.706325 -351.969511) (xy 424.656721 -351.946856)
			(xy 424.610845 -351.917373) (xy 424.569633 -351.881662) (xy 424.533922 -351.840448) (xy 424.50444 -351.794572)
			(xy 424.481786 -351.744968) (xy 424.466423 -351.692644) (xy 424.458662 -351.638666) (xy 422.975814 -351.638666)
			(xy 422.975814 -351.638671) (xy 422.968052 -351.692657) (xy 422.952687 -351.744989) (xy 422.930031 -351.794602)
			(xy 422.900545 -351.840486) (xy 422.864829 -351.881707) (xy 422.823612 -351.917426) (xy 422.77773 -351.946915)
			(xy 422.728119 -351.969576) (xy 422.675788 -351.984945) (xy 422.621803 -351.992711) (xy 422.594532 -351.9932)
			(xy 421.730932 -351.9932) (xy 421.703662 -351.992663) (xy 421.649677 -351.984905) (xy 421.597346 -351.969543)
			(xy 421.547734 -351.94689) (xy 421.501851 -351.917406) (xy 421.460631 -351.881692) (xy 421.424913 -351.840475)
			(xy 421.395426 -351.794594) (xy 421.372768 -351.744984) (xy 421.357402 -351.692654) (xy 421.349639 -351.63867)
			(xy 419.866936 -351.63867) (xy 419.866936 -351.638675) (xy 419.859173 -351.69267) (xy 419.843803 -351.74501)
			(xy 419.821142 -351.79463) (xy 419.791648 -351.840519) (xy 419.755924 -351.881744) (xy 419.714697 -351.917465)
			(xy 419.668805 -351.946955) (xy 419.619184 -351.969613) (xy 419.566842 -351.984979) (xy 419.512847 -351.992738)
			(xy 419.485572 -351.9932) (xy 418.621972 -351.9932) (xy 418.594707 -351.992636) (xy 418.540731 -351.984872)
			(xy 418.48841 -351.969505) (xy 418.438809 -351.94685) (xy 418.392936 -351.917366) (xy 418.351726 -351.881654)
			(xy 418.316017 -351.840442) (xy 418.286537 -351.794567) (xy 418.263885 -351.744963) (xy 418.248522 -351.692641)
			(xy 418.240762 -351.638665) (xy 416.757914 -351.638665) (xy 416.757914 -351.638672) (xy 416.750151 -351.692659)
			(xy 416.734785 -351.744993) (xy 416.712128 -351.794608) (xy 416.68264 -351.840492) (xy 416.646922 -351.881714)
			(xy 416.605702 -351.917433) (xy 416.559818 -351.946922) (xy 416.510204 -351.969581) (xy 416.457871 -351.984949)
			(xy 416.403884 -351.992713) (xy 416.376612 -351.9932) (xy 415.513012 -351.9932) (xy 415.485743 -351.992661)
			(xy 415.43176 -351.984901) (xy 415.379431 -351.969538) (xy 415.329822 -351.946883) (xy 415.283941 -351.917399)
			(xy 415.242724 -351.881685) (xy 415.207008 -351.840469) (xy 415.177523 -351.794589) (xy 415.154866 -351.74498)
			(xy 415.139501 -351.692651) (xy 415.131739 -351.638669) (xy 413.649036 -351.638669) (xy 413.649036 -351.638676)
			(xy 413.641272 -351.692672) (xy 413.625902 -351.745014) (xy 413.603239 -351.794635) (xy 413.573744 -351.840526)
			(xy 413.538017 -351.881751) (xy 413.496787 -351.917472) (xy 413.450893 -351.946962) (xy 413.401269 -351.969619)
			(xy 413.348925 -351.984982) (xy 413.294928 -351.99274) (xy 413.267652 -351.9932) (xy 412.404052 -351.9932)
			(xy 412.376788 -351.992634) (xy 412.322815 -351.984868) (xy 412.270496 -351.9695) (xy 412.220897 -351.946843)
			(xy 412.175026 -351.917359) (xy 412.133819 -351.881647) (xy 412.098112 -351.840435) (xy 412.068634 -351.794561)
			(xy 412.045983 -351.744959) (xy 412.030622 -351.692639) (xy 412.022862 -351.638664) (xy 410.540036 -351.638664)
			(xy 410.540036 -351.638674) (xy 410.532273 -351.692667) (xy 410.516905 -351.745006) (xy 410.494245 -351.794624)
			(xy 410.464753 -351.840513) (xy 410.429032 -351.881737) (xy 410.387806 -351.917458) (xy 410.341917 -351.946949)
			(xy 410.292298 -351.969608) (xy 410.239959 -351.984975) (xy 410.185966 -351.992737) (xy 410.158692 -351.9932)
			(xy 409.295092 -351.9932) (xy 409.267826 -351.992637) (xy 409.213848 -351.984875) (xy 409.161525 -351.969511)
			(xy 409.111921 -351.946856) (xy 409.066045 -351.917373) (xy 409.024833 -351.881662) (xy 408.989122 -351.840448)
			(xy 408.95964 -351.794572) (xy 408.936986 -351.744968) (xy 408.921623 -351.692644) (xy 408.913862 -351.638666)
			(xy 403.522536 -351.638666) (xy 403.522536 -351.638675) (xy 403.514773 -351.692669) (xy 403.499404 -351.745008)
			(xy 403.476743 -351.794628) (xy 403.44725 -351.840517) (xy 403.411527 -351.881741) (xy 403.370301 -351.917462)
			(xy 403.32441 -351.946952) (xy 403.274789 -351.969611) (xy 403.222449 -351.984977) (xy 403.168455 -351.992738)
			(xy 403.14118 -351.9932) (xy 402.27758 -351.9932) (xy 402.250314 -351.992636) (xy 402.196338 -351.984873)
			(xy 402.144016 -351.969508) (xy 402.094414 -351.946852) (xy 402.04854 -351.917369) (xy 402.007329 -351.881657)
			(xy 401.971619 -351.840444) (xy 401.942138 -351.794569) (xy 401.919485 -351.744965) (xy 401.904123 -351.692642)
			(xy 401.896362 -351.638666) (xy 400.413514 -351.638666) (xy 400.413514 -351.638671) (xy 400.405752 -351.692658)
			(xy 400.390386 -351.744992) (xy 400.367729 -351.794605) (xy 400.338242 -351.84049) (xy 400.302525 -351.881711)
			(xy 400.261306 -351.91743) (xy 400.215423 -351.946919) (xy 400.16581 -351.969579) (xy 400.113478 -351.984947)
			(xy 400.059491 -351.992712) (xy 400.03222 -351.9932) (xy 399.16862 -351.9932) (xy 399.141351 -351.992662)
			(xy 399.087367 -351.984903) (xy 399.035037 -351.96954) (xy 398.985426 -351.946886) (xy 398.939545 -351.917402)
			(xy 398.898326 -351.881688) (xy 398.86261 -351.840471) (xy 398.833124 -351.794591) (xy 398.810467 -351.744982)
			(xy 398.795101 -351.692652) (xy 398.787339 -351.638669) (xy 397.304636 -351.638669) (xy 397.304636 -351.638676)
			(xy 397.296872 -351.692671) (xy 397.281503 -351.745012) (xy 397.25884 -351.794633) (xy 397.229346 -351.840523)
			(xy 397.19362 -351.881749) (xy 397.152391 -351.91747) (xy 397.106498 -351.946959) (xy 397.056875 -351.969617)
			(xy 397.004532 -351.984981) (xy 396.950536 -351.992739) (xy 396.92326 -351.9932) (xy 396.05966 -351.9932)
			(xy 396.032395 -351.992635) (xy 395.978421 -351.984869) (xy 395.926102 -351.969502) (xy 395.876502 -351.946846)
			(xy 395.83063 -351.917362) (xy 395.789421 -351.88165) (xy 395.753714 -351.840438) (xy 395.724235 -351.794563)
			(xy 395.701584 -351.744961) (xy 395.686222 -351.69264) (xy 395.678462 -351.638665) (xy 394.195613 -351.638665)
			(xy 394.195613 -351.638672) (xy 394.187851 -351.692661) (xy 394.172484 -351.744996) (xy 394.149826 -351.794611)
			(xy 394.120337 -351.840496) (xy 394.084618 -351.881718) (xy 394.043396 -351.917437) (xy 393.997511 -351.946926)
			(xy 393.947896 -351.969584) (xy 393.895561 -351.984951) (xy 393.841572 -351.992713) (xy 393.8143 -351.9932)
			(xy 392.9507 -351.9932) (xy 392.923433 -351.992638) (xy 392.869455 -351.984877) (xy 392.817131 -351.969513)
			(xy 392.767526 -351.946859) (xy 392.721649 -351.917376) (xy 392.680436 -351.881664) (xy 392.644724 -351.840451)
			(xy 392.615241 -351.794574) (xy 392.592587 -351.744969) (xy 392.577223 -351.692645) (xy 392.569462 -351.638667)
			(xy 391.086614 -351.638667) (xy 391.086614 -351.63867) (xy 391.078852 -351.692656) (xy 391.063487 -351.744987)
			(xy 391.040832 -351.7946) (xy 391.011347 -351.840483) (xy 390.975632 -351.881704) (xy 390.934415 -351.917423)
			(xy 390.888535 -351.946913) (xy 390.838925 -351.969573) (xy 390.786595 -351.984944) (xy 390.73261 -351.992711)
			(xy 390.70534 -351.9932) (xy 389.84174 -351.9932) (xy 389.81447 -351.992663) (xy 389.760484 -351.984907)
			(xy 389.708152 -351.969545) (xy 389.658538 -351.946892) (xy 389.612654 -351.917409) (xy 389.571434 -351.881695)
			(xy 389.535715 -351.840478) (xy 389.506227 -351.794597) (xy 389.483569 -351.744986) (xy 389.468202 -351.692655)
			(xy 389.46044 -351.63867) (xy 387.977736 -351.63867) (xy 387.977736 -351.638675) (xy 387.969973 -351.692669)
			(xy 387.954604 -351.745008) (xy 387.931943 -351.794628) (xy 387.90245 -351.840517) (xy 387.866727 -351.881741)
			(xy 387.825501 -351.917462) (xy 387.77961 -351.946952) (xy 387.729989 -351.969611) (xy 387.677649 -351.984977)
			(xy 387.623655 -351.992738) (xy 387.59638 -351.9932) (xy 386.73278 -351.9932) (xy 386.705514 -351.992636)
			(xy 386.651538 -351.984873) (xy 386.599216 -351.969508) (xy 386.549614 -351.946852) (xy 386.50374 -351.917369)
			(xy 386.462529 -351.881657) (xy 386.426819 -351.840444) (xy 386.397338 -351.794569) (xy 386.374685 -351.744965)
			(xy 386.359323 -351.692642) (xy 386.351562 -351.638666) (xy 384.868714 -351.638666) (xy 384.868714 -351.638671)
			(xy 384.860952 -351.692658) (xy 384.845586 -351.744992) (xy 384.822929 -351.794605) (xy 384.793442 -351.84049)
			(xy 384.757725 -351.881711) (xy 384.716506 -351.91743) (xy 384.670623 -351.946919) (xy 384.62101 -351.969579)
			(xy 384.568678 -351.984947) (xy 384.514691 -351.992712) (xy 384.48742 -351.9932) (xy 383.62382 -351.9932)
			(xy 383.596551 -351.992662) (xy 383.542567 -351.984903) (xy 383.490237 -351.96954) (xy 383.440626 -351.946886)
			(xy 383.394745 -351.917402) (xy 383.353526 -351.881688) (xy 383.31781 -351.840471) (xy 383.288324 -351.794591)
			(xy 383.265667 -351.744982) (xy 383.250301 -351.692652) (xy 383.242539 -351.638669) (xy 381.759836 -351.638669)
			(xy 381.759836 -351.638676) (xy 381.752072 -351.692671) (xy 381.736703 -351.745012) (xy 381.71404 -351.794633)
			(xy 381.684546 -351.840523) (xy 381.64882 -351.881749) (xy 381.607591 -351.91747) (xy 381.561698 -351.946959)
			(xy 381.512075 -351.969617) (xy 381.459732 -351.984981) (xy 381.405736 -351.992739) (xy 381.37846 -351.9932)
			(xy 380.51486 -351.9932) (xy 380.487595 -351.992635) (xy 380.433621 -351.984869) (xy 380.381302 -351.969502)
			(xy 380.331702 -351.946846) (xy 380.28583 -351.917362) (xy 380.244621 -351.88165) (xy 380.208914 -351.840438)
			(xy 380.179435 -351.794563) (xy 380.156784 -351.744961) (xy 380.141422 -351.69264) (xy 380.133662 -351.638665)
			(xy 378.650813 -351.638665) (xy 378.650813 -351.638672) (xy 378.643051 -351.692661) (xy 378.627684 -351.744996)
			(xy 378.605026 -351.794611) (xy 378.575537 -351.840496) (xy 378.539818 -351.881718) (xy 378.498596 -351.917437)
			(xy 378.452711 -351.946926) (xy 378.403096 -351.969584) (xy 378.350761 -351.984951) (xy 378.296772 -351.992713)
			(xy 378.2695 -351.9932) (xy 377.4059 -351.9932) (xy 377.378633 -351.992638) (xy 377.324655 -351.984877)
			(xy 377.272331 -351.969513) (xy 377.222726 -351.946859) (xy 377.176849 -351.917376) (xy 377.135636 -351.881664)
			(xy 377.099924 -351.840451) (xy 377.070441 -351.794574) (xy 377.047787 -351.744969) (xy 377.032423 -351.692645)
			(xy 377.024662 -351.638667) (xy 375.541814 -351.638667) (xy 375.541814 -351.63867) (xy 375.534052 -351.692656)
			(xy 375.518687 -351.744987) (xy 375.496032 -351.7946) (xy 375.466547 -351.840483) (xy 375.430832 -351.881704)
			(xy 375.389615 -351.917423) (xy 375.343735 -351.946913) (xy 375.294125 -351.969573) (xy 375.241795 -351.984944)
			(xy 375.18781 -351.992711) (xy 375.16054 -351.9932) (xy 374.29694 -351.9932) (xy 374.26967 -351.992663)
			(xy 374.215684 -351.984907) (xy 374.163352 -351.969545) (xy 374.113738 -351.946892) (xy 374.067854 -351.917409)
			(xy 374.026634 -351.881695) (xy 373.990915 -351.840478) (xy 373.961427 -351.794597) (xy 373.938769 -351.744986)
			(xy 373.923402 -351.692655) (xy 373.91564 -351.63867) (xy 372.432936 -351.63867) (xy 372.432936 -351.638675)
			(xy 372.425173 -351.692669) (xy 372.409804 -351.745008) (xy 372.387143 -351.794628) (xy 372.35765 -351.840517)
			(xy 372.321927 -351.881741) (xy 372.280701 -351.917462) (xy 372.23481 -351.946952) (xy 372.185189 -351.969611)
			(xy 372.132849 -351.984977) (xy 372.078855 -351.992738) (xy 372.05158 -351.9932) (xy 371.18798 -351.9932)
			(xy 371.160714 -351.992636) (xy 371.106738 -351.984873) (xy 371.054416 -351.969508) (xy 371.004814 -351.946852)
			(xy 370.95894 -351.917369) (xy 370.917729 -351.881657) (xy 370.882019 -351.840444) (xy 370.852538 -351.794569)
			(xy 370.829885 -351.744965) (xy 370.814523 -351.692642) (xy 370.806762 -351.638666) (xy 344.837313 -351.638666)
			(xy 344.837313 -351.638672) (xy 344.829551 -351.692661) (xy 344.814184 -351.744995) (xy 344.791526 -351.79461)
			(xy 344.762038 -351.840495) (xy 344.726319 -351.881717) (xy 344.685098 -351.917435) (xy 344.639213 -351.946924)
			(xy 344.589599 -351.969583) (xy 344.537264 -351.98495) (xy 344.483276 -351.992713) (xy 344.456004 -351.9932)
			(xy 343.592404 -351.9932) (xy 343.565136 -351.992661) (xy 343.511154 -351.9849) (xy 343.458826 -351.969536)
			(xy 343.409217 -351.94688) (xy 343.363337 -351.917396) (xy 343.322121 -351.881682) (xy 343.286407 -351.840466)
			(xy 343.256921 -351.794587) (xy 343.234266 -351.744978) (xy 343.218901 -351.69265) (xy 343.211139 -351.638668)
			(xy 341.728314 -351.638668) (xy 341.728314 -351.63867) (xy 341.720552 -351.692655) (xy 341.705188 -351.744986)
			(xy 341.682532 -351.794599) (xy 341.653048 -351.840482) (xy 341.617334 -351.881703) (xy 341.576117 -351.917421)
			(xy 341.530237 -351.946911) (xy 341.480628 -351.969572) (xy 341.428298 -351.984943) (xy 341.374314 -351.99271)
			(xy 341.347044 -351.9932) (xy 340.483444 -351.9932) (xy 340.456174 -351.992664) (xy 340.402187 -351.984907)
			(xy 340.349855 -351.969546) (xy 340.300241 -351.946894) (xy 340.254356 -351.91741) (xy 340.213135 -351.881696)
			(xy 340.177416 -351.840479) (xy 340.147928 -351.794598) (xy 340.125269 -351.744987) (xy 340.109902 -351.692656)
			(xy 340.10214 -351.63867) (xy 338.619436 -351.63867) (xy 338.619436 -351.638674) (xy 338.611673 -351.692668)
			(xy 338.596304 -351.745007) (xy 338.573643 -351.794626) (xy 338.544151 -351.840515) (xy 338.508429 -351.88174)
			(xy 338.467203 -351.917461) (xy 338.421312 -351.946951) (xy 338.371692 -351.96961) (xy 338.319352 -351.984976)
			(xy 338.265358 -351.992738) (xy 338.238084 -351.9932) (xy 337.374484 -351.9932) (xy 337.347218 -351.992637)
			(xy 337.293242 -351.984874) (xy 337.240919 -351.969509) (xy 337.191316 -351.946854) (xy 337.145442 -351.91737)
			(xy 337.10423 -351.881659) (xy 337.06852 -351.840446) (xy 337.039039 -351.79457) (xy 337.016386 -351.744966)
			(xy 337.001023 -351.692643) (xy 336.993262 -351.638666) (xy 335.510414 -351.638666) (xy 335.510414 -351.638671)
			(xy 335.502652 -351.692658) (xy 335.487286 -351.744991) (xy 335.464629 -351.794604) (xy 335.435143 -351.840488)
			(xy 335.399427 -351.88171) (xy 335.358208 -351.917428) (xy 335.312325 -351.946918) (xy 335.262713 -351.969578)
			(xy 335.210381 -351.984947) (xy 335.156395 -351.992712) (xy 335.129124 -351.9932) (xy 334.265524 -351.9932)
			(xy 334.238255 -351.992662) (xy 334.18427 -351.984904) (xy 334.13194 -351.969541) (xy 334.082329 -351.946887)
			(xy 334.036447 -351.917403) (xy 333.995228 -351.881689) (xy 333.959511 -351.840472) (xy 333.930024 -351.794592)
			(xy 333.907367 -351.744982) (xy 333.892001 -351.692653) (xy 333.884239 -351.638669) (xy 332.401536 -351.638669)
			(xy 332.401536 -351.638675) (xy 332.393772 -351.692671) (xy 332.378403 -351.745011) (xy 332.35574 -351.794632)
			(xy 332.326246 -351.840522) (xy 332.290522 -351.881747) (xy 332.249293 -351.917468) (xy 332.2034 -351.946958)
			(xy 332.153778 -351.969615) (xy 332.101436 -351.98498) (xy 332.047439 -351.992739) (xy 332.020164 -351.9932)
			(xy 331.156564 -351.9932) (xy 331.129299 -351.992635) (xy 331.075325 -351.98487) (xy 331.023005 -351.969503)
			(xy 330.973404 -351.946847) (xy 330.927532 -351.917363) (xy 330.886323 -351.881652) (xy 330.850615 -351.840439)
			(xy 330.821136 -351.794564) (xy 330.798484 -351.744962) (xy 330.783122 -351.69264) (xy 330.775362 -351.638665)
			(xy 329.292513 -351.638665) (xy 329.292513 -351.638672) (xy 329.284751 -351.692661) (xy 329.269384 -351.744995)
			(xy 329.246726 -351.79461) (xy 329.217238 -351.840495) (xy 329.181519 -351.881717) (xy 329.140298 -351.917435)
			(xy 329.094413 -351.946924) (xy 329.044799 -351.969583) (xy 328.992464 -351.98495) (xy 328.938476 -351.992713)
			(xy 328.911204 -351.9932) (xy 328.047604 -351.9932) (xy 328.020336 -351.992661) (xy 327.966354 -351.9849)
			(xy 327.914026 -351.969536) (xy 327.864417 -351.94688) (xy 327.818537 -351.917396) (xy 327.777321 -351.881682)
			(xy 327.741607 -351.840466) (xy 327.712121 -351.794587) (xy 327.689466 -351.744978) (xy 327.674101 -351.69265)
			(xy 327.666339 -351.638668) (xy 326.183514 -351.638668) (xy 326.183514 -351.63867) (xy 326.175752 -351.692655)
			(xy 326.160388 -351.744986) (xy 326.137732 -351.794599) (xy 326.108248 -351.840482) (xy 326.072534 -351.881703)
			(xy 326.031317 -351.917421) (xy 325.985437 -351.946911) (xy 325.935828 -351.969572) (xy 325.883498 -351.984943)
			(xy 325.829514 -351.99271) (xy 325.802244 -351.9932) (xy 324.938644 -351.9932) (xy 324.911374 -351.992664)
			(xy 324.857387 -351.984907) (xy 324.805055 -351.969546) (xy 324.755441 -351.946894) (xy 324.709556 -351.91741)
			(xy 324.668335 -351.881696) (xy 324.632616 -351.840479) (xy 324.603128 -351.794598) (xy 324.580469 -351.744987)
			(xy 324.565102 -351.692656) (xy 324.55734 -351.63867) (xy 323.074636 -351.63867) (xy 323.074636 -351.638674)
			(xy 323.066873 -351.692668) (xy 323.051504 -351.745007) (xy 323.028843 -351.794626) (xy 322.999351 -351.840515)
			(xy 322.963629 -351.88174) (xy 322.922403 -351.917461) (xy 322.876512 -351.946951) (xy 322.826892 -351.96961)
			(xy 322.774552 -351.984976) (xy 322.720558 -351.992738) (xy 322.693284 -351.9932) (xy 321.829684 -351.9932)
			(xy 321.802418 -351.992637) (xy 321.748442 -351.984874) (xy 321.696119 -351.969509) (xy 321.646516 -351.946854)
			(xy 321.600642 -351.91737) (xy 321.55943 -351.881659) (xy 321.52372 -351.840446) (xy 321.494239 -351.79457)
			(xy 321.471586 -351.744966) (xy 321.456223 -351.692643) (xy 321.448462 -351.638666) (xy 319.965614 -351.638666)
			(xy 319.965614 -351.638671) (xy 319.957852 -351.692658) (xy 319.942486 -351.744991) (xy 319.919829 -351.794604)
			(xy 319.890343 -351.840488) (xy 319.854627 -351.88171) (xy 319.813408 -351.917428) (xy 319.767525 -351.946918)
			(xy 319.717913 -351.969578) (xy 319.665581 -351.984947) (xy 319.611595 -351.992712) (xy 319.584324 -351.9932)
			(xy 318.720724 -351.9932) (xy 318.693455 -351.992662) (xy 318.63947 -351.984904) (xy 318.58714 -351.969541)
			(xy 318.537529 -351.946887) (xy 318.491647 -351.917403) (xy 318.450428 -351.881689) (xy 318.414711 -351.840472)
			(xy 318.385224 -351.794592) (xy 318.362567 -351.744982) (xy 318.347201 -351.692653) (xy 318.339439 -351.638669)
			(xy 316.856736 -351.638669) (xy 316.856736 -351.638675) (xy 316.848972 -351.692671) (xy 316.833603 -351.745011)
			(xy 316.81094 -351.794632) (xy 316.781446 -351.840522) (xy 316.745722 -351.881747) (xy 316.704493 -351.917468)
			(xy 316.6586 -351.946958) (xy 316.608978 -351.969615) (xy 316.556636 -351.98498) (xy 316.502639 -351.992739)
			(xy 316.475364 -351.9932) (xy 315.611764 -351.9932) (xy 315.584499 -351.992635) (xy 315.530525 -351.98487)
			(xy 315.478205 -351.969503) (xy 315.428604 -351.946847) (xy 315.382732 -351.917363) (xy 315.341523 -351.881652)
			(xy 315.305815 -351.840439) (xy 315.276336 -351.794564) (xy 315.253684 -351.744962) (xy 315.238322 -351.69264)
			(xy 315.230562 -351.638665) (xy 313.747713 -351.638665) (xy 313.747713 -351.638672) (xy 313.739951 -351.692661)
			(xy 313.724584 -351.744995) (xy 313.701926 -351.79461) (xy 313.672438 -351.840495) (xy 313.636719 -351.881717)
			(xy 313.595498 -351.917435) (xy 313.549613 -351.946924) (xy 313.499999 -351.969583) (xy 313.447664 -351.98495)
			(xy 313.393676 -351.992713) (xy 313.366404 -351.9932) (xy 312.502804 -351.9932) (xy 312.475536 -351.992661)
			(xy 312.421554 -351.9849) (xy 312.369226 -351.969536) (xy 312.319617 -351.94688) (xy 312.273737 -351.917396)
			(xy 312.232521 -351.881682) (xy 312.196807 -351.840466) (xy 312.167321 -351.794587) (xy 312.144666 -351.744978)
			(xy 312.129301 -351.69265) (xy 312.121539 -351.638668) (xy 300.231613 -351.638668) (xy 300.231613 -351.638672)
			(xy 300.223851 -351.692661) (xy 300.208484 -351.744995) (xy 300.185826 -351.79461) (xy 300.156337 -351.840496)
			(xy 300.120619 -351.881717) (xy 300.079397 -351.917436) (xy 300.033512 -351.946925) (xy 299.983897 -351.969584)
			(xy 299.931563 -351.984951) (xy 299.877574 -351.992713) (xy 299.850302 -351.9932) (xy 298.986702 -351.9932)
			(xy 298.959434 -351.992661) (xy 298.905452 -351.9849) (xy 298.853124 -351.969535) (xy 298.803516 -351.94688)
			(xy 298.757636 -351.917395) (xy 298.71642 -351.881681) (xy 298.680706 -351.840465) (xy 298.651221 -351.794586)
			(xy 298.628566 -351.744978) (xy 298.613201 -351.69265) (xy 298.605439 -351.638668) (xy 297.122614 -351.638668)
			(xy 297.122614 -351.63867) (xy 297.114852 -351.692655) (xy 297.099488 -351.744987) (xy 297.076832 -351.794599)
			(xy 297.047347 -351.840483) (xy 297.011633 -351.881703) (xy 296.970416 -351.917422) (xy 296.924536 -351.946912)
			(xy 296.874926 -351.969573) (xy 296.822597 -351.984943) (xy 296.768612 -351.992711) (xy 296.741342 -351.9932)
			(xy 295.877742 -351.9932) (xy 295.850472 -351.992663) (xy 295.796486 -351.984907) (xy 295.744153 -351.969546)
			(xy 295.69454 -351.946893) (xy 295.648655 -351.917409) (xy 295.607434 -351.881695) (xy 295.571716 -351.840478)
			(xy 295.542227 -351.794597) (xy 295.519569 -351.744986) (xy 295.504202 -351.692655) (xy 295.49644 -351.63867)
			(xy 294.013736 -351.63867) (xy 294.013736 -351.638675) (xy 294.005973 -351.692668) (xy 293.990604 -351.745008)
			(xy 293.967943 -351.794627) (xy 293.938451 -351.840516) (xy 293.902728 -351.881741) (xy 293.861502 -351.917462)
			(xy 293.815611 -351.946952) (xy 293.765991 -351.969611) (xy 293.713651 -351.984977) (xy 293.659657 -351.992738)
			(xy 293.632382 -351.9932) (xy 292.768782 -351.9932) (xy 292.741516 -351.992636) (xy 292.68754 -351.984873)
			(xy 292.635218 -351.969508) (xy 292.585615 -351.946853) (xy 292.539741 -351.91737) (xy 292.498529 -351.881658)
			(xy 292.46282 -351.840445) (xy 292.433338 -351.794569) (xy 292.410686 -351.744965) (xy 292.395323 -351.692642)
			(xy 292.387562 -351.638666) (xy 290.904714 -351.638666) (xy 290.904714 -351.638671) (xy 290.896952 -351.692658)
			(xy 290.881586 -351.744991) (xy 290.858929 -351.794605) (xy 290.829442 -351.840489) (xy 290.793726 -351.88171)
			(xy 290.752507 -351.917429) (xy 290.706624 -351.946919) (xy 290.657012 -351.969578) (xy 290.60468 -351.984947)
			(xy 290.550693 -351.992712) (xy 290.523422 -351.9932) (xy 289.659822 -351.9932) (xy 289.632553 -351.992662)
			(xy 289.578569 -351.984903) (xy 289.526239 -351.96954) (xy 289.476628 -351.946886) (xy 289.430746 -351.917402)
			(xy 289.389527 -351.881688) (xy 289.353811 -351.840472) (xy 289.324324 -351.794592) (xy 289.301667 -351.744982)
			(xy 289.286301 -351.692653) (xy 289.278539 -351.638669) (xy 287.795836 -351.638669) (xy 287.795836 -351.638675)
			(xy 287.788072 -351.692671) (xy 287.772703 -351.745012) (xy 287.75004 -351.794633) (xy 287.720546 -351.840523)
			(xy 287.684821 -351.881748) (xy 287.643592 -351.917469) (xy 287.597699 -351.946958) (xy 287.548076 -351.969616)
			(xy 287.495734 -351.98498) (xy 287.441737 -351.992739) (xy 287.414462 -351.9932) (xy 286.550862 -351.9932)
			(xy 286.523597 -351.992635) (xy 286.469623 -351.98487) (xy 286.417303 -351.969503) (xy 286.367703 -351.946847)
			(xy 286.321831 -351.917363) (xy 286.280622 -351.881651) (xy 286.244915 -351.840438) (xy 286.215435 -351.794564)
			(xy 286.192784 -351.744961) (xy 286.177422 -351.69264) (xy 286.169662 -351.638665) (xy 284.686813 -351.638665)
			(xy 284.686813 -351.638672) (xy 284.679051 -351.692661) (xy 284.663684 -351.744995) (xy 284.641026 -351.79461)
			(xy 284.611537 -351.840496) (xy 284.575819 -351.881717) (xy 284.534597 -351.917436) (xy 284.488712 -351.946925)
			(xy 284.439097 -351.969584) (xy 284.386763 -351.984951) (xy 284.332774 -351.992713) (xy 284.305502 -351.9932)
			(xy 283.441902 -351.9932) (xy 283.414634 -351.992661) (xy 283.360652 -351.9849) (xy 283.308324 -351.969535)
			(xy 283.258716 -351.94688) (xy 283.212836 -351.917395) (xy 283.17162 -351.881681) (xy 283.135906 -351.840465)
			(xy 283.106421 -351.794586) (xy 283.083766 -351.744978) (xy 283.068401 -351.69265) (xy 283.060639 -351.638668)
			(xy 281.577814 -351.638668) (xy 281.577814 -351.63867) (xy 281.570052 -351.692655) (xy 281.554688 -351.744987)
			(xy 281.532032 -351.794599) (xy 281.502547 -351.840483) (xy 281.466833 -351.881703) (xy 281.425616 -351.917422)
			(xy 281.379736 -351.946912) (xy 281.330126 -351.969573) (xy 281.277797 -351.984943) (xy 281.223812 -351.992711)
			(xy 281.196542 -351.9932) (xy 280.332942 -351.9932) (xy 280.305672 -351.992663) (xy 280.251686 -351.984907)
			(xy 280.199353 -351.969546) (xy 280.14974 -351.946893) (xy 280.103855 -351.917409) (xy 280.062634 -351.881695)
			(xy 280.026916 -351.840478) (xy 279.997427 -351.794597) (xy 279.974769 -351.744986) (xy 279.959402 -351.692655)
			(xy 279.95164 -351.63867) (xy 278.468936 -351.63867) (xy 278.468936 -351.638675) (xy 278.461173 -351.692668)
			(xy 278.445804 -351.745008) (xy 278.423143 -351.794627) (xy 278.393651 -351.840516) (xy 278.357928 -351.881741)
			(xy 278.316702 -351.917462) (xy 278.270811 -351.946952) (xy 278.221191 -351.969611) (xy 278.168851 -351.984977)
			(xy 278.114857 -351.992738) (xy 278.087582 -351.9932) (xy 277.223982 -351.9932) (xy 277.196716 -351.992636)
			(xy 277.14274 -351.984873) (xy 277.090418 -351.969508) (xy 277.040815 -351.946853) (xy 276.994941 -351.91737)
			(xy 276.953729 -351.881658) (xy 276.91802 -351.840445) (xy 276.888538 -351.794569) (xy 276.865886 -351.744965)
			(xy 276.850523 -351.692642) (xy 276.842762 -351.638666) (xy 275.359914 -351.638666) (xy 275.359914 -351.638671)
			(xy 275.352152 -351.692658) (xy 275.336786 -351.744991) (xy 275.314129 -351.794605) (xy 275.284642 -351.840489)
			(xy 275.248926 -351.88171) (xy 275.207707 -351.917429) (xy 275.161824 -351.946919) (xy 275.112212 -351.969578)
			(xy 275.05988 -351.984947) (xy 275.005893 -351.992712) (xy 274.978622 -351.9932) (xy 274.115022 -351.9932)
			(xy 274.087753 -351.992662) (xy 274.033769 -351.984903) (xy 273.981439 -351.96954) (xy 273.931828 -351.946886)
			(xy 273.885946 -351.917402) (xy 273.844727 -351.881688) (xy 273.809011 -351.840472) (xy 273.779524 -351.794592)
			(xy 273.756867 -351.744982) (xy 273.741501 -351.692653) (xy 273.733739 -351.638669) (xy 272.251036 -351.638669)
			(xy 272.251036 -351.638675) (xy 272.243272 -351.692671) (xy 272.227903 -351.745012) (xy 272.20524 -351.794633)
			(xy 272.175746 -351.840523) (xy 272.140021 -351.881748) (xy 272.098792 -351.917469) (xy 272.052899 -351.946958)
			(xy 272.003276 -351.969616) (xy 271.950934 -351.98498) (xy 271.896937 -351.992739) (xy 271.869662 -351.9932)
			(xy 271.006062 -351.9932) (xy 270.978797 -351.992635) (xy 270.924823 -351.98487) (xy 270.872503 -351.969503)
			(xy 270.822903 -351.946847) (xy 270.777031 -351.917363) (xy 270.735822 -351.881651) (xy 270.700115 -351.840438)
			(xy 270.670635 -351.794564) (xy 270.647984 -351.744961) (xy 270.632622 -351.69264) (xy 270.624862 -351.638665)
			(xy 269.142013 -351.638665) (xy 269.142013 -351.638672) (xy 269.134251 -351.692661) (xy 269.118884 -351.744995)
			(xy 269.096226 -351.79461) (xy 269.066737 -351.840496) (xy 269.031019 -351.881717) (xy 268.989797 -351.917436)
			(xy 268.943912 -351.946925) (xy 268.894297 -351.969584) (xy 268.841963 -351.984951) (xy 268.787974 -351.992713)
			(xy 268.760702 -351.9932) (xy 267.897102 -351.9932) (xy 267.869834 -351.992661) (xy 267.815852 -351.9849)
			(xy 267.763524 -351.969535) (xy 267.713916 -351.94688) (xy 267.668036 -351.917395) (xy 267.62682 -351.881681)
			(xy 267.591106 -351.840465) (xy 267.561621 -351.794586) (xy 267.538966 -351.744978) (xy 267.523601 -351.69265)
			(xy 267.515839 -351.638668) (xy 216.123526 -351.638668) (xy 216.080368 -351.642889) (xy 215.896274 -351.652871)
			(xy 215.71192 -351.654868) (xy 215.527653 -351.648877) (xy 215.343818 -351.63491) (xy 215.160761 -351.612992)
			(xy 214.978825 -351.583165) (xy 214.798352 -351.545485) (xy 214.619681 -351.500023) (xy 214.443147 -351.446863)
			(xy 214.269081 -351.386106) (xy 214.097811 -351.317866) (xy 213.929657 -351.24227) (xy 213.764936 -351.159461)
			(xy 213.603957 -351.069595) (xy 213.447022 -350.972839) (xy 213.294425 -350.869376) (xy 213.146454 -350.7594)
			(xy 213.003386 -350.643117) (xy 212.865489 -350.520746) (xy 212.733022 -350.392516) (xy 212.606235 -350.258668)
			(xy 212.485365 -350.119454) (xy 212.370638 -349.975134) (xy 212.262272 -349.82598) (xy 212.160468 -349.672272)
			(xy 212.065418 -349.514298) (xy 211.977301 -349.352354) (xy 211.896281 -349.186746) (xy 211.822512 -349.017783)
			(xy 211.756131 -348.845784) (xy 211.697263 -348.67107) (xy 211.646018 -348.49397) (xy 211.602494 -348.314817)
			(xy 211.566771 -348.133947) (xy 211.538917 -347.951698) (xy 211.518984 -347.768415) (xy 211.507009 -347.584439)
			(xy 211.503015 -347.400118) (xy 8.25588 -347.400118) (xy 8.309695 -347.452301) (xy 8.396695 -347.547736)
			(xy 8.477656 -347.648346) (xy 8.55227 -347.753749) (xy 8.620253 -347.863546) (xy 8.681348 -347.97732)
			(xy 8.735323 -348.094639) (xy 8.781974 -348.215058) (xy 8.821123 -348.338121) (xy 8.852622 -348.46336)
			(xy 8.876351 -348.590301) (xy 8.879169 -348.613059) (xy 18.951174 -348.613059) (xy 18.951174 -348.558521)
			(xy 18.958936 -348.504537) (xy 18.974301 -348.452208) (xy 18.996957 -348.402598) (xy 19.026443 -348.356717)
			(xy 19.062158 -348.315499) (xy 19.103375 -348.279784) (xy 19.149256 -348.250298) (xy 19.198866 -348.227642)
			(xy 19.251195 -348.212276) (xy 19.305179 -348.204515) (xy 19.332448 -348.204028) (xy 20.196048 -348.204028)
			(xy 20.223319 -348.204491) (xy 20.277306 -348.212253) (xy 20.329639 -348.227619) (xy 20.379253 -348.250277)
			(xy 20.425136 -348.279764) (xy 20.466357 -348.315482) (xy 20.502074 -348.356702) (xy 20.531562 -348.402586)
			(xy 20.55422 -348.452199) (xy 20.569586 -348.504532) (xy 20.577349 -348.558519) (xy 20.577349 -348.613061)
			(xy 20.577347 -348.613072) (xy 22.060092 -348.613072) (xy 22.060092 -348.558528) (xy 22.067854 -348.504539)
			(xy 22.083221 -348.452204) (xy 22.10588 -348.402589) (xy 22.135369 -348.356704) (xy 22.171088 -348.315483)
			(xy 22.21231 -348.279764) (xy 22.258196 -348.250276) (xy 22.307812 -348.227618) (xy 22.360147 -348.212252)
			(xy 22.414136 -348.204491) (xy 22.441408 -348.204028) (xy 23.305008 -348.204028) (xy 23.332276 -348.204535)
			(xy 23.386258 -348.212297) (xy 23.438585 -348.227663) (xy 23.488193 -348.250319) (xy 23.534071 -348.279804)
			(xy 23.575287 -348.315519) (xy 23.611 -348.356735) (xy 23.640485 -348.402614) (xy 23.66314 -348.452223)
			(xy 23.678504 -348.50455) (xy 23.686266 -348.558532) (xy 23.686266 -348.613068) (xy 23.686266 -348.613069)
			(xy 25.169114 -348.613069) (xy 25.169114 -348.558531) (xy 25.176875 -348.504549) (xy 25.19224 -348.452221)
			(xy 25.214894 -348.402611) (xy 25.244378 -348.356731) (xy 25.28009 -348.315513) (xy 25.321305 -348.279797)
			(xy 25.367183 -348.250309) (xy 25.416791 -348.227651) (xy 25.469118 -348.212282) (xy 25.523099 -348.204517)
			(xy 25.550368 -348.204028) (xy 26.413968 -348.204028) (xy 26.44124 -348.204509) (xy 26.495229 -348.212268)
			(xy 26.547564 -348.227631) (xy 26.59718 -348.250286) (xy 26.643066 -348.279772) (xy 26.684289 -348.315488)
			(xy 26.720009 -348.356708) (xy 26.749499 -348.402592) (xy 26.772158 -348.452206) (xy 26.787526 -348.50454)
			(xy 26.795288 -348.558528) (xy 26.795288 -348.613072) (xy 26.795288 -348.613073) (xy 28.277992 -348.613073)
			(xy 28.277992 -348.558527) (xy 28.285755 -348.504536) (xy 28.301123 -348.4522) (xy 28.323783 -348.402584)
			(xy 28.353274 -348.356697) (xy 28.388995 -348.315476) (xy 28.43022 -348.279757) (xy 28.476108 -348.25027)
			(xy 28.525726 -348.227613) (xy 28.578064 -348.212249) (xy 28.632055 -348.20449) (xy 28.659328 -348.204028)
			(xy 29.522928 -348.204028) (xy 29.550195 -348.204536) (xy 29.604175 -348.212301) (xy 29.656499 -348.227668)
			(xy 29.706105 -348.250326) (xy 29.751981 -348.279811) (xy 29.793194 -348.315526) (xy 29.828905 -348.356742)
			(xy 29.858388 -348.40262) (xy 29.881041 -348.452227) (xy 29.896405 -348.504553) (xy 29.904166 -348.558533)
			(xy 29.904166 -348.613067) (xy 29.904166 -348.61307) (xy 31.387014 -348.61307) (xy 31.387014 -348.55853)
			(xy 31.394776 -348.504546) (xy 31.410141 -348.452217) (xy 31.432797 -348.402606) (xy 31.462283 -348.356724)
			(xy 31.497997 -348.315506) (xy 31.539215 -348.27979) (xy 31.585095 -348.250303) (xy 31.634705 -348.227645)
			(xy 31.687035 -348.212279) (xy 31.741018 -348.204515) (xy 31.768288 -348.204028) (xy 32.631888 -348.204028)
			(xy 32.659159 -348.204511) (xy 32.713146 -348.212271) (xy 32.765478 -348.227636) (xy 32.815092 -348.250292)
			(xy 32.860976 -348.279779) (xy 32.902196 -348.315495) (xy 32.937914 -348.356715) (xy 32.967402 -348.402598)
			(xy 32.99006 -348.45221) (xy 33.005426 -348.504543) (xy 33.013189 -348.558529) (xy 33.013189 -348.613071)
			(xy 33.013189 -348.613074) (xy 34.495892 -348.613074) (xy 34.495892 -348.558526) (xy 34.503655 -348.504534)
			(xy 34.519024 -348.452196) (xy 34.541686 -348.402578) (xy 34.571179 -348.356691) (xy 34.606902 -348.315468)
			(xy 34.648129 -348.27975) (xy 34.69402 -348.250263) (xy 34.743641 -348.227608) (xy 34.795981 -348.212245)
			(xy 34.849974 -348.204488) (xy 34.877248 -348.204028) (xy 35.740848 -348.204028) (xy 35.768114 -348.204538)
			(xy 35.822091 -348.212305) (xy 35.874414 -348.227674) (xy 35.924017 -348.250332) (xy 35.96989 -348.279819)
			(xy 36.011101 -348.315533) (xy 36.04681 -348.356748) (xy 36.076291 -348.402626) (xy 36.098943 -348.452231)
			(xy 36.114306 -348.504556) (xy 36.122066 -348.558534) (xy 36.122066 -348.613066) (xy 36.122065 -348.613072)
			(xy 37.604892 -348.613072) (xy 37.604892 -348.558528) (xy 37.612654 -348.504539) (xy 37.628021 -348.452204)
			(xy 37.65068 -348.402589) (xy 37.680169 -348.356704) (xy 37.715888 -348.315483) (xy 37.75711 -348.279764)
			(xy 37.802996 -348.250276) (xy 37.852612 -348.227618) (xy 37.904947 -348.212252) (xy 37.958936 -348.204491)
			(xy 37.986208 -348.204028) (xy 38.849808 -348.204028) (xy 38.877076 -348.204535) (xy 38.931058 -348.212297)
			(xy 38.983385 -348.227663) (xy 39.032993 -348.250319) (xy 39.078871 -348.279804) (xy 39.120087 -348.315519)
			(xy 39.1558 -348.356735) (xy 39.185285 -348.402614) (xy 39.20794 -348.452223) (xy 39.223304 -348.50455)
			(xy 39.231066 -348.558532) (xy 39.231066 -348.613068) (xy 39.231066 -348.613069) (xy 40.713914 -348.613069)
			(xy 40.713914 -348.558531) (xy 40.721675 -348.504549) (xy 40.73704 -348.452221) (xy 40.759694 -348.402611)
			(xy 40.789178 -348.356731) (xy 40.82489 -348.315513) (xy 40.866105 -348.279797) (xy 40.911983 -348.250309)
			(xy 40.961591 -348.227651) (xy 41.013918 -348.212282) (xy 41.067899 -348.204517) (xy 41.095168 -348.204028)
			(xy 41.958768 -348.204028) (xy 41.98604 -348.204509) (xy 42.040029 -348.212268) (xy 42.092364 -348.227631)
			(xy 42.14198 -348.250286) (xy 42.187866 -348.279772) (xy 42.229089 -348.315488) (xy 42.264809 -348.356708)
			(xy 42.294299 -348.402592) (xy 42.316958 -348.452206) (xy 42.332326 -348.50454) (xy 42.340088 -348.558528)
			(xy 42.340088 -348.613072) (xy 42.340088 -348.613073) (xy 43.822792 -348.613073) (xy 43.822792 -348.558527)
			(xy 43.830555 -348.504536) (xy 43.845923 -348.4522) (xy 43.868583 -348.402584) (xy 43.898074 -348.356697)
			(xy 43.933795 -348.315476) (xy 43.97502 -348.279757) (xy 44.020908 -348.25027) (xy 44.070526 -348.227613)
			(xy 44.122864 -348.212249) (xy 44.176855 -348.20449) (xy 44.204128 -348.204028) (xy 45.067728 -348.204028)
			(xy 45.094995 -348.204536) (xy 45.148975 -348.212301) (xy 45.201299 -348.227668) (xy 45.250905 -348.250326)
			(xy 45.296781 -348.279811) (xy 45.337994 -348.315526) (xy 45.373705 -348.356742) (xy 45.403188 -348.40262)
			(xy 45.425841 -348.452227) (xy 45.441205 -348.504553) (xy 45.448966 -348.558533) (xy 45.448966 -348.613067)
			(xy 45.448966 -348.61307) (xy 46.931814 -348.61307) (xy 46.931814 -348.55853) (xy 46.939576 -348.504546)
			(xy 46.954941 -348.452217) (xy 46.977597 -348.402606) (xy 47.007083 -348.356724) (xy 47.042797 -348.315506)
			(xy 47.084015 -348.27979) (xy 47.129895 -348.250303) (xy 47.179505 -348.227645) (xy 47.231835 -348.212279)
			(xy 47.285818 -348.204515) (xy 47.313088 -348.204028) (xy 48.176688 -348.204028) (xy 48.203959 -348.204511)
			(xy 48.257946 -348.212271) (xy 48.310278 -348.227636) (xy 48.359892 -348.250292) (xy 48.405776 -348.279779)
			(xy 48.446996 -348.315495) (xy 48.482714 -348.356715) (xy 48.512202 -348.402598) (xy 48.53486 -348.45221)
			(xy 48.550226 -348.504543) (xy 48.557989 -348.558529) (xy 48.557989 -348.613071) (xy 48.557989 -348.613074)
			(xy 50.040692 -348.613074) (xy 50.040692 -348.558526) (xy 50.048455 -348.504534) (xy 50.063824 -348.452196)
			(xy 50.086486 -348.402578) (xy 50.115979 -348.356691) (xy 50.151702 -348.315468) (xy 50.192929 -348.27975)
			(xy 50.23882 -348.250263) (xy 50.288441 -348.227608) (xy 50.340781 -348.212245) (xy 50.394774 -348.204488)
			(xy 50.422048 -348.204028) (xy 51.285648 -348.204028) (xy 51.312914 -348.204538) (xy 51.366891 -348.212305)
			(xy 51.419214 -348.227674) (xy 51.468817 -348.250332) (xy 51.51469 -348.279819) (xy 51.555901 -348.315533)
			(xy 51.59161 -348.356748) (xy 51.621091 -348.402626) (xy 51.643743 -348.452231) (xy 51.659106 -348.504556)
			(xy 51.666866 -348.558534) (xy 51.666866 -348.613066) (xy 51.666865 -348.613074) (xy 60.990892 -348.613074)
			(xy 60.990892 -348.558526) (xy 60.998655 -348.504534) (xy 61.014024 -348.452197) (xy 61.036685 -348.40258)
			(xy 61.066177 -348.356693) (xy 61.1019 -348.315471) (xy 61.143127 -348.279752) (xy 61.189017 -348.250265)
			(xy 61.238636 -348.227609) (xy 61.290976 -348.212246) (xy 61.344968 -348.204489) (xy 61.372242 -348.204028)
			(xy 62.235842 -348.204028) (xy 62.263109 -348.204537) (xy 62.317086 -348.212304) (xy 62.369409 -348.227672)
			(xy 62.419013 -348.25033) (xy 62.464887 -348.279816) (xy 62.506099 -348.315531) (xy 62.541809 -348.356746)
			(xy 62.57129 -348.402624) (xy 62.593943 -348.45223) (xy 62.609305 -348.504555) (xy 62.617066 -348.558533)
			(xy 62.617066 -348.613067) (xy 62.617065 -348.613072) (xy 64.099892 -348.613072) (xy 64.099892 -348.558528)
			(xy 64.107654 -348.50454) (xy 64.123021 -348.452206) (xy 64.145679 -348.402591) (xy 64.175168 -348.356706)
			(xy 64.210886 -348.315485) (xy 64.252108 -348.279766) (xy 64.297993 -348.250278) (xy 64.347607 -348.22762)
			(xy 64.399942 -348.212253) (xy 64.45393 -348.204491) (xy 64.481202 -348.204028) (xy 65.344802 -348.204028)
			(xy 65.372071 -348.204535) (xy 65.426053 -348.212296) (xy 65.47838 -348.227661) (xy 65.527989 -348.250317)
			(xy 65.573869 -348.279802) (xy 65.615085 -348.315517) (xy 65.650799 -348.356733) (xy 65.680284 -348.402613)
			(xy 65.702939 -348.452221) (xy 65.718304 -348.504549) (xy 65.726066 -348.558531) (xy 65.726066 -348.613068)
			(xy 67.208914 -348.613068) (xy 67.208914 -348.558532) (xy 67.216675 -348.50455) (xy 67.232039 -348.452222)
			(xy 67.254693 -348.402613) (xy 67.284176 -348.356733) (xy 67.319888 -348.315515) (xy 67.361102 -348.279799)
			(xy 67.40698 -348.250311) (xy 67.456586 -348.227652) (xy 67.508913 -348.212283) (xy 67.562894 -348.204517)
			(xy 67.590162 -348.204028) (xy 68.453762 -348.204028) (xy 68.481034 -348.204509) (xy 68.535024 -348.212266)
			(xy 68.58736 -348.227629) (xy 68.636976 -348.250284) (xy 68.682863 -348.27977) (xy 68.724087 -348.315486)
			(xy 68.759808 -348.356706) (xy 68.789298 -348.40259) (xy 68.811958 -348.452205) (xy 68.827326 -348.504539)
			(xy 68.835088 -348.558528) (xy 68.835088 -348.613072) (xy 68.835088 -348.613073) (xy 70.317792 -348.613073)
			(xy 70.317792 -348.558527) (xy 70.325554 -348.504537) (xy 70.340922 -348.452201) (xy 70.363582 -348.402585)
			(xy 70.393072 -348.356699) (xy 70.428793 -348.315478) (xy 70.470017 -348.279759) (xy 70.515905 -348.250271)
			(xy 70.565522 -348.227615) (xy 70.617859 -348.21225) (xy 70.671849 -348.20449) (xy 70.699122 -348.204028)
			(xy 71.562722 -348.204028) (xy 71.58999 -348.204536) (xy 71.643969 -348.2123) (xy 71.696295 -348.227667)
			(xy 71.745901 -348.250324) (xy 71.791778 -348.279809) (xy 71.832992 -348.315524) (xy 71.868704 -348.35674)
			(xy 71.898187 -348.402618) (xy 71.920841 -348.452226) (xy 71.936205 -348.504552) (xy 71.943966 -348.558532)
			(xy 71.943966 -348.613068) (xy 71.943966 -348.613069) (xy 73.426814 -348.613069) (xy 73.426814 -348.558531)
			(xy 73.434576 -348.504547) (xy 73.449941 -348.452218) (xy 73.472596 -348.402608) (xy 73.502081 -348.356726)
			(xy 73.537795 -348.315508) (xy 73.579012 -348.279792) (xy 73.624892 -348.250305) (xy 73.674501 -348.227647)
			(xy 73.72683 -348.21228) (xy 73.780813 -348.204516) (xy 73.808082 -348.204028) (xy 74.671682 -348.204028)
			(xy 74.698953 -348.20451) (xy 74.752941 -348.21227) (xy 74.805274 -348.227634) (xy 74.854888 -348.25029)
			(xy 74.900773 -348.279777) (xy 74.941994 -348.315493) (xy 74.977712 -348.356713) (xy 75.007201 -348.402596)
			(xy 75.029859 -348.452209) (xy 75.045226 -348.504542) (xy 75.052988 -348.558529) (xy 75.052988 -348.613071)
			(xy 75.052988 -348.613074) (xy 76.535692 -348.613074) (xy 76.535692 -348.558526) (xy 76.543455 -348.504534)
			(xy 76.558824 -348.452197) (xy 76.581485 -348.40258) (xy 76.610977 -348.356693) (xy 76.6467 -348.315471)
			(xy 76.687927 -348.279752) (xy 76.733817 -348.250265) (xy 76.783436 -348.227609) (xy 76.835776 -348.212246)
			(xy 76.889768 -348.204489) (xy 76.917042 -348.204028) (xy 77.780642 -348.204028) (xy 77.807909 -348.204537)
			(xy 77.861886 -348.212304) (xy 77.914209 -348.227672) (xy 77.963813 -348.25033) (xy 78.009687 -348.279816)
			(xy 78.050899 -348.315531) (xy 78.086609 -348.356746) (xy 78.11609 -348.402624) (xy 78.138743 -348.45223)
			(xy 78.154105 -348.504555) (xy 78.161866 -348.558533) (xy 78.161866 -348.613067) (xy 78.161865 -348.613072)
			(xy 79.644692 -348.613072) (xy 79.644692 -348.558528) (xy 79.652454 -348.50454) (xy 79.667821 -348.452206)
			(xy 79.690479 -348.402591) (xy 79.719968 -348.356706) (xy 79.755686 -348.315485) (xy 79.796908 -348.279766)
			(xy 79.842793 -348.250278) (xy 79.892407 -348.22762) (xy 79.944742 -348.212253) (xy 79.99873 -348.204491)
			(xy 80.026002 -348.204028) (xy 80.889602 -348.204028) (xy 80.916871 -348.204535) (xy 80.970853 -348.212296)
			(xy 81.02318 -348.227661) (xy 81.072789 -348.250317) (xy 81.118669 -348.279802) (xy 81.159885 -348.315517)
			(xy 81.195599 -348.356733) (xy 81.225084 -348.402613) (xy 81.247739 -348.452221) (xy 81.263104 -348.504549)
			(xy 81.270866 -348.558531) (xy 81.270866 -348.613068) (xy 82.753714 -348.613068) (xy 82.753714 -348.558532)
			(xy 82.761475 -348.50455) (xy 82.776839 -348.452222) (xy 82.799493 -348.402613) (xy 82.828976 -348.356733)
			(xy 82.864688 -348.315515) (xy 82.905902 -348.279799) (xy 82.95178 -348.250311) (xy 83.001386 -348.227652)
			(xy 83.053713 -348.212283) (xy 83.107694 -348.204517) (xy 83.134962 -348.204028) (xy 83.998562 -348.204028)
			(xy 84.025834 -348.204509) (xy 84.079824 -348.212266) (xy 84.13216 -348.227629) (xy 84.181776 -348.250284)
			(xy 84.227663 -348.27977) (xy 84.268887 -348.315486) (xy 84.304608 -348.356706) (xy 84.334098 -348.40259)
			(xy 84.356758 -348.452205) (xy 84.372126 -348.504539) (xy 84.379888 -348.558528) (xy 84.379888 -348.613072)
			(xy 84.379888 -348.613073) (xy 85.862592 -348.613073) (xy 85.862592 -348.558527) (xy 85.870354 -348.504537)
			(xy 85.885722 -348.452201) (xy 85.908382 -348.402585) (xy 85.937872 -348.356699) (xy 85.973593 -348.315478)
			(xy 86.014817 -348.279759) (xy 86.060705 -348.250271) (xy 86.110322 -348.227615) (xy 86.162659 -348.21225)
			(xy 86.216649 -348.20449) (xy 86.243922 -348.204028) (xy 87.107522 -348.204028) (xy 87.13479 -348.204536)
			(xy 87.188769 -348.2123) (xy 87.241095 -348.227667) (xy 87.290701 -348.250324) (xy 87.336578 -348.279809)
			(xy 87.377792 -348.315524) (xy 87.413504 -348.35674) (xy 87.442987 -348.402618) (xy 87.465641 -348.452226)
			(xy 87.481005 -348.504552) (xy 87.488766 -348.558532) (xy 87.488766 -348.613068) (xy 87.488766 -348.613069)
			(xy 88.971614 -348.613069) (xy 88.971614 -348.558531) (xy 88.979376 -348.504547) (xy 88.994741 -348.452218)
			(xy 89.017396 -348.402608) (xy 89.046881 -348.356726) (xy 89.082595 -348.315508) (xy 89.123812 -348.279792)
			(xy 89.169692 -348.250305) (xy 89.219301 -348.227647) (xy 89.27163 -348.21228) (xy 89.325613 -348.204516)
			(xy 89.352882 -348.204028) (xy 90.216482 -348.204028) (xy 90.243753 -348.20451) (xy 90.297741 -348.21227)
			(xy 90.350074 -348.227634) (xy 90.399688 -348.25029) (xy 90.445573 -348.279777) (xy 90.486794 -348.315493)
			(xy 90.522512 -348.356713) (xy 90.552001 -348.402596) (xy 90.574659 -348.452209) (xy 90.590026 -348.504542)
			(xy 90.597788 -348.558529) (xy 90.597788 -348.613071) (xy 90.597788 -348.613074) (xy 92.080492 -348.613074)
			(xy 92.080492 -348.558526) (xy 92.088255 -348.504534) (xy 92.103624 -348.452197) (xy 92.126285 -348.40258)
			(xy 92.155777 -348.356693) (xy 92.1915 -348.315471) (xy 92.232727 -348.279752) (xy 92.278617 -348.250265)
			(xy 92.328236 -348.227609) (xy 92.380576 -348.212246) (xy 92.434568 -348.204489) (xy 92.461842 -348.204028)
			(xy 93.325442 -348.204028) (xy 93.352709 -348.204537) (xy 93.406686 -348.212304) (xy 93.459009 -348.227672)
			(xy 93.508613 -348.25033) (xy 93.554487 -348.279816) (xy 93.595699 -348.315531) (xy 93.631409 -348.356746)
			(xy 93.66089 -348.402624) (xy 93.683543 -348.45223) (xy 93.698905 -348.504555) (xy 93.706666 -348.558533)
			(xy 93.706666 -348.613067) (xy 93.706665 -348.613072) (xy 111.480792 -348.613072) (xy 111.480792 -348.558528)
			(xy 111.488554 -348.504539) (xy 111.503921 -348.452204) (xy 111.52658 -348.402589) (xy 111.556069 -348.356704)
			(xy 111.591788 -348.315483) (xy 111.63301 -348.279764) (xy 111.678896 -348.250276) (xy 111.728512 -348.227618)
			(xy 111.780847 -348.212252) (xy 111.834836 -348.204491) (xy 111.862108 -348.204028) (xy 112.725708 -348.204028)
			(xy 112.752976 -348.204535) (xy 112.806958 -348.212297) (xy 112.859285 -348.227663) (xy 112.908893 -348.250319)
			(xy 112.954771 -348.279804) (xy 112.995987 -348.315519) (xy 113.0317 -348.356735) (xy 113.061185 -348.402614)
			(xy 113.08384 -348.452223) (xy 113.099204 -348.50455) (xy 113.106966 -348.558532) (xy 113.106966 -348.613068)
			(xy 113.106966 -348.613069) (xy 114.589814 -348.613069) (xy 114.589814 -348.558531) (xy 114.597575 -348.504549)
			(xy 114.61294 -348.452221) (xy 114.635594 -348.402611) (xy 114.665078 -348.356731) (xy 114.70079 -348.315513)
			(xy 114.742005 -348.279797) (xy 114.787883 -348.250309) (xy 114.837491 -348.227651) (xy 114.889818 -348.212282)
			(xy 114.943799 -348.204517) (xy 114.971068 -348.204028) (xy 115.834668 -348.204028) (xy 115.86194 -348.204509)
			(xy 115.915929 -348.212268) (xy 115.968264 -348.227631) (xy 116.01788 -348.250286) (xy 116.063766 -348.279772)
			(xy 116.104989 -348.315488) (xy 116.140709 -348.356708) (xy 116.170199 -348.402592) (xy 116.192858 -348.452206)
			(xy 116.208226 -348.50454) (xy 116.215988 -348.558528) (xy 116.215988 -348.613072) (xy 116.215988 -348.613073)
			(xy 117.698692 -348.613073) (xy 117.698692 -348.558527) (xy 117.706455 -348.504536) (xy 117.721823 -348.4522)
			(xy 117.744483 -348.402584) (xy 117.773974 -348.356697) (xy 117.809695 -348.315476) (xy 117.85092 -348.279757)
			(xy 117.896808 -348.25027) (xy 117.946426 -348.227613) (xy 117.998764 -348.212249) (xy 118.052755 -348.20449)
			(xy 118.080028 -348.204028) (xy 118.943628 -348.204028) (xy 118.970895 -348.204536) (xy 119.024875 -348.212301)
			(xy 119.077199 -348.227668) (xy 119.126805 -348.250326) (xy 119.172681 -348.279811) (xy 119.213894 -348.315526)
			(xy 119.249605 -348.356742) (xy 119.279088 -348.40262) (xy 119.301741 -348.452227) (xy 119.317105 -348.504553)
			(xy 119.324866 -348.558533) (xy 119.324866 -348.613067) (xy 119.324866 -348.61307) (xy 120.807714 -348.61307)
			(xy 120.807714 -348.55853) (xy 120.815476 -348.504546) (xy 120.830841 -348.452217) (xy 120.853497 -348.402606)
			(xy 120.882983 -348.356724) (xy 120.918697 -348.315506) (xy 120.959915 -348.27979) (xy 121.005795 -348.250303)
			(xy 121.055405 -348.227645) (xy 121.107735 -348.212279) (xy 121.161718 -348.204515) (xy 121.188988 -348.204028)
			(xy 122.052588 -348.204028) (xy 122.079859 -348.204511) (xy 122.133846 -348.212271) (xy 122.186178 -348.227636)
			(xy 122.235792 -348.250292) (xy 122.281676 -348.279779) (xy 122.322896 -348.315495) (xy 122.358614 -348.356715)
			(xy 122.388102 -348.402598) (xy 122.41076 -348.45221) (xy 122.426126 -348.504543) (xy 122.433889 -348.558529)
			(xy 122.433889 -348.613071) (xy 122.433889 -348.613074) (xy 123.916592 -348.613074) (xy 123.916592 -348.558526)
			(xy 123.924355 -348.504534) (xy 123.939724 -348.452196) (xy 123.962386 -348.402578) (xy 123.991879 -348.356691)
			(xy 124.027602 -348.315468) (xy 124.068829 -348.27975) (xy 124.11472 -348.250263) (xy 124.164341 -348.227608)
			(xy 124.216681 -348.212245) (xy 124.270674 -348.204488) (xy 124.297948 -348.204028) (xy 125.161548 -348.204028)
			(xy 125.188814 -348.204538) (xy 125.242791 -348.212305) (xy 125.295114 -348.227674) (xy 125.344717 -348.250332)
			(xy 125.39059 -348.279819) (xy 125.431801 -348.315533) (xy 125.46751 -348.356748) (xy 125.496991 -348.402626)
			(xy 125.519643 -348.452231) (xy 125.535006 -348.504556) (xy 125.542766 -348.558534) (xy 125.542766 -348.613066)
			(xy 125.542765 -348.613072) (xy 127.025592 -348.613072) (xy 127.025592 -348.558528) (xy 127.033354 -348.504539)
			(xy 127.048721 -348.452204) (xy 127.07138 -348.402589) (xy 127.100869 -348.356704) (xy 127.136588 -348.315483)
			(xy 127.17781 -348.279764) (xy 127.223696 -348.250276) (xy 127.273312 -348.227618) (xy 127.325647 -348.212252)
			(xy 127.379636 -348.204491) (xy 127.406908 -348.204028) (xy 128.270508 -348.204028) (xy 128.297776 -348.204535)
			(xy 128.351758 -348.212297) (xy 128.404085 -348.227663) (xy 128.453693 -348.250319) (xy 128.499571 -348.279804)
			(xy 128.540787 -348.315519) (xy 128.5765 -348.356735) (xy 128.605985 -348.402614) (xy 128.62864 -348.452223)
			(xy 128.644004 -348.50455) (xy 128.651766 -348.558532) (xy 128.651766 -348.613068) (xy 128.651766 -348.613069)
			(xy 130.134614 -348.613069) (xy 130.134614 -348.558531) (xy 130.142375 -348.504549) (xy 130.15774 -348.452221)
			(xy 130.180394 -348.402611) (xy 130.209878 -348.356731) (xy 130.24559 -348.315513) (xy 130.286805 -348.279797)
			(xy 130.332683 -348.250309) (xy 130.382291 -348.227651) (xy 130.434618 -348.212282) (xy 130.488599 -348.204517)
			(xy 130.515868 -348.204028) (xy 131.379468 -348.204028) (xy 131.40674 -348.204509) (xy 131.460729 -348.212268)
			(xy 131.513064 -348.227631) (xy 131.56268 -348.250286) (xy 131.608566 -348.279772) (xy 131.649789 -348.315488)
			(xy 131.685509 -348.356708) (xy 131.714999 -348.402592) (xy 131.737658 -348.452206) (xy 131.753026 -348.50454)
			(xy 131.760788 -348.558528) (xy 131.760788 -348.613072) (xy 131.760788 -348.613073) (xy 133.243492 -348.613073)
			(xy 133.243492 -348.558527) (xy 133.251255 -348.504536) (xy 133.266623 -348.4522) (xy 133.289283 -348.402584)
			(xy 133.318774 -348.356697) (xy 133.354495 -348.315476) (xy 133.39572 -348.279757) (xy 133.441608 -348.25027)
			(xy 133.491226 -348.227613) (xy 133.543564 -348.212249) (xy 133.597555 -348.20449) (xy 133.624828 -348.204028)
			(xy 134.488428 -348.204028) (xy 134.515695 -348.204536) (xy 134.569675 -348.212301) (xy 134.621999 -348.227668)
			(xy 134.671605 -348.250326) (xy 134.717481 -348.279811) (xy 134.758694 -348.315526) (xy 134.794405 -348.356742)
			(xy 134.823888 -348.40262) (xy 134.846541 -348.452227) (xy 134.861905 -348.504553) (xy 134.869666 -348.558533)
			(xy 134.869666 -348.613067) (xy 134.869666 -348.61307) (xy 136.352514 -348.61307) (xy 136.352514 -348.55853)
			(xy 136.360276 -348.504546) (xy 136.375641 -348.452217) (xy 136.398297 -348.402606) (xy 136.427783 -348.356724)
			(xy 136.463497 -348.315506) (xy 136.504715 -348.27979) (xy 136.550595 -348.250303) (xy 136.600205 -348.227645)
			(xy 136.652535 -348.212279) (xy 136.706518 -348.204515) (xy 136.733788 -348.204028) (xy 137.597388 -348.204028)
			(xy 137.624659 -348.204511) (xy 137.678646 -348.212271) (xy 137.730978 -348.227636) (xy 137.780592 -348.250292)
			(xy 137.826476 -348.279779) (xy 137.867696 -348.315495) (xy 137.903414 -348.356715) (xy 137.932902 -348.402598)
			(xy 137.95556 -348.45221) (xy 137.970926 -348.504543) (xy 137.978689 -348.558529) (xy 137.978689 -348.613071)
			(xy 137.978689 -348.613074) (xy 139.461392 -348.613074) (xy 139.461392 -348.558526) (xy 139.469155 -348.504534)
			(xy 139.484524 -348.452196) (xy 139.507186 -348.402578) (xy 139.536679 -348.356691) (xy 139.572402 -348.315468)
			(xy 139.613629 -348.27975) (xy 139.65952 -348.250263) (xy 139.709141 -348.227608) (xy 139.761481 -348.212245)
			(xy 139.815474 -348.204488) (xy 139.842748 -348.204028) (xy 140.706348 -348.204028) (xy 140.733614 -348.204538)
			(xy 140.787591 -348.212305) (xy 140.839914 -348.227674) (xy 140.889517 -348.250332) (xy 140.93539 -348.279819)
			(xy 140.976601 -348.315533) (xy 141.01231 -348.356748) (xy 141.041791 -348.402626) (xy 141.064443 -348.452231)
			(xy 141.079806 -348.504556) (xy 141.087566 -348.558534) (xy 141.087566 -348.613066) (xy 141.087565 -348.613072)
			(xy 142.570392 -348.613072) (xy 142.570392 -348.558528) (xy 142.578154 -348.504539) (xy 142.593521 -348.452204)
			(xy 142.61618 -348.402589) (xy 142.645669 -348.356704) (xy 142.681388 -348.315483) (xy 142.72261 -348.279764)
			(xy 142.768496 -348.250276) (xy 142.818112 -348.227618) (xy 142.870447 -348.212252) (xy 142.924436 -348.204491)
			(xy 142.951708 -348.204028) (xy 143.815308 -348.204028) (xy 143.842576 -348.204535) (xy 143.896558 -348.212297)
			(xy 143.948885 -348.227663) (xy 143.998493 -348.250319) (xy 144.044371 -348.279804) (xy 144.085587 -348.315519)
			(xy 144.1213 -348.356735) (xy 144.150785 -348.402614) (xy 144.17344 -348.452223) (xy 144.188804 -348.50455)
			(xy 144.196566 -348.558532) (xy 144.196566 -348.613068) (xy 144.196565 -348.613072) (xy 161.804792 -348.613072)
			(xy 161.804792 -348.558528) (xy 161.812554 -348.504538) (xy 161.827921 -348.452203) (xy 161.850581 -348.402588)
			(xy 161.88007 -348.356703) (xy 161.91579 -348.315481) (xy 161.957012 -348.279763) (xy 162.002899 -348.250275)
			(xy 162.052515 -348.227617) (xy 162.10485 -348.212252) (xy 162.15884 -348.204491) (xy 162.186112 -348.204028)
			(xy 163.049712 -348.204028) (xy 163.07698 -348.204535) (xy 163.130961 -348.212298) (xy 163.183288 -348.227664)
			(xy 163.232895 -348.25032) (xy 163.278773 -348.279806) (xy 163.319988 -348.31552) (xy 163.355701 -348.356736)
			(xy 163.385185 -348.402615) (xy 163.40784 -348.452224) (xy 163.423204 -348.504551) (xy 163.430966 -348.558532)
			(xy 163.430966 -348.613068) (xy 163.430966 -348.613069) (xy 164.913814 -348.613069) (xy 164.913814 -348.558531)
			(xy 164.921576 -348.504549) (xy 164.93694 -348.45222) (xy 164.959595 -348.40261) (xy 164.989079 -348.35673)
			(xy 165.024792 -348.315512) (xy 165.066007 -348.279795) (xy 165.111886 -348.250308) (xy 165.161494 -348.22765)
			(xy 165.213821 -348.212281) (xy 165.267803 -348.204516) (xy 165.295072 -348.204028) (xy 166.158672 -348.204028)
			(xy 166.185944 -348.20451) (xy 166.239932 -348.212268) (xy 166.292267 -348.227632) (xy 166.341882 -348.250287)
			(xy 166.387768 -348.279773) (xy 166.42899 -348.31549) (xy 166.46471 -348.356709) (xy 166.494199 -348.402593)
			(xy 166.516859 -348.452207) (xy 166.532226 -348.504541) (xy 166.539988 -348.558528) (xy 166.539988 -348.613072)
			(xy 166.539988 -348.613073) (xy 168.022692 -348.613073) (xy 168.022692 -348.558527) (xy 168.030455 -348.504536)
			(xy 168.045823 -348.452199) (xy 168.068484 -348.402583) (xy 168.097975 -348.356696) (xy 168.133697 -348.315474)
			(xy 168.174922 -348.279756) (xy 168.220811 -348.250268) (xy 168.270429 -348.227612) (xy 168.322767 -348.212248)
			(xy 168.376759 -348.204489) (xy 168.404032 -348.204028) (xy 169.267632 -348.204028) (xy 169.294899 -348.204537)
			(xy 169.348878 -348.212302) (xy 169.401202 -348.227669) (xy 169.450807 -348.250327) (xy 169.496683 -348.279813)
			(xy 169.537895 -348.315527) (xy 169.573606 -348.356743) (xy 169.603088 -348.402621) (xy 169.625742 -348.452228)
			(xy 169.641105 -348.504553) (xy 169.648866 -348.558533) (xy 169.648866 -348.613067) (xy 169.648866 -348.61307)
			(xy 171.131714 -348.61307) (xy 171.131714 -348.55853) (xy 171.139476 -348.504546) (xy 171.154841 -348.452216)
			(xy 171.177498 -348.402605) (xy 171.206984 -348.356723) (xy 171.242699 -348.315505) (xy 171.283917 -348.279788)
			(xy 171.329798 -348.250301) (xy 171.379408 -348.227644) (xy 171.431738 -348.212278) (xy 171.485722 -348.204515)
			(xy 171.512992 -348.204028) (xy 172.376592 -348.204028) (xy 172.403863 -348.204511) (xy 172.457849 -348.212272)
			(xy 172.510181 -348.227637) (xy 172.559794 -348.250294) (xy 172.605678 -348.27978) (xy 172.646898 -348.315497)
			(xy 172.682615 -348.356716) (xy 172.712103 -348.402599) (xy 172.73476 -348.452211) (xy 172.750126 -348.504543)
			(xy 172.757889 -348.558529) (xy 172.757889 -348.613068) (xy 174.240714 -348.613068) (xy 174.240714 -348.558532)
			(xy 174.248475 -348.504551) (xy 174.263838 -348.452224) (xy 174.286492 -348.402616) (xy 174.315974 -348.356736)
			(xy 174.351685 -348.315519) (xy 174.392898 -348.279803) (xy 174.438774 -348.250315) (xy 174.488379 -348.227655)
			(xy 174.540704 -348.212285) (xy 174.594684 -348.204518) (xy 174.621952 -348.204028) (xy 175.485552 -348.204028)
			(xy 175.512825 -348.204508) (xy 175.566815 -348.212265) (xy 175.619152 -348.227626) (xy 175.66877 -348.250281)
			(xy 175.714659 -348.279766) (xy 175.755883 -348.315483) (xy 175.791605 -348.356703) (xy 175.821096 -348.402588)
			(xy 175.843757 -348.452203) (xy 175.859125 -348.504538) (xy 175.866888 -348.558528) (xy 175.866888 -348.613072)
			(xy 177.349592 -348.613072) (xy 177.349592 -348.558528) (xy 177.357354 -348.504538) (xy 177.372721 -348.452203)
			(xy 177.395381 -348.402588) (xy 177.42487 -348.356703) (xy 177.46059 -348.315481) (xy 177.501812 -348.279763)
			(xy 177.547699 -348.250275) (xy 177.597315 -348.227617) (xy 177.64965 -348.212252) (xy 177.70364 -348.204491)
			(xy 177.730912 -348.204028) (xy 178.594512 -348.204028) (xy 178.62178 -348.204535) (xy 178.675761 -348.212298)
			(xy 178.728088 -348.227664) (xy 178.777695 -348.25032) (xy 178.823573 -348.279806) (xy 178.864788 -348.31552)
			(xy 178.900501 -348.356736) (xy 178.929985 -348.402615) (xy 178.95264 -348.452224) (xy 178.968004 -348.504551)
			(xy 178.975766 -348.558532) (xy 178.975766 -348.613068) (xy 178.975766 -348.613069) (xy 180.458614 -348.613069)
			(xy 180.458614 -348.558531) (xy 180.466376 -348.504549) (xy 180.48174 -348.45222) (xy 180.504395 -348.40261)
			(xy 180.533879 -348.35673) (xy 180.569592 -348.315512) (xy 180.610807 -348.279795) (xy 180.656686 -348.250308)
			(xy 180.706294 -348.22765) (xy 180.758621 -348.212281) (xy 180.812603 -348.204516) (xy 180.839872 -348.204028)
			(xy 181.703472 -348.204028) (xy 181.730744 -348.20451) (xy 181.784732 -348.212268) (xy 181.837067 -348.227632)
			(xy 181.886682 -348.250287) (xy 181.932568 -348.279773) (xy 181.97379 -348.31549) (xy 182.00951 -348.356709)
			(xy 182.038999 -348.402593) (xy 182.061659 -348.452207) (xy 182.077026 -348.504541) (xy 182.084788 -348.558528)
			(xy 182.084788 -348.613072) (xy 182.084788 -348.613073) (xy 183.567492 -348.613073) (xy 183.567492 -348.558527)
			(xy 183.575255 -348.504536) (xy 183.590623 -348.452199) (xy 183.613284 -348.402583) (xy 183.642775 -348.356696)
			(xy 183.678497 -348.315474) (xy 183.719722 -348.279756) (xy 183.765611 -348.250268) (xy 183.815229 -348.227612)
			(xy 183.867567 -348.212248) (xy 183.921559 -348.204489) (xy 183.948832 -348.204028) (xy 184.812432 -348.204028)
			(xy 184.839699 -348.204537) (xy 184.893678 -348.212302) (xy 184.946002 -348.227669) (xy 184.995607 -348.250327)
			(xy 185.041483 -348.279813) (xy 185.082695 -348.315527) (xy 185.118406 -348.356743) (xy 185.147888 -348.402621)
			(xy 185.170542 -348.452228) (xy 185.185905 -348.504553) (xy 185.193666 -348.558533) (xy 185.193666 -348.613067)
			(xy 185.193666 -348.61307) (xy 186.676514 -348.61307) (xy 186.676514 -348.55853) (xy 186.684276 -348.504546)
			(xy 186.699641 -348.452216) (xy 186.722298 -348.402605) (xy 186.751784 -348.356723) (xy 186.787499 -348.315505)
			(xy 186.828717 -348.279788) (xy 186.874598 -348.250301) (xy 186.924208 -348.227644) (xy 186.976538 -348.212278)
			(xy 187.030522 -348.204515) (xy 187.057792 -348.204028) (xy 187.921392 -348.204028) (xy 187.948663 -348.204511)
			(xy 188.002649 -348.212272) (xy 188.054981 -348.227637) (xy 188.104594 -348.250294) (xy 188.150478 -348.27978)
			(xy 188.191698 -348.315497) (xy 188.227415 -348.356716) (xy 188.256903 -348.402599) (xy 188.27956 -348.452211)
			(xy 188.294926 -348.504543) (xy 188.302689 -348.558529) (xy 188.302689 -348.613068) (xy 189.785514 -348.613068)
			(xy 189.785514 -348.558532) (xy 189.793275 -348.504551) (xy 189.808638 -348.452224) (xy 189.831292 -348.402616)
			(xy 189.860774 -348.356736) (xy 189.896485 -348.315519) (xy 189.937698 -348.279803) (xy 189.983574 -348.250315)
			(xy 190.033179 -348.227655) (xy 190.085504 -348.212285) (xy 190.139484 -348.204518) (xy 190.166752 -348.204028)
			(xy 191.030352 -348.204028) (xy 191.057625 -348.204508) (xy 191.111615 -348.212265) (xy 191.163952 -348.227626)
			(xy 191.21357 -348.250281) (xy 191.259459 -348.279766) (xy 191.300683 -348.315483) (xy 191.336405 -348.356703)
			(xy 191.365896 -348.402588) (xy 191.388557 -348.452203) (xy 191.403925 -348.504538) (xy 191.411688 -348.558528)
			(xy 191.411688 -348.613072) (xy 192.894392 -348.613072) (xy 192.894392 -348.558528) (xy 192.902154 -348.504538)
			(xy 192.917521 -348.452203) (xy 192.940181 -348.402588) (xy 192.96967 -348.356703) (xy 193.00539 -348.315481)
			(xy 193.046612 -348.279763) (xy 193.092499 -348.250275) (xy 193.142115 -348.227617) (xy 193.19445 -348.212252)
			(xy 193.24844 -348.204491) (xy 193.275712 -348.204028) (xy 194.139312 -348.204028) (xy 194.16658 -348.204535)
			(xy 194.220561 -348.212298) (xy 194.272888 -348.227664) (xy 194.322495 -348.25032) (xy 194.368373 -348.279806)
			(xy 194.409588 -348.31552) (xy 194.445301 -348.356736) (xy 194.474785 -348.402615) (xy 194.49744 -348.452224)
			(xy 194.512804 -348.504551) (xy 194.520566 -348.558532) (xy 194.520566 -348.613068) (xy 194.512804 -348.667049)
			(xy 194.49744 -348.719376) (xy 194.474785 -348.768985) (xy 194.445301 -348.814864) (xy 194.409588 -348.85608)
			(xy 194.368373 -348.891794) (xy 194.322495 -348.92128) (xy 194.272888 -348.943936) (xy 194.220561 -348.959302)
			(xy 194.16658 -348.967065) (xy 194.139312 -348.967552) (xy 193.275712 -348.967552) (xy 193.24844 -348.967109)
			(xy 193.19445 -348.959348) (xy 193.142115 -348.943983) (xy 193.092499 -348.921325) (xy 193.046612 -348.891837)
			(xy 193.00539 -348.856119) (xy 192.96967 -348.814897) (xy 192.940181 -348.769012) (xy 192.917521 -348.719397)
			(xy 192.902154 -348.667062) (xy 192.894392 -348.613072) (xy 191.411688 -348.613072) (xy 191.403925 -348.667062)
			(xy 191.388557 -348.719397) (xy 191.365896 -348.769012) (xy 191.336405 -348.814897) (xy 191.300683 -348.856117)
			(xy 191.259459 -348.891834) (xy 191.21357 -348.921319) (xy 191.163952 -348.943974) (xy 191.111615 -348.959335)
			(xy 191.057625 -348.967092) (xy 191.030352 -348.967552) (xy 190.166752 -348.967552) (xy 190.139484 -348.967082)
			(xy 190.085504 -348.959315) (xy 190.033179 -348.943945) (xy 189.983574 -348.921285) (xy 189.937698 -348.891797)
			(xy 189.896485 -348.856081) (xy 189.860774 -348.814864) (xy 189.831292 -348.768984) (xy 189.808638 -348.719376)
			(xy 189.793275 -348.667049) (xy 189.785514 -348.613068) (xy 188.302689 -348.613068) (xy 188.302689 -348.613071)
			(xy 188.294926 -348.667057) (xy 188.27956 -348.719389) (xy 188.256903 -348.769001) (xy 188.227415 -348.814884)
			(xy 188.191698 -348.856103) (xy 188.150478 -348.89182) (xy 188.104594 -348.921306) (xy 188.054981 -348.943963)
			(xy 188.002649 -348.959328) (xy 187.948663 -348.967089) (xy 187.921392 -348.967552) (xy 187.057792 -348.967552)
			(xy 187.030522 -348.967085) (xy 186.976538 -348.959322) (xy 186.924208 -348.943956) (xy 186.874598 -348.921299)
			(xy 186.828717 -348.891812) (xy 186.787499 -348.856095) (xy 186.751784 -348.814877) (xy 186.722298 -348.768995)
			(xy 186.699641 -348.719384) (xy 186.684276 -348.667054) (xy 186.676514 -348.61307) (xy 185.193666 -348.61307)
			(xy 185.185905 -348.667047) (xy 185.170542 -348.719372) (xy 185.147888 -348.768979) (xy 185.118406 -348.814857)
			(xy 185.082695 -348.856073) (xy 185.041483 -348.891787) (xy 184.995607 -348.921273) (xy 184.946002 -348.943931)
			(xy 184.893678 -348.959298) (xy 184.839699 -348.967063) (xy 184.812432 -348.967552) (xy 183.948832 -348.967552)
			(xy 183.921559 -348.967111) (xy 183.867567 -348.959352) (xy 183.815229 -348.943988) (xy 183.765611 -348.921332)
			(xy 183.719722 -348.891844) (xy 183.678497 -348.856126) (xy 183.642775 -348.814904) (xy 183.613284 -348.769017)
			(xy 183.590623 -348.719401) (xy 183.575255 -348.667064) (xy 183.567492 -348.613073) (xy 182.084788 -348.613073)
			(xy 182.077026 -348.667059) (xy 182.061659 -348.719393) (xy 182.038999 -348.769007) (xy 182.00951 -348.814891)
			(xy 181.97379 -348.85611) (xy 181.932568 -348.891827) (xy 181.886682 -348.921313) (xy 181.837067 -348.943968)
			(xy 181.784732 -348.959332) (xy 181.730744 -348.96709) (xy 181.703472 -348.967552) (xy 180.839872 -348.967552)
			(xy 180.812603 -348.967084) (xy 180.758621 -348.959319) (xy 180.706294 -348.94395) (xy 180.656686 -348.921292)
			(xy 180.610807 -348.891805) (xy 180.569592 -348.856088) (xy 180.533879 -348.81487) (xy 180.504395 -348.76899)
			(xy 180.48174 -348.71938) (xy 180.466376 -348.667051) (xy 180.458614 -348.613069) (xy 178.975766 -348.613069)
			(xy 178.968004 -348.667049) (xy 178.95264 -348.719376) (xy 178.929985 -348.768985) (xy 178.900501 -348.814864)
			(xy 178.864788 -348.85608) (xy 178.823573 -348.891794) (xy 178.777695 -348.92128) (xy 178.728088 -348.943936)
			(xy 178.675761 -348.959302) (xy 178.62178 -348.967065) (xy 178.594512 -348.967552) (xy 177.730912 -348.967552)
			(xy 177.70364 -348.967109) (xy 177.64965 -348.959348) (xy 177.597315 -348.943983) (xy 177.547699 -348.921325)
			(xy 177.501812 -348.891837) (xy 177.46059 -348.856119) (xy 177.42487 -348.814897) (xy 177.395381 -348.769012)
			(xy 177.372721 -348.719397) (xy 177.357354 -348.667062) (xy 177.349592 -348.613072) (xy 175.866888 -348.613072)
			(xy 175.859125 -348.667062) (xy 175.843757 -348.719397) (xy 175.821096 -348.769012) (xy 175.791605 -348.814897)
			(xy 175.755883 -348.856117) (xy 175.714659 -348.891834) (xy 175.66877 -348.921319) (xy 175.619152 -348.943974)
			(xy 175.566815 -348.959335) (xy 175.512825 -348.967092) (xy 175.485552 -348.967552) (xy 174.621952 -348.967552)
			(xy 174.594684 -348.967082) (xy 174.540704 -348.959315) (xy 174.488379 -348.943945) (xy 174.438774 -348.921285)
			(xy 174.392898 -348.891797) (xy 174.351685 -348.856081) (xy 174.315974 -348.814864) (xy 174.286492 -348.768984)
			(xy 174.263838 -348.719376) (xy 174.248475 -348.667049) (xy 174.240714 -348.613068) (xy 172.757889 -348.613068)
			(xy 172.757889 -348.613071) (xy 172.750126 -348.667057) (xy 172.73476 -348.719389) (xy 172.712103 -348.769001)
			(xy 172.682615 -348.814884) (xy 172.646898 -348.856103) (xy 172.605678 -348.89182) (xy 172.559794 -348.921306)
			(xy 172.510181 -348.943963) (xy 172.457849 -348.959328) (xy 172.403863 -348.967089) (xy 172.376592 -348.967552)
			(xy 171.512992 -348.967552) (xy 171.485722 -348.967085) (xy 171.431738 -348.959322) (xy 171.379408 -348.943956)
			(xy 171.329798 -348.921299) (xy 171.283917 -348.891812) (xy 171.242699 -348.856095) (xy 171.206984 -348.814877)
			(xy 171.177498 -348.768995) (xy 171.154841 -348.719384) (xy 171.139476 -348.667054) (xy 171.131714 -348.61307)
			(xy 169.648866 -348.61307) (xy 169.641105 -348.667047) (xy 169.625742 -348.719372) (xy 169.603088 -348.768979)
			(xy 169.573606 -348.814857) (xy 169.537895 -348.856073) (xy 169.496683 -348.891787) (xy 169.450807 -348.921273)
			(xy 169.401202 -348.943931) (xy 169.348878 -348.959298) (xy 169.294899 -348.967063) (xy 169.267632 -348.967552)
			(xy 168.404032 -348.967552) (xy 168.376759 -348.967111) (xy 168.322767 -348.959352) (xy 168.270429 -348.943988)
			(xy 168.220811 -348.921332) (xy 168.174922 -348.891844) (xy 168.133697 -348.856126) (xy 168.097975 -348.814904)
			(xy 168.068484 -348.769017) (xy 168.045823 -348.719401) (xy 168.030455 -348.667064) (xy 168.022692 -348.613073)
			(xy 166.539988 -348.613073) (xy 166.532226 -348.667059) (xy 166.516859 -348.719393) (xy 166.494199 -348.769007)
			(xy 166.46471 -348.814891) (xy 166.42899 -348.85611) (xy 166.387768 -348.891827) (xy 166.341882 -348.921313)
			(xy 166.292267 -348.943968) (xy 166.239932 -348.959332) (xy 166.185944 -348.96709) (xy 166.158672 -348.967552)
			(xy 165.295072 -348.967552) (xy 165.267803 -348.967084) (xy 165.213821 -348.959319) (xy 165.161494 -348.94395)
			(xy 165.111886 -348.921292) (xy 165.066007 -348.891805) (xy 165.024792 -348.856088) (xy 164.989079 -348.81487)
			(xy 164.959595 -348.76899) (xy 164.93694 -348.71938) (xy 164.921576 -348.667051) (xy 164.913814 -348.613069)
			(xy 163.430966 -348.613069) (xy 163.423204 -348.667049) (xy 163.40784 -348.719376) (xy 163.385185 -348.768985)
			(xy 163.355701 -348.814864) (xy 163.319988 -348.85608) (xy 163.278773 -348.891794) (xy 163.232895 -348.92128)
			(xy 163.183288 -348.943936) (xy 163.130961 -348.959302) (xy 163.07698 -348.967065) (xy 163.049712 -348.967552)
			(xy 162.186112 -348.967552) (xy 162.15884 -348.967109) (xy 162.10485 -348.959348) (xy 162.052515 -348.943983)
			(xy 162.002899 -348.921325) (xy 161.957012 -348.891837) (xy 161.91579 -348.856119) (xy 161.88007 -348.814897)
			(xy 161.850581 -348.769012) (xy 161.827921 -348.719397) (xy 161.812554 -348.667062) (xy 161.804792 -348.613072)
			(xy 144.196565 -348.613072) (xy 144.188804 -348.66705) (xy 144.17344 -348.719377) (xy 144.150785 -348.768986)
			(xy 144.1213 -348.814865) (xy 144.085587 -348.856081) (xy 144.044371 -348.891796) (xy 143.998493 -348.921281)
			(xy 143.948885 -348.943937) (xy 143.896558 -348.959303) (xy 143.842576 -348.967065) (xy 143.815308 -348.967552)
			(xy 142.951708 -348.967552) (xy 142.924436 -348.967109) (xy 142.870447 -348.959348) (xy 142.818112 -348.943982)
			(xy 142.768496 -348.921324) (xy 142.72261 -348.891836) (xy 142.681388 -348.856117) (xy 142.645669 -348.814896)
			(xy 142.61618 -348.769011) (xy 142.593521 -348.719396) (xy 142.578154 -348.667061) (xy 142.570392 -348.613072)
			(xy 141.087565 -348.613072) (xy 141.079806 -348.667044) (xy 141.064443 -348.719369) (xy 141.041791 -348.768974)
			(xy 141.01231 -348.814852) (xy 140.976601 -348.856067) (xy 140.93539 -348.891781) (xy 140.889517 -348.921268)
			(xy 140.839914 -348.943926) (xy 140.787591 -348.959295) (xy 140.733614 -348.967062) (xy 140.706348 -348.967552)
			(xy 139.842748 -348.967552) (xy 139.815474 -348.967112) (xy 139.761481 -348.959355) (xy 139.709141 -348.943992)
			(xy 139.65952 -348.921337) (xy 139.613629 -348.89185) (xy 139.572402 -348.856132) (xy 139.536679 -348.814909)
			(xy 139.507186 -348.769022) (xy 139.484524 -348.719404) (xy 139.469155 -348.667066) (xy 139.461392 -348.613074)
			(xy 137.978689 -348.613074) (xy 137.970926 -348.667057) (xy 137.95556 -348.71939) (xy 137.932902 -348.769002)
			(xy 137.903414 -348.814885) (xy 137.867696 -348.856105) (xy 137.826476 -348.891821) (xy 137.780592 -348.921308)
			(xy 137.730978 -348.943964) (xy 137.678646 -348.959329) (xy 137.624659 -348.967089) (xy 137.597388 -348.967552)
			(xy 136.733788 -348.967552) (xy 136.706518 -348.967085) (xy 136.652535 -348.959321) (xy 136.600205 -348.943955)
			(xy 136.550595 -348.921297) (xy 136.504715 -348.89181) (xy 136.463497 -348.856094) (xy 136.427783 -348.814876)
			(xy 136.398297 -348.768994) (xy 136.375641 -348.719383) (xy 136.360276 -348.667053) (xy 136.352514 -348.61307)
			(xy 134.869666 -348.61307) (xy 134.861905 -348.667047) (xy 134.846541 -348.719373) (xy 134.823888 -348.76898)
			(xy 134.794405 -348.814858) (xy 134.758694 -348.856074) (xy 134.717481 -348.891789) (xy 134.671605 -348.921274)
			(xy 134.621999 -348.943932) (xy 134.569675 -348.959299) (xy 134.515695 -348.967064) (xy 134.488428 -348.967552)
			(xy 133.624828 -348.967552) (xy 133.597555 -348.96711) (xy 133.543564 -348.959351) (xy 133.491226 -348.943987)
			(xy 133.441608 -348.92133) (xy 133.39572 -348.891843) (xy 133.354495 -348.856124) (xy 133.318774 -348.814903)
			(xy 133.289283 -348.769016) (xy 133.266623 -348.7194) (xy 133.251255 -348.667064) (xy 133.243492 -348.613073)
			(xy 131.760788 -348.613073) (xy 131.753026 -348.66706) (xy 131.737658 -348.719394) (xy 131.714999 -348.769008)
			(xy 131.685509 -348.814892) (xy 131.649789 -348.856112) (xy 131.608566 -348.891828) (xy 131.56268 -348.921314)
			(xy 131.513064 -348.943969) (xy 131.460729 -348.959332) (xy 131.40674 -348.967091) (xy 131.379468 -348.967552)
			(xy 130.515868 -348.967552) (xy 130.488599 -348.967083) (xy 130.434618 -348.959318) (xy 130.382291 -348.943949)
			(xy 130.332683 -348.921291) (xy 130.286805 -348.891803) (xy 130.24559 -348.856087) (xy 130.209878 -348.814869)
			(xy 130.180394 -348.768989) (xy 130.15774 -348.719379) (xy 130.142375 -348.667051) (xy 130.134614 -348.613069)
			(xy 128.651766 -348.613069) (xy 128.644004 -348.66705) (xy 128.62864 -348.719377) (xy 128.605985 -348.768986)
			(xy 128.5765 -348.814865) (xy 128.540787 -348.856081) (xy 128.499571 -348.891796) (xy 128.453693 -348.921281)
			(xy 128.404085 -348.943937) (xy 128.351758 -348.959303) (xy 128.297776 -348.967065) (xy 128.270508 -348.967552)
			(xy 127.406908 -348.967552) (xy 127.379636 -348.967109) (xy 127.325647 -348.959348) (xy 127.273312 -348.943982)
			(xy 127.223696 -348.921324) (xy 127.17781 -348.891836) (xy 127.136588 -348.856117) (xy 127.100869 -348.814896)
			(xy 127.07138 -348.769011) (xy 127.048721 -348.719396) (xy 127.033354 -348.667061) (xy 127.025592 -348.613072)
			(xy 125.542765 -348.613072) (xy 125.535006 -348.667044) (xy 125.519643 -348.719369) (xy 125.496991 -348.768974)
			(xy 125.46751 -348.814852) (xy 125.431801 -348.856067) (xy 125.39059 -348.891781) (xy 125.344717 -348.921268)
			(xy 125.295114 -348.943926) (xy 125.242791 -348.959295) (xy 125.188814 -348.967062) (xy 125.161548 -348.967552)
			(xy 124.297948 -348.967552) (xy 124.270674 -348.967112) (xy 124.216681 -348.959355) (xy 124.164341 -348.943992)
			(xy 124.11472 -348.921337) (xy 124.068829 -348.89185) (xy 124.027602 -348.856132) (xy 123.991879 -348.814909)
			(xy 123.962386 -348.769022) (xy 123.939724 -348.719404) (xy 123.924355 -348.667066) (xy 123.916592 -348.613074)
			(xy 122.433889 -348.613074) (xy 122.426126 -348.667057) (xy 122.41076 -348.71939) (xy 122.388102 -348.769002)
			(xy 122.358614 -348.814885) (xy 122.322896 -348.856105) (xy 122.281676 -348.891821) (xy 122.235792 -348.921308)
			(xy 122.186178 -348.943964) (xy 122.133846 -348.959329) (xy 122.079859 -348.967089) (xy 122.052588 -348.967552)
			(xy 121.188988 -348.967552) (xy 121.161718 -348.967085) (xy 121.107735 -348.959321) (xy 121.055405 -348.943955)
			(xy 121.005795 -348.921297) (xy 120.959915 -348.89181) (xy 120.918697 -348.856094) (xy 120.882983 -348.814876)
			(xy 120.853497 -348.768994) (xy 120.830841 -348.719383) (xy 120.815476 -348.667053) (xy 120.807714 -348.61307)
			(xy 119.324866 -348.61307) (xy 119.317105 -348.667047) (xy 119.301741 -348.719373) (xy 119.279088 -348.76898)
			(xy 119.249605 -348.814858) (xy 119.213894 -348.856074) (xy 119.172681 -348.891789) (xy 119.126805 -348.921274)
			(xy 119.077199 -348.943932) (xy 119.024875 -348.959299) (xy 118.970895 -348.967064) (xy 118.943628 -348.967552)
			(xy 118.080028 -348.967552) (xy 118.052755 -348.96711) (xy 117.998764 -348.959351) (xy 117.946426 -348.943987)
			(xy 117.896808 -348.92133) (xy 117.85092 -348.891843) (xy 117.809695 -348.856124) (xy 117.773974 -348.814903)
			(xy 117.744483 -348.769016) (xy 117.721823 -348.7194) (xy 117.706455 -348.667064) (xy 117.698692 -348.613073)
			(xy 116.215988 -348.613073) (xy 116.208226 -348.66706) (xy 116.192858 -348.719394) (xy 116.170199 -348.769008)
			(xy 116.140709 -348.814892) (xy 116.104989 -348.856112) (xy 116.063766 -348.891828) (xy 116.01788 -348.921314)
			(xy 115.968264 -348.943969) (xy 115.915929 -348.959332) (xy 115.86194 -348.967091) (xy 115.834668 -348.967552)
			(xy 114.971068 -348.967552) (xy 114.943799 -348.967083) (xy 114.889818 -348.959318) (xy 114.837491 -348.943949)
			(xy 114.787883 -348.921291) (xy 114.742005 -348.891803) (xy 114.70079 -348.856087) (xy 114.665078 -348.814869)
			(xy 114.635594 -348.768989) (xy 114.61294 -348.719379) (xy 114.597575 -348.667051) (xy 114.589814 -348.613069)
			(xy 113.106966 -348.613069) (xy 113.099204 -348.66705) (xy 113.08384 -348.719377) (xy 113.061185 -348.768986)
			(xy 113.0317 -348.814865) (xy 112.995987 -348.856081) (xy 112.954771 -348.891796) (xy 112.908893 -348.921281)
			(xy 112.859285 -348.943937) (xy 112.806958 -348.959303) (xy 112.752976 -348.967065) (xy 112.725708 -348.967552)
			(xy 111.862108 -348.967552) (xy 111.834836 -348.967109) (xy 111.780847 -348.959348) (xy 111.728512 -348.943982)
			(xy 111.678896 -348.921324) (xy 111.63301 -348.891836) (xy 111.591788 -348.856117) (xy 111.556069 -348.814896)
			(xy 111.52658 -348.769011) (xy 111.503921 -348.719396) (xy 111.488554 -348.667061) (xy 111.480792 -348.613072)
			(xy 93.706665 -348.613072) (xy 93.698905 -348.667045) (xy 93.683543 -348.71937) (xy 93.66089 -348.768976)
			(xy 93.631409 -348.814854) (xy 93.595699 -348.856069) (xy 93.554487 -348.891784) (xy 93.508613 -348.92127)
			(xy 93.459009 -348.943928) (xy 93.406686 -348.959296) (xy 93.352709 -348.967063) (xy 93.325442 -348.967552)
			(xy 92.461842 -348.967552) (xy 92.434568 -348.967111) (xy 92.380576 -348.959354) (xy 92.328236 -348.943991)
			(xy 92.278617 -348.921335) (xy 92.232727 -348.891848) (xy 92.1915 -348.856129) (xy 92.155777 -348.814907)
			(xy 92.126285 -348.76902) (xy 92.103624 -348.719403) (xy 92.088255 -348.667066) (xy 92.080492 -348.613074)
			(xy 90.597788 -348.613074) (xy 90.590026 -348.667058) (xy 90.574659 -348.719391) (xy 90.552001 -348.769004)
			(xy 90.522512 -348.814887) (xy 90.486794 -348.856107) (xy 90.445573 -348.891823) (xy 90.399688 -348.92131)
			(xy 90.350074 -348.943966) (xy 90.297741 -348.95933) (xy 90.243753 -348.96709) (xy 90.216482 -348.967552)
			(xy 89.352882 -348.967552) (xy 89.325613 -348.967084) (xy 89.27163 -348.95932) (xy 89.219301 -348.943953)
			(xy 89.169692 -348.921295) (xy 89.123812 -348.891808) (xy 89.082595 -348.856092) (xy 89.046881 -348.814874)
			(xy 89.017396 -348.768992) (xy 88.994741 -348.719382) (xy 88.979376 -348.667053) (xy 88.971614 -348.613069)
			(xy 87.488766 -348.613069) (xy 87.481005 -348.667048) (xy 87.465641 -348.719374) (xy 87.442987 -348.768982)
			(xy 87.413504 -348.81486) (xy 87.377792 -348.856076) (xy 87.336578 -348.891791) (xy 87.290701 -348.921276)
			(xy 87.241095 -348.943933) (xy 87.188769 -348.9593) (xy 87.13479 -348.967064) (xy 87.107522 -348.967552)
			(xy 86.243922 -348.967552) (xy 86.216649 -348.96711) (xy 86.162659 -348.95935) (xy 86.110322 -348.943985)
			(xy 86.060705 -348.921329) (xy 86.014817 -348.891841) (xy 85.973593 -348.856122) (xy 85.937872 -348.814901)
			(xy 85.908382 -348.769015) (xy 85.885722 -348.719399) (xy 85.870354 -348.667063) (xy 85.862592 -348.613073)
			(xy 84.379888 -348.613073) (xy 84.372126 -348.667061) (xy 84.356758 -348.719395) (xy 84.334098 -348.76901)
			(xy 84.304608 -348.814894) (xy 84.268887 -348.856114) (xy 84.227663 -348.89183) (xy 84.181776 -348.921316)
			(xy 84.13216 -348.943971) (xy 84.079824 -348.959334) (xy 84.025834 -348.967091) (xy 83.998562 -348.967552)
			(xy 83.134962 -348.967552) (xy 83.107694 -348.967083) (xy 83.053713 -348.959317) (xy 83.001386 -348.943948)
			(xy 82.95178 -348.921289) (xy 82.905902 -348.891801) (xy 82.864688 -348.856085) (xy 82.828976 -348.814867)
			(xy 82.799493 -348.768987) (xy 82.776839 -348.719378) (xy 82.761475 -348.66705) (xy 82.753714 -348.613068)
			(xy 81.270866 -348.613068) (xy 81.270866 -348.613069) (xy 81.263104 -348.667051) (xy 81.247739 -348.719379)
			(xy 81.225084 -348.768987) (xy 81.195599 -348.814867) (xy 81.159885 -348.856083) (xy 81.118669 -348.891798)
			(xy 81.072789 -348.921283) (xy 81.02318 -348.943939) (xy 80.970853 -348.959304) (xy 80.916871 -348.967065)
			(xy 80.889602 -348.967552) (xy 80.026002 -348.967552) (xy 79.99873 -348.967109) (xy 79.944742 -348.959347)
			(xy 79.892407 -348.94398) (xy 79.842793 -348.921322) (xy 79.796908 -348.891834) (xy 79.755686 -348.856115)
			(xy 79.719968 -348.814894) (xy 79.690479 -348.769009) (xy 79.667821 -348.719394) (xy 79.652454 -348.66706)
			(xy 79.644692 -348.613072) (xy 78.161865 -348.613072) (xy 78.154105 -348.667045) (xy 78.138743 -348.71937)
			(xy 78.11609 -348.768976) (xy 78.086609 -348.814854) (xy 78.050899 -348.856069) (xy 78.009687 -348.891784)
			(xy 77.963813 -348.92127) (xy 77.914209 -348.943928) (xy 77.861886 -348.959296) (xy 77.807909 -348.967063)
			(xy 77.780642 -348.967552) (xy 76.917042 -348.967552) (xy 76.889768 -348.967111) (xy 76.835776 -348.959354)
			(xy 76.783436 -348.943991) (xy 76.733817 -348.921335) (xy 76.687927 -348.891848) (xy 76.6467 -348.856129)
			(xy 76.610977 -348.814907) (xy 76.581485 -348.76902) (xy 76.558824 -348.719403) (xy 76.543455 -348.667066)
			(xy 76.535692 -348.613074) (xy 75.052988 -348.613074) (xy 75.045226 -348.667058) (xy 75.029859 -348.719391)
			(xy 75.007201 -348.769004) (xy 74.977712 -348.814887) (xy 74.941994 -348.856107) (xy 74.900773 -348.891823)
			(xy 74.854888 -348.92131) (xy 74.805274 -348.943966) (xy 74.752941 -348.95933) (xy 74.698953 -348.96709)
			(xy 74.671682 -348.967552) (xy 73.808082 -348.967552) (xy 73.780813 -348.967084) (xy 73.72683 -348.95932)
			(xy 73.674501 -348.943953) (xy 73.624892 -348.921295) (xy 73.579012 -348.891808) (xy 73.537795 -348.856092)
			(xy 73.502081 -348.814874) (xy 73.472596 -348.768992) (xy 73.449941 -348.719382) (xy 73.434576 -348.667053)
			(xy 73.426814 -348.613069) (xy 71.943966 -348.613069) (xy 71.936205 -348.667048) (xy 71.920841 -348.719374)
			(xy 71.898187 -348.768982) (xy 71.868704 -348.81486) (xy 71.832992 -348.856076) (xy 71.791778 -348.891791)
			(xy 71.745901 -348.921276) (xy 71.696295 -348.943933) (xy 71.643969 -348.9593) (xy 71.58999 -348.967064)
			(xy 71.562722 -348.967552) (xy 70.699122 -348.967552) (xy 70.671849 -348.96711) (xy 70.617859 -348.95935)
			(xy 70.565522 -348.943985) (xy 70.515905 -348.921329) (xy 70.470017 -348.891841) (xy 70.428793 -348.856122)
			(xy 70.393072 -348.814901) (xy 70.363582 -348.769015) (xy 70.340922 -348.719399) (xy 70.325554 -348.667063)
			(xy 70.317792 -348.613073) (xy 68.835088 -348.613073) (xy 68.827326 -348.667061) (xy 68.811958 -348.719395)
			(xy 68.789298 -348.76901) (xy 68.759808 -348.814894) (xy 68.724087 -348.856114) (xy 68.682863 -348.89183)
			(xy 68.636976 -348.921316) (xy 68.58736 -348.943971) (xy 68.535024 -348.959334) (xy 68.481034 -348.967091)
			(xy 68.453762 -348.967552) (xy 67.590162 -348.967552) (xy 67.562894 -348.967083) (xy 67.508913 -348.959317)
			(xy 67.456586 -348.943948) (xy 67.40698 -348.921289) (xy 67.361102 -348.891801) (xy 67.319888 -348.856085)
			(xy 67.284176 -348.814867) (xy 67.254693 -348.768987) (xy 67.232039 -348.719378) (xy 67.216675 -348.66705)
			(xy 67.208914 -348.613068) (xy 65.726066 -348.613068) (xy 65.726066 -348.613069) (xy 65.718304 -348.667051)
			(xy 65.702939 -348.719379) (xy 65.680284 -348.768987) (xy 65.650799 -348.814867) (xy 65.615085 -348.856083)
			(xy 65.573869 -348.891798) (xy 65.527989 -348.921283) (xy 65.47838 -348.943939) (xy 65.426053 -348.959304)
			(xy 65.372071 -348.967065) (xy 65.344802 -348.967552) (xy 64.481202 -348.967552) (xy 64.45393 -348.967109)
			(xy 64.399942 -348.959347) (xy 64.347607 -348.94398) (xy 64.297993 -348.921322) (xy 64.252108 -348.891834)
			(xy 64.210886 -348.856115) (xy 64.175168 -348.814894) (xy 64.145679 -348.769009) (xy 64.123021 -348.719394)
			(xy 64.107654 -348.66706) (xy 64.099892 -348.613072) (xy 62.617065 -348.613072) (xy 62.609305 -348.667045)
			(xy 62.593943 -348.71937) (xy 62.57129 -348.768976) (xy 62.541809 -348.814854) (xy 62.506099 -348.856069)
			(xy 62.464887 -348.891784) (xy 62.419013 -348.92127) (xy 62.369409 -348.943928) (xy 62.317086 -348.959296)
			(xy 62.263109 -348.967063) (xy 62.235842 -348.967552) (xy 61.372242 -348.967552) (xy 61.344968 -348.967111)
			(xy 61.290976 -348.959354) (xy 61.238636 -348.943991) (xy 61.189017 -348.921335) (xy 61.143127 -348.891848)
			(xy 61.1019 -348.856129) (xy 61.066177 -348.814907) (xy 61.036685 -348.76902) (xy 61.014024 -348.719403)
			(xy 60.998655 -348.667066) (xy 60.990892 -348.613074) (xy 51.666865 -348.613074) (xy 51.659106 -348.667044)
			(xy 51.643743 -348.719369) (xy 51.621091 -348.768974) (xy 51.59161 -348.814852) (xy 51.555901 -348.856067)
			(xy 51.51469 -348.891781) (xy 51.468817 -348.921268) (xy 51.419214 -348.943926) (xy 51.366891 -348.959295)
			(xy 51.312914 -348.967062) (xy 51.285648 -348.967552) (xy 50.422048 -348.967552) (xy 50.394774 -348.967112)
			(xy 50.340781 -348.959355) (xy 50.288441 -348.943992) (xy 50.23882 -348.921337) (xy 50.192929 -348.89185)
			(xy 50.151702 -348.856132) (xy 50.115979 -348.814909) (xy 50.086486 -348.769022) (xy 50.063824 -348.719404)
			(xy 50.048455 -348.667066) (xy 50.040692 -348.613074) (xy 48.557989 -348.613074) (xy 48.550226 -348.667057)
			(xy 48.53486 -348.71939) (xy 48.512202 -348.769002) (xy 48.482714 -348.814885) (xy 48.446996 -348.856105)
			(xy 48.405776 -348.891821) (xy 48.359892 -348.921308) (xy 48.310278 -348.943964) (xy 48.257946 -348.959329)
			(xy 48.203959 -348.967089) (xy 48.176688 -348.967552) (xy 47.313088 -348.967552) (xy 47.285818 -348.967085)
			(xy 47.231835 -348.959321) (xy 47.179505 -348.943955) (xy 47.129895 -348.921297) (xy 47.084015 -348.89181)
			(xy 47.042797 -348.856094) (xy 47.007083 -348.814876) (xy 46.977597 -348.768994) (xy 46.954941 -348.719383)
			(xy 46.939576 -348.667053) (xy 46.931814 -348.61307) (xy 45.448966 -348.61307) (xy 45.441205 -348.667047)
			(xy 45.425841 -348.719373) (xy 45.403188 -348.76898) (xy 45.373705 -348.814858) (xy 45.337994 -348.856074)
			(xy 45.296781 -348.891789) (xy 45.250905 -348.921274) (xy 45.201299 -348.943932) (xy 45.148975 -348.959299)
			(xy 45.094995 -348.967064) (xy 45.067728 -348.967552) (xy 44.204128 -348.967552) (xy 44.176855 -348.96711)
			(xy 44.122864 -348.959351) (xy 44.070526 -348.943987) (xy 44.020908 -348.92133) (xy 43.97502 -348.891843)
			(xy 43.933795 -348.856124) (xy 43.898074 -348.814903) (xy 43.868583 -348.769016) (xy 43.845923 -348.7194)
			(xy 43.830555 -348.667064) (xy 43.822792 -348.613073) (xy 42.340088 -348.613073) (xy 42.332326 -348.66706)
			(xy 42.316958 -348.719394) (xy 42.294299 -348.769008) (xy 42.264809 -348.814892) (xy 42.229089 -348.856112)
			(xy 42.187866 -348.891828) (xy 42.14198 -348.921314) (xy 42.092364 -348.943969) (xy 42.040029 -348.959332)
			(xy 41.98604 -348.967091) (xy 41.958768 -348.967552) (xy 41.095168 -348.967552) (xy 41.067899 -348.967083)
			(xy 41.013918 -348.959318) (xy 40.961591 -348.943949) (xy 40.911983 -348.921291) (xy 40.866105 -348.891803)
			(xy 40.82489 -348.856087) (xy 40.789178 -348.814869) (xy 40.759694 -348.768989) (xy 40.73704 -348.719379)
			(xy 40.721675 -348.667051) (xy 40.713914 -348.613069) (xy 39.231066 -348.613069) (xy 39.223304 -348.66705)
			(xy 39.20794 -348.719377) (xy 39.185285 -348.768986) (xy 39.1558 -348.814865) (xy 39.120087 -348.856081)
			(xy 39.078871 -348.891796) (xy 39.032993 -348.921281) (xy 38.983385 -348.943937) (xy 38.931058 -348.959303)
			(xy 38.877076 -348.967065) (xy 38.849808 -348.967552) (xy 37.986208 -348.967552) (xy 37.958936 -348.967109)
			(xy 37.904947 -348.959348) (xy 37.852612 -348.943982) (xy 37.802996 -348.921324) (xy 37.75711 -348.891836)
			(xy 37.715888 -348.856117) (xy 37.680169 -348.814896) (xy 37.65068 -348.769011) (xy 37.628021 -348.719396)
			(xy 37.612654 -348.667061) (xy 37.604892 -348.613072) (xy 36.122065 -348.613072) (xy 36.114306 -348.667044)
			(xy 36.098943 -348.719369) (xy 36.076291 -348.768974) (xy 36.04681 -348.814852) (xy 36.011101 -348.856067)
			(xy 35.96989 -348.891781) (xy 35.924017 -348.921268) (xy 35.874414 -348.943926) (xy 35.822091 -348.959295)
			(xy 35.768114 -348.967062) (xy 35.740848 -348.967552) (xy 34.877248 -348.967552) (xy 34.849974 -348.967112)
			(xy 34.795981 -348.959355) (xy 34.743641 -348.943992) (xy 34.69402 -348.921337) (xy 34.648129 -348.89185)
			(xy 34.606902 -348.856132) (xy 34.571179 -348.814909) (xy 34.541686 -348.769022) (xy 34.519024 -348.719404)
			(xy 34.503655 -348.667066) (xy 34.495892 -348.613074) (xy 33.013189 -348.613074) (xy 33.005426 -348.667057)
			(xy 32.99006 -348.71939) (xy 32.967402 -348.769002) (xy 32.937914 -348.814885) (xy 32.902196 -348.856105)
			(xy 32.860976 -348.891821) (xy 32.815092 -348.921308) (xy 32.765478 -348.943964) (xy 32.713146 -348.959329)
			(xy 32.659159 -348.967089) (xy 32.631888 -348.967552) (xy 31.768288 -348.967552) (xy 31.741018 -348.967085)
			(xy 31.687035 -348.959321) (xy 31.634705 -348.943955) (xy 31.585095 -348.921297) (xy 31.539215 -348.89181)
			(xy 31.497997 -348.856094) (xy 31.462283 -348.814876) (xy 31.432797 -348.768994) (xy 31.410141 -348.719383)
			(xy 31.394776 -348.667053) (xy 31.387014 -348.61307) (xy 29.904166 -348.61307) (xy 29.896405 -348.667047)
			(xy 29.881041 -348.719373) (xy 29.858388 -348.76898) (xy 29.828905 -348.814858) (xy 29.793194 -348.856074)
			(xy 29.751981 -348.891789) (xy 29.706105 -348.921274) (xy 29.656499 -348.943932) (xy 29.604175 -348.959299)
			(xy 29.550195 -348.967064) (xy 29.522928 -348.967552) (xy 28.659328 -348.967552) (xy 28.632055 -348.96711)
			(xy 28.578064 -348.959351) (xy 28.525726 -348.943987) (xy 28.476108 -348.92133) (xy 28.43022 -348.891843)
			(xy 28.388995 -348.856124) (xy 28.353274 -348.814903) (xy 28.323783 -348.769016) (xy 28.301123 -348.7194)
			(xy 28.285755 -348.667064) (xy 28.277992 -348.613073) (xy 26.795288 -348.613073) (xy 26.787526 -348.66706)
			(xy 26.772158 -348.719394) (xy 26.749499 -348.769008) (xy 26.720009 -348.814892) (xy 26.684289 -348.856112)
			(xy 26.643066 -348.891828) (xy 26.59718 -348.921314) (xy 26.547564 -348.943969) (xy 26.495229 -348.959332)
			(xy 26.44124 -348.967091) (xy 26.413968 -348.967552) (xy 25.550368 -348.967552) (xy 25.523099 -348.967083)
			(xy 25.469118 -348.959318) (xy 25.416791 -348.943949) (xy 25.367183 -348.921291) (xy 25.321305 -348.891803)
			(xy 25.28009 -348.856087) (xy 25.244378 -348.814869) (xy 25.214894 -348.768989) (xy 25.19224 -348.719379)
			(xy 25.176875 -348.667051) (xy 25.169114 -348.613069) (xy 23.686266 -348.613069) (xy 23.678504 -348.66705)
			(xy 23.66314 -348.719377) (xy 23.640485 -348.768986) (xy 23.611 -348.814865) (xy 23.575287 -348.856081)
			(xy 23.534071 -348.891796) (xy 23.488193 -348.921281) (xy 23.438585 -348.943937) (xy 23.386258 -348.959303)
			(xy 23.332276 -348.967065) (xy 23.305008 -348.967552) (xy 22.441408 -348.967552) (xy 22.414136 -348.967109)
			(xy 22.360147 -348.959348) (xy 22.307812 -348.943982) (xy 22.258196 -348.921324) (xy 22.21231 -348.891836)
			(xy 22.171088 -348.856117) (xy 22.135369 -348.814896) (xy 22.10588 -348.769011) (xy 22.083221 -348.719396)
			(xy 22.067854 -348.667061) (xy 22.060092 -348.613072) (xy 20.577347 -348.613072) (xy 20.569586 -348.667048)
			(xy 20.55422 -348.719381) (xy 20.531562 -348.768994) (xy 20.502074 -348.814878) (xy 20.466357 -348.856098)
			(xy 20.425136 -348.891816) (xy 20.379253 -348.921303) (xy 20.329639 -348.943961) (xy 20.277306 -348.959327)
			(xy 20.223319 -348.967089) (xy 20.196048 -348.967552) (xy 19.332448 -348.967552) (xy 19.305179 -348.967065)
			(xy 19.251195 -348.959304) (xy 19.198866 -348.943938) (xy 19.149256 -348.921282) (xy 19.103375 -348.891796)
			(xy 19.062158 -348.856081) (xy 19.026443 -348.814863) (xy 18.996957 -348.768982) (xy 18.974301 -348.719372)
			(xy 18.958936 -348.667043) (xy 18.951174 -348.613059) (xy 8.879169 -348.613059) (xy 8.892221 -348.718461)
			(xy 8.900171 -348.847356) (xy 8.900668 -348.911926) (xy 8.900171 -348.976496) (xy 8.892221 -349.105391)
			(xy 8.876351 -349.233551) (xy 8.852622 -349.360492) (xy 8.821123 -349.485731) (xy 8.781974 -349.608794)
			(xy 8.735323 -349.729213) (xy 8.681348 -349.846532) (xy 8.620253 -349.960306) (xy 8.55227 -350.070103)
			(xy 8.477656 -350.175506) (xy 8.396695 -350.276116) (xy 8.309695 -350.371551) (xy 8.216984 -350.46145)
			(xy 8.118914 -350.545471) (xy 8.015859 -350.623295) (xy 7.908208 -350.694627) (xy 7.796369 -350.759197)
			(xy 7.680768 -350.816759) (xy 7.561843 -350.867096) (xy 7.440044 -350.910016) (xy 7.315834 -350.945357)
			(xy 7.189685 -350.972984) (xy 7.062073 -350.992793) (xy 6.933484 -351.004709) (xy 6.804406 -351.008686)
			(xy 6.675328 -351.004709) (xy 6.546739 -350.992793) (xy 6.419127 -350.972984) (xy 6.292978 -350.945357)
			(xy 6.168768 -350.910016) (xy 6.046969 -350.867096) (xy 5.928044 -350.816759) (xy 5.812443 -350.759197)
			(xy 5.700604 -350.694627) (xy 5.592953 -350.623295) (xy 5.489898 -350.545471) (xy 5.391828 -350.46145)
			(xy 5.299117 -350.371551) (xy 5.212117 -350.276116) (xy 5.131156 -350.175506) (xy 5.056542 -350.070103)
			(xy 4.988559 -349.960306) (xy 4.927464 -349.846532) (xy 4.873489 -349.729213) (xy 4.826838 -349.608794)
			(xy 4.787689 -349.485731) (xy 4.75619 -349.360492) (xy 4.732461 -349.233551) (xy 4.716591 -349.105391)
			(xy 4.708641 -348.976496) (xy 1.524 -348.976496) (xy 1.524 -351.638709) (xy 18.951172 -351.638709)
			(xy 18.951172 -351.584171) (xy 18.958934 -351.530187) (xy 18.974299 -351.477857) (xy 18.996956 -351.428247)
			(xy 19.026441 -351.382366) (xy 19.062157 -351.341148) (xy 19.103374 -351.305433) (xy 19.149255 -351.275947)
			(xy 19.198865 -351.25329) (xy 19.251195 -351.237925) (xy 19.305179 -351.230163) (xy 19.332448 -351.229676)
			(xy 20.196048 -351.229676) (xy 20.223319 -351.230143) (xy 20.277306 -351.237905) (xy 20.329638 -351.253271)
			(xy 20.379252 -351.275929) (xy 20.425135 -351.305416) (xy 20.466355 -351.341133) (xy 20.502073 -351.382353)
			(xy 20.53156 -351.428237) (xy 20.554218 -351.47785) (xy 20.569584 -351.530182) (xy 20.577347 -351.584169)
			(xy 20.577347 -351.638669) (xy 22.060139 -351.638669) (xy 22.060139 -351.584131) (xy 22.067901 -351.530149)
			(xy 22.083266 -351.477821) (xy 22.105922 -351.428212) (xy 22.135407 -351.382333) (xy 22.171122 -351.341117)
			(xy 22.212339 -351.305403) (xy 22.258219 -351.275918) (xy 22.307829 -351.253263) (xy 22.360157 -351.237899)
			(xy 22.414139 -351.230139) (xy 22.441408 -351.229676) (xy 23.305008 -351.229676) (xy 23.33228 -351.230087)
			(xy 23.386268 -351.23785) (xy 23.438602 -351.253218) (xy 23.488216 -351.275877) (xy 23.5341 -351.305366)
			(xy 23.575321 -351.341085) (xy 23.611039 -351.382306) (xy 23.640527 -351.428191) (xy 23.663185 -351.477806)
			(xy 23.678551 -351.53014) (xy 23.686314 -351.584128) (xy 23.686314 -351.638665) (xy 25.169162 -351.638665)
			(xy 25.169162 -351.584135) (xy 25.176922 -351.530159) (xy 25.192284 -351.477838) (xy 25.214936 -351.428234)
			(xy 25.244416 -351.38236) (xy 25.280124 -351.341147) (xy 25.321334 -351.305435) (xy 25.367206 -351.275951)
			(xy 25.416808 -351.253296) (xy 25.469128 -351.237929) (xy 25.523103 -351.230165) (xy 25.550368 -351.229676)
			(xy 26.413968 -351.229676) (xy 26.441243 -351.230061) (xy 26.495239 -351.237821) (xy 26.547581 -351.253186)
			(xy 26.597203 -351.275844) (xy 26.643095 -351.305333) (xy 26.684323 -351.341054) (xy 26.720047 -351.382279)
			(xy 26.749541 -351.428169) (xy 26.772203 -351.477789) (xy 26.787573 -351.53013) (xy 26.795336 -351.584125)
			(xy 26.795336 -351.63867) (xy 28.278039 -351.63867) (xy 28.278039 -351.58413) (xy 28.285802 -351.530146)
			(xy 28.301168 -351.477817) (xy 28.323825 -351.428207) (xy 28.353312 -351.382326) (xy 28.389029 -351.341109)
			(xy 28.430249 -351.305396) (xy 28.476131 -351.275912) (xy 28.525743 -351.253258) (xy 28.578074 -351.237896)
			(xy 28.632058 -351.230137) (xy 28.659328 -351.229676) (xy 29.522928 -351.229676) (xy 29.550199 -351.230088)
			(xy 29.604185 -351.237854) (xy 29.656516 -351.253223) (xy 29.706128 -351.275883) (xy 29.75201 -351.305373)
			(xy 29.793228 -351.341092) (xy 29.828944 -351.382313) (xy 29.85843 -351.428197) (xy 29.881086 -351.47781)
			(xy 29.896452 -351.530143) (xy 29.904214 -351.584129) (xy 29.904214 -351.638666) (xy 31.387062 -351.638666)
			(xy 31.387062 -351.584134) (xy 31.394823 -351.530157) (xy 31.410186 -351.477833) (xy 31.432839 -351.428229)
			(xy 31.462321 -351.382353) (xy 31.498031 -351.34114) (xy 31.539243 -351.305428) (xy 31.585118 -351.275945)
			(xy 31.634722 -351.25329) (xy 31.687045 -351.237925) (xy 31.741022 -351.230163) (xy 31.768288 -351.229676)
			(xy 32.631888 -351.229676) (xy 32.659162 -351.230063) (xy 32.713156 -351.237824) (xy 32.765495 -351.253191)
			(xy 32.815115 -351.27585) (xy 32.861004 -351.30534) (xy 32.90223 -351.341061) (xy 32.937952 -351.382286)
			(xy 32.967444 -351.428175) (xy 32.990105 -351.477794) (xy 33.005473 -351.530132) (xy 33.013236 -351.584126)
			(xy 33.013236 -351.63867) (xy 34.49594 -351.63867) (xy 34.49594 -351.58413) (xy 34.503702 -351.530144)
			(xy 34.519069 -351.477812) (xy 34.541728 -351.428201) (xy 34.571217 -351.38232) (xy 34.606936 -351.341102)
			(xy 34.648158 -351.305388) (xy 34.694043 -351.275905) (xy 34.743658 -351.253253) (xy 34.795991 -351.237892)
			(xy 34.849977 -351.230136) (xy 34.877248 -351.229676) (xy 35.740848 -351.229676) (xy 35.768118 -351.23009)
			(xy 35.822102 -351.237858) (xy 35.874431 -351.253229) (xy 35.92404 -351.27589) (xy 35.969919 -351.30538)
			(xy 36.011135 -351.341099) (xy 36.046849 -351.382319) (xy 36.076333 -351.428203) (xy 36.098988 -351.477814)
			(xy 36.114352 -351.530145) (xy 36.122114 -351.58413) (xy 36.122114 -351.638669) (xy 37.604939 -351.638669)
			(xy 37.604939 -351.584131) (xy 37.612701 -351.530149) (xy 37.628066 -351.477821) (xy 37.650722 -351.428212)
			(xy 37.680207 -351.382333) (xy 37.715922 -351.341117) (xy 37.757139 -351.305403) (xy 37.803019 -351.275918)
			(xy 37.852629 -351.253263) (xy 37.904957 -351.237899) (xy 37.958939 -351.230139) (xy 37.986208 -351.229676)
			(xy 38.849808 -351.229676) (xy 38.87708 -351.230087) (xy 38.931068 -351.23785) (xy 38.983402 -351.253218)
			(xy 39.033016 -351.275877) (xy 39.0789 -351.305366) (xy 39.120121 -351.341085) (xy 39.155839 -351.382306)
			(xy 39.185327 -351.428191) (xy 39.207985 -351.477806) (xy 39.223351 -351.53014) (xy 39.231114 -351.584128)
			(xy 39.231114 -351.638665) (xy 40.713962 -351.638665) (xy 40.713962 -351.584135) (xy 40.721722 -351.530159)
			(xy 40.737084 -351.477838) (xy 40.759736 -351.428234) (xy 40.789216 -351.38236) (xy 40.824924 -351.341147)
			(xy 40.866134 -351.305435) (xy 40.912006 -351.275951) (xy 40.961608 -351.253296) (xy 41.013928 -351.237929)
			(xy 41.067903 -351.230165) (xy 41.095168 -351.229676) (xy 41.958768 -351.229676) (xy 41.986043 -351.230061)
			(xy 42.040039 -351.237821) (xy 42.092381 -351.253186) (xy 42.142003 -351.275844) (xy 42.187895 -351.305333)
			(xy 42.229123 -351.341054) (xy 42.264847 -351.382279) (xy 42.294341 -351.428169) (xy 42.317003 -351.477789)
			(xy 42.332373 -351.53013) (xy 42.340136 -351.584125) (xy 42.340136 -351.63867) (xy 43.822839 -351.63867)
			(xy 43.822839 -351.58413) (xy 43.830602 -351.530146) (xy 43.845968 -351.477817) (xy 43.868625 -351.428207)
			(xy 43.898112 -351.382326) (xy 43.933829 -351.341109) (xy 43.975049 -351.305396) (xy 44.020931 -351.275912)
			(xy 44.070543 -351.253258) (xy 44.122874 -351.237896) (xy 44.176858 -351.230137) (xy 44.204128 -351.229676)
			(xy 45.067728 -351.229676) (xy 45.094999 -351.230088) (xy 45.148985 -351.237854) (xy 45.201316 -351.253223)
			(xy 45.250928 -351.275883) (xy 45.29681 -351.305373) (xy 45.338028 -351.341092) (xy 45.373744 -351.382313)
			(xy 45.40323 -351.428197) (xy 45.425886 -351.47781) (xy 45.441252 -351.530143) (xy 45.449014 -351.584129)
			(xy 45.449014 -351.638666) (xy 46.931862 -351.638666) (xy 46.931862 -351.584134) (xy 46.939623 -351.530157)
			(xy 46.954986 -351.477833) (xy 46.977639 -351.428229) (xy 47.007121 -351.382353) (xy 47.042831 -351.34114)
			(xy 47.084043 -351.305428) (xy 47.129918 -351.275945) (xy 47.179522 -351.25329) (xy 47.231845 -351.237925)
			(xy 47.285822 -351.230163) (xy 47.313088 -351.229676) (xy 48.176688 -351.229676) (xy 48.203962 -351.230063)
			(xy 48.257956 -351.237824) (xy 48.310295 -351.253191) (xy 48.359915 -351.27585) (xy 48.405804 -351.30534)
			(xy 48.44703 -351.341061) (xy 48.482752 -351.382286) (xy 48.512244 -351.428175) (xy 48.534905 -351.477794)
			(xy 48.550273 -351.530132) (xy 48.558036 -351.584126) (xy 48.558036 -351.63867) (xy 50.04074 -351.63867)
			(xy 50.04074 -351.58413) (xy 50.048502 -351.530144) (xy 50.063869 -351.477812) (xy 50.086528 -351.428201)
			(xy 50.116017 -351.38232) (xy 50.151736 -351.341102) (xy 50.192958 -351.305388) (xy 50.238843 -351.275905)
			(xy 50.288458 -351.253253) (xy 50.340791 -351.237892) (xy 50.394777 -351.230136) (xy 50.422048 -351.229676)
			(xy 51.285648 -351.229676) (xy 51.312918 -351.23009) (xy 51.366902 -351.237858) (xy 51.419231 -351.253229)
			(xy 51.46884 -351.27589) (xy 51.514719 -351.30538) (xy 51.555935 -351.341099) (xy 51.591649 -351.382319)
			(xy 51.621133 -351.428203) (xy 51.643788 -351.477814) (xy 51.659152 -351.530145) (xy 51.666914 -351.58413)
			(xy 51.666914 -351.63867) (xy 60.99094 -351.63867) (xy 60.99094 -351.58413) (xy 60.998702 -351.530145)
			(xy 61.014069 -351.477814) (xy 61.036727 -351.428203) (xy 61.066216 -351.382322) (xy 61.101934 -351.341105)
			(xy 61.143155 -351.305391) (xy 61.18904 -351.275907) (xy 61.238653 -351.253254) (xy 61.290986 -351.237893)
			(xy 61.344972 -351.230137) (xy 61.372242 -351.229676) (xy 62.235842 -351.229676) (xy 62.263112 -351.230089)
			(xy 62.317097 -351.237857) (xy 62.369426 -351.253227) (xy 62.419036 -351.275888) (xy 62.464916 -351.305378)
			(xy 62.506133 -351.341097) (xy 62.541847 -351.382317) (xy 62.571332 -351.428201) (xy 62.593988 -351.477813)
			(xy 62.609352 -351.530145) (xy 62.617114 -351.58413) (xy 62.617114 -351.638668) (xy 64.099939 -351.638668)
			(xy 64.099939 -351.584132) (xy 64.107701 -351.53015) (xy 64.123066 -351.477822) (xy 64.145721 -351.428214)
			(xy 64.175206 -351.382335) (xy 64.21092 -351.341119) (xy 64.252136 -351.305405) (xy 64.298016 -351.27592)
			(xy 64.347624 -351.253265) (xy 64.399952 -351.2379) (xy 64.453934 -351.230139) (xy 64.481202 -351.229676)
			(xy 65.344802 -351.229676) (xy 65.372074 -351.230087) (xy 65.426063 -351.237849) (xy 65.478397 -351.253216)
			(xy 65.528012 -351.275875) (xy 65.573897 -351.305364) (xy 65.615119 -351.341083) (xy 65.650837 -351.382304)
			(xy 65.680326 -351.42819) (xy 65.702984 -351.477805) (xy 65.718351 -351.530139) (xy 65.726113 -351.584128)
			(xy 65.726113 -351.638665) (xy 67.208962 -351.638665) (xy 67.208962 -351.584135) (xy 67.216722 -351.53016)
			(xy 67.232084 -351.477839) (xy 67.254735 -351.428236) (xy 67.284215 -351.382362) (xy 67.319922 -351.341149)
			(xy 67.361131 -351.305437) (xy 67.407003 -351.275953) (xy 67.456603 -351.253297) (xy 67.508923 -351.23793)
			(xy 67.562897 -351.230165) (xy 67.590162 -351.229676) (xy 68.453762 -351.229676) (xy 68.481037 -351.230061)
			(xy 68.535034 -351.23782) (xy 68.587376 -351.253184) (xy 68.636999 -351.275842) (xy 68.682892 -351.305331)
			(xy 68.724121 -351.341052) (xy 68.759846 -351.382277) (xy 68.78934 -351.428167) (xy 68.812003 -351.477788)
			(xy 68.827372 -351.530129) (xy 68.835136 -351.584125) (xy 68.835136 -351.638669) (xy 70.317839 -351.638669)
			(xy 70.317839 -351.584131) (xy 70.325601 -351.530147) (xy 70.340967 -351.477818) (xy 70.363624 -351.428208)
			(xy 70.393111 -351.382328) (xy 70.428827 -351.341112) (xy 70.470046 -351.305398) (xy 70.515928 -351.275914)
			(xy 70.565539 -351.25326) (xy 70.617869 -351.237897) (xy 70.671853 -351.230138) (xy 70.699122 -351.229676)
			(xy 71.562722 -351.229676) (xy 71.589993 -351.230088) (xy 71.64398 -351.237853) (xy 71.696312 -351.253222)
			(xy 71.745924 -351.275881) (xy 71.791807 -351.305371) (xy 71.833026 -351.34109) (xy 71.868742 -351.382311)
			(xy 71.898229 -351.428195) (xy 71.920886 -351.477809) (xy 71.936252 -351.530142) (xy 71.944014 -351.584129)
			(xy 71.944014 -351.638666) (xy 73.426862 -351.638666) (xy 73.426862 -351.584134) (xy 73.434623 -351.530158)
			(xy 73.449986 -351.477835) (xy 73.472638 -351.428231) (xy 73.50212 -351.382355) (xy 73.537829 -351.341142)
			(xy 73.579041 -351.30543) (xy 73.624915 -351.275947) (xy 73.674518 -351.253292) (xy 73.72684 -351.237927)
			(xy 73.780816 -351.230164) (xy 73.808082 -351.229676) (xy 74.671682 -351.229676) (xy 74.698957 -351.230062)
			(xy 74.752951 -351.237823) (xy 74.805291 -351.253189) (xy 74.854911 -351.275848) (xy 74.900802 -351.305338)
			(xy 74.942028 -351.341059) (xy 74.977751 -351.382284) (xy 75.007243 -351.428173) (xy 75.029904 -351.477792)
			(xy 75.045273 -351.530132) (xy 75.053036 -351.584125) (xy 75.053036 -351.63867) (xy 76.53574 -351.63867)
			(xy 76.53574 -351.58413) (xy 76.543502 -351.530145) (xy 76.558869 -351.477814) (xy 76.581527 -351.428203)
			(xy 76.611016 -351.382322) (xy 76.646734 -351.341105) (xy 76.687955 -351.305391) (xy 76.73384 -351.275907)
			(xy 76.783453 -351.253254) (xy 76.835786 -351.237893) (xy 76.889772 -351.230137) (xy 76.917042 -351.229676)
			(xy 77.780642 -351.229676) (xy 77.807912 -351.230089) (xy 77.861897 -351.237857) (xy 77.914226 -351.253227)
			(xy 77.963836 -351.275888) (xy 78.009716 -351.305378) (xy 78.050933 -351.341097) (xy 78.086647 -351.382317)
			(xy 78.116132 -351.428201) (xy 78.138788 -351.477813) (xy 78.154152 -351.530145) (xy 78.161914 -351.58413)
			(xy 78.161914 -351.638668) (xy 79.644739 -351.638668) (xy 79.644739 -351.584132) (xy 79.652501 -351.53015)
			(xy 79.667866 -351.477822) (xy 79.690521 -351.428214) (xy 79.720006 -351.382335) (xy 79.75572 -351.341119)
			(xy 79.796936 -351.305405) (xy 79.842816 -351.27592) (xy 79.892424 -351.253265) (xy 79.944752 -351.2379)
			(xy 79.998734 -351.230139) (xy 80.026002 -351.229676) (xy 80.889602 -351.229676) (xy 80.916874 -351.230087)
			(xy 80.970863 -351.237849) (xy 81.023197 -351.253216) (xy 81.072812 -351.275875) (xy 81.118697 -351.305364)
			(xy 81.159919 -351.341083) (xy 81.195637 -351.382304) (xy 81.225126 -351.42819) (xy 81.247784 -351.477805)
			(xy 81.263151 -351.530139) (xy 81.270913 -351.584128) (xy 81.270913 -351.638665) (xy 82.753762 -351.638665)
			(xy 82.753762 -351.584135) (xy 82.761522 -351.53016) (xy 82.776884 -351.477839) (xy 82.799535 -351.428236)
			(xy 82.829015 -351.382362) (xy 82.864722 -351.341149) (xy 82.905931 -351.305437) (xy 82.951803 -351.275953)
			(xy 83.001403 -351.253297) (xy 83.053723 -351.23793) (xy 83.107697 -351.230165) (xy 83.134962 -351.229676)
			(xy 83.998562 -351.229676) (xy 84.025837 -351.230061) (xy 84.079834 -351.23782) (xy 84.132176 -351.253184)
			(xy 84.181799 -351.275842) (xy 84.227692 -351.305331) (xy 84.268921 -351.341052) (xy 84.304646 -351.382277)
			(xy 84.33414 -351.428167) (xy 84.356803 -351.477788) (xy 84.372172 -351.530129) (xy 84.379936 -351.584125)
			(xy 84.379936 -351.638669) (xy 85.862639 -351.638669) (xy 85.862639 -351.584131) (xy 85.870401 -351.530147)
			(xy 85.885767 -351.477818) (xy 85.908424 -351.428208) (xy 85.937911 -351.382328) (xy 85.973627 -351.341112)
			(xy 86.014846 -351.305398) (xy 86.060728 -351.275914) (xy 86.110339 -351.25326) (xy 86.162669 -351.237897)
			(xy 86.216653 -351.230138) (xy 86.243922 -351.229676) (xy 87.107522 -351.229676) (xy 87.134793 -351.230088)
			(xy 87.18878 -351.237853) (xy 87.241112 -351.253222) (xy 87.290724 -351.275881) (xy 87.336607 -351.305371)
			(xy 87.377826 -351.34109) (xy 87.413542 -351.382311) (xy 87.443029 -351.428195) (xy 87.465686 -351.477809)
			(xy 87.481052 -351.530142) (xy 87.488814 -351.584129) (xy 87.488814 -351.638666) (xy 88.971662 -351.638666)
			(xy 88.971662 -351.584134) (xy 88.979423 -351.530158) (xy 88.994786 -351.477835) (xy 89.017438 -351.428231)
			(xy 89.04692 -351.382355) (xy 89.082629 -351.341142) (xy 89.123841 -351.30543) (xy 89.169715 -351.275947)
			(xy 89.219318 -351.253292) (xy 89.27164 -351.237927) (xy 89.325616 -351.230164) (xy 89.352882 -351.229676)
			(xy 90.216482 -351.229676) (xy 90.243757 -351.230062) (xy 90.297751 -351.237823) (xy 90.350091 -351.253189)
			(xy 90.399711 -351.275848) (xy 90.445602 -351.305338) (xy 90.486828 -351.341059) (xy 90.522551 -351.382284)
			(xy 90.552043 -351.428173) (xy 90.574704 -351.477792) (xy 90.590073 -351.530132) (xy 90.597836 -351.584125)
			(xy 90.597836 -351.63867) (xy 92.08054 -351.63867) (xy 92.08054 -351.58413) (xy 92.088302 -351.530145)
			(xy 92.103669 -351.477814) (xy 92.126327 -351.428203) (xy 92.155816 -351.382322) (xy 92.191534 -351.341105)
			(xy 92.232755 -351.305391) (xy 92.27864 -351.275907) (xy 92.328253 -351.253254) (xy 92.380586 -351.237893)
			(xy 92.434572 -351.230137) (xy 92.461842 -351.229676) (xy 93.325442 -351.229676) (xy 93.352712 -351.230089)
			(xy 93.406697 -351.237857) (xy 93.459026 -351.253227) (xy 93.508636 -351.275888) (xy 93.554516 -351.305378)
			(xy 93.595733 -351.341097) (xy 93.631447 -351.382317) (xy 93.660932 -351.428201) (xy 93.683588 -351.477813)
			(xy 93.698952 -351.530145) (xy 93.706714 -351.58413) (xy 93.706714 -351.638669) (xy 111.480839 -351.638669)
			(xy 111.480839 -351.584131) (xy 111.488601 -351.530149) (xy 111.503966 -351.477821) (xy 111.526622 -351.428212)
			(xy 111.556107 -351.382333) (xy 111.591822 -351.341117) (xy 111.633039 -351.305403) (xy 111.678919 -351.275918)
			(xy 111.728529 -351.253263) (xy 111.780857 -351.237899) (xy 111.834839 -351.230139) (xy 111.862108 -351.229676)
			(xy 112.725708 -351.229676) (xy 112.75298 -351.230087) (xy 112.806968 -351.23785) (xy 112.859302 -351.253218)
			(xy 112.908916 -351.275877) (xy 112.9548 -351.305366) (xy 112.996021 -351.341085) (xy 113.031739 -351.382306)
			(xy 113.061227 -351.428191) (xy 113.083885 -351.477806) (xy 113.099251 -351.53014) (xy 113.107014 -351.584128)
			(xy 113.107014 -351.638665) (xy 114.589862 -351.638665) (xy 114.589862 -351.584135) (xy 114.597622 -351.530159)
			(xy 114.612984 -351.477838) (xy 114.635636 -351.428234) (xy 114.665116 -351.38236) (xy 114.700824 -351.341147)
			(xy 114.742034 -351.305435) (xy 114.787906 -351.275951) (xy 114.837508 -351.253296) (xy 114.889828 -351.237929)
			(xy 114.943803 -351.230165) (xy 114.971068 -351.229676) (xy 115.834668 -351.229676) (xy 115.861943 -351.230061)
			(xy 115.915939 -351.237821) (xy 115.968281 -351.253186) (xy 116.017903 -351.275844) (xy 116.063795 -351.305333)
			(xy 116.105023 -351.341054) (xy 116.140747 -351.382279) (xy 116.170241 -351.428169) (xy 116.192903 -351.477789)
			(xy 116.208273 -351.53013) (xy 116.216036 -351.584125) (xy 116.216036 -351.63867) (xy 117.698739 -351.63867)
			(xy 117.698739 -351.58413) (xy 117.706502 -351.530146) (xy 117.721868 -351.477817) (xy 117.744525 -351.428207)
			(xy 117.774012 -351.382326) (xy 117.809729 -351.341109) (xy 117.850949 -351.305396) (xy 117.896831 -351.275912)
			(xy 117.946443 -351.253258) (xy 117.998774 -351.237896) (xy 118.052758 -351.230137) (xy 118.080028 -351.229676)
			(xy 118.943628 -351.229676) (xy 118.970899 -351.230088) (xy 119.024885 -351.237854) (xy 119.077216 -351.253223)
			(xy 119.126828 -351.275883) (xy 119.17271 -351.305373) (xy 119.213928 -351.341092) (xy 119.249644 -351.382313)
			(xy 119.27913 -351.428197) (xy 119.301786 -351.47781) (xy 119.317152 -351.530143) (xy 119.324914 -351.584129)
			(xy 119.324914 -351.638666) (xy 120.807762 -351.638666) (xy 120.807762 -351.584134) (xy 120.815523 -351.530157)
			(xy 120.830886 -351.477833) (xy 120.853539 -351.428229) (xy 120.883021 -351.382353) (xy 120.918731 -351.34114)
			(xy 120.959943 -351.305428) (xy 121.005818 -351.275945) (xy 121.055422 -351.25329) (xy 121.107745 -351.237925)
			(xy 121.161722 -351.230163) (xy 121.188988 -351.229676) (xy 122.052588 -351.229676) (xy 122.079862 -351.230063)
			(xy 122.133856 -351.237824) (xy 122.186195 -351.253191) (xy 122.235815 -351.27585) (xy 122.281704 -351.30534)
			(xy 122.32293 -351.341061) (xy 122.358652 -351.382286) (xy 122.388144 -351.428175) (xy 122.410805 -351.477794)
			(xy 122.426173 -351.530132) (xy 122.433936 -351.584126) (xy 122.433936 -351.63867) (xy 123.91664 -351.63867)
			(xy 123.91664 -351.58413) (xy 123.924402 -351.530144) (xy 123.939769 -351.477812) (xy 123.962428 -351.428201)
			(xy 123.991917 -351.38232) (xy 124.027636 -351.341102) (xy 124.068858 -351.305388) (xy 124.114743 -351.275905)
			(xy 124.164358 -351.253253) (xy 124.216691 -351.237892) (xy 124.270677 -351.230136) (xy 124.297948 -351.229676)
			(xy 125.161548 -351.229676) (xy 125.188818 -351.23009) (xy 125.242802 -351.237858) (xy 125.295131 -351.253229)
			(xy 125.34474 -351.27589) (xy 125.390619 -351.30538) (xy 125.431835 -351.341099) (xy 125.467549 -351.382319)
			(xy 125.497033 -351.428203) (xy 125.519688 -351.477814) (xy 125.535052 -351.530145) (xy 125.542814 -351.58413)
			(xy 125.542814 -351.638669) (xy 127.025639 -351.638669) (xy 127.025639 -351.584131) (xy 127.033401 -351.530149)
			(xy 127.048766 -351.477821) (xy 127.071422 -351.428212) (xy 127.100907 -351.382333) (xy 127.136622 -351.341117)
			(xy 127.177839 -351.305403) (xy 127.223719 -351.275918) (xy 127.273329 -351.253263) (xy 127.325657 -351.237899)
			(xy 127.379639 -351.230139) (xy 127.406908 -351.229676) (xy 128.270508 -351.229676) (xy 128.29778 -351.230087)
			(xy 128.351768 -351.23785) (xy 128.404102 -351.253218) (xy 128.453716 -351.275877) (xy 128.4996 -351.305366)
			(xy 128.540821 -351.341085) (xy 128.576539 -351.382306) (xy 128.606027 -351.428191) (xy 128.628685 -351.477806)
			(xy 128.644051 -351.53014) (xy 128.651814 -351.584128) (xy 128.651814 -351.638665) (xy 130.134662 -351.638665)
			(xy 130.134662 -351.584135) (xy 130.142422 -351.530159) (xy 130.157784 -351.477838) (xy 130.180436 -351.428234)
			(xy 130.209916 -351.38236) (xy 130.245624 -351.341147) (xy 130.286834 -351.305435) (xy 130.332706 -351.275951)
			(xy 130.382308 -351.253296) (xy 130.434628 -351.237929) (xy 130.488603 -351.230165) (xy 130.515868 -351.229676)
			(xy 131.379468 -351.229676) (xy 131.406743 -351.230061) (xy 131.460739 -351.237821) (xy 131.513081 -351.253186)
			(xy 131.562703 -351.275844) (xy 131.608595 -351.305333) (xy 131.649823 -351.341054) (xy 131.685547 -351.382279)
			(xy 131.715041 -351.428169) (xy 131.737703 -351.477789) (xy 131.753073 -351.53013) (xy 131.760836 -351.584125)
			(xy 131.760836 -351.63867) (xy 133.243539 -351.63867) (xy 133.243539 -351.58413) (xy 133.251302 -351.530146)
			(xy 133.266668 -351.477817) (xy 133.289325 -351.428207) (xy 133.318812 -351.382326) (xy 133.354529 -351.341109)
			(xy 133.395749 -351.305396) (xy 133.441631 -351.275912) (xy 133.491243 -351.253258) (xy 133.543574 -351.237896)
			(xy 133.597558 -351.230137) (xy 133.624828 -351.229676) (xy 134.488428 -351.229676) (xy 134.515699 -351.230088)
			(xy 134.569685 -351.237854) (xy 134.622016 -351.253223) (xy 134.671628 -351.275883) (xy 134.71751 -351.305373)
			(xy 134.758728 -351.341092) (xy 134.794444 -351.382313) (xy 134.82393 -351.428197) (xy 134.846586 -351.47781)
			(xy 134.861952 -351.530143) (xy 134.869714 -351.584129) (xy 134.869714 -351.638666) (xy 136.352562 -351.638666)
			(xy 136.352562 -351.584134) (xy 136.360323 -351.530157) (xy 136.375686 -351.477833) (xy 136.398339 -351.428229)
			(xy 136.427821 -351.382353) (xy 136.463531 -351.34114) (xy 136.504743 -351.305428) (xy 136.550618 -351.275945)
			(xy 136.600222 -351.25329) (xy 136.652545 -351.237925) (xy 136.706522 -351.230163) (xy 136.733788 -351.229676)
			(xy 137.597388 -351.229676) (xy 137.624662 -351.230063) (xy 137.678656 -351.237824) (xy 137.730995 -351.253191)
			(xy 137.780615 -351.27585) (xy 137.826504 -351.30534) (xy 137.86773 -351.341061) (xy 137.903452 -351.382286)
			(xy 137.932944 -351.428175) (xy 137.955605 -351.477794) (xy 137.970973 -351.530132) (xy 137.978736 -351.584126)
			(xy 137.978736 -351.63867) (xy 139.46144 -351.63867) (xy 139.46144 -351.58413) (xy 139.469202 -351.530144)
			(xy 139.484569 -351.477812) (xy 139.507228 -351.428201) (xy 139.536717 -351.38232) (xy 139.572436 -351.341102)
			(xy 139.613658 -351.305388) (xy 139.659543 -351.275905) (xy 139.709158 -351.253253) (xy 139.761491 -351.237892)
			(xy 139.815477 -351.230136) (xy 139.842748 -351.229676) (xy 140.706348 -351.229676) (xy 140.733618 -351.23009)
			(xy 140.787602 -351.237858) (xy 140.839931 -351.253229) (xy 140.88954 -351.27589) (xy 140.935419 -351.30538)
			(xy 140.976635 -351.341099) (xy 141.012349 -351.382319) (xy 141.041833 -351.428203) (xy 141.064488 -351.477814)
			(xy 141.079852 -351.530145) (xy 141.087614 -351.58413) (xy 141.087614 -351.638669) (xy 142.570439 -351.638669)
			(xy 142.570439 -351.584131) (xy 142.578201 -351.530149) (xy 142.593566 -351.477821) (xy 142.616222 -351.428212)
			(xy 142.645707 -351.382333) (xy 142.681422 -351.341117) (xy 142.722639 -351.305403) (xy 142.768519 -351.275918)
			(xy 142.818129 -351.253263) (xy 142.870457 -351.237899) (xy 142.924439 -351.230139) (xy 142.951708 -351.229676)
			(xy 143.815308 -351.229676) (xy 143.84258 -351.230087) (xy 143.896568 -351.23785) (xy 143.948902 -351.253218)
			(xy 143.998516 -351.275877) (xy 144.0444 -351.305366) (xy 144.085621 -351.341085) (xy 144.121339 -351.382306)
			(xy 144.150827 -351.428191) (xy 144.173485 -351.477806) (xy 144.188851 -351.53014) (xy 144.196614 -351.584128)
			(xy 144.196614 -351.638669) (xy 161.804839 -351.638669) (xy 161.804839 -351.584131) (xy 161.812601 -351.530149)
			(xy 161.827966 -351.47782) (xy 161.850623 -351.428211) (xy 161.880108 -351.382331) (xy 161.915824 -351.341115)
			(xy 161.957041 -351.305401) (xy 162.002922 -351.275917) (xy 162.052531 -351.253262) (xy 162.10486 -351.237899)
			(xy 162.158843 -351.230139) (xy 162.186112 -351.229676) (xy 163.049712 -351.229676) (xy 163.076984 -351.230087)
			(xy 163.130971 -351.237851) (xy 163.183304 -351.253219) (xy 163.232918 -351.275878) (xy 163.278802 -351.305367)
			(xy 163.320022 -351.341086) (xy 163.35574 -351.382308) (xy 163.385228 -351.428192) (xy 163.407885 -351.477807)
			(xy 163.423251 -351.530141) (xy 163.431014 -351.584128) (xy 163.431014 -351.638665) (xy 164.913862 -351.638665)
			(xy 164.913862 -351.584135) (xy 164.921622 -351.530159) (xy 164.936985 -351.477837) (xy 164.959637 -351.428233)
			(xy 164.989117 -351.382358) (xy 165.024826 -351.341146) (xy 165.066036 -351.305434) (xy 165.111909 -351.27595)
			(xy 165.16151 -351.253295) (xy 165.213831 -351.237928) (xy 165.267807 -351.230164) (xy 165.295072 -351.229676)
			(xy 166.158672 -351.229676) (xy 166.185947 -351.230062) (xy 166.239942 -351.237821) (xy 166.292284 -351.253187)
			(xy 166.341905 -351.275845) (xy 166.387797 -351.305335) (xy 166.429024 -351.341056) (xy 166.464748 -351.382281)
			(xy 166.494242 -351.42817) (xy 166.516903 -351.47779) (xy 166.532273 -351.53013) (xy 166.540036 -351.584125)
			(xy 166.540036 -351.63867) (xy 168.022739 -351.63867) (xy 168.022739 -351.58413) (xy 168.030502 -351.530146)
			(xy 168.045868 -351.477816) (xy 168.068526 -351.428206) (xy 168.098013 -351.382325) (xy 168.133731 -351.341108)
			(xy 168.174951 -351.305394) (xy 168.220834 -351.27591) (xy 168.270446 -351.253257) (xy 168.322777 -351.237895)
			(xy 168.376762 -351.230137) (xy 168.404032 -351.229676) (xy 169.267632 -351.229676) (xy 169.294903 -351.230089)
			(xy 169.348888 -351.237855) (xy 169.401219 -351.253224) (xy 169.45083 -351.275885) (xy 169.496712 -351.305374)
			(xy 169.537929 -351.341093) (xy 169.573645 -351.382314) (xy 169.603131 -351.428198) (xy 169.625787 -351.477811)
			(xy 169.641152 -351.530143) (xy 169.648914 -351.584129) (xy 169.648914 -351.638666) (xy 171.131762 -351.638666)
			(xy 171.131762 -351.584134) (xy 171.139523 -351.530156) (xy 171.154886 -351.477832) (xy 171.17754 -351.428228)
			(xy 171.207022 -351.382352) (xy 171.242733 -351.341138) (xy 171.283945 -351.305427) (xy 171.329821 -351.275944)
			(xy 171.379425 -351.253289) (xy 171.431748 -351.237925) (xy 171.485726 -351.230163) (xy 171.512992 -351.229676)
			(xy 172.376592 -351.229676) (xy 172.403866 -351.230063) (xy 172.457859 -351.237825) (xy 172.510198 -351.253192)
			(xy 172.559817 -351.275851) (xy 172.605706 -351.305342) (xy 172.646932 -351.341063) (xy 172.682653 -351.382287)
			(xy 172.712145 -351.428176) (xy 172.734805 -351.477794) (xy 172.750173 -351.530133) (xy 172.757936 -351.584126)
			(xy 172.757936 -351.638664) (xy 174.240762 -351.638664) (xy 174.240762 -351.584136) (xy 174.248522 -351.530162)
			(xy 174.263883 -351.477841) (xy 174.286534 -351.428239) (xy 174.316012 -351.382365) (xy 174.351719 -351.341153)
			(xy 174.392926 -351.305441) (xy 174.438797 -351.275957) (xy 174.488396 -351.2533) (xy 174.540715 -351.237932)
			(xy 174.594688 -351.230166) (xy 174.621952 -351.229676) (xy 175.485552 -351.229676) (xy 175.512828 -351.23006)
			(xy 175.566825 -351.237818) (xy 175.619169 -351.253181) (xy 175.668793 -351.275838) (xy 175.714687 -351.305328)
			(xy 175.755917 -351.341049) (xy 175.791644 -351.382274) (xy 175.821139 -351.428165) (xy 175.843802 -351.477786)
			(xy 175.859172 -351.530128) (xy 175.866936 -351.584124) (xy 175.866936 -351.638669) (xy 177.349639 -351.638669)
			(xy 177.349639 -351.584131) (xy 177.357401 -351.530149) (xy 177.372766 -351.47782) (xy 177.395423 -351.428211)
			(xy 177.424908 -351.382331) (xy 177.460624 -351.341115) (xy 177.501841 -351.305401) (xy 177.547722 -351.275917)
			(xy 177.597331 -351.253262) (xy 177.64966 -351.237899) (xy 177.703643 -351.230139) (xy 177.730912 -351.229676)
			(xy 178.594512 -351.229676) (xy 178.621784 -351.230087) (xy 178.675771 -351.237851) (xy 178.728104 -351.253219)
			(xy 178.777718 -351.275878) (xy 178.823602 -351.305367) (xy 178.864822 -351.341086) (xy 178.90054 -351.382308)
			(xy 178.930028 -351.428192) (xy 178.952685 -351.477807) (xy 178.968051 -351.530141) (xy 178.975814 -351.584128)
			(xy 178.975814 -351.638665) (xy 180.458662 -351.638665) (xy 180.458662 -351.584135) (xy 180.466422 -351.530159)
			(xy 180.481785 -351.477837) (xy 180.504437 -351.428233) (xy 180.533917 -351.382358) (xy 180.569626 -351.341146)
			(xy 180.610836 -351.305434) (xy 180.656709 -351.27595) (xy 180.70631 -351.253295) (xy 180.758631 -351.237928)
			(xy 180.812607 -351.230164) (xy 180.839872 -351.229676) (xy 181.703472 -351.229676) (xy 181.730747 -351.230062)
			(xy 181.784742 -351.237821) (xy 181.837084 -351.253187) (xy 181.886705 -351.275845) (xy 181.932597 -351.305335)
			(xy 181.973824 -351.341056) (xy 182.009548 -351.382281) (xy 182.039042 -351.42817) (xy 182.061703 -351.47779)
			(xy 182.077073 -351.53013) (xy 182.084836 -351.584125) (xy 182.084836 -351.63867) (xy 183.567539 -351.63867)
			(xy 183.567539 -351.58413) (xy 183.575302 -351.530146) (xy 183.590668 -351.477816) (xy 183.613326 -351.428206)
			(xy 183.642813 -351.382325) (xy 183.678531 -351.341108) (xy 183.719751 -351.305394) (xy 183.765634 -351.27591)
			(xy 183.815246 -351.253257) (xy 183.867577 -351.237895) (xy 183.921562 -351.230137) (xy 183.948832 -351.229676)
			(xy 184.812432 -351.229676) (xy 184.839703 -351.230089) (xy 184.893688 -351.237855) (xy 184.946019 -351.253224)
			(xy 184.99563 -351.275885) (xy 185.041512 -351.305374) (xy 185.082729 -351.341093) (xy 185.118445 -351.382314)
			(xy 185.147931 -351.428198) (xy 185.170587 -351.477811) (xy 185.185952 -351.530143) (xy 185.193714 -351.584129)
			(xy 185.193714 -351.638666) (xy 186.676562 -351.638666) (xy 186.676562 -351.584134) (xy 186.684323 -351.530156)
			(xy 186.699686 -351.477832) (xy 186.72234 -351.428228) (xy 186.751822 -351.382352) (xy 186.787533 -351.341138)
			(xy 186.828745 -351.305427) (xy 186.874621 -351.275944) (xy 186.924225 -351.253289) (xy 186.976548 -351.237925)
			(xy 187.030526 -351.230163) (xy 187.057792 -351.229676) (xy 187.921392 -351.229676) (xy 187.948666 -351.230063)
			(xy 188.002659 -351.237825) (xy 188.054998 -351.253192) (xy 188.104617 -351.275851) (xy 188.150506 -351.305342)
			(xy 188.191732 -351.341063) (xy 188.227453 -351.382287) (xy 188.256945 -351.428176) (xy 188.279605 -351.477794)
			(xy 188.294973 -351.530133) (xy 188.302736 -351.584126) (xy 188.302736 -351.638664) (xy 189.785562 -351.638664)
			(xy 189.785562 -351.584136) (xy 189.793322 -351.530162) (xy 189.808683 -351.477841) (xy 189.831334 -351.428239)
			(xy 189.860812 -351.382365) (xy 189.896519 -351.341153) (xy 189.937726 -351.305441) (xy 189.983597 -351.275957)
			(xy 190.033196 -351.2533) (xy 190.085515 -351.237932) (xy 190.139488 -351.230166) (xy 190.166752 -351.229676)
			(xy 191.030352 -351.229676) (xy 191.057628 -351.23006) (xy 191.111625 -351.237818) (xy 191.163969 -351.253181)
			(xy 191.213593 -351.275838) (xy 191.259487 -351.305328) (xy 191.300717 -351.341049) (xy 191.336444 -351.382274)
			(xy 191.365939 -351.428165) (xy 191.388602 -351.477786) (xy 191.403972 -351.530128) (xy 191.411736 -351.584124)
			(xy 191.411736 -351.638669) (xy 192.894439 -351.638669) (xy 192.894439 -351.584131) (xy 192.902201 -351.530149)
			(xy 192.917566 -351.47782) (xy 192.940223 -351.428211) (xy 192.969708 -351.382331) (xy 193.005424 -351.341115)
			(xy 193.046641 -351.305401) (xy 193.092522 -351.275917) (xy 193.142131 -351.253262) (xy 193.19446 -351.237899)
			(xy 193.248443 -351.230139) (xy 193.275712 -351.229676) (xy 194.139312 -351.229676) (xy 194.166584 -351.230087)
			(xy 194.220571 -351.237851) (xy 194.272904 -351.253219) (xy 194.322518 -351.275878) (xy 194.368402 -351.305367)
			(xy 194.409622 -351.341086) (xy 194.44534 -351.382308) (xy 194.474828 -351.428192) (xy 194.497485 -351.477807)
			(xy 194.512851 -351.530141) (xy 194.520614 -351.584128) (xy 194.520614 -351.638672) (xy 194.512851 -351.692659)
			(xy 194.497485 -351.744993) (xy 194.474828 -351.794608) (xy 194.44534 -351.840492) (xy 194.409622 -351.881714)
			(xy 194.368402 -351.917433) (xy 194.322518 -351.946922) (xy 194.272904 -351.969581) (xy 194.220571 -351.984949)
			(xy 194.166584 -351.992713) (xy 194.139312 -351.9932) (xy 193.275712 -351.9932) (xy 193.248443 -351.992661)
			(xy 193.19446 -351.984901) (xy 193.142131 -351.969538) (xy 193.092522 -351.946883) (xy 193.046641 -351.917399)
			(xy 193.005424 -351.881685) (xy 192.969708 -351.840469) (xy 192.940223 -351.794589) (xy 192.917566 -351.74498)
			(xy 192.902201 -351.692651) (xy 192.894439 -351.638669) (xy 191.411736 -351.638669) (xy 191.411736 -351.638676)
			(xy 191.403972 -351.692672) (xy 191.388602 -351.745014) (xy 191.365939 -351.794635) (xy 191.336444 -351.840526)
			(xy 191.300717 -351.881751) (xy 191.259487 -351.917472) (xy 191.213593 -351.946962) (xy 191.163969 -351.969619)
			(xy 191.111625 -351.984982) (xy 191.057628 -351.99274) (xy 191.030352 -351.9932) (xy 190.166752 -351.9932)
			(xy 190.139488 -351.992634) (xy 190.085515 -351.984868) (xy 190.033196 -351.9695) (xy 189.983597 -351.946843)
			(xy 189.937726 -351.917359) (xy 189.896519 -351.881647) (xy 189.860812 -351.840435) (xy 189.831334 -351.794561)
			(xy 189.808683 -351.744959) (xy 189.793322 -351.692639) (xy 189.785562 -351.638664) (xy 188.302736 -351.638664)
			(xy 188.302736 -351.638674) (xy 188.294973 -351.692667) (xy 188.279605 -351.745006) (xy 188.256945 -351.794624)
			(xy 188.227453 -351.840513) (xy 188.191732 -351.881737) (xy 188.150506 -351.917458) (xy 188.104617 -351.946949)
			(xy 188.054998 -351.969608) (xy 188.002659 -351.984975) (xy 187.948666 -351.992737) (xy 187.921392 -351.9932)
			(xy 187.057792 -351.9932) (xy 187.030526 -351.992637) (xy 186.976548 -351.984875) (xy 186.924225 -351.969511)
			(xy 186.874621 -351.946856) (xy 186.828745 -351.917373) (xy 186.787533 -351.881662) (xy 186.751822 -351.840448)
			(xy 186.72234 -351.794572) (xy 186.699686 -351.744968) (xy 186.684323 -351.692644) (xy 186.676562 -351.638666)
			(xy 185.193714 -351.638666) (xy 185.193714 -351.638671) (xy 185.185952 -351.692657) (xy 185.170587 -351.744989)
			(xy 185.147931 -351.794602) (xy 185.118445 -351.840486) (xy 185.082729 -351.881707) (xy 185.041512 -351.917426)
			(xy 184.99563 -351.946915) (xy 184.946019 -351.969576) (xy 184.893688 -351.984945) (xy 184.839703 -351.992711)
			(xy 184.812432 -351.9932) (xy 183.948832 -351.9932) (xy 183.921562 -351.992663) (xy 183.867577 -351.984905)
			(xy 183.815246 -351.969543) (xy 183.765634 -351.94689) (xy 183.719751 -351.917406) (xy 183.678531 -351.881692)
			(xy 183.642813 -351.840475) (xy 183.613326 -351.794594) (xy 183.590668 -351.744984) (xy 183.575302 -351.692654)
			(xy 183.567539 -351.63867) (xy 182.084836 -351.63867) (xy 182.084836 -351.638675) (xy 182.077073 -351.69267)
			(xy 182.061703 -351.74501) (xy 182.039042 -351.79463) (xy 182.009548 -351.840519) (xy 181.973824 -351.881744)
			(xy 181.932597 -351.917465) (xy 181.886705 -351.946955) (xy 181.837084 -351.969613) (xy 181.784742 -351.984979)
			(xy 181.730747 -351.992738) (xy 181.703472 -351.9932) (xy 180.839872 -351.9932) (xy 180.812607 -351.992636)
			(xy 180.758631 -351.984872) (xy 180.70631 -351.969505) (xy 180.656709 -351.94685) (xy 180.610836 -351.917366)
			(xy 180.569626 -351.881654) (xy 180.533917 -351.840442) (xy 180.504437 -351.794567) (xy 180.481785 -351.744963)
			(xy 180.466422 -351.692641) (xy 180.458662 -351.638665) (xy 178.975814 -351.638665) (xy 178.975814 -351.638672)
			(xy 178.968051 -351.692659) (xy 178.952685 -351.744993) (xy 178.930028 -351.794608) (xy 178.90054 -351.840492)
			(xy 178.864822 -351.881714) (xy 178.823602 -351.917433) (xy 178.777718 -351.946922) (xy 178.728104 -351.969581)
			(xy 178.675771 -351.984949) (xy 178.621784 -351.992713) (xy 178.594512 -351.9932) (xy 177.730912 -351.9932)
			(xy 177.703643 -351.992661) (xy 177.64966 -351.984901) (xy 177.597331 -351.969538) (xy 177.547722 -351.946883)
			(xy 177.501841 -351.917399) (xy 177.460624 -351.881685) (xy 177.424908 -351.840469) (xy 177.395423 -351.794589)
			(xy 177.372766 -351.74498) (xy 177.357401 -351.692651) (xy 177.349639 -351.638669) (xy 175.866936 -351.638669)
			(xy 175.866936 -351.638676) (xy 175.859172 -351.692672) (xy 175.843802 -351.745014) (xy 175.821139 -351.794635)
			(xy 175.791644 -351.840526) (xy 175.755917 -351.881751) (xy 175.714687 -351.917472) (xy 175.668793 -351.946962)
			(xy 175.619169 -351.969619) (xy 175.566825 -351.984982) (xy 175.512828 -351.99274) (xy 175.485552 -351.9932)
			(xy 174.621952 -351.9932) (xy 174.594688 -351.992634) (xy 174.540715 -351.984868) (xy 174.488396 -351.9695)
			(xy 174.438797 -351.946843) (xy 174.392926 -351.917359) (xy 174.351719 -351.881647) (xy 174.316012 -351.840435)
			(xy 174.286534 -351.794561) (xy 174.263883 -351.744959) (xy 174.248522 -351.692639) (xy 174.240762 -351.638664)
			(xy 172.757936 -351.638664) (xy 172.757936 -351.638674) (xy 172.750173 -351.692667) (xy 172.734805 -351.745006)
			(xy 172.712145 -351.794624) (xy 172.682653 -351.840513) (xy 172.646932 -351.881737) (xy 172.605706 -351.917458)
			(xy 172.559817 -351.946949) (xy 172.510198 -351.969608) (xy 172.457859 -351.984975) (xy 172.403866 -351.992737)
			(xy 172.376592 -351.9932) (xy 171.512992 -351.9932) (xy 171.485726 -351.992637) (xy 171.431748 -351.984875)
			(xy 171.379425 -351.969511) (xy 171.329821 -351.946856) (xy 171.283945 -351.917373) (xy 171.242733 -351.881662)
			(xy 171.207022 -351.840448) (xy 171.17754 -351.794572) (xy 171.154886 -351.744968) (xy 171.139523 -351.692644)
			(xy 171.131762 -351.638666) (xy 169.648914 -351.638666) (xy 169.648914 -351.638671) (xy 169.641152 -351.692657)
			(xy 169.625787 -351.744989) (xy 169.603131 -351.794602) (xy 169.573645 -351.840486) (xy 169.537929 -351.881707)
			(xy 169.496712 -351.917426) (xy 169.45083 -351.946915) (xy 169.401219 -351.969576) (xy 169.348888 -351.984945)
			(xy 169.294903 -351.992711) (xy 169.267632 -351.9932) (xy 168.404032 -351.9932) (xy 168.376762 -351.992663)
			(xy 168.322777 -351.984905) (xy 168.270446 -351.969543) (xy 168.220834 -351.94689) (xy 168.174951 -351.917406)
			(xy 168.133731 -351.881692) (xy 168.098013 -351.840475) (xy 168.068526 -351.794594) (xy 168.045868 -351.744984)
			(xy 168.030502 -351.692654) (xy 168.022739 -351.63867) (xy 166.540036 -351.63867) (xy 166.540036 -351.638675)
			(xy 166.532273 -351.69267) (xy 166.516903 -351.74501) (xy 166.494242 -351.79463) (xy 166.464748 -351.840519)
			(xy 166.429024 -351.881744) (xy 166.387797 -351.917465) (xy 166.341905 -351.946955) (xy 166.292284 -351.969613)
			(xy 166.239942 -351.984979) (xy 166.185947 -351.992738) (xy 166.158672 -351.9932) (xy 165.295072 -351.9932)
			(xy 165.267807 -351.992636) (xy 165.213831 -351.984872) (xy 165.16151 -351.969505) (xy 165.111909 -351.94685)
			(xy 165.066036 -351.917366) (xy 165.024826 -351.881654) (xy 164.989117 -351.840442) (xy 164.959637 -351.794567)
			(xy 164.936985 -351.744963) (xy 164.921622 -351.692641) (xy 164.913862 -351.638665) (xy 163.431014 -351.638665)
			(xy 163.431014 -351.638672) (xy 163.423251 -351.692659) (xy 163.407885 -351.744993) (xy 163.385228 -351.794608)
			(xy 163.35574 -351.840492) (xy 163.320022 -351.881714) (xy 163.278802 -351.917433) (xy 163.232918 -351.946922)
			(xy 163.183304 -351.969581) (xy 163.130971 -351.984949) (xy 163.076984 -351.992713) (xy 163.049712 -351.9932)
			(xy 162.186112 -351.9932) (xy 162.158843 -351.992661) (xy 162.10486 -351.984901) (xy 162.052531 -351.969538)
			(xy 162.002922 -351.946883) (xy 161.957041 -351.917399) (xy 161.915824 -351.881685) (xy 161.880108 -351.840469)
			(xy 161.850623 -351.794589) (xy 161.827966 -351.74498) (xy 161.812601 -351.692651) (xy 161.804839 -351.638669)
			(xy 144.196614 -351.638669) (xy 144.196614 -351.638672) (xy 144.188851 -351.69266) (xy 144.173485 -351.744994)
			(xy 144.150827 -351.794609) (xy 144.121339 -351.840494) (xy 144.085621 -351.881715) (xy 144.0444 -351.917434)
			(xy 143.998516 -351.946923) (xy 143.948902 -351.969582) (xy 143.896568 -351.98495) (xy 143.84258 -351.992713)
			(xy 143.815308 -351.9932) (xy 142.951708 -351.9932) (xy 142.924439 -351.992661) (xy 142.870457 -351.984901)
			(xy 142.818129 -351.969537) (xy 142.768519 -351.946882) (xy 142.722639 -351.917397) (xy 142.681422 -351.881683)
			(xy 142.645707 -351.840467) (xy 142.616222 -351.794588) (xy 142.593566 -351.744979) (xy 142.578201 -351.692651)
			(xy 142.570439 -351.638669) (xy 141.087614 -351.638669) (xy 141.087614 -351.63867) (xy 141.079852 -351.692655)
			(xy 141.064488 -351.744986) (xy 141.041833 -351.794597) (xy 141.012349 -351.840481) (xy 140.976635 -351.881701)
			(xy 140.935419 -351.91742) (xy 140.88954 -351.94691) (xy 140.839931 -351.969571) (xy 140.787602 -351.984942)
			(xy 140.733618 -351.99271) (xy 140.706348 -351.9932) (xy 139.842748 -351.9932) (xy 139.815477 -351.992664)
			(xy 139.761491 -351.984908) (xy 139.709158 -351.969547) (xy 139.659543 -351.946895) (xy 139.613658 -351.917411)
			(xy 139.572436 -351.881698) (xy 139.536717 -351.84048) (xy 139.507228 -351.794599) (xy 139.484569 -351.744987)
			(xy 139.469202 -351.692656) (xy 139.46144 -351.63867) (xy 137.978736 -351.63867) (xy 137.978736 -351.638674)
			(xy 137.970973 -351.692668) (xy 137.955605 -351.745006) (xy 137.932944 -351.794625) (xy 137.903452 -351.840514)
			(xy 137.86773 -351.881739) (xy 137.826504 -351.91746) (xy 137.780615 -351.94695) (xy 137.730995 -351.969609)
			(xy 137.678656 -351.984976) (xy 137.624662 -351.992737) (xy 137.597388 -351.9932) (xy 136.733788 -351.9932)
			(xy 136.706522 -351.992637) (xy 136.652545 -351.984875) (xy 136.600222 -351.96951) (xy 136.550618 -351.946855)
			(xy 136.504744 -351.917372) (xy 136.463531 -351.88166) (xy 136.427821 -351.840447) (xy 136.398339 -351.794571)
			(xy 136.375686 -351.744967) (xy 136.360323 -351.692643) (xy 136.352562 -351.638666) (xy 134.869714 -351.638666)
			(xy 134.869714 -351.638671) (xy 134.861952 -351.692657) (xy 134.846586 -351.74499) (xy 134.82393 -351.794603)
			(xy 134.794444 -351.840487) (xy 134.758728 -351.881708) (xy 134.71751 -351.917427) (xy 134.671628 -351.946917)
			(xy 134.622016 -351.969577) (xy 134.569685 -351.984946) (xy 134.515699 -351.992712) (xy 134.488428 -351.9932)
			(xy 133.624828 -351.9932) (xy 133.597558 -351.992663) (xy 133.543574 -351.984904) (xy 133.491243 -351.969542)
			(xy 133.441631 -351.946888) (xy 133.395749 -351.917404) (xy 133.354529 -351.881691) (xy 133.318812 -351.840474)
			(xy 133.289325 -351.794593) (xy 133.266668 -351.744983) (xy 133.251302 -351.692654) (xy 133.243539 -351.63867)
			(xy 131.760836 -351.63867) (xy 131.760836 -351.638675) (xy 131.753073 -351.69267) (xy 131.737703 -351.745011)
			(xy 131.715041 -351.794631) (xy 131.685547 -351.840521) (xy 131.649823 -351.881746) (xy 131.608595 -351.917467)
			(xy 131.562703 -351.946956) (xy 131.513081 -351.969614) (xy 131.460739 -351.984979) (xy 131.406743 -351.992739)
			(xy 131.379468 -351.9932) (xy 130.515868 -351.9932) (xy 130.488603 -351.992635) (xy 130.434628 -351.984871)
			(xy 130.382308 -351.969504) (xy 130.332706 -351.946849) (xy 130.286834 -351.917365) (xy 130.245624 -351.881653)
			(xy 130.209916 -351.84044) (xy 130.180436 -351.794566) (xy 130.157784 -351.744962) (xy 130.142422 -351.692641)
			(xy 130.134662 -351.638665) (xy 128.651814 -351.638665) (xy 128.651814 -351.638672) (xy 128.644051 -351.69266)
			(xy 128.628685 -351.744994) (xy 128.606027 -351.794609) (xy 128.576539 -351.840494) (xy 128.540821 -351.881715)
			(xy 128.4996 -351.917434) (xy 128.453716 -351.946923) (xy 128.404102 -351.969582) (xy 128.351768 -351.98495)
			(xy 128.29778 -351.992713) (xy 128.270508 -351.9932) (xy 127.406908 -351.9932) (xy 127.379639 -351.992661)
			(xy 127.325657 -351.984901) (xy 127.273329 -351.969537) (xy 127.223719 -351.946882) (xy 127.177839 -351.917397)
			(xy 127.136622 -351.881683) (xy 127.100907 -351.840467) (xy 127.071422 -351.794588) (xy 127.048766 -351.744979)
			(xy 127.033401 -351.692651) (xy 127.025639 -351.638669) (xy 125.542814 -351.638669) (xy 125.542814 -351.63867)
			(xy 125.535052 -351.692655) (xy 125.519688 -351.744986) (xy 125.497033 -351.794597) (xy 125.467549 -351.840481)
			(xy 125.431835 -351.881701) (xy 125.390619 -351.91742) (xy 125.34474 -351.94691) (xy 125.295131 -351.969571)
			(xy 125.242802 -351.984942) (xy 125.188818 -351.99271) (xy 125.161548 -351.9932) (xy 124.297948 -351.9932)
			(xy 124.270677 -351.992664) (xy 124.216691 -351.984908) (xy 124.164358 -351.969547) (xy 124.114743 -351.946895)
			(xy 124.068858 -351.917411) (xy 124.027636 -351.881698) (xy 123.991917 -351.84048) (xy 123.962428 -351.794599)
			(xy 123.939769 -351.744987) (xy 123.924402 -351.692656) (xy 123.91664 -351.63867) (xy 122.433936 -351.63867)
			(xy 122.433936 -351.638674) (xy 122.426173 -351.692668) (xy 122.410805 -351.745006) (xy 122.388144 -351.794625)
			(xy 122.358652 -351.840514) (xy 122.32293 -351.881739) (xy 122.281704 -351.91746) (xy 122.235815 -351.94695)
			(xy 122.186195 -351.969609) (xy 122.133856 -351.984976) (xy 122.079862 -351.992737) (xy 122.052588 -351.9932)
			(xy 121.188988 -351.9932) (xy 121.161722 -351.992637) (xy 121.107745 -351.984875) (xy 121.055422 -351.96951)
			(xy 121.005818 -351.946855) (xy 120.959944 -351.917372) (xy 120.918731 -351.88166) (xy 120.883021 -351.840447)
			(xy 120.853539 -351.794571) (xy 120.830886 -351.744967) (xy 120.815523 -351.692643) (xy 120.807762 -351.638666)
			(xy 119.324914 -351.638666) (xy 119.324914 -351.638671) (xy 119.317152 -351.692657) (xy 119.301786 -351.74499)
			(xy 119.27913 -351.794603) (xy 119.249644 -351.840487) (xy 119.213928 -351.881708) (xy 119.17271 -351.917427)
			(xy 119.126828 -351.946917) (xy 119.077216 -351.969577) (xy 119.024885 -351.984946) (xy 118.970899 -351.992712)
			(xy 118.943628 -351.9932) (xy 118.080028 -351.9932) (xy 118.052758 -351.992663) (xy 117.998774 -351.984904)
			(xy 117.946443 -351.969542) (xy 117.896831 -351.946888) (xy 117.850949 -351.917404) (xy 117.809729 -351.881691)
			(xy 117.774012 -351.840474) (xy 117.744525 -351.794593) (xy 117.721868 -351.744983) (xy 117.706502 -351.692654)
			(xy 117.698739 -351.63867) (xy 116.216036 -351.63867) (xy 116.216036 -351.638675) (xy 116.208273 -351.69267)
			(xy 116.192903 -351.745011) (xy 116.170241 -351.794631) (xy 116.140747 -351.840521) (xy 116.105023 -351.881746)
			(xy 116.063795 -351.917467) (xy 116.017903 -351.946956) (xy 115.968281 -351.969614) (xy 115.915939 -351.984979)
			(xy 115.861943 -351.992739) (xy 115.834668 -351.9932) (xy 114.971068 -351.9932) (xy 114.943803 -351.992635)
			(xy 114.889828 -351.984871) (xy 114.837508 -351.969504) (xy 114.787906 -351.946849) (xy 114.742034 -351.917365)
			(xy 114.700824 -351.881653) (xy 114.665116 -351.84044) (xy 114.635636 -351.794566) (xy 114.612984 -351.744962)
			(xy 114.597622 -351.692641) (xy 114.589862 -351.638665) (xy 113.107014 -351.638665) (xy 113.107014 -351.638672)
			(xy 113.099251 -351.69266) (xy 113.083885 -351.744994) (xy 113.061227 -351.794609) (xy 113.031739 -351.840494)
			(xy 112.996021 -351.881715) (xy 112.9548 -351.917434) (xy 112.908916 -351.946923) (xy 112.859302 -351.969582)
			(xy 112.806968 -351.98495) (xy 112.75298 -351.992713) (xy 112.725708 -351.9932) (xy 111.862108 -351.9932)
			(xy 111.834839 -351.992661) (xy 111.780857 -351.984901) (xy 111.728529 -351.969537) (xy 111.678919 -351.946882)
			(xy 111.633039 -351.917397) (xy 111.591822 -351.881683) (xy 111.556107 -351.840467) (xy 111.526622 -351.794588)
			(xy 111.503966 -351.744979) (xy 111.488601 -351.692651) (xy 111.480839 -351.638669) (xy 93.706714 -351.638669)
			(xy 93.706714 -351.63867) (xy 93.698952 -351.692655) (xy 93.683588 -351.744987) (xy 93.660932 -351.794599)
			(xy 93.631447 -351.840483) (xy 93.595733 -351.881703) (xy 93.554516 -351.917422) (xy 93.508636 -351.946912)
			(xy 93.459026 -351.969573) (xy 93.406697 -351.984943) (xy 93.352712 -351.992711) (xy 93.325442 -351.9932)
			(xy 92.461842 -351.9932) (xy 92.434572 -351.992663) (xy 92.380586 -351.984907) (xy 92.328253 -351.969546)
			(xy 92.27864 -351.946893) (xy 92.232755 -351.917409) (xy 92.191534 -351.881695) (xy 92.155816 -351.840478)
			(xy 92.126327 -351.794597) (xy 92.103669 -351.744986) (xy 92.088302 -351.692655) (xy 92.08054 -351.63867)
			(xy 90.597836 -351.63867) (xy 90.597836 -351.638675) (xy 90.590073 -351.692668) (xy 90.574704 -351.745008)
			(xy 90.552043 -351.794627) (xy 90.522551 -351.840516) (xy 90.486828 -351.881741) (xy 90.445602 -351.917462)
			(xy 90.399711 -351.946952) (xy 90.350091 -351.969611) (xy 90.297751 -351.984977) (xy 90.243757 -351.992738)
			(xy 90.216482 -351.9932) (xy 89.352882 -351.9932) (xy 89.325616 -351.992636) (xy 89.27164 -351.984873)
			(xy 89.219318 -351.969508) (xy 89.169715 -351.946853) (xy 89.123841 -351.91737) (xy 89.082629 -351.881658)
			(xy 89.04692 -351.840445) (xy 89.017438 -351.794569) (xy 88.994786 -351.744965) (xy 88.979423 -351.692642)
			(xy 88.971662 -351.638666) (xy 87.488814 -351.638666) (xy 87.488814 -351.638671) (xy 87.481052 -351.692658)
			(xy 87.465686 -351.744991) (xy 87.443029 -351.794605) (xy 87.413542 -351.840489) (xy 87.377826 -351.88171)
			(xy 87.336607 -351.917429) (xy 87.290724 -351.946919) (xy 87.241112 -351.969578) (xy 87.18878 -351.984947)
			(xy 87.134793 -351.992712) (xy 87.107522 -351.9932) (xy 86.243922 -351.9932) (xy 86.216653 -351.992662)
			(xy 86.162669 -351.984903) (xy 86.110339 -351.96954) (xy 86.060728 -351.946886) (xy 86.014846 -351.917402)
			(xy 85.973627 -351.881688) (xy 85.937911 -351.840472) (xy 85.908424 -351.794592) (xy 85.885767 -351.744982)
			(xy 85.870401 -351.692653) (xy 85.862639 -351.638669) (xy 84.379936 -351.638669) (xy 84.379936 -351.638675)
			(xy 84.372172 -351.692671) (xy 84.356803 -351.745012) (xy 84.33414 -351.794633) (xy 84.304646 -351.840523)
			(xy 84.268921 -351.881748) (xy 84.227692 -351.917469) (xy 84.181799 -351.946958) (xy 84.132176 -351.969616)
			(xy 84.079834 -351.98498) (xy 84.025837 -351.992739) (xy 83.998562 -351.9932) (xy 83.134962 -351.9932)
			(xy 83.107697 -351.992635) (xy 83.053723 -351.98487) (xy 83.001403 -351.969503) (xy 82.951803 -351.946847)
			(xy 82.905931 -351.917363) (xy 82.864722 -351.881651) (xy 82.829015 -351.840438) (xy 82.799535 -351.794564)
			(xy 82.776884 -351.744961) (xy 82.761522 -351.69264) (xy 82.753762 -351.638665) (xy 81.270913 -351.638665)
			(xy 81.270913 -351.638672) (xy 81.263151 -351.692661) (xy 81.247784 -351.744995) (xy 81.225126 -351.79461)
			(xy 81.195637 -351.840496) (xy 81.159919 -351.881717) (xy 81.118697 -351.917436) (xy 81.072812 -351.946925)
			(xy 81.023197 -351.969584) (xy 80.970863 -351.984951) (xy 80.916874 -351.992713) (xy 80.889602 -351.9932)
			(xy 80.026002 -351.9932) (xy 79.998734 -351.992661) (xy 79.944752 -351.9849) (xy 79.892424 -351.969535)
			(xy 79.842816 -351.94688) (xy 79.796936 -351.917395) (xy 79.75572 -351.881681) (xy 79.720006 -351.840465)
			(xy 79.690521 -351.794586) (xy 79.667866 -351.744978) (xy 79.652501 -351.69265) (xy 79.644739 -351.638668)
			(xy 78.161914 -351.638668) (xy 78.161914 -351.63867) (xy 78.154152 -351.692655) (xy 78.138788 -351.744987)
			(xy 78.116132 -351.794599) (xy 78.086647 -351.840483) (xy 78.050933 -351.881703) (xy 78.009716 -351.917422)
			(xy 77.963836 -351.946912) (xy 77.914226 -351.969573) (xy 77.861897 -351.984943) (xy 77.807912 -351.992711)
			(xy 77.780642 -351.9932) (xy 76.917042 -351.9932) (xy 76.889772 -351.992663) (xy 76.835786 -351.984907)
			(xy 76.783453 -351.969546) (xy 76.73384 -351.946893) (xy 76.687955 -351.917409) (xy 76.646734 -351.881695)
			(xy 76.611016 -351.840478) (xy 76.581527 -351.794597) (xy 76.558869 -351.744986) (xy 76.543502 -351.692655)
			(xy 76.53574 -351.63867) (xy 75.053036 -351.63867) (xy 75.053036 -351.638675) (xy 75.045273 -351.692668)
			(xy 75.029904 -351.745008) (xy 75.007243 -351.794627) (xy 74.977751 -351.840516) (xy 74.942028 -351.881741)
			(xy 74.900802 -351.917462) (xy 74.854911 -351.946952) (xy 74.805291 -351.969611) (xy 74.752951 -351.984977)
			(xy 74.698957 -351.992738) (xy 74.671682 -351.9932) (xy 73.808082 -351.9932) (xy 73.780816 -351.992636)
			(xy 73.72684 -351.984873) (xy 73.674518 -351.969508) (xy 73.624915 -351.946853) (xy 73.579041 -351.91737)
			(xy 73.537829 -351.881658) (xy 73.50212 -351.840445) (xy 73.472638 -351.794569) (xy 73.449986 -351.744965)
			(xy 73.434623 -351.692642) (xy 73.426862 -351.638666) (xy 71.944014 -351.638666) (xy 71.944014 -351.638671)
			(xy 71.936252 -351.692658) (xy 71.920886 -351.744991) (xy 71.898229 -351.794605) (xy 71.868742 -351.840489)
			(xy 71.833026 -351.88171) (xy 71.791807 -351.917429) (xy 71.745924 -351.946919) (xy 71.696312 -351.969578)
			(xy 71.64398 -351.984947) (xy 71.589993 -351.992712) (xy 71.562722 -351.9932) (xy 70.699122 -351.9932)
			(xy 70.671853 -351.992662) (xy 70.617869 -351.984903) (xy 70.565539 -351.96954) (xy 70.515928 -351.946886)
			(xy 70.470046 -351.917402) (xy 70.428827 -351.881688) (xy 70.393111 -351.840472) (xy 70.363624 -351.794592)
			(xy 70.340967 -351.744982) (xy 70.325601 -351.692653) (xy 70.317839 -351.638669) (xy 68.835136 -351.638669)
			(xy 68.835136 -351.638675) (xy 68.827372 -351.692671) (xy 68.812003 -351.745012) (xy 68.78934 -351.794633)
			(xy 68.759846 -351.840523) (xy 68.724121 -351.881748) (xy 68.682892 -351.917469) (xy 68.636999 -351.946958)
			(xy 68.587376 -351.969616) (xy 68.535034 -351.98498) (xy 68.481037 -351.992739) (xy 68.453762 -351.9932)
			(xy 67.590162 -351.9932) (xy 67.562897 -351.992635) (xy 67.508923 -351.98487) (xy 67.456603 -351.969503)
			(xy 67.407003 -351.946847) (xy 67.361131 -351.917363) (xy 67.319922 -351.881651) (xy 67.284215 -351.840438)
			(xy 67.254735 -351.794564) (xy 67.232084 -351.744961) (xy 67.216722 -351.69264) (xy 67.208962 -351.638665)
			(xy 65.726113 -351.638665) (xy 65.726113 -351.638672) (xy 65.718351 -351.692661) (xy 65.702984 -351.744995)
			(xy 65.680326 -351.79461) (xy 65.650837 -351.840496) (xy 65.615119 -351.881717) (xy 65.573897 -351.917436)
			(xy 65.528012 -351.946925) (xy 65.478397 -351.969584) (xy 65.426063 -351.984951) (xy 65.372074 -351.992713)
			(xy 65.344802 -351.9932) (xy 64.481202 -351.9932) (xy 64.453934 -351.992661) (xy 64.399952 -351.9849)
			(xy 64.347624 -351.969535) (xy 64.298016 -351.94688) (xy 64.252136 -351.917395) (xy 64.21092 -351.881681)
			(xy 64.175206 -351.840465) (xy 64.145721 -351.794586) (xy 64.123066 -351.744978) (xy 64.107701 -351.69265)
			(xy 64.099939 -351.638668) (xy 62.617114 -351.638668) (xy 62.617114 -351.63867) (xy 62.609352 -351.692655)
			(xy 62.593988 -351.744987) (xy 62.571332 -351.794599) (xy 62.541847 -351.840483) (xy 62.506133 -351.881703)
			(xy 62.464916 -351.917422) (xy 62.419036 -351.946912) (xy 62.369426 -351.969573) (xy 62.317097 -351.984943)
			(xy 62.263112 -351.992711) (xy 62.235842 -351.9932) (xy 61.372242 -351.9932) (xy 61.344972 -351.992663)
			(xy 61.290986 -351.984907) (xy 61.238653 -351.969546) (xy 61.18904 -351.946893) (xy 61.143155 -351.917409)
			(xy 61.101934 -351.881695) (xy 61.066216 -351.840478) (xy 61.036727 -351.794597) (xy 61.014069 -351.744986)
			(xy 60.998702 -351.692655) (xy 60.99094 -351.63867) (xy 51.666914 -351.63867) (xy 51.659152 -351.692655)
			(xy 51.643788 -351.744986) (xy 51.621133 -351.794597) (xy 51.591649 -351.840481) (xy 51.555935 -351.881701)
			(xy 51.514719 -351.91742) (xy 51.46884 -351.94691) (xy 51.419231 -351.969571) (xy 51.366902 -351.984942)
			(xy 51.312918 -351.99271) (xy 51.285648 -351.9932) (xy 50.422048 -351.9932) (xy 50.394777 -351.992664)
			(xy 50.340791 -351.984908) (xy 50.288458 -351.969547) (xy 50.238843 -351.946895) (xy 50.192958 -351.917411)
			(xy 50.151736 -351.881698) (xy 50.116017 -351.84048) (xy 50.086528 -351.794599) (xy 50.063869 -351.744987)
			(xy 50.048502 -351.692656) (xy 50.04074 -351.63867) (xy 48.558036 -351.63867) (xy 48.558036 -351.638674)
			(xy 48.550273 -351.692668) (xy 48.534905 -351.745006) (xy 48.512244 -351.794625) (xy 48.482752 -351.840514)
			(xy 48.44703 -351.881739) (xy 48.405804 -351.91746) (xy 48.359915 -351.94695) (xy 48.310295 -351.969609)
			(xy 48.257956 -351.984976) (xy 48.203962 -351.992737) (xy 48.176688 -351.9932) (xy 47.313088 -351.9932)
			(xy 47.285822 -351.992637) (xy 47.231845 -351.984875) (xy 47.179522 -351.96951) (xy 47.129918 -351.946855)
			(xy 47.084044 -351.917372) (xy 47.042831 -351.88166) (xy 47.007121 -351.840447) (xy 46.977639 -351.794571)
			(xy 46.954986 -351.744967) (xy 46.939623 -351.692643) (xy 46.931862 -351.638666) (xy 45.449014 -351.638666)
			(xy 45.449014 -351.638671) (xy 45.441252 -351.692657) (xy 45.425886 -351.74499) (xy 45.40323 -351.794603)
			(xy 45.373744 -351.840487) (xy 45.338028 -351.881708) (xy 45.29681 -351.917427) (xy 45.250928 -351.946917)
			(xy 45.201316 -351.969577) (xy 45.148985 -351.984946) (xy 45.094999 -351.992712) (xy 45.067728 -351.9932)
			(xy 44.204128 -351.9932) (xy 44.176858 -351.992663) (xy 44.122874 -351.984904) (xy 44.070543 -351.969542)
			(xy 44.020931 -351.946888) (xy 43.975049 -351.917404) (xy 43.933829 -351.881691) (xy 43.898112 -351.840474)
			(xy 43.868625 -351.794593) (xy 43.845968 -351.744983) (xy 43.830602 -351.692654) (xy 43.822839 -351.63867)
			(xy 42.340136 -351.63867) (xy 42.340136 -351.638675) (xy 42.332373 -351.69267) (xy 42.317003 -351.745011)
			(xy 42.294341 -351.794631) (xy 42.264847 -351.840521) (xy 42.229123 -351.881746) (xy 42.187895 -351.917467)
			(xy 42.142003 -351.946956) (xy 42.092381 -351.969614) (xy 42.040039 -351.984979) (xy 41.986043 -351.992739)
			(xy 41.958768 -351.9932) (xy 41.095168 -351.9932) (xy 41.067903 -351.992635) (xy 41.013928 -351.984871)
			(xy 40.961608 -351.969504) (xy 40.912006 -351.946849) (xy 40.866134 -351.917365) (xy 40.824924 -351.881653)
			(xy 40.789216 -351.84044) (xy 40.759736 -351.794566) (xy 40.737084 -351.744962) (xy 40.721722 -351.692641)
			(xy 40.713962 -351.638665) (xy 39.231114 -351.638665) (xy 39.231114 -351.638672) (xy 39.223351 -351.69266)
			(xy 39.207985 -351.744994) (xy 39.185327 -351.794609) (xy 39.155839 -351.840494) (xy 39.120121 -351.881715)
			(xy 39.0789 -351.917434) (xy 39.033016 -351.946923) (xy 38.983402 -351.969582) (xy 38.931068 -351.98495)
			(xy 38.87708 -351.992713) (xy 38.849808 -351.9932) (xy 37.986208 -351.9932) (xy 37.958939 -351.992661)
			(xy 37.904957 -351.984901) (xy 37.852629 -351.969537) (xy 37.803019 -351.946882) (xy 37.757139 -351.917397)
			(xy 37.715922 -351.881683) (xy 37.680207 -351.840467) (xy 37.650722 -351.794588) (xy 37.628066 -351.744979)
			(xy 37.612701 -351.692651) (xy 37.604939 -351.638669) (xy 36.122114 -351.638669) (xy 36.122114 -351.63867)
			(xy 36.114352 -351.692655) (xy 36.098988 -351.744986) (xy 36.076333 -351.794597) (xy 36.046849 -351.840481)
			(xy 36.011135 -351.881701) (xy 35.969919 -351.91742) (xy 35.92404 -351.94691) (xy 35.874431 -351.969571)
			(xy 35.822102 -351.984942) (xy 35.768118 -351.99271) (xy 35.740848 -351.9932) (xy 34.877248 -351.9932)
			(xy 34.849977 -351.992664) (xy 34.795991 -351.984908) (xy 34.743658 -351.969547) (xy 34.694043 -351.946895)
			(xy 34.648158 -351.917411) (xy 34.606936 -351.881698) (xy 34.571217 -351.84048) (xy 34.541728 -351.794599)
			(xy 34.519069 -351.744987) (xy 34.503702 -351.692656) (xy 34.49594 -351.63867) (xy 33.013236 -351.63867)
			(xy 33.013236 -351.638674) (xy 33.005473 -351.692668) (xy 32.990105 -351.745006) (xy 32.967444 -351.794625)
			(xy 32.937952 -351.840514) (xy 32.90223 -351.881739) (xy 32.861004 -351.91746) (xy 32.815115 -351.94695)
			(xy 32.765495 -351.969609) (xy 32.713156 -351.984976) (xy 32.659162 -351.992737) (xy 32.631888 -351.9932)
			(xy 31.768288 -351.9932) (xy 31.741022 -351.992637) (xy 31.687045 -351.984875) (xy 31.634722 -351.96951)
			(xy 31.585118 -351.946855) (xy 31.539244 -351.917372) (xy 31.498031 -351.88166) (xy 31.462321 -351.840447)
			(xy 31.432839 -351.794571) (xy 31.410186 -351.744967) (xy 31.394823 -351.692643) (xy 31.387062 -351.638666)
			(xy 29.904214 -351.638666) (xy 29.904214 -351.638671) (xy 29.896452 -351.692657) (xy 29.881086 -351.74499)
			(xy 29.85843 -351.794603) (xy 29.828944 -351.840487) (xy 29.793228 -351.881708) (xy 29.75201 -351.917427)
			(xy 29.706128 -351.946917) (xy 29.656516 -351.969577) (xy 29.604185 -351.984946) (xy 29.550199 -351.992712)
			(xy 29.522928 -351.9932) (xy 28.659328 -351.9932) (xy 28.632058 -351.992663) (xy 28.578074 -351.984904)
			(xy 28.525743 -351.969542) (xy 28.476131 -351.946888) (xy 28.430249 -351.917404) (xy 28.389029 -351.881691)
			(xy 28.353312 -351.840474) (xy 28.323825 -351.794593) (xy 28.301168 -351.744983) (xy 28.285802 -351.692654)
			(xy 28.278039 -351.63867) (xy 26.795336 -351.63867) (xy 26.795336 -351.638675) (xy 26.787573 -351.69267)
			(xy 26.772203 -351.745011) (xy 26.749541 -351.794631) (xy 26.720047 -351.840521) (xy 26.684323 -351.881746)
			(xy 26.643095 -351.917467) (xy 26.597203 -351.946956) (xy 26.547581 -351.969614) (xy 26.495239 -351.984979)
			(xy 26.441243 -351.992739) (xy 26.413968 -351.9932) (xy 25.550368 -351.9932) (xy 25.523103 -351.992635)
			(xy 25.469128 -351.984871) (xy 25.416808 -351.969504) (xy 25.367206 -351.946849) (xy 25.321334 -351.917365)
			(xy 25.280124 -351.881653) (xy 25.244416 -351.84044) (xy 25.214936 -351.794566) (xy 25.192284 -351.744962)
			(xy 25.176922 -351.692641) (xy 25.169162 -351.638665) (xy 23.686314 -351.638665) (xy 23.686314 -351.638672)
			(xy 23.678551 -351.69266) (xy 23.663185 -351.744994) (xy 23.640527 -351.794609) (xy 23.611039 -351.840494)
			(xy 23.575321 -351.881715) (xy 23.5341 -351.917434) (xy 23.488216 -351.946923) (xy 23.438602 -351.969582)
			(xy 23.386268 -351.98495) (xy 23.33228 -351.992713) (xy 23.305008 -351.9932) (xy 22.441408 -351.9932)
			(xy 22.414139 -351.992661) (xy 22.360157 -351.984901) (xy 22.307829 -351.969537) (xy 22.258219 -351.946882)
			(xy 22.212339 -351.917397) (xy 22.171122 -351.881683) (xy 22.135407 -351.840467) (xy 22.105922 -351.794588)
			(xy 22.083266 -351.744979) (xy 22.067901 -351.692651) (xy 22.060139 -351.638669) (xy 20.577347 -351.638669)
			(xy 20.577347 -351.638711) (xy 20.569584 -351.692698) (xy 20.554218 -351.74503) (xy 20.53156 -351.794643)
			(xy 20.502073 -351.840527) (xy 20.466355 -351.881747) (xy 20.425135 -351.917464) (xy 20.379252 -351.946951)
			(xy 20.329638 -351.969609) (xy 20.277306 -351.984975) (xy 20.223319 -351.992737) (xy 20.196048 -351.9932)
			(xy 19.332448 -351.9932) (xy 19.305179 -351.992717) (xy 19.251195 -351.984955) (xy 19.198865 -351.96959)
			(xy 19.149255 -351.946933) (xy 19.103374 -351.917447) (xy 19.062157 -351.881732) (xy 19.026441 -351.840514)
			(xy 18.996956 -351.794633) (xy 18.974299 -351.745023) (xy 18.958934 -351.692693) (xy 18.951172 -351.638709)
			(xy 1.524 -351.638709) (xy 1.524 -354.759373) (xy 22.060084 -354.759373) (xy 22.060084 -354.704827)
			(xy 22.067846 -354.650837) (xy 22.083214 -354.598501) (xy 22.105873 -354.548885) (xy 22.135363 -354.502999)
			(xy 22.171083 -354.461777) (xy 22.212306 -354.426058) (xy 22.258192 -354.396569) (xy 22.307809 -354.373911)
			(xy 22.360145 -354.358545) (xy 22.414135 -354.350783) (xy 22.441408 -354.35032) (xy 23.305008 -354.35032)
			(xy 23.332276 -354.350843) (xy 23.386256 -354.358605) (xy 23.438582 -354.37397) (xy 23.488189 -354.396626)
			(xy 23.534067 -354.426111) (xy 23.575281 -354.461824) (xy 23.610994 -354.50304) (xy 23.640478 -354.548918)
			(xy 23.663132 -354.598525) (xy 23.678497 -354.650852) (xy 23.686258 -354.704832) (xy 23.686258 -354.759368)
			(xy 23.686258 -354.759369) (xy 25.169106 -354.759369) (xy 25.169106 -354.704831) (xy 25.176868 -354.650847)
			(xy 25.192232 -354.598518) (xy 25.214887 -354.548908) (xy 25.244371 -354.503026) (xy 25.280085 -354.461807)
			(xy 25.3213 -354.42609) (xy 25.36718 -354.396602) (xy 25.416788 -354.373943) (xy 25.469116 -354.358574)
			(xy 25.523099 -354.350809) (xy 25.550368 -354.35032) (xy 26.413968 -354.35032) (xy 26.441239 -354.350817)
			(xy 26.495227 -354.358575) (xy 26.547561 -354.373938) (xy 26.597176 -354.396593) (xy 26.643061 -354.426078)
			(xy 26.684283 -354.461794) (xy 26.720003 -354.503013) (xy 26.749492 -354.548896) (xy 26.772151 -354.598509)
			(xy 26.787518 -354.650842) (xy 26.79528 -354.704829) (xy 26.79528 -354.759371) (xy 26.79528 -354.759374)
			(xy 28.277984 -354.759374) (xy 28.277984 -354.704826) (xy 28.285747 -354.650835) (xy 28.301115 -354.598497)
			(xy 28.323776 -354.54888) (xy 28.353268 -354.502993) (xy 28.38899 -354.46177) (xy 28.430215 -354.426051)
			(xy 28.476104 -354.396562) (xy 28.525723 -354.373905) (xy 28.578062 -354.358541) (xy 28.632054 -354.350782)
			(xy 28.659328 -354.35032) (xy 29.522928 -354.35032) (xy 29.550195 -354.350844) (xy 29.604173 -354.358609)
			(xy 29.656497 -354.373976) (xy 29.706101 -354.396633) (xy 29.751976 -354.426118) (xy 29.793188 -354.461831)
			(xy 29.828899 -354.503046) (xy 29.858381 -354.548924) (xy 29.881034 -354.59853) (xy 29.896397 -354.650855)
			(xy 29.904158 -354.704833) (xy 29.904158 -354.759367) (xy 29.904158 -354.75937) (xy 31.387006 -354.75937)
			(xy 31.387006 -354.70483) (xy 31.394768 -354.650845) (xy 31.410134 -354.598514) (xy 31.43279 -354.548902)
			(xy 31.462276 -354.50302) (xy 31.497992 -354.4618) (xy 31.53921 -354.426083) (xy 31.585091 -354.396596)
			(xy 31.634703 -354.373938) (xy 31.687033 -354.358571) (xy 31.741018 -354.350807) (xy 31.768288 -354.35032)
			(xy 32.631888 -354.35032) (xy 32.659158 -354.350819) (xy 32.713144 -354.358579) (xy 32.765476 -354.373944)
			(xy 32.815088 -354.396599) (xy 32.860971 -354.426085) (xy 32.902191 -354.461801) (xy 32.937908 -354.503019)
			(xy 32.967395 -354.548902) (xy 32.990052 -354.598513) (xy 33.005418 -354.650844) (xy 33.013181 -354.70483)
			(xy 33.013181 -354.75937) (xy 33.01318 -354.759374) (xy 34.495884 -354.759374) (xy 34.495884 -354.704826)
			(xy 34.503647 -354.650832) (xy 34.519017 -354.598493) (xy 34.541679 -354.548874) (xy 34.571172 -354.502986)
			(xy 34.606897 -354.461763) (xy 34.648125 -354.426044) (xy 34.694016 -354.396556) (xy 34.743638 -354.3739)
			(xy 34.795979 -354.358537) (xy 34.849973 -354.35078) (xy 34.877248 -354.35032) (xy 35.740848 -354.35032)
			(xy 35.768114 -354.350846) (xy 35.82209 -354.358613) (xy 35.874411 -354.373981) (xy 35.924013 -354.396639)
			(xy 35.969886 -354.426125) (xy 36.011095 -354.461839) (xy 36.046804 -354.503053) (xy 36.076284 -354.548929)
			(xy 36.098936 -354.598534) (xy 36.114298 -354.650857) (xy 36.122058 -354.704834) (xy 36.122058 -354.759366)
			(xy 36.122057 -354.759373) (xy 37.604884 -354.759373) (xy 37.604884 -354.704827) (xy 37.612646 -354.650837)
			(xy 37.628014 -354.598501) (xy 37.650673 -354.548885) (xy 37.680163 -354.502999) (xy 37.715883 -354.461777)
			(xy 37.757106 -354.426058) (xy 37.802992 -354.396569) (xy 37.852609 -354.373911) (xy 37.904945 -354.358545)
			(xy 37.958935 -354.350783) (xy 37.986208 -354.35032) (xy 38.849808 -354.35032) (xy 38.877076 -354.350843)
			(xy 38.931056 -354.358605) (xy 38.983382 -354.37397) (xy 39.032989 -354.396626) (xy 39.078867 -354.426111)
			(xy 39.120081 -354.461824) (xy 39.155794 -354.50304) (xy 39.185278 -354.548918) (xy 39.207932 -354.598525)
			(xy 39.223297 -354.650852) (xy 39.231058 -354.704832) (xy 39.231058 -354.759368) (xy 39.231058 -354.759369)
			(xy 40.713906 -354.759369) (xy 40.713906 -354.704831) (xy 40.721668 -354.650847) (xy 40.737032 -354.598518)
			(xy 40.759687 -354.548908) (xy 40.789171 -354.503026) (xy 40.824885 -354.461807) (xy 40.8661 -354.42609)
			(xy 40.91198 -354.396602) (xy 40.961588 -354.373943) (xy 41.013916 -354.358574) (xy 41.067899 -354.350809)
			(xy 41.095168 -354.35032) (xy 41.958768 -354.35032) (xy 41.986039 -354.350817) (xy 42.040027 -354.358575)
			(xy 42.092361 -354.373938) (xy 42.141976 -354.396593) (xy 42.187861 -354.426078) (xy 42.229083 -354.461794)
			(xy 42.264803 -354.503013) (xy 42.294292 -354.548896) (xy 42.316951 -354.598509) (xy 42.332318 -354.650842)
			(xy 42.34008 -354.704829) (xy 42.34008 -354.759371) (xy 42.34008 -354.759374) (xy 43.822784 -354.759374)
			(xy 43.822784 -354.704826) (xy 43.830547 -354.650835) (xy 43.845915 -354.598497) (xy 43.868576 -354.54888)
			(xy 43.898068 -354.502993) (xy 43.93379 -354.46177) (xy 43.975015 -354.426051) (xy 44.020904 -354.396562)
			(xy 44.070523 -354.373905) (xy 44.122862 -354.358541) (xy 44.176854 -354.350782) (xy 44.204128 -354.35032)
			(xy 45.067728 -354.35032) (xy 45.094995 -354.350844) (xy 45.148973 -354.358609) (xy 45.201297 -354.373976)
			(xy 45.250901 -354.396633) (xy 45.296776 -354.426118) (xy 45.337988 -354.461831) (xy 45.373699 -354.503046)
			(xy 45.403181 -354.548924) (xy 45.425834 -354.59853) (xy 45.441197 -354.650855) (xy 45.448958 -354.704833)
			(xy 45.448958 -354.759367) (xy 45.448958 -354.75937) (xy 46.931806 -354.75937) (xy 46.931806 -354.70483)
			(xy 46.939568 -354.650845) (xy 46.954934 -354.598514) (xy 46.97759 -354.548902) (xy 47.007076 -354.50302)
			(xy 47.042792 -354.4618) (xy 47.08401 -354.426083) (xy 47.129891 -354.396596) (xy 47.179503 -354.373938)
			(xy 47.231833 -354.358571) (xy 47.285818 -354.350807) (xy 47.313088 -354.35032) (xy 48.176688 -354.35032)
			(xy 48.203958 -354.350819) (xy 48.257944 -354.358579) (xy 48.310276 -354.373944) (xy 48.359888 -354.396599)
			(xy 48.405771 -354.426085) (xy 48.446991 -354.461801) (xy 48.482708 -354.503019) (xy 48.512195 -354.548902)
			(xy 48.534852 -354.598513) (xy 48.550218 -354.650844) (xy 48.557981 -354.70483) (xy 48.557981 -354.75937)
			(xy 48.55798 -354.759374) (xy 50.040684 -354.759374) (xy 50.040684 -354.704826) (xy 50.048447 -354.650832)
			(xy 50.063817 -354.598493) (xy 50.086479 -354.548874) (xy 50.115972 -354.502986) (xy 50.151697 -354.461763)
			(xy 50.192925 -354.426044) (xy 50.238816 -354.396556) (xy 50.288438 -354.3739) (xy 50.340779 -354.358537)
			(xy 50.394773 -354.35078) (xy 50.422048 -354.35032) (xy 51.285648 -354.35032) (xy 51.312914 -354.350846)
			(xy 51.36689 -354.358613) (xy 51.419211 -354.373981) (xy 51.468813 -354.396639) (xy 51.514686 -354.426125)
			(xy 51.555895 -354.461839) (xy 51.591604 -354.503053) (xy 51.621084 -354.548929) (xy 51.643736 -354.598534)
			(xy 51.659098 -354.650857) (xy 51.666858 -354.704834) (xy 51.666858 -354.759366) (xy 51.666857 -354.759372)
			(xy 64.099884 -354.759372) (xy 64.099884 -354.704828) (xy 64.107646 -354.650838) (xy 64.123013 -354.598503)
			(xy 64.145672 -354.548887) (xy 64.175161 -354.503001) (xy 64.210881 -354.461779) (xy 64.252103 -354.42606)
			(xy 64.297989 -354.396571) (xy 64.347605 -354.373912) (xy 64.39994 -354.358546) (xy 64.45393 -354.350783)
			(xy 64.481202 -354.35032) (xy 65.344802 -354.35032) (xy 65.37207 -354.350843) (xy 65.426051 -354.358604)
			(xy 65.478378 -354.373969) (xy 65.527985 -354.396624) (xy 65.573864 -354.426109) (xy 65.615079 -354.461822)
			(xy 65.650793 -354.503038) (xy 65.680277 -354.548917) (xy 65.702932 -354.598524) (xy 65.718296 -354.650851)
			(xy 65.726058 -354.704832) (xy 65.726058 -354.759368) (xy 65.726058 -354.759369) (xy 67.208906 -354.759369)
			(xy 67.208906 -354.704831) (xy 67.216667 -354.650848) (xy 67.232032 -354.598519) (xy 67.254686 -354.548909)
			(xy 67.28417 -354.503028) (xy 67.319883 -354.46181) (xy 67.361098 -354.426093) (xy 67.406976 -354.396604)
			(xy 67.456584 -354.373945) (xy 67.508911 -354.358575) (xy 67.562893 -354.350809) (xy 67.590162 -354.35032)
			(xy 68.453762 -354.35032) (xy 68.481033 -354.350817) (xy 68.535022 -354.358574) (xy 68.587357 -354.373936)
			(xy 68.636972 -354.396591) (xy 68.682859 -354.426076) (xy 68.724081 -354.461792) (xy 68.759801 -354.503011)
			(xy 68.789291 -354.548894) (xy 68.81195 -354.598508) (xy 68.827318 -354.650841) (xy 68.83508 -354.704829)
			(xy 68.83508 -354.759371) (xy 68.83508 -354.759373) (xy 70.317784 -354.759373) (xy 70.317784 -354.704827)
			(xy 70.325547 -354.650835) (xy 70.340915 -354.598498) (xy 70.363575 -354.548882) (xy 70.393066 -354.502995)
			(xy 70.428788 -354.461772) (xy 70.470012 -354.426053) (xy 70.515901 -354.396564) (xy 70.565519 -354.373907)
			(xy 70.617857 -354.358542) (xy 70.671849 -354.350782) (xy 70.699122 -354.35032) (xy 71.562722 -354.35032)
			(xy 71.589989 -354.350844) (xy 71.643968 -354.358608) (xy 71.696292 -354.373974) (xy 71.745897 -354.396631)
			(xy 71.791773 -354.426116) (xy 71.832986 -354.461829) (xy 71.868697 -354.503044) (xy 71.89818 -354.548922)
			(xy 71.920833 -354.598528) (xy 71.936197 -354.650854) (xy 71.943958 -354.704833) (xy 71.943958 -354.759367)
			(xy 71.943958 -354.75937) (xy 73.426806 -354.75937) (xy 73.426806 -354.70483) (xy 73.434568 -354.650846)
			(xy 73.449933 -354.598515) (xy 73.472589 -354.548904) (xy 73.502075 -354.503022) (xy 73.53779 -354.461802)
			(xy 73.579007 -354.426085) (xy 73.624888 -354.396598) (xy 73.674498 -354.373939) (xy 73.726828 -354.358572)
			(xy 73.780812 -354.350808) (xy 73.808082 -354.35032) (xy 74.671682 -354.35032) (xy 74.698953 -354.350818)
			(xy 74.752939 -354.358578) (xy 74.805271 -354.373942) (xy 74.854884 -354.396597) (xy 74.900768 -354.426083)
			(xy 74.941988 -354.461799) (xy 74.977706 -354.503018) (xy 75.007194 -354.5489) (xy 75.029852 -354.598512)
			(xy 75.045218 -354.650844) (xy 75.052981 -354.704829) (xy 75.052981 -354.759371) (xy 75.052981 -354.759374)
			(xy 76.535684 -354.759374) (xy 76.535684 -354.704826) (xy 76.543447 -354.650833) (xy 76.558816 -354.598494)
			(xy 76.581478 -354.548876) (xy 76.610971 -354.502988) (xy 76.646695 -354.461765) (xy 76.687922 -354.426046)
			(xy 76.733813 -354.396558) (xy 76.783434 -354.373902) (xy 76.835774 -354.358538) (xy 76.889768 -354.350781)
			(xy 76.917042 -354.35032) (xy 77.780642 -354.35032) (xy 77.807908 -354.350845) (xy 77.861885 -354.358611)
			(xy 77.914207 -354.37398) (xy 77.963809 -354.396637) (xy 78.009683 -354.426123) (xy 78.050893 -354.461836)
			(xy 78.086602 -354.503051) (xy 78.116083 -354.548928) (xy 78.138735 -354.598533) (xy 78.154098 -354.650856)
			(xy 78.161858 -354.704834) (xy 78.161858 -354.759366) (xy 78.161857 -354.759372) (xy 79.644684 -354.759372)
			(xy 79.644684 -354.704828) (xy 79.652446 -354.650838) (xy 79.667813 -354.598503) (xy 79.690472 -354.548887)
			(xy 79.719961 -354.503001) (xy 79.755681 -354.461779) (xy 79.796903 -354.42606) (xy 79.842789 -354.396571)
			(xy 79.892405 -354.373912) (xy 79.94474 -354.358546) (xy 79.99873 -354.350783) (xy 80.026002 -354.35032)
			(xy 80.889602 -354.35032) (xy 80.91687 -354.350843) (xy 80.970851 -354.358604) (xy 81.023178 -354.373969)
			(xy 81.072785 -354.396624) (xy 81.118664 -354.426109) (xy 81.159879 -354.461822) (xy 81.195593 -354.503038)
			(xy 81.225077 -354.548917) (xy 81.247732 -354.598524) (xy 81.263096 -354.650851) (xy 81.270858 -354.704832)
			(xy 81.270858 -354.759368) (xy 81.270858 -354.759369) (xy 82.753706 -354.759369) (xy 82.753706 -354.704831)
			(xy 82.761467 -354.650848) (xy 82.776832 -354.598519) (xy 82.799486 -354.548909) (xy 82.82897 -354.503028)
			(xy 82.864683 -354.46181) (xy 82.905898 -354.426093) (xy 82.951776 -354.396604) (xy 83.001384 -354.373945)
			(xy 83.053711 -354.358575) (xy 83.107693 -354.350809) (xy 83.134962 -354.35032) (xy 83.998562 -354.35032)
			(xy 84.025833 -354.350817) (xy 84.079822 -354.358574) (xy 84.132157 -354.373936) (xy 84.181772 -354.396591)
			(xy 84.227659 -354.426076) (xy 84.268881 -354.461792) (xy 84.304601 -354.503011) (xy 84.334091 -354.548894)
			(xy 84.35675 -354.598508) (xy 84.372118 -354.650841) (xy 84.37988 -354.704829) (xy 84.37988 -354.759371)
			(xy 84.37988 -354.759373) (xy 85.862584 -354.759373) (xy 85.862584 -354.704827) (xy 85.870347 -354.650835)
			(xy 85.885715 -354.598498) (xy 85.908375 -354.548882) (xy 85.937866 -354.502995) (xy 85.973588 -354.461772)
			(xy 86.014812 -354.426053) (xy 86.060701 -354.396564) (xy 86.110319 -354.373907) (xy 86.162657 -354.358542)
			(xy 86.216649 -354.350782) (xy 86.243922 -354.35032) (xy 87.107522 -354.35032) (xy 87.134789 -354.350844)
			(xy 87.188768 -354.358608) (xy 87.241092 -354.373974) (xy 87.290697 -354.396631) (xy 87.336573 -354.426116)
			(xy 87.377786 -354.461829) (xy 87.413497 -354.503044) (xy 87.44298 -354.548922) (xy 87.465633 -354.598528)
			(xy 87.480997 -354.650854) (xy 87.488758 -354.704833) (xy 87.488758 -354.759367) (xy 87.488758 -354.75937)
			(xy 88.971606 -354.75937) (xy 88.971606 -354.70483) (xy 88.979368 -354.650846) (xy 88.994733 -354.598515)
			(xy 89.017389 -354.548904) (xy 89.046875 -354.503022) (xy 89.08259 -354.461802) (xy 89.123807 -354.426085)
			(xy 89.169688 -354.396598) (xy 89.219298 -354.373939) (xy 89.271628 -354.358572) (xy 89.325612 -354.350808)
			(xy 89.352882 -354.35032) (xy 90.216482 -354.35032) (xy 90.243753 -354.350818) (xy 90.297739 -354.358578)
			(xy 90.350071 -354.373942) (xy 90.399684 -354.396597) (xy 90.445568 -354.426083) (xy 90.486788 -354.461799)
			(xy 90.522506 -354.503018) (xy 90.551994 -354.5489) (xy 90.574652 -354.598512) (xy 90.590018 -354.650844)
			(xy 90.597781 -354.704829) (xy 90.597781 -354.759371) (xy 90.597781 -354.759374) (xy 92.080484 -354.759374)
			(xy 92.080484 -354.704826) (xy 92.088247 -354.650833) (xy 92.103616 -354.598494) (xy 92.126278 -354.548876)
			(xy 92.155771 -354.502988) (xy 92.191495 -354.461765) (xy 92.232722 -354.426046) (xy 92.278613 -354.396558)
			(xy 92.328234 -354.373902) (xy 92.380574 -354.358538) (xy 92.434568 -354.350781) (xy 92.461842 -354.35032)
			(xy 93.325442 -354.35032) (xy 93.352708 -354.350845) (xy 93.406685 -354.358611) (xy 93.459007 -354.37398)
			(xy 93.508609 -354.396637) (xy 93.554483 -354.426123) (xy 93.595693 -354.461836) (xy 93.631402 -354.503051)
			(xy 93.660883 -354.548928) (xy 93.683535 -354.598533) (xy 93.698898 -354.650856) (xy 93.706658 -354.704834)
			(xy 93.706658 -354.759366) (xy 93.706658 -354.759369) (xy 114.589806 -354.759369) (xy 114.589806 -354.704831)
			(xy 114.597568 -354.650847) (xy 114.612932 -354.598518) (xy 114.635587 -354.548908) (xy 114.665071 -354.503026)
			(xy 114.700785 -354.461807) (xy 114.742 -354.42609) (xy 114.78788 -354.396602) (xy 114.837488 -354.373943)
			(xy 114.889816 -354.358574) (xy 114.943799 -354.350809) (xy 114.971068 -354.35032) (xy 115.834668 -354.35032)
			(xy 115.861939 -354.350817) (xy 115.915927 -354.358575) (xy 115.968261 -354.373938) (xy 116.017876 -354.396593)
			(xy 116.063761 -354.426078) (xy 116.104983 -354.461794) (xy 116.140703 -354.503013) (xy 116.170192 -354.548896)
			(xy 116.192851 -354.598509) (xy 116.208218 -354.650842) (xy 116.21598 -354.704829) (xy 116.21598 -354.759371)
			(xy 116.21598 -354.759374) (xy 117.698684 -354.759374) (xy 117.698684 -354.704826) (xy 117.706447 -354.650835)
			(xy 117.721815 -354.598497) (xy 117.744476 -354.54888) (xy 117.773968 -354.502993) (xy 117.80969 -354.46177)
			(xy 117.850915 -354.426051) (xy 117.896804 -354.396562) (xy 117.946423 -354.373905) (xy 117.998762 -354.358541)
			(xy 118.052754 -354.350782) (xy 118.080028 -354.35032) (xy 118.943628 -354.35032) (xy 118.970895 -354.350844)
			(xy 119.024873 -354.358609) (xy 119.077197 -354.373976) (xy 119.126801 -354.396633) (xy 119.172676 -354.426118)
			(xy 119.213888 -354.461831) (xy 119.249599 -354.503046) (xy 119.279081 -354.548924) (xy 119.301734 -354.59853)
			(xy 119.317097 -354.650855) (xy 119.324858 -354.704833) (xy 119.324858 -354.759367) (xy 119.324858 -354.75937)
			(xy 120.807706 -354.75937) (xy 120.807706 -354.70483) (xy 120.815468 -354.650845) (xy 120.830834 -354.598514)
			(xy 120.85349 -354.548902) (xy 120.882976 -354.50302) (xy 120.918692 -354.4618) (xy 120.95991 -354.426083)
			(xy 121.005791 -354.396596) (xy 121.055403 -354.373938) (xy 121.107733 -354.358571) (xy 121.161718 -354.350807)
			(xy 121.188988 -354.35032) (xy 122.052588 -354.35032) (xy 122.079858 -354.350819) (xy 122.133844 -354.358579)
			(xy 122.186176 -354.373944) (xy 122.235788 -354.396599) (xy 122.281671 -354.426085) (xy 122.322891 -354.461801)
			(xy 122.358608 -354.503019) (xy 122.388095 -354.548902) (xy 122.410752 -354.598513) (xy 122.426118 -354.650844)
			(xy 122.433881 -354.70483) (xy 122.433881 -354.75937) (xy 122.43388 -354.759374) (xy 123.916584 -354.759374)
			(xy 123.916584 -354.704826) (xy 123.924347 -354.650832) (xy 123.939717 -354.598493) (xy 123.962379 -354.548874)
			(xy 123.991872 -354.502986) (xy 124.027597 -354.461763) (xy 124.068825 -354.426044) (xy 124.114716 -354.396556)
			(xy 124.164338 -354.3739) (xy 124.216679 -354.358537) (xy 124.270673 -354.35078) (xy 124.297948 -354.35032)
			(xy 125.161548 -354.35032) (xy 125.188814 -354.350846) (xy 125.24279 -354.358613) (xy 125.295111 -354.373981)
			(xy 125.344713 -354.396639) (xy 125.390586 -354.426125) (xy 125.431795 -354.461839) (xy 125.467504 -354.503053)
			(xy 125.496984 -354.548929) (xy 125.519636 -354.598534) (xy 125.534998 -354.650857) (xy 125.542758 -354.704834)
			(xy 125.542758 -354.759366) (xy 125.542757 -354.759373) (xy 127.025584 -354.759373) (xy 127.025584 -354.704827)
			(xy 127.033346 -354.650837) (xy 127.048714 -354.598501) (xy 127.071373 -354.548885) (xy 127.100863 -354.502999)
			(xy 127.136583 -354.461777) (xy 127.177806 -354.426058) (xy 127.223692 -354.396569) (xy 127.273309 -354.373911)
			(xy 127.325645 -354.358545) (xy 127.379635 -354.350783) (xy 127.406908 -354.35032) (xy 128.270508 -354.35032)
			(xy 128.297776 -354.350843) (xy 128.351756 -354.358605) (xy 128.404082 -354.37397) (xy 128.453689 -354.396626)
			(xy 128.499567 -354.426111) (xy 128.540781 -354.461824) (xy 128.576494 -354.50304) (xy 128.605978 -354.548918)
			(xy 128.628632 -354.598525) (xy 128.643997 -354.650852) (xy 128.651758 -354.704832) (xy 128.651758 -354.759368)
			(xy 128.651758 -354.759369) (xy 130.134606 -354.759369) (xy 130.134606 -354.704831) (xy 130.142368 -354.650847)
			(xy 130.157732 -354.598518) (xy 130.180387 -354.548908) (xy 130.209871 -354.503026) (xy 130.245585 -354.461807)
			(xy 130.2868 -354.42609) (xy 130.33268 -354.396602) (xy 130.382288 -354.373943) (xy 130.434616 -354.358574)
			(xy 130.488599 -354.350809) (xy 130.515868 -354.35032) (xy 131.379468 -354.35032) (xy 131.406739 -354.350817)
			(xy 131.460727 -354.358575) (xy 131.513061 -354.373938) (xy 131.562676 -354.396593) (xy 131.608561 -354.426078)
			(xy 131.649783 -354.461794) (xy 131.685503 -354.503013) (xy 131.714992 -354.548896) (xy 131.737651 -354.598509)
			(xy 131.753018 -354.650842) (xy 131.76078 -354.704829) (xy 131.76078 -354.759371) (xy 131.76078 -354.759374)
			(xy 133.243484 -354.759374) (xy 133.243484 -354.704826) (xy 133.251247 -354.650835) (xy 133.266615 -354.598497)
			(xy 133.289276 -354.54888) (xy 133.318768 -354.502993) (xy 133.35449 -354.46177) (xy 133.395715 -354.426051)
			(xy 133.441604 -354.396562) (xy 133.491223 -354.373905) (xy 133.543562 -354.358541) (xy 133.597554 -354.350782)
			(xy 133.624828 -354.35032) (xy 134.488428 -354.35032) (xy 134.515695 -354.350844) (xy 134.569673 -354.358609)
			(xy 134.621997 -354.373976) (xy 134.671601 -354.396633) (xy 134.717476 -354.426118) (xy 134.758688 -354.461831)
			(xy 134.794399 -354.503046) (xy 134.823881 -354.548924) (xy 134.846534 -354.59853) (xy 134.861897 -354.650855)
			(xy 134.869658 -354.704833) (xy 134.869658 -354.759367) (xy 134.869658 -354.75937) (xy 136.352506 -354.75937)
			(xy 136.352506 -354.70483) (xy 136.360268 -354.650845) (xy 136.375634 -354.598514) (xy 136.39829 -354.548902)
			(xy 136.427776 -354.50302) (xy 136.463492 -354.4618) (xy 136.50471 -354.426083) (xy 136.550591 -354.396596)
			(xy 136.600203 -354.373938) (xy 136.652533 -354.358571) (xy 136.706518 -354.350807) (xy 136.733788 -354.35032)
			(xy 137.597388 -354.35032) (xy 137.624658 -354.350819) (xy 137.678644 -354.358579) (xy 137.730976 -354.373944)
			(xy 137.780588 -354.396599) (xy 137.826471 -354.426085) (xy 137.867691 -354.461801) (xy 137.903408 -354.503019)
			(xy 137.932895 -354.548902) (xy 137.955552 -354.598513) (xy 137.970918 -354.650844) (xy 137.978681 -354.70483)
			(xy 137.978681 -354.75937) (xy 137.97868 -354.759374) (xy 139.461384 -354.759374) (xy 139.461384 -354.704826)
			(xy 139.469147 -354.650832) (xy 139.484517 -354.598493) (xy 139.507179 -354.548874) (xy 139.536672 -354.502986)
			(xy 139.572397 -354.461763) (xy 139.613625 -354.426044) (xy 139.659516 -354.396556) (xy 139.709138 -354.3739)
			(xy 139.761479 -354.358537) (xy 139.815473 -354.35078) (xy 139.842748 -354.35032) (xy 140.706348 -354.35032)
			(xy 140.733614 -354.350846) (xy 140.78759 -354.358613) (xy 140.839911 -354.373981) (xy 140.889513 -354.396639)
			(xy 140.935386 -354.426125) (xy 140.976595 -354.461839) (xy 141.012304 -354.503053) (xy 141.041784 -354.548929)
			(xy 141.064436 -354.598534) (xy 141.079798 -354.650857) (xy 141.087558 -354.704834) (xy 141.087558 -354.759366)
			(xy 141.087557 -354.759373) (xy 142.570384 -354.759373) (xy 142.570384 -354.704827) (xy 142.578146 -354.650837)
			(xy 142.593514 -354.598501) (xy 142.616173 -354.548885) (xy 142.645663 -354.502999) (xy 142.681383 -354.461777)
			(xy 142.722606 -354.426058) (xy 142.768492 -354.396569) (xy 142.818109 -354.373911) (xy 142.870445 -354.358545)
			(xy 142.924435 -354.350783) (xy 142.951708 -354.35032) (xy 143.815308 -354.35032) (xy 143.842576 -354.350843)
			(xy 143.896556 -354.358605) (xy 143.948882 -354.37397) (xy 143.998489 -354.396626) (xy 144.044367 -354.426111)
			(xy 144.085581 -354.461824) (xy 144.121294 -354.50304) (xy 144.150778 -354.548918) (xy 144.173432 -354.598525)
			(xy 144.188797 -354.650852) (xy 144.196558 -354.704832) (xy 144.196558 -354.759368) (xy 158.695906 -354.759368)
			(xy 158.695906 -354.704832) (xy 158.703667 -354.65085) (xy 158.719031 -354.598521) (xy 158.741685 -354.548912)
			(xy 158.771167 -354.503031) (xy 158.806879 -354.461813) (xy 158.848093 -354.426096) (xy 158.89397 -354.396608)
			(xy 158.943576 -354.373948) (xy 158.995903 -354.358577) (xy 159.049884 -354.35081) (xy 159.077152 -354.35032)
			(xy 159.940752 -354.35032) (xy 159.968024 -354.350816) (xy 160.022013 -354.358572) (xy 160.074349 -354.373934)
			(xy 160.123966 -354.396588) (xy 160.169854 -354.426072) (xy 160.211078 -354.461788) (xy 160.246799 -354.503008)
			(xy 160.276289 -354.548891) (xy 160.298949 -354.598506) (xy 160.314317 -354.65084) (xy 160.32208 -354.704828)
			(xy 160.32208 -354.759372) (xy 160.32208 -354.759373) (xy 161.804784 -354.759373) (xy 161.804784 -354.704827)
			(xy 161.812546 -354.650837) (xy 161.827914 -354.598501) (xy 161.850573 -354.548884) (xy 161.880064 -354.502998)
			(xy 161.915784 -354.461776) (xy 161.957008 -354.426056) (xy 162.002895 -354.396568) (xy 162.052512 -354.37391)
			(xy 162.104848 -354.358544) (xy 162.158839 -354.350783) (xy 162.186112 -354.35032) (xy 163.049712 -354.35032)
			(xy 163.07698 -354.350843) (xy 163.130959 -354.358606) (xy 163.183285 -354.373972) (xy 163.232891 -354.396627)
			(xy 163.278768 -354.426112) (xy 163.319983 -354.461826) (xy 163.355695 -354.503041) (xy 163.385178 -354.548919)
			(xy 163.407833 -354.598526) (xy 163.423197 -354.650852) (xy 163.430958 -354.704832) (xy 163.430958 -354.759368)
			(xy 163.430958 -354.759369) (xy 164.913806 -354.759369) (xy 164.913806 -354.704831) (xy 164.921568 -354.650847)
			(xy 164.936932 -354.598517) (xy 164.959588 -354.548907) (xy 164.989072 -354.503025) (xy 165.024786 -354.461806)
			(xy 165.066002 -354.426089) (xy 165.111882 -354.396601) (xy 165.161491 -354.373942) (xy 165.21382 -354.358574)
			(xy 165.267803 -354.350808) (xy 165.295072 -354.35032) (xy 166.158672 -354.35032) (xy 166.185943 -354.350818)
			(xy 166.23993 -354.358576) (xy 166.292264 -354.373939) (xy 166.341878 -354.396594) (xy 166.387763 -354.42608)
			(xy 166.428985 -354.461795) (xy 166.464704 -354.503014) (xy 166.494192 -354.548897) (xy 166.516851 -354.59851)
			(xy 166.532218 -354.650842) (xy 166.53998 -354.704829) (xy 166.53998 -354.759371) (xy 166.53998 -354.759374)
			(xy 168.022684 -354.759374) (xy 168.022684 -354.704826) (xy 168.030447 -354.650834) (xy 168.045816 -354.598496)
			(xy 168.068477 -354.548879) (xy 168.097969 -354.502991) (xy 168.133691 -354.461768) (xy 168.174917 -354.426049)
			(xy 168.220807 -354.396561) (xy 168.270426 -354.373904) (xy 168.322765 -354.35854) (xy 168.376758 -354.350781)
			(xy 168.404032 -354.35032) (xy 169.267632 -354.35032) (xy 169.294899 -354.350845) (xy 169.348876 -354.35861)
			(xy 169.401199 -354.373977) (xy 169.450803 -354.396634) (xy 169.496678 -354.426119) (xy 169.53789 -354.461833)
			(xy 169.5736 -354.503048) (xy 169.603081 -354.548925) (xy 169.625734 -354.598531) (xy 169.641097 -354.650855)
			(xy 169.648858 -354.704833) (xy 169.648858 -354.759367) (xy 169.648858 -354.75937) (xy 171.131706 -354.75937)
			(xy 171.131706 -354.70483) (xy 171.139468 -354.650844) (xy 171.154834 -354.598513) (xy 171.177491 -354.548901)
			(xy 171.206977 -354.503018) (xy 171.242693 -354.461799) (xy 171.283912 -354.426082) (xy 171.329794 -354.396594)
			(xy 171.379405 -354.373937) (xy 171.431736 -354.35857) (xy 171.485722 -354.350807) (xy 171.512992 -354.35032)
			(xy 172.376592 -354.35032) (xy 172.403862 -354.350819) (xy 172.457847 -354.35858) (xy 172.510178 -354.373945)
			(xy 172.55979 -354.396601) (xy 172.605673 -354.426087) (xy 172.646892 -354.461802) (xy 172.682609 -354.503021)
			(xy 172.712096 -354.548903) (xy 172.734753 -354.598514) (xy 172.750119 -354.650845) (xy 172.757881 -354.70483)
			(xy 172.757881 -354.759368) (xy 174.240706 -354.759368) (xy 174.240706 -354.704832) (xy 174.248467 -354.65085)
			(xy 174.263831 -354.598521) (xy 174.286485 -354.548912) (xy 174.315967 -354.503031) (xy 174.351679 -354.461813)
			(xy 174.392893 -354.426096) (xy 174.43877 -354.396608) (xy 174.488376 -354.373948) (xy 174.540703 -354.358577)
			(xy 174.594684 -354.35081) (xy 174.621952 -354.35032) (xy 175.485552 -354.35032) (xy 175.512824 -354.350816)
			(xy 175.566813 -354.358572) (xy 175.619149 -354.373934) (xy 175.668766 -354.396588) (xy 175.714654 -354.426072)
			(xy 175.755878 -354.461788) (xy 175.791599 -354.503008) (xy 175.821089 -354.548891) (xy 175.843749 -354.598506)
			(xy 175.859117 -354.65084) (xy 175.86688 -354.704828) (xy 175.86688 -354.759372) (xy 175.86688 -354.759373)
			(xy 177.349584 -354.759373) (xy 177.349584 -354.704827) (xy 177.357346 -354.650837) (xy 177.372714 -354.598501)
			(xy 177.395373 -354.548884) (xy 177.424864 -354.502998) (xy 177.460584 -354.461776) (xy 177.501808 -354.426056)
			(xy 177.547695 -354.396568) (xy 177.597312 -354.37391) (xy 177.649648 -354.358544) (xy 177.703639 -354.350783)
			(xy 177.730912 -354.35032) (xy 178.594512 -354.35032) (xy 178.62178 -354.350843) (xy 178.675759 -354.358606)
			(xy 178.728085 -354.373972) (xy 178.777691 -354.396627) (xy 178.823568 -354.426112) (xy 178.864783 -354.461826)
			(xy 178.900495 -354.503041) (xy 178.929978 -354.548919) (xy 178.952633 -354.598526) (xy 178.967997 -354.650852)
			(xy 178.975758 -354.704832) (xy 178.975758 -354.759368) (xy 178.975758 -354.759369) (xy 180.458606 -354.759369)
			(xy 180.458606 -354.704831) (xy 180.466368 -354.650847) (xy 180.481732 -354.598517) (xy 180.504388 -354.548907)
			(xy 180.533872 -354.503025) (xy 180.569586 -354.461806) (xy 180.610802 -354.426089) (xy 180.656682 -354.396601)
			(xy 180.706291 -354.373942) (xy 180.75862 -354.358574) (xy 180.812603 -354.350808) (xy 180.839872 -354.35032)
			(xy 181.703472 -354.35032) (xy 181.730743 -354.350818) (xy 181.78473 -354.358576) (xy 181.837064 -354.373939)
			(xy 181.886678 -354.396594) (xy 181.932563 -354.42608) (xy 181.973785 -354.461795) (xy 182.009504 -354.503014)
			(xy 182.038992 -354.548897) (xy 182.061651 -354.59851) (xy 182.077018 -354.650842) (xy 182.08478 -354.704829)
			(xy 182.08478 -354.735472) (xy 183.567508 -354.735472) (xy 183.567508 -354.680928) (xy 183.57527 -354.626939)
			(xy 183.590638 -354.574605) (xy 183.613298 -354.52499) (xy 183.642788 -354.479106) (xy 183.678508 -354.437885)
			(xy 183.719731 -354.402169) (xy 183.765618 -354.372682) (xy 183.815235 -354.350027) (xy 183.86757 -354.334664)
			(xy 183.92156 -354.326905) (xy 183.948832 -354.326444) (xy 184.812432 -354.326444) (xy 184.8397 -354.326921)
			(xy 184.893681 -354.334686) (xy 184.946008 -354.350054) (xy 184.995615 -354.372713) (xy 185.041492 -354.4022)
			(xy 185.082707 -354.437916) (xy 185.118419 -354.479133) (xy 185.147903 -354.525013) (xy 185.170557 -354.574622)
			(xy 185.185921 -354.62695) (xy 185.193682 -354.680932) (xy 185.193682 -354.735468) (xy 185.193682 -354.735469)
			(xy 186.67653 -354.735469) (xy 186.67653 -354.680931) (xy 186.684292 -354.626949) (xy 186.699656 -354.574621)
			(xy 186.722312 -354.525012) (xy 186.751796 -354.479133) (xy 186.78751 -354.437916) (xy 186.828726 -354.402201)
			(xy 186.874605 -354.372716) (xy 186.924214 -354.350059) (xy 186.976542 -354.334693) (xy 187.030523 -354.326931)
			(xy 187.057792 -354.326444) (xy 187.921392 -354.326444) (xy 187.948664 -354.326895) (xy 188.002652 -354.334656)
			(xy 188.054987 -354.350022) (xy 188.104602 -354.37268) (xy 188.150487 -354.402167) (xy 188.191709 -354.437885)
			(xy 188.227428 -354.479106) (xy 188.256917 -354.524991) (xy 188.279575 -354.574606) (xy 188.294942 -354.62694)
			(xy 188.302704 -354.680928) (xy 188.302704 -354.735472) (xy 188.299268 -354.759369) (xy 270.624806 -354.759369)
			(xy 270.624806 -354.704831) (xy 270.632567 -354.650848) (xy 270.647932 -354.598519) (xy 270.670586 -354.548909)
			(xy 270.70007 -354.503028) (xy 270.735783 -354.46181) (xy 270.776998 -354.426093) (xy 270.822876 -354.396604)
			(xy 270.872484 -354.373945) (xy 270.924811 -354.358575) (xy 270.978793 -354.350809) (xy 271.006062 -354.35032)
			(xy 271.869662 -354.35032) (xy 271.896933 -354.350817) (xy 271.950922 -354.358574) (xy 272.003257 -354.373936)
			(xy 272.052872 -354.396591) (xy 272.098759 -354.426076) (xy 272.139981 -354.461792) (xy 272.175701 -354.503011)
			(xy 272.205191 -354.548894) (xy 272.22785 -354.598508) (xy 272.243218 -354.650841) (xy 272.25098 -354.704829)
			(xy 272.25098 -354.759371) (xy 272.25098 -354.759373) (xy 273.733684 -354.759373) (xy 273.733684 -354.704827)
			(xy 273.741447 -354.650835) (xy 273.756815 -354.598498) (xy 273.779475 -354.548882) (xy 273.808966 -354.502995)
			(xy 273.844688 -354.461772) (xy 273.885912 -354.426053) (xy 273.931801 -354.396564) (xy 273.981419 -354.373907)
			(xy 274.033757 -354.358542) (xy 274.087749 -354.350782) (xy 274.115022 -354.35032) (xy 274.978622 -354.35032)
			(xy 275.005889 -354.350844) (xy 275.059868 -354.358608) (xy 275.112192 -354.373974) (xy 275.161797 -354.396631)
			(xy 275.207673 -354.426116) (xy 275.248886 -354.461829) (xy 275.284597 -354.503044) (xy 275.31408 -354.548922)
			(xy 275.336733 -354.598528) (xy 275.352097 -354.650854) (xy 275.359858 -354.704833) (xy 275.359858 -354.759367)
			(xy 275.359858 -354.75937) (xy 276.842706 -354.75937) (xy 276.842706 -354.70483) (xy 276.850468 -354.650846)
			(xy 276.865833 -354.598515) (xy 276.888489 -354.548904) (xy 276.917975 -354.503022) (xy 276.95369 -354.461802)
			(xy 276.994907 -354.426085) (xy 277.040788 -354.396598) (xy 277.090398 -354.373939) (xy 277.142728 -354.358572)
			(xy 277.196712 -354.350808) (xy 277.223982 -354.35032) (xy 278.087582 -354.35032) (xy 278.114853 -354.350818)
			(xy 278.168839 -354.358578) (xy 278.221171 -354.373942) (xy 278.270784 -354.396597) (xy 278.316668 -354.426083)
			(xy 278.357888 -354.461799) (xy 278.393606 -354.503018) (xy 278.423094 -354.5489) (xy 278.445752 -354.598512)
			(xy 278.461118 -354.650844) (xy 278.468881 -354.704829) (xy 278.468881 -354.759371) (xy 278.468881 -354.759374)
			(xy 279.951584 -354.759374) (xy 279.951584 -354.704826) (xy 279.959347 -354.650833) (xy 279.974716 -354.598494)
			(xy 279.997378 -354.548876) (xy 280.026871 -354.502988) (xy 280.062595 -354.461765) (xy 280.103822 -354.426046)
			(xy 280.149713 -354.396558) (xy 280.199334 -354.373902) (xy 280.251674 -354.358538) (xy 280.305668 -354.350781)
			(xy 280.332942 -354.35032) (xy 281.196542 -354.35032) (xy 281.223808 -354.350845) (xy 281.277785 -354.358611)
			(xy 281.330107 -354.37398) (xy 281.379709 -354.396637) (xy 281.425583 -354.426123) (xy 281.466793 -354.461836)
			(xy 281.502502 -354.503051) (xy 281.531983 -354.548928) (xy 281.554635 -354.598533) (xy 281.569998 -354.650856)
			(xy 281.577758 -354.704834) (xy 281.577758 -354.759366) (xy 281.577757 -354.759372) (xy 283.060584 -354.759372)
			(xy 283.060584 -354.704828) (xy 283.068346 -354.650838) (xy 283.083713 -354.598503) (xy 283.106372 -354.548887)
			(xy 283.135861 -354.503001) (xy 283.171581 -354.461779) (xy 283.212803 -354.42606) (xy 283.258689 -354.396571)
			(xy 283.308305 -354.373912) (xy 283.36064 -354.358546) (xy 283.41463 -354.350783) (xy 283.441902 -354.35032)
			(xy 284.305502 -354.35032) (xy 284.33277 -354.350843) (xy 284.386751 -354.358604) (xy 284.439078 -354.373969)
			(xy 284.488685 -354.396624) (xy 284.534564 -354.426109) (xy 284.575779 -354.461822) (xy 284.611493 -354.503038)
			(xy 284.640977 -354.548917) (xy 284.663632 -354.598524) (xy 284.678996 -354.650851) (xy 284.686758 -354.704832)
			(xy 284.686758 -354.759368) (xy 284.686758 -354.759369) (xy 286.169606 -354.759369) (xy 286.169606 -354.704831)
			(xy 286.177367 -354.650848) (xy 286.192732 -354.598519) (xy 286.215386 -354.548909) (xy 286.24487 -354.503028)
			(xy 286.280583 -354.46181) (xy 286.321798 -354.426093) (xy 286.367676 -354.396604) (xy 286.417284 -354.373945)
			(xy 286.469611 -354.358575) (xy 286.523593 -354.350809) (xy 286.550862 -354.35032) (xy 287.414462 -354.35032)
			(xy 287.441733 -354.350817) (xy 287.495722 -354.358574) (xy 287.548057 -354.373936) (xy 287.597672 -354.396591)
			(xy 287.643559 -354.426076) (xy 287.684781 -354.461792) (xy 287.720501 -354.503011) (xy 287.749991 -354.548894)
			(xy 287.77265 -354.598508) (xy 287.788018 -354.650841) (xy 287.79578 -354.704829) (xy 287.79578 -354.759371)
			(xy 287.79578 -354.759373) (xy 289.278484 -354.759373) (xy 289.278484 -354.704827) (xy 289.286247 -354.650835)
			(xy 289.301615 -354.598498) (xy 289.324275 -354.548882) (xy 289.353766 -354.502995) (xy 289.389488 -354.461772)
			(xy 289.430712 -354.426053) (xy 289.476601 -354.396564) (xy 289.526219 -354.373907) (xy 289.578557 -354.358542)
			(xy 289.632549 -354.350782) (xy 289.659822 -354.35032) (xy 290.523422 -354.35032) (xy 290.550689 -354.350844)
			(xy 290.604668 -354.358608) (xy 290.656992 -354.373974) (xy 290.706597 -354.396631) (xy 290.752473 -354.426116)
			(xy 290.793686 -354.461829) (xy 290.829397 -354.503044) (xy 290.85888 -354.548922) (xy 290.881533 -354.598528)
			(xy 290.896897 -354.650854) (xy 290.904658 -354.704833) (xy 290.904658 -354.759367) (xy 290.904658 -354.75937)
			(xy 292.387506 -354.75937) (xy 292.387506 -354.70483) (xy 292.395268 -354.650846) (xy 292.410633 -354.598515)
			(xy 292.433289 -354.548904) (xy 292.462775 -354.503022) (xy 292.49849 -354.461802) (xy 292.539707 -354.426085)
			(xy 292.585588 -354.396598) (xy 292.635198 -354.373939) (xy 292.687528 -354.358572) (xy 292.741512 -354.350808)
			(xy 292.768782 -354.35032) (xy 293.632382 -354.35032) (xy 293.659653 -354.350818) (xy 293.713639 -354.358578)
			(xy 293.765971 -354.373942) (xy 293.815584 -354.396597) (xy 293.861468 -354.426083) (xy 293.902688 -354.461799)
			(xy 293.938406 -354.503018) (xy 293.967894 -354.5489) (xy 293.990552 -354.598512) (xy 294.005918 -354.650844)
			(xy 294.013681 -354.704829) (xy 294.013681 -354.759371) (xy 294.013681 -354.759374) (xy 295.496384 -354.759374)
			(xy 295.496384 -354.704826) (xy 295.504147 -354.650833) (xy 295.519516 -354.598494) (xy 295.542178 -354.548876)
			(xy 295.571671 -354.502988) (xy 295.607395 -354.461765) (xy 295.648622 -354.426046) (xy 295.694513 -354.396558)
			(xy 295.744134 -354.373902) (xy 295.796474 -354.358538) (xy 295.850468 -354.350781) (xy 295.877742 -354.35032)
			(xy 296.741342 -354.35032) (xy 296.768608 -354.350845) (xy 296.822585 -354.358611) (xy 296.874907 -354.37398)
			(xy 296.924509 -354.396637) (xy 296.970383 -354.426123) (xy 297.011593 -354.461836) (xy 297.047302 -354.503051)
			(xy 297.076783 -354.548928) (xy 297.099435 -354.598533) (xy 297.114798 -354.650856) (xy 297.122558 -354.704834)
			(xy 297.122558 -354.759366) (xy 297.122557 -354.759372) (xy 298.605384 -354.759372) (xy 298.605384 -354.704828)
			(xy 298.613146 -354.650838) (xy 298.628513 -354.598503) (xy 298.651172 -354.548887) (xy 298.680661 -354.503001)
			(xy 298.716381 -354.461779) (xy 298.757603 -354.42606) (xy 298.803489 -354.396571) (xy 298.853105 -354.373912)
			(xy 298.90544 -354.358546) (xy 298.95943 -354.350783) (xy 298.986702 -354.35032) (xy 299.850302 -354.35032)
			(xy 299.87757 -354.350843) (xy 299.931551 -354.358604) (xy 299.983878 -354.373969) (xy 300.033485 -354.396624)
			(xy 300.079364 -354.426109) (xy 300.120579 -354.461822) (xy 300.156293 -354.503038) (xy 300.185777 -354.548917)
			(xy 300.208432 -354.598524) (xy 300.223796 -354.650851) (xy 300.231558 -354.704832) (xy 300.231558 -354.759368)
			(xy 300.231558 -354.759369) (xy 315.230506 -354.759369) (xy 315.230506 -354.704831) (xy 315.238267 -354.650848)
			(xy 315.253632 -354.598519) (xy 315.276286 -354.548909) (xy 315.30577 -354.503027) (xy 315.341483 -354.461809)
			(xy 315.382699 -354.426092) (xy 315.428577 -354.396604) (xy 315.478185 -354.373944) (xy 315.530513 -354.358575)
			(xy 315.584495 -354.350809) (xy 315.611764 -354.35032) (xy 316.475364 -354.35032) (xy 316.502635 -354.350817)
			(xy 316.556624 -354.358575) (xy 316.608958 -354.373937) (xy 316.658574 -354.396591) (xy 316.70446 -354.426077)
			(xy 316.745682 -354.461793) (xy 316.781402 -354.503012) (xy 316.810891 -354.548895) (xy 316.83355 -354.598508)
			(xy 316.848918 -354.650841) (xy 316.85668 -354.704829) (xy 316.85668 -354.759371) (xy 316.85668 -354.759373)
			(xy 318.339384 -354.759373) (xy 318.339384 -354.704827) (xy 318.347147 -354.650835) (xy 318.362515 -354.598498)
			(xy 318.385175 -354.548881) (xy 318.414667 -354.502994) (xy 318.450388 -354.461771) (xy 318.491613 -354.426052)
			(xy 318.537502 -354.396564) (xy 318.587121 -354.373907) (xy 318.639459 -354.358542) (xy 318.693451 -354.350782)
			(xy 318.720724 -354.35032) (xy 319.584324 -354.35032) (xy 319.611591 -354.350844) (xy 319.665569 -354.358608)
			(xy 319.717894 -354.373975) (xy 319.767498 -354.396631) (xy 319.813374 -354.426116) (xy 319.854587 -354.46183)
			(xy 319.890298 -354.503045) (xy 319.91978 -354.548923) (xy 319.942434 -354.598529) (xy 319.957797 -354.650854)
			(xy 319.965558 -354.704833) (xy 319.965558 -354.759367) (xy 319.965558 -354.75937) (xy 321.448406 -354.75937)
			(xy 321.448406 -354.70483) (xy 321.456168 -354.650845) (xy 321.471533 -354.598515) (xy 321.494189 -354.548903)
			(xy 321.523675 -354.503021) (xy 321.55939 -354.461802) (xy 321.600608 -354.426085) (xy 321.646489 -354.396597)
			(xy 321.6961 -354.373939) (xy 321.74843 -354.358571) (xy 321.802414 -354.350808) (xy 321.829684 -354.35032)
			(xy 322.693284 -354.35032) (xy 322.720554 -354.350818) (xy 322.774541 -354.358578) (xy 322.826873 -354.373942)
			(xy 322.876485 -354.396598) (xy 322.922369 -354.426084) (xy 322.963589 -354.4618) (xy 322.999307 -354.503018)
			(xy 323.028794 -354.5489) (xy 323.051452 -354.598512) (xy 323.066818 -354.650844) (xy 323.074581 -354.70483)
			(xy 323.074581 -354.75937) (xy 323.07458 -354.759374) (xy 324.557284 -354.759374) (xy 324.557284 -354.704826)
			(xy 324.565047 -354.650832) (xy 324.580417 -354.598494) (xy 324.603078 -354.548875) (xy 324.632571 -354.502987)
			(xy 324.668295 -354.461764) (xy 324.709523 -354.426045) (xy 324.755414 -354.396557) (xy 324.805035 -354.373901)
			(xy 324.857375 -354.358538) (xy 324.91137 -354.350781) (xy 324.938644 -354.35032) (xy 325.802244 -354.35032)
			(xy 325.82951 -354.350845) (xy 325.883486 -354.358612) (xy 325.935808 -354.37398) (xy 325.98541 -354.396638)
			(xy 326.031284 -354.426124) (xy 326.072494 -354.461837) (xy 326.108203 -354.503052) (xy 326.137683 -354.548928)
			(xy 326.160335 -354.598533) (xy 326.175698 -354.650857) (xy 326.183458 -354.704834) (xy 326.183458 -354.759366)
			(xy 326.183457 -354.759372) (xy 327.666284 -354.759372) (xy 327.666284 -354.704828) (xy 327.674046 -354.650838)
			(xy 327.689413 -354.598502) (xy 327.712072 -354.548887) (xy 327.741562 -354.503001) (xy 327.777281 -354.461778)
			(xy 327.818504 -354.426059) (xy 327.86439 -354.39657) (xy 327.914006 -354.373912) (xy 327.966342 -354.358545)
			(xy 328.020332 -354.350783) (xy 328.047604 -354.35032) (xy 328.911204 -354.35032) (xy 328.938472 -354.350843)
			(xy 328.992453 -354.358604) (xy 329.044779 -354.373969) (xy 329.094386 -354.396625) (xy 329.140265 -354.426109)
			(xy 329.18148 -354.461823) (xy 329.217193 -354.503039) (xy 329.246677 -354.548917) (xy 329.269332 -354.598525)
			(xy 329.284696 -354.650851) (xy 329.292458 -354.704832) (xy 329.292458 -354.759368) (xy 329.292458 -354.759369)
			(xy 330.775306 -354.759369) (xy 330.775306 -354.704831) (xy 330.783067 -354.650848) (xy 330.798432 -354.598519)
			(xy 330.821086 -354.548909) (xy 330.85057 -354.503027) (xy 330.886283 -354.461809) (xy 330.927499 -354.426092)
			(xy 330.973377 -354.396604) (xy 331.022985 -354.373944) (xy 331.075313 -354.358575) (xy 331.129295 -354.350809)
			(xy 331.156564 -354.35032) (xy 332.020164 -354.35032) (xy 332.047435 -354.350817) (xy 332.101424 -354.358575)
			(xy 332.153758 -354.373937) (xy 332.203374 -354.396591) (xy 332.24926 -354.426077) (xy 332.290482 -354.461793)
			(xy 332.326202 -354.503012) (xy 332.355691 -354.548895) (xy 332.37835 -354.598508) (xy 332.393718 -354.650841)
			(xy 332.40148 -354.704829) (xy 332.40148 -354.759371) (xy 332.40148 -354.759373) (xy 333.884184 -354.759373)
			(xy 333.884184 -354.704827) (xy 333.891947 -354.650835) (xy 333.907315 -354.598498) (xy 333.929975 -354.548881)
			(xy 333.959467 -354.502994) (xy 333.995188 -354.461771) (xy 334.036413 -354.426052) (xy 334.082302 -354.396564)
			(xy 334.131921 -354.373907) (xy 334.184259 -354.358542) (xy 334.238251 -354.350782) (xy 334.265524 -354.35032)
			(xy 335.129124 -354.35032) (xy 335.156391 -354.350844) (xy 335.210369 -354.358608) (xy 335.262694 -354.373975)
			(xy 335.312298 -354.396631) (xy 335.358174 -354.426116) (xy 335.399387 -354.46183) (xy 335.435098 -354.503045)
			(xy 335.46458 -354.548923) (xy 335.487234 -354.598529) (xy 335.502597 -354.650854) (xy 335.510358 -354.704833)
			(xy 335.510358 -354.759367) (xy 335.510358 -354.75937) (xy 336.993206 -354.75937) (xy 336.993206 -354.70483)
			(xy 337.000968 -354.650845) (xy 337.016333 -354.598515) (xy 337.038989 -354.548903) (xy 337.068475 -354.503021)
			(xy 337.10419 -354.461802) (xy 337.145408 -354.426085) (xy 337.191289 -354.396597) (xy 337.2409 -354.373939)
			(xy 337.29323 -354.358571) (xy 337.347214 -354.350808) (xy 337.374484 -354.35032) (xy 338.238084 -354.35032)
			(xy 338.265354 -354.350818) (xy 338.319341 -354.358578) (xy 338.371673 -354.373942) (xy 338.421285 -354.396598)
			(xy 338.467169 -354.426084) (xy 338.508389 -354.4618) (xy 338.544107 -354.503018) (xy 338.573594 -354.5489)
			(xy 338.596252 -354.598512) (xy 338.611618 -354.650844) (xy 338.619381 -354.70483) (xy 338.619381 -354.75937)
			(xy 338.61938 -354.759374) (xy 340.102084 -354.759374) (xy 340.102084 -354.704826) (xy 340.109847 -354.650832)
			(xy 340.125217 -354.598494) (xy 340.147878 -354.548875) (xy 340.177371 -354.502987) (xy 340.213095 -354.461764)
			(xy 340.254323 -354.426045) (xy 340.300214 -354.396557) (xy 340.349835 -354.373901) (xy 340.402175 -354.358538)
			(xy 340.45617 -354.350781) (xy 340.483444 -354.35032) (xy 341.347044 -354.35032) (xy 341.37431 -354.350845)
			(xy 341.428286 -354.358612) (xy 341.480608 -354.37398) (xy 341.53021 -354.396638) (xy 341.576084 -354.426124)
			(xy 341.617294 -354.461837) (xy 341.653003 -354.503052) (xy 341.682483 -354.548928) (xy 341.705135 -354.598533)
			(xy 341.720498 -354.650857) (xy 341.728258 -354.704834) (xy 341.728258 -354.759366) (xy 341.728257 -354.759372)
			(xy 343.211084 -354.759372) (xy 343.211084 -354.704828) (xy 343.218846 -354.650838) (xy 343.234213 -354.598502)
			(xy 343.256872 -354.548887) (xy 343.286362 -354.503001) (xy 343.322081 -354.461778) (xy 343.363304 -354.426059)
			(xy 343.40919 -354.39657) (xy 343.458806 -354.373912) (xy 343.511142 -354.358545) (xy 343.565132 -354.350783)
			(xy 343.592404 -354.35032) (xy 344.456004 -354.35032) (xy 344.483272 -354.350843) (xy 344.537253 -354.358604)
			(xy 344.589579 -354.373969) (xy 344.639186 -354.396625) (xy 344.685065 -354.426109) (xy 344.72628 -354.461823)
			(xy 344.761993 -354.503039) (xy 344.791477 -354.548917) (xy 344.814132 -354.598525) (xy 344.829496 -354.650851)
			(xy 344.837258 -354.704832) (xy 344.837258 -354.759368) (xy 344.837257 -354.759374) (xy 373.915584 -354.759374)
			(xy 373.915584 -354.704826) (xy 373.923347 -354.650833) (xy 373.938716 -354.598495) (xy 373.961378 -354.548876)
			(xy 373.990871 -354.502989) (xy 374.026594 -354.461766) (xy 374.067821 -354.426047) (xy 374.113712 -354.396559)
			(xy 374.163332 -354.373902) (xy 374.215672 -354.358539) (xy 374.269666 -354.350781) (xy 374.29694 -354.35032)
			(xy 375.16054 -354.35032) (xy 375.187806 -354.350845) (xy 375.241783 -354.358611) (xy 375.294105 -354.373979)
			(xy 375.343708 -354.396637) (xy 375.389582 -354.426122) (xy 375.430793 -354.461836) (xy 375.466502 -354.50305)
			(xy 375.495983 -354.548927) (xy 375.518635 -354.598532) (xy 375.533997 -354.650856) (xy 375.541758 -354.704834)
			(xy 375.541758 -354.759366) (xy 375.541757 -354.759371) (xy 377.024606 -354.759371) (xy 377.024606 -354.704829)
			(xy 377.032369 -354.650843) (xy 377.047735 -354.598511) (xy 377.070392 -354.548899) (xy 377.099879 -354.503016)
			(xy 377.135596 -354.461796) (xy 377.176816 -354.426079) (xy 377.222699 -354.396592) (xy 377.272311 -354.373935)
			(xy 377.324643 -354.358569) (xy 377.378629 -354.350806) (xy 377.4059 -354.35032) (xy 378.2695 -354.35032)
			(xy 378.296768 -354.350842) (xy 378.350749 -354.358604) (xy 378.403076 -354.373968) (xy 378.452684 -354.396623)
			(xy 378.498563 -354.426108) (xy 378.539778 -354.461822) (xy 378.575492 -354.503037) (xy 378.604977 -354.548916)
			(xy 378.627632 -354.598524) (xy 378.642996 -354.650851) (xy 378.650758 -354.704832) (xy 378.650758 -354.759368)
			(xy 378.650758 -354.759369) (xy 380.133606 -354.759369) (xy 380.133606 -354.704831) (xy 380.141367 -354.650849)
			(xy 380.156731 -354.59852) (xy 380.179386 -354.54891) (xy 380.208869 -354.503029) (xy 380.244582 -354.46181)
			(xy 380.285797 -354.426093) (xy 380.331675 -354.396605) (xy 380.381282 -354.373945) (xy 380.433609 -354.358576)
			(xy 380.487591 -354.350809) (xy 380.51486 -354.35032) (xy 381.37846 -354.35032) (xy 381.405732 -354.350817)
			(xy 381.45972 -354.358574) (xy 381.512055 -354.373936) (xy 381.561671 -354.39659) (xy 381.607558 -354.426075)
			(xy 381.648781 -354.461791) (xy 381.684501 -354.50301) (xy 381.713991 -354.548894) (xy 381.73665 -354.598507)
			(xy 381.752018 -354.650841) (xy 381.75978 -354.704828) (xy 381.75978 -354.759372) (xy 381.75978 -354.759373)
			(xy 383.242484 -354.759373) (xy 383.242484 -354.704827) (xy 383.250247 -354.650836) (xy 383.265615 -354.598499)
			(xy 383.288275 -354.548882) (xy 383.317766 -354.502995) (xy 383.353487 -354.461773) (xy 383.394711 -354.426054)
			(xy 383.4406 -354.396565) (xy 383.490218 -354.373908) (xy 383.542555 -354.358542) (xy 383.596547 -354.350782)
			(xy 383.62382 -354.35032) (xy 384.48742 -354.35032) (xy 384.514687 -354.350844) (xy 384.568666 -354.358607)
			(xy 384.620991 -354.373974) (xy 384.670596 -354.39663) (xy 384.716472 -354.426115) (xy 384.757686 -354.461829)
			(xy 384.793397 -354.503044) (xy 384.82288 -354.548922) (xy 384.845533 -354.598528) (xy 384.860897 -354.650854)
			(xy 384.868658 -354.704833) (xy 384.868658 -354.759367) (xy 384.868658 -354.75937) (xy 386.351506 -354.75937)
			(xy 386.351506 -354.70483) (xy 386.359268 -354.650846) (xy 386.374633 -354.598515) (xy 386.397289 -354.548904)
			(xy 386.426774 -354.503022) (xy 386.462489 -354.461803) (xy 386.503706 -354.426086) (xy 386.549587 -354.396598)
			(xy 386.599197 -354.37394) (xy 386.651526 -354.358572) (xy 386.70551 -354.350808) (xy 386.73278 -354.35032)
			(xy 387.59638 -354.35032) (xy 387.623651 -354.350818) (xy 387.677637 -354.358578) (xy 387.72997 -354.373941)
			(xy 387.779583 -354.396597) (xy 387.825467 -354.426082) (xy 387.866688 -354.461798) (xy 387.902406 -354.503017)
			(xy 387.931894 -354.548899) (xy 387.954552 -354.598511) (xy 387.969918 -354.650843) (xy 387.97768 -354.704829)
			(xy 387.97768 -354.759371) (xy 387.97768 -354.759374) (xy 389.460384 -354.759374) (xy 389.460384 -354.704826)
			(xy 389.468147 -354.650833) (xy 389.483516 -354.598495) (xy 389.506178 -354.548876) (xy 389.535671 -354.502989)
			(xy 389.571394 -354.461766) (xy 389.612621 -354.426047) (xy 389.658512 -354.396559) (xy 389.708132 -354.373902)
			(xy 389.760472 -354.358539) (xy 389.814466 -354.350781) (xy 389.84174 -354.35032) (xy 390.70534 -354.35032)
			(xy 390.732606 -354.350845) (xy 390.786583 -354.358611) (xy 390.838905 -354.373979) (xy 390.888508 -354.396637)
			(xy 390.934382 -354.426122) (xy 390.975593 -354.461836) (xy 391.011302 -354.50305) (xy 391.040783 -354.548927)
			(xy 391.063435 -354.598532) (xy 391.078797 -354.650856) (xy 391.086558 -354.704834) (xy 391.086558 -354.759366)
			(xy 391.086557 -354.759371) (xy 392.569406 -354.759371) (xy 392.569406 -354.704829) (xy 392.577169 -354.650843)
			(xy 392.592535 -354.598511) (xy 392.615192 -354.548899) (xy 392.644679 -354.503016) (xy 392.680396 -354.461796)
			(xy 392.721616 -354.426079) (xy 392.767499 -354.396592) (xy 392.817111 -354.373935) (xy 392.869443 -354.358569)
			(xy 392.923429 -354.350806) (xy 392.9507 -354.35032) (xy 393.8143 -354.35032) (xy 393.841568 -354.350842)
			(xy 393.895549 -354.358604) (xy 393.947876 -354.373968) (xy 393.997484 -354.396623) (xy 394.043363 -354.426108)
			(xy 394.084578 -354.461822) (xy 394.120292 -354.503037) (xy 394.149777 -354.548916) (xy 394.172432 -354.598524)
			(xy 394.187796 -354.650851) (xy 394.195558 -354.704832) (xy 394.195558 -354.759368) (xy 394.195558 -354.759369)
			(xy 395.678406 -354.759369) (xy 395.678406 -354.704831) (xy 395.686167 -354.650849) (xy 395.701531 -354.59852)
			(xy 395.724186 -354.54891) (xy 395.753669 -354.503029) (xy 395.789382 -354.46181) (xy 395.830597 -354.426093)
			(xy 395.876475 -354.396605) (xy 395.926082 -354.373945) (xy 395.978409 -354.358576) (xy 396.032391 -354.350809)
			(xy 396.05966 -354.35032) (xy 396.92326 -354.35032) (xy 396.950532 -354.350817) (xy 397.00452 -354.358574)
			(xy 397.056855 -354.373936) (xy 397.106471 -354.39659) (xy 397.152358 -354.426075) (xy 397.193581 -354.461791)
			(xy 397.229301 -354.50301) (xy 397.258791 -354.548894) (xy 397.28145 -354.598507) (xy 397.296818 -354.650841)
			(xy 397.30458 -354.704828) (xy 397.30458 -354.759372) (xy 397.30458 -354.759373) (xy 398.787284 -354.759373)
			(xy 398.787284 -354.704827) (xy 398.795047 -354.650836) (xy 398.810415 -354.598499) (xy 398.833075 -354.548882)
			(xy 398.862566 -354.502995) (xy 398.898287 -354.461773) (xy 398.939511 -354.426054) (xy 398.9854 -354.396565)
			(xy 399.035018 -354.373908) (xy 399.087355 -354.358542) (xy 399.141347 -354.350782) (xy 399.16862 -354.35032)
			(xy 400.03222 -354.35032) (xy 400.059487 -354.350844) (xy 400.113466 -354.358607) (xy 400.165791 -354.373974)
			(xy 400.215396 -354.39663) (xy 400.261272 -354.426115) (xy 400.302486 -354.461829) (xy 400.338197 -354.503044)
			(xy 400.36768 -354.548922) (xy 400.390333 -354.598528) (xy 400.405697 -354.650854) (xy 400.413458 -354.704833)
			(xy 400.413458 -354.759367) (xy 400.413458 -354.75937) (xy 401.896306 -354.75937) (xy 401.896306 -354.70483)
			(xy 401.904068 -354.650846) (xy 401.919433 -354.598515) (xy 401.942089 -354.548904) (xy 401.971574 -354.503022)
			(xy 402.007289 -354.461803) (xy 402.048506 -354.426086) (xy 402.094387 -354.396598) (xy 402.143997 -354.37394)
			(xy 402.196326 -354.358572) (xy 402.25031 -354.350808) (xy 402.27758 -354.35032) (xy 403.14118 -354.35032)
			(xy 403.168451 -354.350818) (xy 403.222437 -354.358578) (xy 403.27477 -354.373941) (xy 403.324383 -354.396597)
			(xy 403.370267 -354.426082) (xy 403.411488 -354.461798) (xy 403.447206 -354.503017) (xy 403.476694 -354.548899)
			(xy 403.499352 -354.598511) (xy 403.514718 -354.650843) (xy 403.52248 -354.704829) (xy 403.52248 -354.759368)
			(xy 412.022806 -354.759368) (xy 412.022806 -354.704832) (xy 412.030567 -354.65085) (xy 412.045931 -354.598521)
			(xy 412.068585 -354.548912) (xy 412.098067 -354.503031) (xy 412.133779 -354.461813) (xy 412.174993 -354.426096)
			(xy 412.22087 -354.396608) (xy 412.270476 -354.373948) (xy 412.322803 -354.358577) (xy 412.376784 -354.35081)
			(xy 412.404052 -354.35032) (xy 413.267652 -354.35032) (xy 413.294924 -354.350816) (xy 413.348913 -354.358572)
			(xy 413.401249 -354.373934) (xy 413.450866 -354.396588) (xy 413.496754 -354.426072) (xy 413.537978 -354.461788)
			(xy 413.573699 -354.503008) (xy 413.603189 -354.548891) (xy 413.625849 -354.598506) (xy 413.641217 -354.65084)
			(xy 413.64898 -354.704828) (xy 413.64898 -354.759372) (xy 413.64898 -354.759373) (xy 415.131684 -354.759373)
			(xy 415.131684 -354.704827) (xy 415.139446 -354.650837) (xy 415.154814 -354.598501) (xy 415.177473 -354.548884)
			(xy 415.206964 -354.502998) (xy 415.242684 -354.461776) (xy 415.283908 -354.426056) (xy 415.329795 -354.396568)
			(xy 415.379412 -354.37391) (xy 415.431748 -354.358544) (xy 415.485739 -354.350783) (xy 415.513012 -354.35032)
			(xy 416.376612 -354.35032) (xy 416.40388 -354.350843) (xy 416.457859 -354.358606) (xy 416.510185 -354.373972)
			(xy 416.559791 -354.396627) (xy 416.605668 -354.426112) (xy 416.646883 -354.461826) (xy 416.682595 -354.503041)
			(xy 416.712078 -354.548919) (xy 416.734733 -354.598526) (xy 416.750097 -354.650852) (xy 416.757858 -354.704832)
			(xy 416.757858 -354.759368) (xy 416.757858 -354.759369) (xy 418.240706 -354.759369) (xy 418.240706 -354.704831)
			(xy 418.248468 -354.650847) (xy 418.263832 -354.598517) (xy 418.286488 -354.548907) (xy 418.315972 -354.503025)
			(xy 418.351686 -354.461806) (xy 418.392902 -354.426089) (xy 418.438782 -354.396601) (xy 418.488391 -354.373942)
			(xy 418.54072 -354.358574) (xy 418.594703 -354.350808) (xy 418.621972 -354.35032) (xy 419.485572 -354.35032)
			(xy 419.512843 -354.350818) (xy 419.56683 -354.358576) (xy 419.619164 -354.373939) (xy 419.668778 -354.396594)
			(xy 419.714663 -354.42608) (xy 419.755885 -354.461795) (xy 419.791604 -354.503014) (xy 419.821092 -354.548897)
			(xy 419.843751 -354.59851) (xy 419.859118 -354.650842) (xy 419.86688 -354.704829) (xy 419.86688 -354.759371)
			(xy 419.86688 -354.759374) (xy 421.349584 -354.759374) (xy 421.349584 -354.704826) (xy 421.357347 -354.650834)
			(xy 421.372716 -354.598496) (xy 421.395377 -354.548879) (xy 421.424869 -354.502991) (xy 421.460591 -354.461768)
			(xy 421.501817 -354.426049) (xy 421.547707 -354.396561) (xy 421.597326 -354.373904) (xy 421.649665 -354.35854)
			(xy 421.703658 -354.350781) (xy 421.730932 -354.35032) (xy 422.594532 -354.35032) (xy 422.621799 -354.350845)
			(xy 422.675776 -354.35861) (xy 422.728099 -354.373977) (xy 422.777703 -354.396634) (xy 422.823578 -354.426119)
			(xy 422.86479 -354.461833) (xy 422.9005 -354.503048) (xy 422.929981 -354.548925) (xy 422.952634 -354.598531)
			(xy 422.967997 -354.650855) (xy 422.975758 -354.704833) (xy 422.975758 -354.759367) (xy 422.975758 -354.75937)
			(xy 424.458606 -354.75937) (xy 424.458606 -354.70483) (xy 424.466368 -354.650844) (xy 424.481734 -354.598513)
			(xy 424.504391 -354.548901) (xy 424.533877 -354.503018) (xy 424.569593 -354.461799) (xy 424.610812 -354.426082)
			(xy 424.656694 -354.396594) (xy 424.706305 -354.373937) (xy 424.758636 -354.35857) (xy 424.812622 -354.350807)
			(xy 424.839892 -354.35032) (xy 425.703492 -354.35032) (xy 425.730762 -354.350819) (xy 425.784747 -354.35858)
			(xy 425.837078 -354.373945) (xy 425.88669 -354.396601) (xy 425.932573 -354.426087) (xy 425.973792 -354.461802)
			(xy 426.009509 -354.503021) (xy 426.038996 -354.548903) (xy 426.061653 -354.598514) (xy 426.077019 -354.650845)
			(xy 426.084781 -354.70483) (xy 426.084781 -354.759368) (xy 427.567606 -354.759368) (xy 427.567606 -354.704832)
			(xy 427.575367 -354.65085) (xy 427.590731 -354.598521) (xy 427.613385 -354.548912) (xy 427.642867 -354.503031)
			(xy 427.678579 -354.461813) (xy 427.719793 -354.426096) (xy 427.76567 -354.396608) (xy 427.815276 -354.373948)
			(xy 427.867603 -354.358577) (xy 427.921584 -354.35081) (xy 427.948852 -354.35032) (xy 428.812452 -354.35032)
			(xy 428.839724 -354.350816) (xy 428.893713 -354.358572) (xy 428.946049 -354.373934) (xy 428.995666 -354.396588)
			(xy 429.041554 -354.426072) (xy 429.082778 -354.461788) (xy 429.118499 -354.503008) (xy 429.147989 -354.548891)
			(xy 429.170649 -354.598506) (xy 429.186017 -354.65084) (xy 429.19378 -354.704828) (xy 429.19378 -354.759372)
			(xy 429.19378 -354.759373) (xy 430.676484 -354.759373) (xy 430.676484 -354.704827) (xy 430.684246 -354.650837)
			(xy 430.699614 -354.598501) (xy 430.722273 -354.548884) (xy 430.751764 -354.502998) (xy 430.787484 -354.461776)
			(xy 430.828708 -354.426056) (xy 430.874595 -354.396568) (xy 430.924212 -354.37391) (xy 430.976548 -354.358544)
			(xy 431.030539 -354.350783) (xy 431.057812 -354.35032) (xy 431.921412 -354.35032) (xy 431.94868 -354.350843)
			(xy 432.002659 -354.358606) (xy 432.054985 -354.373972) (xy 432.104591 -354.396627) (xy 432.150468 -354.426112)
			(xy 432.191683 -354.461826) (xy 432.227395 -354.503041) (xy 432.256878 -354.548919) (xy 432.279533 -354.598526)
			(xy 432.294897 -354.650852) (xy 432.302658 -354.704832) (xy 432.302658 -354.759368) (xy 432.302658 -354.759369)
			(xy 433.785506 -354.759369) (xy 433.785506 -354.704831) (xy 433.793268 -354.650847) (xy 433.808632 -354.598517)
			(xy 433.831288 -354.548907) (xy 433.860772 -354.503025) (xy 433.896486 -354.461806) (xy 433.937702 -354.426089)
			(xy 433.983582 -354.396601) (xy 434.033191 -354.373942) (xy 434.08552 -354.358574) (xy 434.139503 -354.350808)
			(xy 434.166772 -354.35032) (xy 435.030372 -354.35032) (xy 435.057643 -354.350818) (xy 435.11163 -354.358576)
			(xy 435.163964 -354.373939) (xy 435.213578 -354.396594) (xy 435.259463 -354.42608) (xy 435.300685 -354.461795)
			(xy 435.336404 -354.503014) (xy 435.365892 -354.548897) (xy 435.388551 -354.59851) (xy 435.403918 -354.650842)
			(xy 435.41168 -354.704829) (xy 435.41168 -354.759371) (xy 435.41168 -354.759374) (xy 436.894384 -354.759374)
			(xy 436.894384 -354.704826) (xy 436.902147 -354.650834) (xy 436.917516 -354.598496) (xy 436.940177 -354.548879)
			(xy 436.969669 -354.502991) (xy 437.005391 -354.461768) (xy 437.046617 -354.426049) (xy 437.092507 -354.396561)
			(xy 437.142126 -354.373904) (xy 437.194465 -354.35854) (xy 437.248458 -354.350781) (xy 437.275732 -354.35032)
			(xy 438.139332 -354.35032) (xy 438.166599 -354.350845) (xy 438.220576 -354.35861) (xy 438.272899 -354.373977)
			(xy 438.322503 -354.396634) (xy 438.368378 -354.426119) (xy 438.40959 -354.461833) (xy 438.4453 -354.503048)
			(xy 438.474781 -354.548925) (xy 438.497434 -354.598531) (xy 438.512797 -354.650855) (xy 438.520558 -354.704833)
			(xy 438.520558 -354.759367) (xy 438.520558 -354.75937) (xy 440.003406 -354.75937) (xy 440.003406 -354.70483)
			(xy 440.011168 -354.650844) (xy 440.026534 -354.598513) (xy 440.049191 -354.548901) (xy 440.078677 -354.503018)
			(xy 440.114393 -354.461799) (xy 440.155612 -354.426082) (xy 440.201494 -354.396594) (xy 440.251105 -354.373937)
			(xy 440.303436 -354.35857) (xy 440.357422 -354.350807) (xy 440.384692 -354.35032) (xy 441.248292 -354.35032)
			(xy 441.275562 -354.350819) (xy 441.329547 -354.35858) (xy 441.381878 -354.373945) (xy 441.43149 -354.396601)
			(xy 441.477373 -354.426087) (xy 441.518592 -354.461802) (xy 441.554309 -354.503021) (xy 441.583796 -354.548903)
			(xy 441.606453 -354.598514) (xy 441.621819 -354.650845) (xy 441.629581 -354.70483) (xy 441.629581 -354.75937)
			(xy 441.621819 -354.813355) (xy 441.606453 -354.865686) (xy 441.583796 -354.915297) (xy 441.554309 -354.961179)
			(xy 441.518592 -355.002398) (xy 441.477373 -355.038113) (xy 441.43149 -355.067599) (xy 441.381878 -355.090255)
			(xy 441.329547 -355.10562) (xy 441.275562 -355.113381) (xy 441.248292 -355.113844) (xy 440.384692 -355.113844)
			(xy 440.357422 -355.113393) (xy 440.303436 -355.10563) (xy 440.251105 -355.090263) (xy 440.201494 -355.067606)
			(xy 440.155612 -355.038118) (xy 440.114393 -355.002401) (xy 440.078677 -354.961182) (xy 440.049191 -354.915299)
			(xy 440.026534 -354.865687) (xy 440.011168 -354.813356) (xy 440.003406 -354.75937) (xy 438.520558 -354.75937)
			(xy 438.512797 -354.813345) (xy 438.497434 -354.865669) (xy 438.474781 -354.915275) (xy 438.4453 -354.961152)
			(xy 438.40959 -355.002367) (xy 438.368378 -355.038081) (xy 438.322503 -355.067566) (xy 438.272899 -355.090223)
			(xy 438.220576 -355.10559) (xy 438.166599 -355.113355) (xy 438.139332 -355.113844) (xy 437.275732 -355.113844)
			(xy 437.248458 -355.113419) (xy 437.194465 -355.10566) (xy 437.142126 -355.090296) (xy 437.092507 -355.067639)
			(xy 437.046617 -355.038151) (xy 437.005391 -355.002432) (xy 436.969669 -354.961209) (xy 436.940177 -354.915321)
			(xy 436.917516 -354.865704) (xy 436.902147 -354.813366) (xy 436.894384 -354.759374) (xy 435.41168 -354.759374)
			(xy 435.403918 -354.813358) (xy 435.388551 -354.86569) (xy 435.365892 -354.915303) (xy 435.336404 -354.961186)
			(xy 435.300685 -355.002405) (xy 435.259463 -355.03812) (xy 435.213578 -355.067606) (xy 435.163964 -355.090261)
			(xy 435.11163 -355.105624) (xy 435.057643 -355.113382) (xy 435.030372 -355.113844) (xy 434.166772 -355.113844)
			(xy 434.139503 -355.113392) (xy 434.08552 -355.105626) (xy 434.033191 -355.090258) (xy 433.983582 -355.067599)
			(xy 433.937702 -355.038111) (xy 433.896486 -355.002394) (xy 433.860772 -354.961175) (xy 433.831288 -354.915293)
			(xy 433.808632 -354.865683) (xy 433.793268 -354.813353) (xy 433.785506 -354.759369) (xy 432.302658 -354.759369)
			(xy 432.294897 -354.813348) (xy 432.279533 -354.865674) (xy 432.256878 -354.915281) (xy 432.227395 -354.961159)
			(xy 432.191683 -355.002374) (xy 432.150468 -355.038088) (xy 432.104591 -355.067573) (xy 432.054985 -355.090228)
			(xy 432.002659 -355.105594) (xy 431.94868 -355.113357) (xy 431.921412 -355.113844) (xy 431.057812 -355.113844)
			(xy 431.030539 -355.113417) (xy 430.976548 -355.105656) (xy 430.924212 -355.09029) (xy 430.874595 -355.067632)
			(xy 430.828708 -355.038144) (xy 430.787484 -355.002424) (xy 430.751764 -354.961202) (xy 430.722273 -354.915316)
			(xy 430.699614 -354.865699) (xy 430.684246 -354.813363) (xy 430.676484 -354.759373) (xy 429.19378 -354.759373)
			(xy 429.186017 -354.81336) (xy 429.170649 -354.865694) (xy 429.147989 -354.915309) (xy 429.118499 -354.961192)
			(xy 429.082778 -355.002412) (xy 429.041554 -355.038128) (xy 428.995666 -355.067612) (xy 428.946049 -355.090266)
			(xy 428.893713 -355.105628) (xy 428.839724 -355.113384) (xy 428.812452 -355.113844) (xy 427.948852 -355.113844)
			(xy 427.921584 -355.11339) (xy 427.867603 -355.105623) (xy 427.815276 -355.090252) (xy 427.76567 -355.067592)
			(xy 427.719793 -355.038104) (xy 427.678579 -355.002387) (xy 427.642867 -354.961169) (xy 427.613385 -354.915288)
			(xy 427.590731 -354.865679) (xy 427.575367 -354.81335) (xy 427.567606 -354.759368) (xy 426.084781 -354.759368)
			(xy 426.084781 -354.75937) (xy 426.077019 -354.813355) (xy 426.061653 -354.865686) (xy 426.038996 -354.915297)
			(xy 426.009509 -354.961179) (xy 425.973792 -355.002398) (xy 425.932573 -355.038113) (xy 425.88669 -355.067599)
			(xy 425.837078 -355.090255) (xy 425.784747 -355.10562) (xy 425.730762 -355.113381) (xy 425.703492 -355.113844)
			(xy 424.839892 -355.113844) (xy 424.812622 -355.113393) (xy 424.758636 -355.10563) (xy 424.706305 -355.090263)
			(xy 424.656694 -355.067606) (xy 424.610812 -355.038118) (xy 424.569593 -355.002401) (xy 424.533877 -354.961182)
			(xy 424.504391 -354.915299) (xy 424.481734 -354.865687) (xy 424.466368 -354.813356) (xy 424.458606 -354.75937)
			(xy 422.975758 -354.75937) (xy 422.967997 -354.813345) (xy 422.952634 -354.865669) (xy 422.929981 -354.915275)
			(xy 422.9005 -354.961152) (xy 422.86479 -355.002367) (xy 422.823578 -355.038081) (xy 422.777703 -355.067566)
			(xy 422.728099 -355.090223) (xy 422.675776 -355.10559) (xy 422.621799 -355.113355) (xy 422.594532 -355.113844)
			(xy 421.730932 -355.113844) (xy 421.703658 -355.113419) (xy 421.649665 -355.10566) (xy 421.597326 -355.090296)
			(xy 421.547707 -355.067639) (xy 421.501817 -355.038151) (xy 421.460591 -355.002432) (xy 421.424869 -354.961209)
			(xy 421.395377 -354.915321) (xy 421.372716 -354.865704) (xy 421.357347 -354.813366) (xy 421.349584 -354.759374)
			(xy 419.86688 -354.759374) (xy 419.859118 -354.813358) (xy 419.843751 -354.86569) (xy 419.821092 -354.915303)
			(xy 419.791604 -354.961186) (xy 419.755885 -355.002405) (xy 419.714663 -355.03812) (xy 419.668778 -355.067606)
			(xy 419.619164 -355.090261) (xy 419.56683 -355.105624) (xy 419.512843 -355.113382) (xy 419.485572 -355.113844)
			(xy 418.621972 -355.113844) (xy 418.594703 -355.113392) (xy 418.54072 -355.105626) (xy 418.488391 -355.090258)
			(xy 418.438782 -355.067599) (xy 418.392902 -355.038111) (xy 418.351686 -355.002394) (xy 418.315972 -354.961175)
			(xy 418.286488 -354.915293) (xy 418.263832 -354.865683) (xy 418.248468 -354.813353) (xy 418.240706 -354.759369)
			(xy 416.757858 -354.759369) (xy 416.750097 -354.813348) (xy 416.734733 -354.865674) (xy 416.712078 -354.915281)
			(xy 416.682595 -354.961159) (xy 416.646883 -355.002374) (xy 416.605668 -355.038088) (xy 416.559791 -355.067573)
			(xy 416.510185 -355.090228) (xy 416.457859 -355.105594) (xy 416.40388 -355.113357) (xy 416.376612 -355.113844)
			(xy 415.513012 -355.113844) (xy 415.485739 -355.113417) (xy 415.431748 -355.105656) (xy 415.379412 -355.09029)
			(xy 415.329795 -355.067632) (xy 415.283908 -355.038144) (xy 415.242684 -355.002424) (xy 415.206964 -354.961202)
			(xy 415.177473 -354.915316) (xy 415.154814 -354.865699) (xy 415.139446 -354.813363) (xy 415.131684 -354.759373)
			(xy 413.64898 -354.759373) (xy 413.641217 -354.81336) (xy 413.625849 -354.865694) (xy 413.603189 -354.915309)
			(xy 413.573699 -354.961192) (xy 413.537978 -355.002412) (xy 413.496754 -355.038128) (xy 413.450866 -355.067612)
			(xy 413.401249 -355.090266) (xy 413.348913 -355.105628) (xy 413.294924 -355.113384) (xy 413.267652 -355.113844)
			(xy 412.404052 -355.113844) (xy 412.376784 -355.11339) (xy 412.322803 -355.105623) (xy 412.270476 -355.090252)
			(xy 412.22087 -355.067592) (xy 412.174993 -355.038104) (xy 412.133779 -355.002387) (xy 412.098067 -354.961169)
			(xy 412.068585 -354.915288) (xy 412.045931 -354.865679) (xy 412.030567 -354.81335) (xy 412.022806 -354.759368)
			(xy 403.52248 -354.759368) (xy 403.52248 -354.759371) (xy 403.514718 -354.813357) (xy 403.499352 -354.865689)
			(xy 403.476694 -354.915301) (xy 403.447206 -354.961183) (xy 403.411488 -355.002402) (xy 403.370267 -355.038118)
			(xy 403.324383 -355.067603) (xy 403.27477 -355.090259) (xy 403.222437 -355.105622) (xy 403.168451 -355.113382)
			(xy 403.14118 -355.113844) (xy 402.27758 -355.113844) (xy 402.25031 -355.113392) (xy 402.196326 -355.105628)
			(xy 402.143997 -355.09026) (xy 402.094387 -355.067602) (xy 402.048506 -355.038114) (xy 402.007289 -355.002397)
			(xy 401.971574 -354.961178) (xy 401.942089 -354.915296) (xy 401.919433 -354.865685) (xy 401.904068 -354.813354)
			(xy 401.896306 -354.75937) (xy 400.413458 -354.75937) (xy 400.405697 -354.813346) (xy 400.390333 -354.865672)
			(xy 400.36768 -354.915278) (xy 400.338197 -354.961156) (xy 400.302486 -355.002371) (xy 400.261272 -355.038085)
			(xy 400.215396 -355.06757) (xy 400.165791 -355.090226) (xy 400.113466 -355.105593) (xy 400.059487 -355.113356)
			(xy 400.03222 -355.113844) (xy 399.16862 -355.113844) (xy 399.141347 -355.113418) (xy 399.087355 -355.105658)
			(xy 399.035018 -355.090292) (xy 398.9854 -355.067635) (xy 398.939511 -355.038146) (xy 398.898287 -355.002427)
			(xy 398.862566 -354.961205) (xy 398.833075 -354.915318) (xy 398.810415 -354.865701) (xy 398.795047 -354.813364)
			(xy 398.787284 -354.759373) (xy 397.30458 -354.759373) (xy 397.296818 -354.813359) (xy 397.28145 -354.865693)
			(xy 397.258791 -354.915306) (xy 397.229301 -354.96119) (xy 397.193581 -355.002409) (xy 397.152358 -355.038125)
			(xy 397.106471 -355.06761) (xy 397.056855 -355.090264) (xy 397.00452 -355.105626) (xy 396.950532 -355.113383)
			(xy 396.92326 -355.113844) (xy 396.05966 -355.113844) (xy 396.032391 -355.113391) (xy 395.978409 -355.105624)
			(xy 395.926082 -355.090255) (xy 395.876475 -355.067595) (xy 395.830597 -355.038107) (xy 395.789382 -355.00239)
			(xy 395.753669 -354.961171) (xy 395.724186 -354.91529) (xy 395.701531 -354.86568) (xy 395.686167 -354.813351)
			(xy 395.678406 -354.759369) (xy 394.195558 -354.759369) (xy 394.187796 -354.813349) (xy 394.172432 -354.865676)
			(xy 394.149777 -354.915284) (xy 394.120292 -354.961163) (xy 394.084578 -355.002378) (xy 394.043363 -355.038092)
			(xy 393.997484 -355.067577) (xy 393.947876 -355.090232) (xy 393.895549 -355.105596) (xy 393.841568 -355.113358)
			(xy 393.8143 -355.113844) (xy 392.9507 -355.113844) (xy 392.923429 -355.113394) (xy 392.869443 -355.105631)
			(xy 392.817111 -355.090265) (xy 392.767499 -355.067608) (xy 392.721616 -355.038121) (xy 392.680396 -355.002404)
			(xy 392.644679 -354.961184) (xy 392.615192 -354.915301) (xy 392.592535 -354.865689) (xy 392.577169 -354.813357)
			(xy 392.569406 -354.759371) (xy 391.086557 -354.759371) (xy 391.078797 -354.813344) (xy 391.063435 -354.865668)
			(xy 391.040783 -354.915273) (xy 391.011302 -354.96115) (xy 390.975593 -355.002364) (xy 390.934382 -355.038078)
			(xy 390.888508 -355.067563) (xy 390.838905 -355.090221) (xy 390.786583 -355.105589) (xy 390.732606 -355.113355)
			(xy 390.70534 -355.113844) (xy 389.84174 -355.113844) (xy 389.814466 -355.113419) (xy 389.760472 -355.105661)
			(xy 389.708132 -355.090298) (xy 389.658512 -355.067641) (xy 389.612621 -355.038153) (xy 389.571394 -355.002434)
			(xy 389.535671 -354.961211) (xy 389.506178 -354.915324) (xy 389.483516 -354.865705) (xy 389.468147 -354.813367)
			(xy 389.460384 -354.759374) (xy 387.97768 -354.759374) (xy 387.969918 -354.813357) (xy 387.954552 -354.865689)
			(xy 387.931894 -354.915301) (xy 387.902406 -354.961183) (xy 387.866688 -355.002402) (xy 387.825467 -355.038118)
			(xy 387.779583 -355.067603) (xy 387.72997 -355.090259) (xy 387.677637 -355.105622) (xy 387.623651 -355.113382)
			(xy 387.59638 -355.113844) (xy 386.73278 -355.113844) (xy 386.70551 -355.113392) (xy 386.651526 -355.105628)
			(xy 386.599197 -355.09026) (xy 386.549587 -355.067602) (xy 386.503706 -355.038114) (xy 386.462489 -355.002397)
			(xy 386.426774 -354.961178) (xy 386.397289 -354.915296) (xy 386.374633 -354.865685) (xy 386.359268 -354.813354)
			(xy 386.351506 -354.75937) (xy 384.868658 -354.75937) (xy 384.860897 -354.813346) (xy 384.845533 -354.865672)
			(xy 384.82288 -354.915278) (xy 384.793397 -354.961156) (xy 384.757686 -355.002371) (xy 384.716472 -355.038085)
			(xy 384.670596 -355.06757) (xy 384.620991 -355.090226) (xy 384.568666 -355.105593) (xy 384.514687 -355.113356)
			(xy 384.48742 -355.113844) (xy 383.62382 -355.113844) (xy 383.596547 -355.113418) (xy 383.542555 -355.105658)
			(xy 383.490218 -355.090292) (xy 383.4406 -355.067635) (xy 383.394711 -355.038146) (xy 383.353487 -355.002427)
			(xy 383.317766 -354.961205) (xy 383.288275 -354.915318) (xy 383.265615 -354.865701) (xy 383.250247 -354.813364)
			(xy 383.242484 -354.759373) (xy 381.75978 -354.759373) (xy 381.752018 -354.813359) (xy 381.73665 -354.865693)
			(xy 381.713991 -354.915306) (xy 381.684501 -354.96119) (xy 381.648781 -355.002409) (xy 381.607558 -355.038125)
			(xy 381.561671 -355.06761) (xy 381.512055 -355.090264) (xy 381.45972 -355.105626) (xy 381.405732 -355.113383)
			(xy 381.37846 -355.113844) (xy 380.51486 -355.113844) (xy 380.487591 -355.113391) (xy 380.433609 -355.105624)
			(xy 380.381282 -355.090255) (xy 380.331675 -355.067595) (xy 380.285797 -355.038107) (xy 380.244582 -355.00239)
			(xy 380.208869 -354.961171) (xy 380.179386 -354.91529) (xy 380.156731 -354.86568) (xy 380.141367 -354.813351)
			(xy 380.133606 -354.759369) (xy 378.650758 -354.759369) (xy 378.642996 -354.813349) (xy 378.627632 -354.865676)
			(xy 378.604977 -354.915284) (xy 378.575492 -354.961163) (xy 378.539778 -355.002378) (xy 378.498563 -355.038092)
			(xy 378.452684 -355.067577) (xy 378.403076 -355.090232) (xy 378.350749 -355.105596) (xy 378.296768 -355.113358)
			(xy 378.2695 -355.113844) (xy 377.4059 -355.113844) (xy 377.378629 -355.113394) (xy 377.324643 -355.105631)
			(xy 377.272311 -355.090265) (xy 377.222699 -355.067608) (xy 377.176816 -355.038121) (xy 377.135596 -355.002404)
			(xy 377.099879 -354.961184) (xy 377.070392 -354.915301) (xy 377.047735 -354.865689) (xy 377.032369 -354.813357)
			(xy 377.024606 -354.759371) (xy 375.541757 -354.759371) (xy 375.533997 -354.813344) (xy 375.518635 -354.865668)
			(xy 375.495983 -354.915273) (xy 375.466502 -354.96115) (xy 375.430793 -355.002364) (xy 375.389582 -355.038078)
			(xy 375.343708 -355.067563) (xy 375.294105 -355.090221) (xy 375.241783 -355.105589) (xy 375.187806 -355.113355)
			(xy 375.16054 -355.113844) (xy 374.29694 -355.113844) (xy 374.269666 -355.113419) (xy 374.215672 -355.105661)
			(xy 374.163332 -355.090298) (xy 374.113712 -355.067641) (xy 374.067821 -355.038153) (xy 374.026594 -355.002434)
			(xy 373.990871 -354.961211) (xy 373.961378 -354.915324) (xy 373.938716 -354.865705) (xy 373.923347 -354.813367)
			(xy 373.915584 -354.759374) (xy 344.837257 -354.759374) (xy 344.829496 -354.813349) (xy 344.814132 -354.865675)
			(xy 344.791477 -354.915283) (xy 344.761993 -354.961161) (xy 344.72628 -355.002377) (xy 344.685065 -355.038091)
			(xy 344.639186 -355.067575) (xy 344.589579 -355.090231) (xy 344.537253 -355.105596) (xy 344.483272 -355.113357)
			(xy 344.456004 -355.113844) (xy 343.592404 -355.113844) (xy 343.565132 -355.113417) (xy 343.511142 -355.105655)
			(xy 343.458806 -355.090288) (xy 343.40919 -355.06763) (xy 343.363304 -355.038141) (xy 343.322081 -355.002422)
			(xy 343.286362 -354.961199) (xy 343.256872 -354.915313) (xy 343.234213 -354.865698) (xy 343.218846 -354.813362)
			(xy 343.211084 -354.759372) (xy 341.728257 -354.759372) (xy 341.720498 -354.813343) (xy 341.705135 -354.865667)
			(xy 341.682483 -354.915272) (xy 341.653003 -354.961148) (xy 341.617294 -355.002363) (xy 341.576084 -355.038076)
			(xy 341.53021 -355.067562) (xy 341.480608 -355.09022) (xy 341.428286 -355.105588) (xy 341.37431 -355.113355)
			(xy 341.347044 -355.113844) (xy 340.483444 -355.113844) (xy 340.45617 -355.113419) (xy 340.402175 -355.105662)
			(xy 340.349835 -355.090299) (xy 340.300214 -355.067643) (xy 340.254323 -355.038155) (xy 340.213095 -355.002436)
			(xy 340.177371 -354.961213) (xy 340.147878 -354.915325) (xy 340.125217 -354.865706) (xy 340.109847 -354.813368)
			(xy 340.102084 -354.759374) (xy 338.61938 -354.759374) (xy 338.611618 -354.813356) (xy 338.596252 -354.865688)
			(xy 338.573594 -354.9153) (xy 338.544107 -354.961182) (xy 338.508389 -355.0024) (xy 338.467169 -355.038116)
			(xy 338.421285 -355.067602) (xy 338.371673 -355.090258) (xy 338.319341 -355.105622) (xy 338.265354 -355.113382)
			(xy 338.238084 -355.113844) (xy 337.374484 -355.113844) (xy 337.347214 -355.113392) (xy 337.29323 -355.105629)
			(xy 337.2409 -355.090261) (xy 337.191289 -355.067603) (xy 337.145408 -355.038115) (xy 337.10419 -355.002398)
			(xy 337.068475 -354.961179) (xy 337.038989 -354.915297) (xy 337.016333 -354.865685) (xy 337.000968 -354.813355)
			(xy 336.993206 -354.75937) (xy 335.510358 -354.75937) (xy 335.502597 -354.813346) (xy 335.487234 -354.865671)
			(xy 335.46458 -354.915277) (xy 335.435098 -354.961155) (xy 335.399387 -355.00237) (xy 335.358174 -355.038084)
			(xy 335.312298 -355.067569) (xy 335.262694 -355.090225) (xy 335.210369 -355.105592) (xy 335.156391 -355.113356)
			(xy 335.129124 -355.113844) (xy 334.265524 -355.113844) (xy 334.238251 -355.113418) (xy 334.184259 -355.105658)
			(xy 334.131921 -355.090293) (xy 334.082302 -355.067636) (xy 334.036413 -355.038148) (xy 333.995188 -355.002429)
			(xy 333.959467 -354.961206) (xy 333.929975 -354.915319) (xy 333.907315 -354.865702) (xy 333.891947 -354.813365)
			(xy 333.884184 -354.759373) (xy 332.40148 -354.759373) (xy 332.393718 -354.813359) (xy 332.37835 -354.865692)
			(xy 332.355691 -354.915305) (xy 332.326202 -354.961188) (xy 332.290482 -355.002407) (xy 332.24926 -355.038123)
			(xy 332.203374 -355.067609) (xy 332.153758 -355.090263) (xy 332.101424 -355.105625) (xy 332.047435 -355.113383)
			(xy 332.020164 -355.113844) (xy 331.156564 -355.113844) (xy 331.129295 -355.113391) (xy 331.075313 -355.105625)
			(xy 331.022985 -355.090256) (xy 330.973377 -355.067596) (xy 330.927499 -355.038108) (xy 330.886283 -355.002391)
			(xy 330.85057 -354.961173) (xy 330.821086 -354.915291) (xy 330.798432 -354.865681) (xy 330.783067 -354.813352)
			(xy 330.775306 -354.759369) (xy 329.292458 -354.759369) (xy 329.284696 -354.813349) (xy 329.269332 -354.865675)
			(xy 329.246677 -354.915283) (xy 329.217193 -354.961161) (xy 329.18148 -355.002377) (xy 329.140265 -355.038091)
			(xy 329.094386 -355.067575) (xy 329.044779 -355.090231) (xy 328.992453 -355.105596) (xy 328.938472 -355.113357)
			(xy 328.911204 -355.113844) (xy 328.047604 -355.113844) (xy 328.020332 -355.113417) (xy 327.966342 -355.105655)
			(xy 327.914006 -355.090288) (xy 327.86439 -355.06763) (xy 327.818504 -355.038141) (xy 327.777281 -355.002422)
			(xy 327.741562 -354.961199) (xy 327.712072 -354.915313) (xy 327.689413 -354.865698) (xy 327.674046 -354.813362)
			(xy 327.666284 -354.759372) (xy 326.183457 -354.759372) (xy 326.175698 -354.813343) (xy 326.160335 -354.865667)
			(xy 326.137683 -354.915272) (xy 326.108203 -354.961148) (xy 326.072494 -355.002363) (xy 326.031284 -355.038076)
			(xy 325.98541 -355.067562) (xy 325.935808 -355.09022) (xy 325.883486 -355.105588) (xy 325.82951 -355.113355)
			(xy 325.802244 -355.113844) (xy 324.938644 -355.113844) (xy 324.91137 -355.113419) (xy 324.857375 -355.105662)
			(xy 324.805035 -355.090299) (xy 324.755414 -355.067643) (xy 324.709523 -355.038155) (xy 324.668295 -355.002436)
			(xy 324.632571 -354.961213) (xy 324.603078 -354.915325) (xy 324.580417 -354.865706) (xy 324.565047 -354.813368)
			(xy 324.557284 -354.759374) (xy 323.07458 -354.759374) (xy 323.066818 -354.813356) (xy 323.051452 -354.865688)
			(xy 323.028794 -354.9153) (xy 322.999307 -354.961182) (xy 322.963589 -355.0024) (xy 322.922369 -355.038116)
			(xy 322.876485 -355.067602) (xy 322.826873 -355.090258) (xy 322.774541 -355.105622) (xy 322.720554 -355.113382)
			(xy 322.693284 -355.113844) (xy 321.829684 -355.113844) (xy 321.802414 -355.113392) (xy 321.74843 -355.105629)
			(xy 321.6961 -355.090261) (xy 321.646489 -355.067603) (xy 321.600608 -355.038115) (xy 321.55939 -355.002398)
			(xy 321.523675 -354.961179) (xy 321.494189 -354.915297) (xy 321.471533 -354.865685) (xy 321.456168 -354.813355)
			(xy 321.448406 -354.75937) (xy 319.965558 -354.75937) (xy 319.957797 -354.813346) (xy 319.942434 -354.865671)
			(xy 319.91978 -354.915277) (xy 319.890298 -354.961155) (xy 319.854587 -355.00237) (xy 319.813374 -355.038084)
			(xy 319.767498 -355.067569) (xy 319.717894 -355.090225) (xy 319.665569 -355.105592) (xy 319.611591 -355.113356)
			(xy 319.584324 -355.113844) (xy 318.720724 -355.113844) (xy 318.693451 -355.113418) (xy 318.639459 -355.105658)
			(xy 318.587121 -355.090293) (xy 318.537502 -355.067636) (xy 318.491613 -355.038148) (xy 318.450388 -355.002429)
			(xy 318.414667 -354.961206) (xy 318.385175 -354.915319) (xy 318.362515 -354.865702) (xy 318.347147 -354.813365)
			(xy 318.339384 -354.759373) (xy 316.85668 -354.759373) (xy 316.848918 -354.813359) (xy 316.83355 -354.865692)
			(xy 316.810891 -354.915305) (xy 316.781402 -354.961188) (xy 316.745682 -355.002407) (xy 316.70446 -355.038123)
			(xy 316.658574 -355.067609) (xy 316.608958 -355.090263) (xy 316.556624 -355.105625) (xy 316.502635 -355.113383)
			(xy 316.475364 -355.113844) (xy 315.611764 -355.113844) (xy 315.584495 -355.113391) (xy 315.530513 -355.105625)
			(xy 315.478185 -355.090256) (xy 315.428577 -355.067596) (xy 315.382699 -355.038108) (xy 315.341483 -355.002391)
			(xy 315.30577 -354.961173) (xy 315.276286 -354.915291) (xy 315.253632 -354.865681) (xy 315.238267 -354.813352)
			(xy 315.230506 -354.759369) (xy 300.231558 -354.759369) (xy 300.223796 -354.813349) (xy 300.208432 -354.865676)
			(xy 300.185777 -354.915283) (xy 300.156293 -354.961162) (xy 300.120579 -355.002378) (xy 300.079364 -355.038091)
			(xy 300.033485 -355.067576) (xy 299.983878 -355.090231) (xy 299.931551 -355.105596) (xy 299.87757 -355.113357)
			(xy 299.850302 -355.113844) (xy 298.986702 -355.113844) (xy 298.95943 -355.113417) (xy 298.90544 -355.105654)
			(xy 298.853105 -355.090288) (xy 298.803489 -355.067629) (xy 298.757603 -355.03814) (xy 298.716381 -355.002421)
			(xy 298.680661 -354.961199) (xy 298.651172 -354.915313) (xy 298.628513 -354.865697) (xy 298.613146 -354.813362)
			(xy 298.605384 -354.759372) (xy 297.122557 -354.759372) (xy 297.114798 -354.813344) (xy 297.099435 -354.865667)
			(xy 297.076783 -354.915272) (xy 297.047302 -354.961149) (xy 297.011593 -355.002364) (xy 296.970383 -355.038077)
			(xy 296.924509 -355.067563) (xy 296.874907 -355.09022) (xy 296.822585 -355.105589) (xy 296.768608 -355.113355)
			(xy 296.741342 -355.113844) (xy 295.877742 -355.113844) (xy 295.850468 -355.113419) (xy 295.796474 -355.105662)
			(xy 295.744134 -355.090298) (xy 295.694513 -355.067642) (xy 295.648622 -355.038154) (xy 295.607395 -355.002435)
			(xy 295.571671 -354.961212) (xy 295.542178 -354.915324) (xy 295.519516 -354.865706) (xy 295.504147 -354.813367)
			(xy 295.496384 -354.759374) (xy 294.013681 -354.759374) (xy 294.005918 -354.813356) (xy 293.990552 -354.865688)
			(xy 293.967894 -354.9153) (xy 293.938406 -354.961182) (xy 293.902688 -355.002401) (xy 293.861468 -355.038117)
			(xy 293.815584 -355.067603) (xy 293.765971 -355.090258) (xy 293.713639 -355.105622) (xy 293.659653 -355.113382)
			(xy 293.632382 -355.113844) (xy 292.768782 -355.113844) (xy 292.741512 -355.113392) (xy 292.687528 -355.105628)
			(xy 292.635198 -355.090261) (xy 292.585588 -355.067602) (xy 292.539707 -355.038115) (xy 292.49849 -355.002398)
			(xy 292.462775 -354.961178) (xy 292.433289 -354.915296) (xy 292.410633 -354.865685) (xy 292.395268 -354.813354)
			(xy 292.387506 -354.75937) (xy 290.904658 -354.75937) (xy 290.896897 -354.813346) (xy 290.881533 -354.865672)
			(xy 290.85888 -354.915278) (xy 290.829397 -354.961156) (xy 290.793686 -355.002371) (xy 290.752473 -355.038084)
			(xy 290.706597 -355.067569) (xy 290.656992 -355.090226) (xy 290.604668 -355.105592) (xy 290.550689 -355.113356)
			(xy 290.523422 -355.113844) (xy 289.659822 -355.113844) (xy 289.632549 -355.113418) (xy 289.578557 -355.105658)
			(xy 289.526219 -355.090293) (xy 289.476601 -355.067636) (xy 289.430712 -355.038147) (xy 289.389488 -355.002428)
			(xy 289.353766 -354.961205) (xy 289.324275 -354.915318) (xy 289.301615 -354.865702) (xy 289.286247 -354.813365)
			(xy 289.278484 -354.759373) (xy 287.79578 -354.759373) (xy 287.788018 -354.813359) (xy 287.77265 -354.865692)
			(xy 287.749991 -354.915306) (xy 287.720501 -354.961189) (xy 287.684781 -355.002408) (xy 287.643559 -355.038124)
			(xy 287.597672 -355.067609) (xy 287.548057 -355.090264) (xy 287.495722 -355.105626) (xy 287.441733 -355.113383)
			(xy 287.414462 -355.113844) (xy 286.550862 -355.113844) (xy 286.523593 -355.113391) (xy 286.469611 -355.105625)
			(xy 286.417284 -355.090255) (xy 286.367676 -355.067596) (xy 286.321798 -355.038107) (xy 286.280583 -355.00239)
			(xy 286.24487 -354.961172) (xy 286.215386 -354.915291) (xy 286.192732 -354.865681) (xy 286.177367 -354.813352)
			(xy 286.169606 -354.759369) (xy 284.686758 -354.759369) (xy 284.678996 -354.813349) (xy 284.663632 -354.865676)
			(xy 284.640977 -354.915283) (xy 284.611493 -354.961162) (xy 284.575779 -355.002378) (xy 284.534564 -355.038091)
			(xy 284.488685 -355.067576) (xy 284.439078 -355.090231) (xy 284.386751 -355.105596) (xy 284.33277 -355.113357)
			(xy 284.305502 -355.113844) (xy 283.441902 -355.113844) (xy 283.41463 -355.113417) (xy 283.36064 -355.105654)
			(xy 283.308305 -355.090288) (xy 283.258689 -355.067629) (xy 283.212803 -355.03814) (xy 283.171581 -355.002421)
			(xy 283.135861 -354.961199) (xy 283.106372 -354.915313) (xy 283.083713 -354.865697) (xy 283.068346 -354.813362)
			(xy 283.060584 -354.759372) (xy 281.577757 -354.759372) (xy 281.569998 -354.813344) (xy 281.554635 -354.865667)
			(xy 281.531983 -354.915272) (xy 281.502502 -354.961149) (xy 281.466793 -355.002364) (xy 281.425583 -355.038077)
			(xy 281.379709 -355.067563) (xy 281.330107 -355.09022) (xy 281.277785 -355.105589) (xy 281.223808 -355.113355)
			(xy 281.196542 -355.113844) (xy 280.332942 -355.113844) (xy 280.305668 -355.113419) (xy 280.251674 -355.105662)
			(xy 280.199334 -355.090298) (xy 280.149713 -355.067642) (xy 280.103822 -355.038154) (xy 280.062595 -355.002435)
			(xy 280.026871 -354.961212) (xy 279.997378 -354.915324) (xy 279.974716 -354.865706) (xy 279.959347 -354.813367)
			(xy 279.951584 -354.759374) (xy 278.468881 -354.759374) (xy 278.461118 -354.813356) (xy 278.445752 -354.865688)
			(xy 278.423094 -354.9153) (xy 278.393606 -354.961182) (xy 278.357888 -355.002401) (xy 278.316668 -355.038117)
			(xy 278.270784 -355.067603) (xy 278.221171 -355.090258) (xy 278.168839 -355.105622) (xy 278.114853 -355.113382)
			(xy 278.087582 -355.113844) (xy 277.223982 -355.113844) (xy 277.196712 -355.113392) (xy 277.142728 -355.105628)
			(xy 277.090398 -355.090261) (xy 277.040788 -355.067602) (xy 276.994907 -355.038115) (xy 276.95369 -355.002398)
			(xy 276.917975 -354.961178) (xy 276.888489 -354.915296) (xy 276.865833 -354.865685) (xy 276.850468 -354.813354)
			(xy 276.842706 -354.75937) (xy 275.359858 -354.75937) (xy 275.352097 -354.813346) (xy 275.336733 -354.865672)
			(xy 275.31408 -354.915278) (xy 275.284597 -354.961156) (xy 275.248886 -355.002371) (xy 275.207673 -355.038084)
			(xy 275.161797 -355.067569) (xy 275.112192 -355.090226) (xy 275.059868 -355.105592) (xy 275.005889 -355.113356)
			(xy 274.978622 -355.113844) (xy 274.115022 -355.113844) (xy 274.087749 -355.113418) (xy 274.033757 -355.105658)
			(xy 273.981419 -355.090293) (xy 273.931801 -355.067636) (xy 273.885912 -355.038147) (xy 273.844688 -355.002428)
			(xy 273.808966 -354.961205) (xy 273.779475 -354.915318) (xy 273.756815 -354.865702) (xy 273.741447 -354.813365)
			(xy 273.733684 -354.759373) (xy 272.25098 -354.759373) (xy 272.243218 -354.813359) (xy 272.22785 -354.865692)
			(xy 272.205191 -354.915306) (xy 272.175701 -354.961189) (xy 272.139981 -355.002408) (xy 272.098759 -355.038124)
			(xy 272.052872 -355.067609) (xy 272.003257 -355.090264) (xy 271.950922 -355.105626) (xy 271.896933 -355.113383)
			(xy 271.869662 -355.113844) (xy 271.006062 -355.113844) (xy 270.978793 -355.113391) (xy 270.924811 -355.105625)
			(xy 270.872484 -355.090255) (xy 270.822876 -355.067596) (xy 270.776998 -355.038107) (xy 270.735783 -355.00239)
			(xy 270.70007 -354.961172) (xy 270.670586 -354.915291) (xy 270.647932 -354.865681) (xy 270.632567 -354.813352)
			(xy 270.624806 -354.759369) (xy 188.299268 -354.759369) (xy 188.294942 -354.78946) (xy 188.279575 -354.841794)
			(xy 188.256917 -354.891409) (xy 188.227428 -354.937294) (xy 188.191709 -354.978515) (xy 188.150487 -355.014233)
			(xy 188.104602 -355.04372) (xy 188.054987 -355.066378) (xy 188.002652 -355.081744) (xy 187.948664 -355.089505)
			(xy 187.921392 -355.089968) (xy 187.057792 -355.089968) (xy 187.030523 -355.089469) (xy 186.976542 -355.081707)
			(xy 186.924214 -355.066341) (xy 186.874605 -355.043684) (xy 186.828726 -355.014199) (xy 186.78751 -354.978484)
			(xy 186.751796 -354.937267) (xy 186.722312 -354.891388) (xy 186.699656 -354.841779) (xy 186.684292 -354.789451)
			(xy 186.67653 -354.735469) (xy 185.193682 -354.735469) (xy 185.185921 -354.78945) (xy 185.170557 -354.841778)
			(xy 185.147903 -354.891387) (xy 185.118419 -354.937267) (xy 185.082707 -354.978484) (xy 185.041492 -355.0142)
			(xy 184.995615 -355.043687) (xy 184.946008 -355.066346) (xy 184.893681 -355.081714) (xy 184.8397 -355.089479)
			(xy 184.812432 -355.089968) (xy 183.948832 -355.089968) (xy 183.92156 -355.089495) (xy 183.86757 -355.081736)
			(xy 183.815235 -355.066373) (xy 183.765618 -355.043718) (xy 183.719731 -355.014231) (xy 183.678508 -354.978515)
			(xy 183.642788 -354.937294) (xy 183.613298 -354.89141) (xy 183.590638 -354.841795) (xy 183.57527 -354.789461)
			(xy 183.567508 -354.735472) (xy 182.08478 -354.735472) (xy 182.08478 -354.759371) (xy 182.077018 -354.813358)
			(xy 182.061651 -354.86569) (xy 182.038992 -354.915303) (xy 182.009504 -354.961186) (xy 181.973785 -355.002405)
			(xy 181.932563 -355.03812) (xy 181.886678 -355.067606) (xy 181.837064 -355.090261) (xy 181.78473 -355.105624)
			(xy 181.730743 -355.113382) (xy 181.703472 -355.113844) (xy 180.839872 -355.113844) (xy 180.812603 -355.113392)
			(xy 180.75862 -355.105626) (xy 180.706291 -355.090258) (xy 180.656682 -355.067599) (xy 180.610802 -355.038111)
			(xy 180.569586 -355.002394) (xy 180.533872 -354.961175) (xy 180.504388 -354.915293) (xy 180.481732 -354.865683)
			(xy 180.466368 -354.813353) (xy 180.458606 -354.759369) (xy 178.975758 -354.759369) (xy 178.967997 -354.813348)
			(xy 178.952633 -354.865674) (xy 178.929978 -354.915281) (xy 178.900495 -354.961159) (xy 178.864783 -355.002374)
			(xy 178.823568 -355.038088) (xy 178.777691 -355.067573) (xy 178.728085 -355.090228) (xy 178.675759 -355.105594)
			(xy 178.62178 -355.113357) (xy 178.594512 -355.113844) (xy 177.730912 -355.113844) (xy 177.703639 -355.113417)
			(xy 177.649648 -355.105656) (xy 177.597312 -355.09029) (xy 177.547695 -355.067632) (xy 177.501808 -355.038144)
			(xy 177.460584 -355.002424) (xy 177.424864 -354.961202) (xy 177.395373 -354.915316) (xy 177.372714 -354.865699)
			(xy 177.357346 -354.813363) (xy 177.349584 -354.759373) (xy 175.86688 -354.759373) (xy 175.859117 -354.81336)
			(xy 175.843749 -354.865694) (xy 175.821089 -354.915309) (xy 175.791599 -354.961192) (xy 175.755878 -355.002412)
			(xy 175.714654 -355.038128) (xy 175.668766 -355.067612) (xy 175.619149 -355.090266) (xy 175.566813 -355.105628)
			(xy 175.512824 -355.113384) (xy 175.485552 -355.113844) (xy 174.621952 -355.113844) (xy 174.594684 -355.11339)
			(xy 174.540703 -355.105623) (xy 174.488376 -355.090252) (xy 174.43877 -355.067592) (xy 174.392893 -355.038104)
			(xy 174.351679 -355.002387) (xy 174.315967 -354.961169) (xy 174.286485 -354.915288) (xy 174.263831 -354.865679)
			(xy 174.248467 -354.81335) (xy 174.240706 -354.759368) (xy 172.757881 -354.759368) (xy 172.757881 -354.75937)
			(xy 172.750119 -354.813355) (xy 172.734753 -354.865686) (xy 172.712096 -354.915297) (xy 172.682609 -354.961179)
			(xy 172.646892 -355.002398) (xy 172.605673 -355.038113) (xy 172.55979 -355.067599) (xy 172.510178 -355.090255)
			(xy 172.457847 -355.10562) (xy 172.403862 -355.113381) (xy 172.376592 -355.113844) (xy 171.512992 -355.113844)
			(xy 171.485722 -355.113393) (xy 171.431736 -355.10563) (xy 171.379405 -355.090263) (xy 171.329794 -355.067606)
			(xy 171.283912 -355.038118) (xy 171.242693 -355.002401) (xy 171.206977 -354.961182) (xy 171.177491 -354.915299)
			(xy 171.154834 -354.865687) (xy 171.139468 -354.813356) (xy 171.131706 -354.75937) (xy 169.648858 -354.75937)
			(xy 169.641097 -354.813345) (xy 169.625734 -354.865669) (xy 169.603081 -354.915275) (xy 169.5736 -354.961152)
			(xy 169.53789 -355.002367) (xy 169.496678 -355.038081) (xy 169.450803 -355.067566) (xy 169.401199 -355.090223)
			(xy 169.348876 -355.10559) (xy 169.294899 -355.113355) (xy 169.267632 -355.113844) (xy 168.404032 -355.113844)
			(xy 168.376758 -355.113419) (xy 168.322765 -355.10566) (xy 168.270426 -355.090296) (xy 168.220807 -355.067639)
			(xy 168.174917 -355.038151) (xy 168.133691 -355.002432) (xy 168.097969 -354.961209) (xy 168.068477 -354.915321)
			(xy 168.045816 -354.865704) (xy 168.030447 -354.813366) (xy 168.022684 -354.759374) (xy 166.53998 -354.759374)
			(xy 166.532218 -354.813358) (xy 166.516851 -354.86569) (xy 166.494192 -354.915303) (xy 166.464704 -354.961186)
			(xy 166.428985 -355.002405) (xy 166.387763 -355.03812) (xy 166.341878 -355.067606) (xy 166.292264 -355.090261)
			(xy 166.23993 -355.105624) (xy 166.185943 -355.113382) (xy 166.158672 -355.113844) (xy 165.295072 -355.113844)
			(xy 165.267803 -355.113392) (xy 165.21382 -355.105626) (xy 165.161491 -355.090258) (xy 165.111882 -355.067599)
			(xy 165.066002 -355.038111) (xy 165.024786 -355.002394) (xy 164.989072 -354.961175) (xy 164.959588 -354.915293)
			(xy 164.936932 -354.865683) (xy 164.921568 -354.813353) (xy 164.913806 -354.759369) (xy 163.430958 -354.759369)
			(xy 163.423197 -354.813348) (xy 163.407833 -354.865674) (xy 163.385178 -354.915281) (xy 163.355695 -354.961159)
			(xy 163.319983 -355.002374) (xy 163.278768 -355.038088) (xy 163.232891 -355.067573) (xy 163.183285 -355.090228)
			(xy 163.130959 -355.105594) (xy 163.07698 -355.113357) (xy 163.049712 -355.113844) (xy 162.186112 -355.113844)
			(xy 162.158839 -355.113417) (xy 162.104848 -355.105656) (xy 162.052512 -355.09029) (xy 162.002895 -355.067632)
			(xy 161.957008 -355.038144) (xy 161.915784 -355.002424) (xy 161.880064 -354.961202) (xy 161.850573 -354.915316)
			(xy 161.827914 -354.865699) (xy 161.812546 -354.813363) (xy 161.804784 -354.759373) (xy 160.32208 -354.759373)
			(xy 160.314317 -354.81336) (xy 160.298949 -354.865694) (xy 160.276289 -354.915309) (xy 160.246799 -354.961192)
			(xy 160.211078 -355.002412) (xy 160.169854 -355.038128) (xy 160.123966 -355.067612) (xy 160.074349 -355.090266)
			(xy 160.022013 -355.105628) (xy 159.968024 -355.113384) (xy 159.940752 -355.113844) (xy 159.077152 -355.113844)
			(xy 159.049884 -355.11339) (xy 158.995903 -355.105623) (xy 158.943576 -355.090252) (xy 158.89397 -355.067592)
			(xy 158.848093 -355.038104) (xy 158.806879 -355.002387) (xy 158.771167 -354.961169) (xy 158.741685 -354.915288)
			(xy 158.719031 -354.865679) (xy 158.703667 -354.81335) (xy 158.695906 -354.759368) (xy 144.196558 -354.759368)
			(xy 144.188797 -354.813348) (xy 144.173432 -354.865675) (xy 144.150778 -354.915282) (xy 144.121294 -354.96116)
			(xy 144.085581 -355.002376) (xy 144.044367 -355.038089) (xy 143.998489 -355.067574) (xy 143.948882 -355.09023)
			(xy 143.896556 -355.105595) (xy 143.842576 -355.113357) (xy 143.815308 -355.113844) (xy 142.951708 -355.113844)
			(xy 142.924435 -355.113417) (xy 142.870445 -355.105655) (xy 142.818109 -355.090289) (xy 142.768492 -355.067631)
			(xy 142.722606 -355.038142) (xy 142.681383 -355.002423) (xy 142.645663 -354.961201) (xy 142.616173 -354.915315)
			(xy 142.593514 -354.865699) (xy 142.578146 -354.813363) (xy 142.570384 -354.759373) (xy 141.087557 -354.759373)
			(xy 141.079798 -354.813343) (xy 141.064436 -354.865666) (xy 141.041784 -354.915271) (xy 141.012304 -354.961147)
			(xy 140.976595 -355.002361) (xy 140.935386 -355.038075) (xy 140.889513 -355.067561) (xy 140.839911 -355.090219)
			(xy 140.78759 -355.105587) (xy 140.733614 -355.113354) (xy 140.706348 -355.113844) (xy 139.842748 -355.113844)
			(xy 139.815473 -355.11342) (xy 139.761479 -355.105663) (xy 139.709138 -355.0903) (xy 139.659516 -355.067644)
			(xy 139.613625 -355.038156) (xy 139.572397 -355.002437) (xy 139.536672 -354.961214) (xy 139.507179 -354.915326)
			(xy 139.484517 -354.865707) (xy 139.469147 -354.813368) (xy 139.461384 -354.759374) (xy 137.97868 -354.759374)
			(xy 137.970918 -354.813356) (xy 137.955552 -354.865687) (xy 137.932895 -354.915298) (xy 137.903408 -354.961181)
			(xy 137.867691 -355.002399) (xy 137.826471 -355.038115) (xy 137.780588 -355.067601) (xy 137.730976 -355.090256)
			(xy 137.678644 -355.105621) (xy 137.624658 -355.113381) (xy 137.597388 -355.113844) (xy 136.733788 -355.113844)
			(xy 136.706518 -355.113393) (xy 136.652533 -355.105629) (xy 136.600203 -355.090262) (xy 136.550591 -355.067604)
			(xy 136.50471 -355.038117) (xy 136.463492 -355.0024) (xy 136.427776 -354.96118) (xy 136.39829 -354.915298)
			(xy 136.375634 -354.865686) (xy 136.360268 -354.813355) (xy 136.352506 -354.75937) (xy 134.869658 -354.75937)
			(xy 134.861897 -354.813345) (xy 134.846534 -354.86567) (xy 134.823881 -354.915276) (xy 134.794399 -354.961154)
			(xy 134.758688 -355.002369) (xy 134.717476 -355.038082) (xy 134.671601 -355.067567) (xy 134.621997 -355.090224)
			(xy 134.569673 -355.105591) (xy 134.515695 -355.113356) (xy 134.488428 -355.113844) (xy 133.624828 -355.113844)
			(xy 133.597554 -355.113418) (xy 133.543562 -355.105659) (xy 133.491223 -355.090295) (xy 133.441604 -355.067638)
			(xy 133.395715 -355.038149) (xy 133.35449 -355.00243) (xy 133.318768 -354.961207) (xy 133.289276 -354.91532)
			(xy 133.266615 -354.865703) (xy 133.251247 -354.813365) (xy 133.243484 -354.759374) (xy 131.76078 -354.759374)
			(xy 131.753018 -354.813358) (xy 131.737651 -354.865691) (xy 131.714992 -354.915304) (xy 131.685503 -354.961187)
			(xy 131.649783 -355.002406) (xy 131.608561 -355.038122) (xy 131.562676 -355.067607) (xy 131.513061 -355.090262)
			(xy 131.460727 -355.105625) (xy 131.406739 -355.113383) (xy 131.379468 -355.113844) (xy 130.515868 -355.113844)
			(xy 130.488599 -355.113391) (xy 130.434616 -355.105626) (xy 130.382288 -355.090257) (xy 130.33268 -355.067598)
			(xy 130.2868 -355.03811) (xy 130.245585 -355.002393) (xy 130.209871 -354.961174) (xy 130.180387 -354.915292)
			(xy 130.157732 -354.865682) (xy 130.142368 -354.813353) (xy 130.134606 -354.759369) (xy 128.651758 -354.759369)
			(xy 128.643997 -354.813348) (xy 128.628632 -354.865675) (xy 128.605978 -354.915282) (xy 128.576494 -354.96116)
			(xy 128.540781 -355.002376) (xy 128.499567 -355.038089) (xy 128.453689 -355.067574) (xy 128.404082 -355.09023)
			(xy 128.351756 -355.105595) (xy 128.297776 -355.113357) (xy 128.270508 -355.113844) (xy 127.406908 -355.113844)
			(xy 127.379635 -355.113417) (xy 127.325645 -355.105655) (xy 127.273309 -355.090289) (xy 127.223692 -355.067631)
			(xy 127.177806 -355.038142) (xy 127.136583 -355.002423) (xy 127.100863 -354.961201) (xy 127.071373 -354.915315)
			(xy 127.048714 -354.865699) (xy 127.033346 -354.813363) (xy 127.025584 -354.759373) (xy 125.542757 -354.759373)
			(xy 125.534998 -354.813343) (xy 125.519636 -354.865666) (xy 125.496984 -354.915271) (xy 125.467504 -354.961147)
			(xy 125.431795 -355.002361) (xy 125.390586 -355.038075) (xy 125.344713 -355.067561) (xy 125.295111 -355.090219)
			(xy 125.24279 -355.105587) (xy 125.188814 -355.113354) (xy 125.161548 -355.113844) (xy 124.297948 -355.113844)
			(xy 124.270673 -355.11342) (xy 124.216679 -355.105663) (xy 124.164338 -355.0903) (xy 124.114716 -355.067644)
			(xy 124.068825 -355.038156) (xy 124.027597 -355.002437) (xy 123.991872 -354.961214) (xy 123.962379 -354.915326)
			(xy 123.939717 -354.865707) (xy 123.924347 -354.813368) (xy 123.916584 -354.759374) (xy 122.43388 -354.759374)
			(xy 122.426118 -354.813356) (xy 122.410752 -354.865687) (xy 122.388095 -354.915298) (xy 122.358608 -354.961181)
			(xy 122.322891 -355.002399) (xy 122.281671 -355.038115) (xy 122.235788 -355.067601) (xy 122.186176 -355.090256)
			(xy 122.133844 -355.105621) (xy 122.079858 -355.113381) (xy 122.052588 -355.113844) (xy 121.188988 -355.113844)
			(xy 121.161718 -355.113393) (xy 121.107733 -355.105629) (xy 121.055403 -355.090262) (xy 121.005791 -355.067604)
			(xy 120.95991 -355.038117) (xy 120.918692 -355.0024) (xy 120.882976 -354.96118) (xy 120.85349 -354.915298)
			(xy 120.830834 -354.865686) (xy 120.815468 -354.813355) (xy 120.807706 -354.75937) (xy 119.324858 -354.75937)
			(xy 119.317097 -354.813345) (xy 119.301734 -354.86567) (xy 119.279081 -354.915276) (xy 119.249599 -354.961154)
			(xy 119.213888 -355.002369) (xy 119.172676 -355.038082) (xy 119.126801 -355.067567) (xy 119.077197 -355.090224)
			(xy 119.024873 -355.105591) (xy 118.970895 -355.113356) (xy 118.943628 -355.113844) (xy 118.080028 -355.113844)
			(xy 118.052754 -355.113418) (xy 117.998762 -355.105659) (xy 117.946423 -355.090295) (xy 117.896804 -355.067638)
			(xy 117.850915 -355.038149) (xy 117.80969 -355.00243) (xy 117.773968 -354.961207) (xy 117.744476 -354.91532)
			(xy 117.721815 -354.865703) (xy 117.706447 -354.813365) (xy 117.698684 -354.759374) (xy 116.21598 -354.759374)
			(xy 116.208218 -354.813358) (xy 116.192851 -354.865691) (xy 116.170192 -354.915304) (xy 116.140703 -354.961187)
			(xy 116.104983 -355.002406) (xy 116.063761 -355.038122) (xy 116.017876 -355.067607) (xy 115.968261 -355.090262)
			(xy 115.915927 -355.105625) (xy 115.861939 -355.113383) (xy 115.834668 -355.113844) (xy 114.971068 -355.113844)
			(xy 114.943799 -355.113391) (xy 114.889816 -355.105626) (xy 114.837488 -355.090257) (xy 114.78788 -355.067598)
			(xy 114.742 -355.03811) (xy 114.700785 -355.002393) (xy 114.665071 -354.961174) (xy 114.635587 -354.915292)
			(xy 114.612932 -354.865682) (xy 114.597568 -354.813353) (xy 114.589806 -354.759369) (xy 93.706658 -354.759369)
			(xy 93.698898 -354.813344) (xy 93.683535 -354.865667) (xy 93.660883 -354.915272) (xy 93.631402 -354.961149)
			(xy 93.595693 -355.002364) (xy 93.554483 -355.038077) (xy 93.508609 -355.067563) (xy 93.459007 -355.09022)
			(xy 93.406685 -355.105589) (xy 93.352708 -355.113355) (xy 93.325442 -355.113844) (xy 92.461842 -355.113844)
			(xy 92.434568 -355.113419) (xy 92.380574 -355.105662) (xy 92.328234 -355.090298) (xy 92.278613 -355.067642)
			(xy 92.232722 -355.038154) (xy 92.191495 -355.002435) (xy 92.155771 -354.961212) (xy 92.126278 -354.915324)
			(xy 92.103616 -354.865706) (xy 92.088247 -354.813367) (xy 92.080484 -354.759374) (xy 90.597781 -354.759374)
			(xy 90.590018 -354.813356) (xy 90.574652 -354.865688) (xy 90.551994 -354.9153) (xy 90.522506 -354.961182)
			(xy 90.486788 -355.002401) (xy 90.445568 -355.038117) (xy 90.399684 -355.067603) (xy 90.350071 -355.090258)
			(xy 90.297739 -355.105622) (xy 90.243753 -355.113382) (xy 90.216482 -355.113844) (xy 89.352882 -355.113844)
			(xy 89.325612 -355.113392) (xy 89.271628 -355.105628) (xy 89.219298 -355.090261) (xy 89.169688 -355.067602)
			(xy 89.123807 -355.038115) (xy 89.08259 -355.002398) (xy 89.046875 -354.961178) (xy 89.017389 -354.915296)
			(xy 88.994733 -354.865685) (xy 88.979368 -354.813354) (xy 88.971606 -354.75937) (xy 87.488758 -354.75937)
			(xy 87.480997 -354.813346) (xy 87.465633 -354.865672) (xy 87.44298 -354.915278) (xy 87.413497 -354.961156)
			(xy 87.377786 -355.002371) (xy 87.336573 -355.038084) (xy 87.290697 -355.067569) (xy 87.241092 -355.090226)
			(xy 87.188768 -355.105592) (xy 87.134789 -355.113356) (xy 87.107522 -355.113844) (xy 86.243922 -355.113844)
			(xy 86.216649 -355.113418) (xy 86.162657 -355.105658) (xy 86.110319 -355.090293) (xy 86.060701 -355.067636)
			(xy 86.014812 -355.038147) (xy 85.973588 -355.002428) (xy 85.937866 -354.961205) (xy 85.908375 -354.915318)
			(xy 85.885715 -354.865702) (xy 85.870347 -354.813365) (xy 85.862584 -354.759373) (xy 84.37988 -354.759373)
			(xy 84.372118 -354.813359) (xy 84.35675 -354.865692) (xy 84.334091 -354.915306) (xy 84.304601 -354.961189)
			(xy 84.268881 -355.002408) (xy 84.227659 -355.038124) (xy 84.181772 -355.067609) (xy 84.132157 -355.090264)
			(xy 84.079822 -355.105626) (xy 84.025833 -355.113383) (xy 83.998562 -355.113844) (xy 83.134962 -355.113844)
			(xy 83.107693 -355.113391) (xy 83.053711 -355.105625) (xy 83.001384 -355.090255) (xy 82.951776 -355.067596)
			(xy 82.905898 -355.038107) (xy 82.864683 -355.00239) (xy 82.82897 -354.961172) (xy 82.799486 -354.915291)
			(xy 82.776832 -354.865681) (xy 82.761467 -354.813352) (xy 82.753706 -354.759369) (xy 81.270858 -354.759369)
			(xy 81.263096 -354.813349) (xy 81.247732 -354.865676) (xy 81.225077 -354.915283) (xy 81.195593 -354.961162)
			(xy 81.159879 -355.002378) (xy 81.118664 -355.038091) (xy 81.072785 -355.067576) (xy 81.023178 -355.090231)
			(xy 80.970851 -355.105596) (xy 80.91687 -355.113357) (xy 80.889602 -355.113844) (xy 80.026002 -355.113844)
			(xy 79.99873 -355.113417) (xy 79.94474 -355.105654) (xy 79.892405 -355.090288) (xy 79.842789 -355.067629)
			(xy 79.796903 -355.03814) (xy 79.755681 -355.002421) (xy 79.719961 -354.961199) (xy 79.690472 -354.915313)
			(xy 79.667813 -354.865697) (xy 79.652446 -354.813362) (xy 79.644684 -354.759372) (xy 78.161857 -354.759372)
			(xy 78.154098 -354.813344) (xy 78.138735 -354.865667) (xy 78.116083 -354.915272) (xy 78.086602 -354.961149)
			(xy 78.050893 -355.002364) (xy 78.009683 -355.038077) (xy 77.963809 -355.067563) (xy 77.914207 -355.09022)
			(xy 77.861885 -355.105589) (xy 77.807908 -355.113355) (xy 77.780642 -355.113844) (xy 76.917042 -355.113844)
			(xy 76.889768 -355.113419) (xy 76.835774 -355.105662) (xy 76.783434 -355.090298) (xy 76.733813 -355.067642)
			(xy 76.687922 -355.038154) (xy 76.646695 -355.002435) (xy 76.610971 -354.961212) (xy 76.581478 -354.915324)
			(xy 76.558816 -354.865706) (xy 76.543447 -354.813367) (xy 76.535684 -354.759374) (xy 75.052981 -354.759374)
			(xy 75.045218 -354.813356) (xy 75.029852 -354.865688) (xy 75.007194 -354.9153) (xy 74.977706 -354.961182)
			(xy 74.941988 -355.002401) (xy 74.900768 -355.038117) (xy 74.854884 -355.067603) (xy 74.805271 -355.090258)
			(xy 74.752939 -355.105622) (xy 74.698953 -355.113382) (xy 74.671682 -355.113844) (xy 73.808082 -355.113844)
			(xy 73.780812 -355.113392) (xy 73.726828 -355.105628) (xy 73.674498 -355.090261) (xy 73.624888 -355.067602)
			(xy 73.579007 -355.038115) (xy 73.53779 -355.002398) (xy 73.502075 -354.961178) (xy 73.472589 -354.915296)
			(xy 73.449933 -354.865685) (xy 73.434568 -354.813354) (xy 73.426806 -354.75937) (xy 71.943958 -354.75937)
			(xy 71.936197 -354.813346) (xy 71.920833 -354.865672) (xy 71.89818 -354.915278) (xy 71.868697 -354.961156)
			(xy 71.832986 -355.002371) (xy 71.791773 -355.038084) (xy 71.745897 -355.067569) (xy 71.696292 -355.090226)
			(xy 71.643968 -355.105592) (xy 71.589989 -355.113356) (xy 71.562722 -355.113844) (xy 70.699122 -355.113844)
			(xy 70.671849 -355.113418) (xy 70.617857 -355.105658) (xy 70.565519 -355.090293) (xy 70.515901 -355.067636)
			(xy 70.470012 -355.038147) (xy 70.428788 -355.002428) (xy 70.393066 -354.961205) (xy 70.363575 -354.915318)
			(xy 70.340915 -354.865702) (xy 70.325547 -354.813365) (xy 70.317784 -354.759373) (xy 68.83508 -354.759373)
			(xy 68.827318 -354.813359) (xy 68.81195 -354.865692) (xy 68.789291 -354.915306) (xy 68.759801 -354.961189)
			(xy 68.724081 -355.002408) (xy 68.682859 -355.038124) (xy 68.636972 -355.067609) (xy 68.587357 -355.090264)
			(xy 68.535022 -355.105626) (xy 68.481033 -355.113383) (xy 68.453762 -355.113844) (xy 67.590162 -355.113844)
			(xy 67.562893 -355.113391) (xy 67.508911 -355.105625) (xy 67.456584 -355.090255) (xy 67.406976 -355.067596)
			(xy 67.361098 -355.038107) (xy 67.319883 -355.00239) (xy 67.28417 -354.961172) (xy 67.254686 -354.915291)
			(xy 67.232032 -354.865681) (xy 67.216667 -354.813352) (xy 67.208906 -354.759369) (xy 65.726058 -354.759369)
			(xy 65.718296 -354.813349) (xy 65.702932 -354.865676) (xy 65.680277 -354.915283) (xy 65.650793 -354.961162)
			(xy 65.615079 -355.002378) (xy 65.573864 -355.038091) (xy 65.527985 -355.067576) (xy 65.478378 -355.090231)
			(xy 65.426051 -355.105596) (xy 65.37207 -355.113357) (xy 65.344802 -355.113844) (xy 64.481202 -355.113844)
			(xy 64.45393 -355.113417) (xy 64.39994 -355.105654) (xy 64.347605 -355.090288) (xy 64.297989 -355.067629)
			(xy 64.252103 -355.03814) (xy 64.210881 -355.002421) (xy 64.175161 -354.961199) (xy 64.145672 -354.915313)
			(xy 64.123013 -354.865697) (xy 64.107646 -354.813362) (xy 64.099884 -354.759372) (xy 51.666857 -354.759372)
			(xy 51.659098 -354.813343) (xy 51.643736 -354.865666) (xy 51.621084 -354.915271) (xy 51.591604 -354.961147)
			(xy 51.555895 -355.002361) (xy 51.514686 -355.038075) (xy 51.468813 -355.067561) (xy 51.419211 -355.090219)
			(xy 51.36689 -355.105587) (xy 51.312914 -355.113354) (xy 51.285648 -355.113844) (xy 50.422048 -355.113844)
			(xy 50.394773 -355.11342) (xy 50.340779 -355.105663) (xy 50.288438 -355.0903) (xy 50.238816 -355.067644)
			(xy 50.192925 -355.038156) (xy 50.151697 -355.002437) (xy 50.115972 -354.961214) (xy 50.086479 -354.915326)
			(xy 50.063817 -354.865707) (xy 50.048447 -354.813368) (xy 50.040684 -354.759374) (xy 48.55798 -354.759374)
			(xy 48.550218 -354.813356) (xy 48.534852 -354.865687) (xy 48.512195 -354.915298) (xy 48.482708 -354.961181)
			(xy 48.446991 -355.002399) (xy 48.405771 -355.038115) (xy 48.359888 -355.067601) (xy 48.310276 -355.090256)
			(xy 48.257944 -355.105621) (xy 48.203958 -355.113381) (xy 48.176688 -355.113844) (xy 47.313088 -355.113844)
			(xy 47.285818 -355.113393) (xy 47.231833 -355.105629) (xy 47.179503 -355.090262) (xy 47.129891 -355.067604)
			(xy 47.08401 -355.038117) (xy 47.042792 -355.0024) (xy 47.007076 -354.96118) (xy 46.97759 -354.915298)
			(xy 46.954934 -354.865686) (xy 46.939568 -354.813355) (xy 46.931806 -354.75937) (xy 45.448958 -354.75937)
			(xy 45.441197 -354.813345) (xy 45.425834 -354.86567) (xy 45.403181 -354.915276) (xy 45.373699 -354.961154)
			(xy 45.337988 -355.002369) (xy 45.296776 -355.038082) (xy 45.250901 -355.067567) (xy 45.201297 -355.090224)
			(xy 45.148973 -355.105591) (xy 45.094995 -355.113356) (xy 45.067728 -355.113844) (xy 44.204128 -355.113844)
			(xy 44.176854 -355.113418) (xy 44.122862 -355.105659) (xy 44.070523 -355.090295) (xy 44.020904 -355.067638)
			(xy 43.975015 -355.038149) (xy 43.93379 -355.00243) (xy 43.898068 -354.961207) (xy 43.868576 -354.91532)
			(xy 43.845915 -354.865703) (xy 43.830547 -354.813365) (xy 43.822784 -354.759374) (xy 42.34008 -354.759374)
			(xy 42.332318 -354.813358) (xy 42.316951 -354.865691) (xy 42.294292 -354.915304) (xy 42.264803 -354.961187)
			(xy 42.229083 -355.002406) (xy 42.187861 -355.038122) (xy 42.141976 -355.067607) (xy 42.092361 -355.090262)
			(xy 42.040027 -355.105625) (xy 41.986039 -355.113383) (xy 41.958768 -355.113844) (xy 41.095168 -355.113844)
			(xy 41.067899 -355.113391) (xy 41.013916 -355.105626) (xy 40.961588 -355.090257) (xy 40.91198 -355.067598)
			(xy 40.8661 -355.03811) (xy 40.824885 -355.002393) (xy 40.789171 -354.961174) (xy 40.759687 -354.915292)
			(xy 40.737032 -354.865682) (xy 40.721668 -354.813353) (xy 40.713906 -354.759369) (xy 39.231058 -354.759369)
			(xy 39.223297 -354.813348) (xy 39.207932 -354.865675) (xy 39.185278 -354.915282) (xy 39.155794 -354.96116)
			(xy 39.120081 -355.002376) (xy 39.078867 -355.038089) (xy 39.032989 -355.067574) (xy 38.983382 -355.09023)
			(xy 38.931056 -355.105595) (xy 38.877076 -355.113357) (xy 38.849808 -355.113844) (xy 37.986208 -355.113844)
			(xy 37.958935 -355.113417) (xy 37.904945 -355.105655) (xy 37.852609 -355.090289) (xy 37.802992 -355.067631)
			(xy 37.757106 -355.038142) (xy 37.715883 -355.002423) (xy 37.680163 -354.961201) (xy 37.650673 -354.915315)
			(xy 37.628014 -354.865699) (xy 37.612646 -354.813363) (xy 37.604884 -354.759373) (xy 36.122057 -354.759373)
			(xy 36.114298 -354.813343) (xy 36.098936 -354.865666) (xy 36.076284 -354.915271) (xy 36.046804 -354.961147)
			(xy 36.011095 -355.002361) (xy 35.969886 -355.038075) (xy 35.924013 -355.067561) (xy 35.874411 -355.090219)
			(xy 35.82209 -355.105587) (xy 35.768114 -355.113354) (xy 35.740848 -355.113844) (xy 34.877248 -355.113844)
			(xy 34.849973 -355.11342) (xy 34.795979 -355.105663) (xy 34.743638 -355.0903) (xy 34.694016 -355.067644)
			(xy 34.648125 -355.038156) (xy 34.606897 -355.002437) (xy 34.571172 -354.961214) (xy 34.541679 -354.915326)
			(xy 34.519017 -354.865707) (xy 34.503647 -354.813368) (xy 34.495884 -354.759374) (xy 33.01318 -354.759374)
			(xy 33.005418 -354.813356) (xy 32.990052 -354.865687) (xy 32.967395 -354.915298) (xy 32.937908 -354.961181)
			(xy 32.902191 -355.002399) (xy 32.860971 -355.038115) (xy 32.815088 -355.067601) (xy 32.765476 -355.090256)
			(xy 32.713144 -355.105621) (xy 32.659158 -355.113381) (xy 32.631888 -355.113844) (xy 31.768288 -355.113844)
			(xy 31.741018 -355.113393) (xy 31.687033 -355.105629) (xy 31.634703 -355.090262) (xy 31.585091 -355.067604)
			(xy 31.53921 -355.038117) (xy 31.497992 -355.0024) (xy 31.462276 -354.96118) (xy 31.43279 -354.915298)
			(xy 31.410134 -354.865686) (xy 31.394768 -354.813355) (xy 31.387006 -354.75937) (xy 29.904158 -354.75937)
			(xy 29.896397 -354.813345) (xy 29.881034 -354.86567) (xy 29.858381 -354.915276) (xy 29.828899 -354.961154)
			(xy 29.793188 -355.002369) (xy 29.751976 -355.038082) (xy 29.706101 -355.067567) (xy 29.656497 -355.090224)
			(xy 29.604173 -355.105591) (xy 29.550195 -355.113356) (xy 29.522928 -355.113844) (xy 28.659328 -355.113844)
			(xy 28.632054 -355.113418) (xy 28.578062 -355.105659) (xy 28.525723 -355.090295) (xy 28.476104 -355.067638)
			(xy 28.430215 -355.038149) (xy 28.38899 -355.00243) (xy 28.353268 -354.961207) (xy 28.323776 -354.91532)
			(xy 28.301115 -354.865703) (xy 28.285747 -354.813365) (xy 28.277984 -354.759374) (xy 26.79528 -354.759374)
			(xy 26.787518 -354.813358) (xy 26.772151 -354.865691) (xy 26.749492 -354.915304) (xy 26.720003 -354.961187)
			(xy 26.684283 -355.002406) (xy 26.643061 -355.038122) (xy 26.597176 -355.067607) (xy 26.547561 -355.090262)
			(xy 26.495227 -355.105625) (xy 26.441239 -355.113383) (xy 26.413968 -355.113844) (xy 25.550368 -355.113844)
			(xy 25.523099 -355.113391) (xy 25.469116 -355.105626) (xy 25.416788 -355.090257) (xy 25.36718 -355.067598)
			(xy 25.3213 -355.03811) (xy 25.280085 -355.002393) (xy 25.244371 -354.961174) (xy 25.214887 -354.915292)
			(xy 25.192232 -354.865682) (xy 25.176868 -354.813353) (xy 25.169106 -354.759369) (xy 23.686258 -354.759369)
			(xy 23.678497 -354.813348) (xy 23.663132 -354.865675) (xy 23.640478 -354.915282) (xy 23.610994 -354.96116)
			(xy 23.575281 -355.002376) (xy 23.534067 -355.038089) (xy 23.488189 -355.067574) (xy 23.438582 -355.09023)
			(xy 23.386256 -355.105595) (xy 23.332276 -355.113357) (xy 23.305008 -355.113844) (xy 22.441408 -355.113844)
			(xy 22.414135 -355.113417) (xy 22.360145 -355.105655) (xy 22.307809 -355.090289) (xy 22.258192 -355.067631)
			(xy 22.212306 -355.038142) (xy 22.171083 -355.002423) (xy 22.135363 -354.961201) (xy 22.105873 -354.915315)
			(xy 22.083214 -354.865699) (xy 22.067846 -354.813363) (xy 22.060084 -354.759373) (xy 1.524 -354.759373)
			(xy 1.524 -357.784969) (xy 22.060131 -357.784969) (xy 22.060131 -357.730431) (xy 22.067893 -357.676447)
			(xy 22.083259 -357.624118) (xy 22.105915 -357.574508) (xy 22.135401 -357.528628) (xy 22.171117 -357.487411)
			(xy 22.212334 -357.451696) (xy 22.258215 -357.422211) (xy 22.307826 -357.399556) (xy 22.360155 -357.384191)
			(xy 22.414139 -357.376431) (xy 22.441408 -357.375968) (xy 23.305008 -357.375968) (xy 23.332279 -357.376395)
			(xy 23.386266 -357.384158) (xy 23.438599 -357.399525) (xy 23.488212 -357.422184) (xy 23.534095 -357.451672)
			(xy 23.575315 -357.48739) (xy 23.611032 -357.528611) (xy 23.64052 -357.574495) (xy 23.663177 -357.624109)
			(xy 23.678543 -357.676442) (xy 23.686306 -357.730429) (xy 23.686306 -357.784966) (xy 25.169154 -357.784966)
			(xy 25.169154 -357.730434) (xy 25.176914 -357.676458) (xy 25.192277 -357.624135) (xy 25.214929 -357.574531)
			(xy 25.24441 -357.528655) (xy 25.280119 -357.487441) (xy 25.321329 -357.451729) (xy 25.367203 -357.422244)
			(xy 25.416805 -357.399588) (xy 25.469126 -357.384221) (xy 25.523102 -357.376457) (xy 25.550368 -357.375968)
			(xy 26.413968 -357.375968) (xy 26.441243 -357.376369) (xy 26.495237 -357.384128) (xy 26.547578 -357.399493)
			(xy 26.597199 -357.422151) (xy 26.64309 -357.45164) (xy 26.684317 -357.48736) (xy 26.720041 -357.528584)
			(xy 26.749534 -357.574473) (xy 26.772196 -357.624092) (xy 26.787565 -357.676431) (xy 26.795328 -357.730425)
			(xy 26.795328 -357.78497) (xy 28.278031 -357.78497) (xy 28.278032 -357.73043) (xy 28.285794 -357.676445)
			(xy 28.30116 -357.624114) (xy 28.323818 -357.574503) (xy 28.353306 -357.528621) (xy 28.389024 -357.487404)
			(xy 28.430244 -357.451689) (xy 28.476127 -357.422205) (xy 28.52574 -357.39955) (xy 28.578072 -357.384188)
			(xy 28.632058 -357.37643) (xy 28.659328 -357.375968) (xy 29.522928 -357.375968) (xy 29.550198 -357.376396)
			(xy 29.604183 -357.384162) (xy 29.656513 -357.399531) (xy 29.706124 -357.42219) (xy 29.752005 -357.451679)
			(xy 29.793222 -357.487397) (xy 29.828937 -357.528618) (xy 29.858423 -357.574501) (xy 29.881079 -357.624113)
			(xy 29.896444 -357.676444) (xy 29.904206 -357.73043) (xy 29.904206 -357.784967) (xy 31.387054 -357.784967)
			(xy 31.387054 -357.730433) (xy 31.394815 -357.676455) (xy 31.410179 -357.624131) (xy 31.432832 -357.574525)
			(xy 31.462315 -357.528648) (xy 31.498026 -357.487434) (xy 31.539239 -357.451722) (xy 31.585115 -357.422238)
			(xy 31.634719 -357.399583) (xy 31.687043 -357.384218) (xy 31.741021 -357.376455) (xy 31.768288 -357.375968)
			(xy 32.631888 -357.375968) (xy 32.659162 -357.376371) (xy 32.713154 -357.384132) (xy 32.765492 -357.399499)
			(xy 32.815111 -357.422157) (xy 32.861 -357.451647) (xy 32.902224 -357.487367) (xy 32.937946 -357.528591)
			(xy 32.967437 -357.574479) (xy 32.990097 -357.624096) (xy 33.005465 -357.676434) (xy 33.013228 -357.730426)
			(xy 33.013228 -357.784971) (xy 34.495932 -357.784971) (xy 34.495932 -357.730429) (xy 34.503694 -357.676442)
			(xy 34.519062 -357.62411) (xy 34.541721 -357.574497) (xy 34.571211 -357.528615) (xy 34.606931 -357.487397)
			(xy 34.648153 -357.451682) (xy 34.694039 -357.422198) (xy 34.743655 -357.399545) (xy 34.795989 -357.384184)
			(xy 34.849977 -357.376428) (xy 34.877248 -357.375968) (xy 35.740848 -357.375968) (xy 35.768117 -357.376398)
			(xy 35.8221 -357.384166) (xy 35.874428 -357.399536) (xy 35.924036 -357.422197) (xy 35.969914 -357.451687)
			(xy 36.011129 -357.487405) (xy 36.046842 -357.528624) (xy 36.076326 -357.574506) (xy 36.09898 -357.624117)
			(xy 36.114345 -357.676447) (xy 36.122106 -357.730431) (xy 36.122106 -357.784969) (xy 37.604931 -357.784969)
			(xy 37.604931 -357.730431) (xy 37.612693 -357.676447) (xy 37.628059 -357.624118) (xy 37.650715 -357.574508)
			(xy 37.680201 -357.528628) (xy 37.715917 -357.487411) (xy 37.757134 -357.451696) (xy 37.803015 -357.422211)
			(xy 37.852626 -357.399556) (xy 37.904955 -357.384191) (xy 37.958939 -357.376431) (xy 37.986208 -357.375968)
			(xy 38.849808 -357.375968) (xy 38.877079 -357.376395) (xy 38.931066 -357.384158) (xy 38.983399 -357.399525)
			(xy 39.033012 -357.422184) (xy 39.078895 -357.451672) (xy 39.120115 -357.48739) (xy 39.155832 -357.528611)
			(xy 39.18532 -357.574495) (xy 39.207977 -357.624109) (xy 39.223343 -357.676442) (xy 39.231106 -357.730429)
			(xy 39.231106 -357.784966) (xy 40.713954 -357.784966) (xy 40.713954 -357.730434) (xy 40.721714 -357.676458)
			(xy 40.737077 -357.624135) (xy 40.759729 -357.574531) (xy 40.78921 -357.528655) (xy 40.824919 -357.487441)
			(xy 40.866129 -357.451729) (xy 40.912003 -357.422244) (xy 40.961605 -357.399588) (xy 41.013926 -357.384221)
			(xy 41.067902 -357.376457) (xy 41.095168 -357.375968) (xy 41.958768 -357.375968) (xy 41.986043 -357.376369)
			(xy 42.040037 -357.384128) (xy 42.092378 -357.399493) (xy 42.141999 -357.422151) (xy 42.18789 -357.45164)
			(xy 42.229117 -357.48736) (xy 42.264841 -357.528584) (xy 42.294334 -357.574473) (xy 42.316996 -357.624092)
			(xy 42.332365 -357.676431) (xy 42.340128 -357.730425) (xy 42.340128 -357.78497) (xy 43.822831 -357.78497)
			(xy 43.822832 -357.73043) (xy 43.830594 -357.676445) (xy 43.84596 -357.624114) (xy 43.868618 -357.574503)
			(xy 43.898106 -357.528621) (xy 43.933824 -357.487404) (xy 43.975044 -357.451689) (xy 44.020927 -357.422205)
			(xy 44.07054 -357.39955) (xy 44.122872 -357.384188) (xy 44.176858 -357.37643) (xy 44.204128 -357.375968)
			(xy 45.067728 -357.375968) (xy 45.094998 -357.376396) (xy 45.148983 -357.384162) (xy 45.201313 -357.399531)
			(xy 45.250924 -357.42219) (xy 45.296805 -357.451679) (xy 45.338022 -357.487397) (xy 45.373737 -357.528618)
			(xy 45.403223 -357.574501) (xy 45.425879 -357.624113) (xy 45.441244 -357.676444) (xy 45.449006 -357.73043)
			(xy 45.449006 -357.784967) (xy 46.931854 -357.784967) (xy 46.931854 -357.730433) (xy 46.939615 -357.676455)
			(xy 46.954979 -357.624131) (xy 46.977632 -357.574525) (xy 47.007115 -357.528648) (xy 47.042826 -357.487434)
			(xy 47.084039 -357.451722) (xy 47.129915 -357.422238) (xy 47.179519 -357.399583) (xy 47.231843 -357.384218)
			(xy 47.285821 -357.376455) (xy 47.313088 -357.375968) (xy 48.176688 -357.375968) (xy 48.203962 -357.376371)
			(xy 48.257954 -357.384132) (xy 48.310292 -357.399499) (xy 48.359911 -357.422157) (xy 48.4058 -357.451647)
			(xy 48.447024 -357.487367) (xy 48.482746 -357.528591) (xy 48.512237 -357.574479) (xy 48.534897 -357.624096)
			(xy 48.550265 -357.676434) (xy 48.558028 -357.730426) (xy 48.558028 -357.784971) (xy 50.040732 -357.784971)
			(xy 50.040732 -357.730429) (xy 50.048494 -357.676442) (xy 50.063862 -357.62411) (xy 50.086521 -357.574497)
			(xy 50.116011 -357.528615) (xy 50.151731 -357.487397) (xy 50.192953 -357.451682) (xy 50.238839 -357.422198)
			(xy 50.288455 -357.399545) (xy 50.340789 -357.384184) (xy 50.394777 -357.376428) (xy 50.422048 -357.375968)
			(xy 51.285648 -357.375968) (xy 51.312917 -357.376398) (xy 51.3669 -357.384166) (xy 51.419228 -357.399536)
			(xy 51.468836 -357.422197) (xy 51.514714 -357.451687) (xy 51.555929 -357.487405) (xy 51.591642 -357.528624)
			(xy 51.621126 -357.574506) (xy 51.64378 -357.624117) (xy 51.659145 -357.676447) (xy 51.666906 -357.730431)
			(xy 51.666906 -357.784969) (xy 64.099931 -357.784969) (xy 64.099931 -357.730431) (xy 64.107693 -357.676448)
			(xy 64.123058 -357.62412) (xy 64.145714 -357.57451) (xy 64.1752 -357.52863) (xy 64.210914 -357.487413)
			(xy 64.252132 -357.451698) (xy 64.298012 -357.422213) (xy 64.347621 -357.399557) (xy 64.39995 -357.384193)
			(xy 64.453933 -357.376431) (xy 64.481202 -357.375968) (xy 65.344802 -357.375968) (xy 65.372073 -357.376395)
			(xy 65.426061 -357.384157) (xy 65.478394 -357.399524) (xy 65.528008 -357.422182) (xy 65.573893 -357.45167)
			(xy 65.615113 -357.487388) (xy 65.650831 -357.528609) (xy 65.680319 -357.574493) (xy 65.702977 -357.624107)
			(xy 65.718343 -357.676441) (xy 65.726106 -357.730429) (xy 65.726106 -357.784966) (xy 67.208954 -357.784966)
			(xy 67.208954 -357.730435) (xy 67.216714 -357.676458) (xy 67.232077 -357.624136) (xy 67.254728 -357.574532)
			(xy 67.284208 -357.528657) (xy 67.319917 -357.487443) (xy 67.361126 -357.451731) (xy 67.406999 -357.422246)
			(xy 67.4566 -357.39959) (xy 67.508921 -357.384222) (xy 67.562897 -357.376457) (xy 67.590162 -357.375968)
			(xy 68.453762 -357.375968) (xy 68.481037 -357.376369) (xy 68.535032 -357.384127) (xy 68.587373 -357.399491)
			(xy 68.636995 -357.422149) (xy 68.682887 -357.451638) (xy 68.724115 -357.487358) (xy 68.75984 -357.528582)
			(xy 68.789333 -357.574471) (xy 68.811995 -357.624091) (xy 68.827365 -357.676431) (xy 68.835128 -357.730425)
			(xy 68.835128 -357.78497) (xy 70.317831 -357.78497) (xy 70.317831 -357.73043) (xy 70.325594 -357.676446)
			(xy 70.34096 -357.624115) (xy 70.363617 -357.574505) (xy 70.393105 -357.528623) (xy 70.428822 -357.487406)
			(xy 70.470041 -357.451691) (xy 70.515924 -357.422207) (xy 70.565536 -357.399552) (xy 70.617867 -357.384189)
			(xy 70.671852 -357.37643) (xy 70.699122 -357.375968) (xy 71.562722 -357.375968) (xy 71.589992 -357.376396)
			(xy 71.643978 -357.384161) (xy 71.696309 -357.399529) (xy 71.74592 -357.422189) (xy 71.791802 -357.451677)
			(xy 71.83302 -357.487395) (xy 71.868736 -357.528616) (xy 71.898222 -357.574499) (xy 71.920878 -357.624112)
			(xy 71.936244 -357.676444) (xy 71.944006 -357.730429) (xy 71.944006 -357.784966) (xy 73.426854 -357.784966)
			(xy 73.426854 -357.730434) (xy 73.434615 -357.676456) (xy 73.449978 -357.624132) (xy 73.472631 -357.574527)
			(xy 73.502113 -357.52865) (xy 73.537824 -357.487436) (xy 73.579036 -357.451724) (xy 73.624911 -357.42224)
			(xy 73.674515 -357.399584) (xy 73.726838 -357.384219) (xy 73.780816 -357.376456) (xy 73.808082 -357.375968)
			(xy 74.671682 -357.375968) (xy 74.698956 -357.37637) (xy 74.752949 -357.384131) (xy 74.805288 -357.399497)
			(xy 74.854907 -357.422155) (xy 74.900797 -357.451645) (xy 74.942022 -357.487365) (xy 74.977744 -357.528589)
			(xy 75.007236 -357.574477) (xy 75.029897 -357.624095) (xy 75.045265 -357.676433) (xy 75.053028 -357.730426)
			(xy 75.053028 -357.784971) (xy 76.535732 -357.784971) (xy 76.535732 -357.730429) (xy 76.543494 -357.676443)
			(xy 76.558861 -357.624111) (xy 76.58152 -357.574499) (xy 76.611009 -357.528617) (xy 76.646729 -357.487399)
			(xy 76.687951 -357.451684) (xy 76.733836 -357.4222) (xy 76.78345 -357.399547) (xy 76.835784 -357.384185)
			(xy 76.889771 -357.376429) (xy 76.917042 -357.375968) (xy 77.780642 -357.375968) (xy 77.807912 -357.376397)
			(xy 77.861895 -357.384165) (xy 77.914223 -357.399535) (xy 77.963832 -357.422195) (xy 78.009711 -357.451684)
			(xy 78.050927 -357.487402) (xy 78.086641 -357.528622) (xy 78.116125 -357.574505) (xy 78.13878 -357.624116)
			(xy 78.154144 -357.676446) (xy 78.161906 -357.73043) (xy 78.161906 -357.784969) (xy 79.644731 -357.784969)
			(xy 79.644731 -357.730431) (xy 79.652493 -357.676448) (xy 79.667858 -357.62412) (xy 79.690514 -357.57451)
			(xy 79.72 -357.52863) (xy 79.755714 -357.487413) (xy 79.796932 -357.451698) (xy 79.842812 -357.422213)
			(xy 79.892421 -357.399557) (xy 79.94475 -357.384193) (xy 79.998733 -357.376431) (xy 80.026002 -357.375968)
			(xy 80.889602 -357.375968) (xy 80.916873 -357.376395) (xy 80.970861 -357.384157) (xy 81.023194 -357.399524)
			(xy 81.072808 -357.422182) (xy 81.118693 -357.45167) (xy 81.159913 -357.487388) (xy 81.195631 -357.528609)
			(xy 81.225119 -357.574493) (xy 81.247777 -357.624107) (xy 81.263143 -357.676441) (xy 81.270906 -357.730429)
			(xy 81.270906 -357.784966) (xy 82.753754 -357.784966) (xy 82.753754 -357.730435) (xy 82.761514 -357.676458)
			(xy 82.776877 -357.624136) (xy 82.799528 -357.574532) (xy 82.829008 -357.528657) (xy 82.864717 -357.487443)
			(xy 82.905926 -357.451731) (xy 82.951799 -357.422246) (xy 83.0014 -357.39959) (xy 83.053721 -357.384222)
			(xy 83.107697 -357.376457) (xy 83.134962 -357.375968) (xy 83.998562 -357.375968) (xy 84.025837 -357.376369)
			(xy 84.079832 -357.384127) (xy 84.132173 -357.399491) (xy 84.181795 -357.422149) (xy 84.227687 -357.451638)
			(xy 84.268915 -357.487358) (xy 84.30464 -357.528582) (xy 84.334133 -357.574471) (xy 84.356795 -357.624091)
			(xy 84.372165 -357.676431) (xy 84.379928 -357.730425) (xy 84.379928 -357.78497) (xy 85.862631 -357.78497)
			(xy 85.862631 -357.73043) (xy 85.870394 -357.676446) (xy 85.88576 -357.624115) (xy 85.908417 -357.574505)
			(xy 85.937905 -357.528623) (xy 85.973622 -357.487406) (xy 86.014841 -357.451691) (xy 86.060724 -357.422207)
			(xy 86.110336 -357.399552) (xy 86.162667 -357.384189) (xy 86.216652 -357.37643) (xy 86.243922 -357.375968)
			(xy 87.107522 -357.375968) (xy 87.134792 -357.376396) (xy 87.188778 -357.384161) (xy 87.241109 -357.399529)
			(xy 87.29072 -357.422189) (xy 87.336602 -357.451677) (xy 87.37782 -357.487395) (xy 87.413536 -357.528616)
			(xy 87.443022 -357.574499) (xy 87.465678 -357.624112) (xy 87.481044 -357.676444) (xy 87.488806 -357.730429)
			(xy 87.488806 -357.784966) (xy 88.971654 -357.784966) (xy 88.971654 -357.730434) (xy 88.979415 -357.676456)
			(xy 88.994778 -357.624132) (xy 89.017431 -357.574527) (xy 89.046913 -357.52865) (xy 89.082624 -357.487436)
			(xy 89.123836 -357.451724) (xy 89.169711 -357.42224) (xy 89.219315 -357.399584) (xy 89.271638 -357.384219)
			(xy 89.325616 -357.376456) (xy 89.352882 -357.375968) (xy 90.216482 -357.375968) (xy 90.243756 -357.37637)
			(xy 90.297749 -357.384131) (xy 90.350088 -357.399497) (xy 90.399707 -357.422155) (xy 90.445597 -357.451645)
			(xy 90.486822 -357.487365) (xy 90.522544 -357.528589) (xy 90.552036 -357.574477) (xy 90.574697 -357.624095)
			(xy 90.590065 -357.676433) (xy 90.597828 -357.730426) (xy 90.597828 -357.784971) (xy 92.080532 -357.784971)
			(xy 92.080532 -357.730429) (xy 92.088294 -357.676443) (xy 92.103661 -357.624111) (xy 92.12632 -357.574499)
			(xy 92.155809 -357.528617) (xy 92.191529 -357.487399) (xy 92.232751 -357.451684) (xy 92.278636 -357.4222)
			(xy 92.32825 -357.399547) (xy 92.380584 -357.384185) (xy 92.434571 -357.376429) (xy 92.461842 -357.375968)
			(xy 93.325442 -357.375968) (xy 93.352712 -357.376397) (xy 93.406695 -357.384165) (xy 93.459023 -357.399535)
			(xy 93.508632 -357.422195) (xy 93.554511 -357.451684) (xy 93.595727 -357.487402) (xy 93.631441 -357.528622)
			(xy 93.660925 -357.574505) (xy 93.68358 -357.624116) (xy 93.698944 -357.676446) (xy 93.706706 -357.73043)
			(xy 93.706706 -357.784966) (xy 114.589854 -357.784966) (xy 114.589854 -357.730434) (xy 114.597614 -357.676458)
			(xy 114.612977 -357.624135) (xy 114.635629 -357.574531) (xy 114.66511 -357.528655) (xy 114.700819 -357.487441)
			(xy 114.742029 -357.451729) (xy 114.787903 -357.422244) (xy 114.837505 -357.399588) (xy 114.889826 -357.384221)
			(xy 114.943802 -357.376457) (xy 114.971068 -357.375968) (xy 115.834668 -357.375968) (xy 115.861943 -357.376369)
			(xy 115.915937 -357.384128) (xy 115.968278 -357.399493) (xy 116.017899 -357.422151) (xy 116.06379 -357.45164)
			(xy 116.105017 -357.48736) (xy 116.140741 -357.528584) (xy 116.170234 -357.574473) (xy 116.192896 -357.624092)
			(xy 116.208265 -357.676431) (xy 116.216028 -357.730425) (xy 116.216028 -357.78497) (xy 117.698731 -357.78497)
			(xy 117.698732 -357.73043) (xy 117.706494 -357.676445) (xy 117.72186 -357.624114) (xy 117.744518 -357.574503)
			(xy 117.774006 -357.528621) (xy 117.809724 -357.487404) (xy 117.850944 -357.451689) (xy 117.896827 -357.422205)
			(xy 117.94644 -357.39955) (xy 117.998772 -357.384188) (xy 118.052758 -357.37643) (xy 118.080028 -357.375968)
			(xy 118.943628 -357.375968) (xy 118.970898 -357.376396) (xy 119.024883 -357.384162) (xy 119.077213 -357.399531)
			(xy 119.126824 -357.42219) (xy 119.172705 -357.451679) (xy 119.213922 -357.487397) (xy 119.249637 -357.528618)
			(xy 119.279123 -357.574501) (xy 119.301779 -357.624113) (xy 119.317144 -357.676444) (xy 119.324906 -357.73043)
			(xy 119.324906 -357.784967) (xy 120.807754 -357.784967) (xy 120.807754 -357.730433) (xy 120.815515 -357.676455)
			(xy 120.830879 -357.624131) (xy 120.853532 -357.574525) (xy 120.883015 -357.528648) (xy 120.918726 -357.487434)
			(xy 120.959939 -357.451722) (xy 121.005815 -357.422238) (xy 121.055419 -357.399583) (xy 121.107743 -357.384218)
			(xy 121.161721 -357.376455) (xy 121.188988 -357.375968) (xy 122.052588 -357.375968) (xy 122.079862 -357.376371)
			(xy 122.133854 -357.384132) (xy 122.186192 -357.399499) (xy 122.235811 -357.422157) (xy 122.2817 -357.451647)
			(xy 122.322924 -357.487367) (xy 122.358646 -357.528591) (xy 122.388137 -357.574479) (xy 122.410797 -357.624096)
			(xy 122.426165 -357.676434) (xy 122.433928 -357.730426) (xy 122.433928 -357.784971) (xy 123.916632 -357.784971)
			(xy 123.916632 -357.730429) (xy 123.924394 -357.676442) (xy 123.939762 -357.62411) (xy 123.962421 -357.574497)
			(xy 123.991911 -357.528615) (xy 124.027631 -357.487397) (xy 124.068853 -357.451682) (xy 124.114739 -357.422198)
			(xy 124.164355 -357.399545) (xy 124.216689 -357.384184) (xy 124.270677 -357.376428) (xy 124.297948 -357.375968)
			(xy 125.161548 -357.375968) (xy 125.188817 -357.376398) (xy 125.2428 -357.384166) (xy 125.295128 -357.399536)
			(xy 125.344736 -357.422197) (xy 125.390614 -357.451687) (xy 125.431829 -357.487405) (xy 125.467542 -357.528624)
			(xy 125.497026 -357.574506) (xy 125.51968 -357.624117) (xy 125.535045 -357.676447) (xy 125.542806 -357.730431)
			(xy 125.542806 -357.784969) (xy 127.025631 -357.784969) (xy 127.025631 -357.730431) (xy 127.033393 -357.676447)
			(xy 127.048759 -357.624118) (xy 127.071415 -357.574508) (xy 127.100901 -357.528628) (xy 127.136617 -357.487411)
			(xy 127.177834 -357.451696) (xy 127.223715 -357.422211) (xy 127.273326 -357.399556) (xy 127.325655 -357.384191)
			(xy 127.379639 -357.376431) (xy 127.406908 -357.375968) (xy 128.270508 -357.375968) (xy 128.297779 -357.376395)
			(xy 128.351766 -357.384158) (xy 128.404099 -357.399525) (xy 128.453712 -357.422184) (xy 128.499595 -357.451672)
			(xy 128.540815 -357.48739) (xy 128.576532 -357.528611) (xy 128.60602 -357.574495) (xy 128.628677 -357.624109)
			(xy 128.644043 -357.676442) (xy 128.651806 -357.730429) (xy 128.651806 -357.784966) (xy 130.134654 -357.784966)
			(xy 130.134654 -357.730434) (xy 130.142414 -357.676458) (xy 130.157777 -357.624135) (xy 130.180429 -357.574531)
			(xy 130.20991 -357.528655) (xy 130.245619 -357.487441) (xy 130.286829 -357.451729) (xy 130.332703 -357.422244)
			(xy 130.382305 -357.399588) (xy 130.434626 -357.384221) (xy 130.488602 -357.376457) (xy 130.515868 -357.375968)
			(xy 131.379468 -357.375968) (xy 131.406743 -357.376369) (xy 131.460737 -357.384128) (xy 131.513078 -357.399493)
			(xy 131.562699 -357.422151) (xy 131.60859 -357.45164) (xy 131.649817 -357.48736) (xy 131.685541 -357.528584)
			(xy 131.715034 -357.574473) (xy 131.737696 -357.624092) (xy 131.753065 -357.676431) (xy 131.760828 -357.730425)
			(xy 131.760828 -357.78497) (xy 133.243531 -357.78497) (xy 133.243532 -357.73043) (xy 133.251294 -357.676445)
			(xy 133.26666 -357.624114) (xy 133.289318 -357.574503) (xy 133.318806 -357.528621) (xy 133.354524 -357.487404)
			(xy 133.395744 -357.451689) (xy 133.441627 -357.422205) (xy 133.49124 -357.39955) (xy 133.543572 -357.384188)
			(xy 133.597558 -357.37643) (xy 133.624828 -357.375968) (xy 134.488428 -357.375968) (xy 134.515698 -357.376396)
			(xy 134.569683 -357.384162) (xy 134.622013 -357.399531) (xy 134.671624 -357.42219) (xy 134.717505 -357.451679)
			(xy 134.758722 -357.487397) (xy 134.794437 -357.528618) (xy 134.823923 -357.574501) (xy 134.846579 -357.624113)
			(xy 134.861944 -357.676444) (xy 134.869706 -357.73043) (xy 134.869706 -357.784967) (xy 136.352554 -357.784967)
			(xy 136.352554 -357.730433) (xy 136.360315 -357.676455) (xy 136.375679 -357.624131) (xy 136.398332 -357.574525)
			(xy 136.427815 -357.528648) (xy 136.463526 -357.487434) (xy 136.504739 -357.451722) (xy 136.550615 -357.422238)
			(xy 136.600219 -357.399583) (xy 136.652543 -357.384218) (xy 136.706521 -357.376455) (xy 136.733788 -357.375968)
			(xy 137.597388 -357.375968) (xy 137.624662 -357.376371) (xy 137.678654 -357.384132) (xy 137.730992 -357.399499)
			(xy 137.780611 -357.422157) (xy 137.8265 -357.451647) (xy 137.867724 -357.487367) (xy 137.903446 -357.528591)
			(xy 137.932937 -357.574479) (xy 137.955597 -357.624096) (xy 137.970965 -357.676434) (xy 137.978728 -357.730426)
			(xy 137.978728 -357.784971) (xy 139.461432 -357.784971) (xy 139.461432 -357.730429) (xy 139.469194 -357.676442)
			(xy 139.484562 -357.62411) (xy 139.507221 -357.574497) (xy 139.536711 -357.528615) (xy 139.572431 -357.487397)
			(xy 139.613653 -357.451682) (xy 139.659539 -357.422198) (xy 139.709155 -357.399545) (xy 139.761489 -357.384184)
			(xy 139.815477 -357.376428) (xy 139.842748 -357.375968) (xy 140.706348 -357.375968) (xy 140.733617 -357.376398)
			(xy 140.7876 -357.384166) (xy 140.839928 -357.399536) (xy 140.889536 -357.422197) (xy 140.935414 -357.451687)
			(xy 140.976629 -357.487405) (xy 141.012342 -357.528624) (xy 141.041826 -357.574506) (xy 141.06448 -357.624117)
			(xy 141.079845 -357.676447) (xy 141.087606 -357.730431) (xy 141.087606 -357.784969) (xy 142.570431 -357.784969)
			(xy 142.570431 -357.730431) (xy 142.578193 -357.676447) (xy 142.593559 -357.624118) (xy 142.616215 -357.574508)
			(xy 142.645701 -357.528628) (xy 142.681417 -357.487411) (xy 142.722634 -357.451696) (xy 142.768515 -357.422211)
			(xy 142.818126 -357.399556) (xy 142.870455 -357.384191) (xy 142.924439 -357.376431) (xy 142.951708 -357.375968)
			(xy 143.815308 -357.375968) (xy 143.842579 -357.376395) (xy 143.896566 -357.384158) (xy 143.948899 -357.399525)
			(xy 143.998512 -357.422184) (xy 144.044395 -357.451672) (xy 144.085615 -357.48739) (xy 144.121332 -357.528611)
			(xy 144.15082 -357.574495) (xy 144.173477 -357.624109) (xy 144.188843 -357.676442) (xy 144.196606 -357.730429)
			(xy 144.196606 -357.784965) (xy 158.695954 -357.784965) (xy 158.695954 -357.730435) (xy 158.703714 -357.67646)
			(xy 158.719076 -357.624138) (xy 158.741727 -357.574535) (xy 158.771206 -357.52866) (xy 158.806913 -357.487447)
			(xy 158.848122 -357.451735) (xy 158.893993 -357.42225) (xy 158.943593 -357.399593) (xy 158.995913 -357.384224)
			(xy 159.049887 -357.376458) (xy 159.077152 -357.375968) (xy 159.940752 -357.375968) (xy 159.968027 -357.376368)
			(xy 160.022024 -357.384125) (xy 160.074366 -357.399489) (xy 160.123989 -357.422145) (xy 160.169883 -357.451634)
			(xy 160.211112 -357.487354) (xy 160.246837 -357.528579) (xy 160.276332 -357.574468) (xy 160.298994 -357.624089)
			(xy 160.314364 -357.676429) (xy 160.322128 -357.730425) (xy 160.322128 -357.784969) (xy 161.804831 -357.784969)
			(xy 161.804831 -357.730431) (xy 161.812593 -357.676447) (xy 161.827959 -357.624117) (xy 161.850616 -357.574507)
			(xy 161.880102 -357.528627) (xy 161.915818 -357.487409) (xy 161.957036 -357.451695) (xy 162.002918 -357.42221)
			(xy 162.052529 -357.399555) (xy 162.104859 -357.384191) (xy 162.158843 -357.376431) (xy 162.186112 -357.375968)
			(xy 163.049712 -357.375968) (xy 163.076983 -357.376395) (xy 163.130969 -357.384159) (xy 163.183302 -357.399527)
			(xy 163.232914 -357.422185) (xy 163.278797 -357.451674) (xy 163.320017 -357.487392) (xy 163.355733 -357.528612)
			(xy 163.385221 -357.574496) (xy 163.407878 -357.62411) (xy 163.423244 -357.676442) (xy 163.431006 -357.730429)
			(xy 163.431006 -357.784966) (xy 164.913854 -357.784966) (xy 164.913854 -357.730434) (xy 164.921615 -357.676457)
			(xy 164.936977 -357.624134) (xy 164.95963 -357.57453) (xy 164.989111 -357.528654) (xy 165.02482 -357.48744)
			(xy 165.066031 -357.451727) (xy 165.111905 -357.422243) (xy 165.161508 -357.399587) (xy 165.21383 -357.384221)
			(xy 165.267806 -357.376456) (xy 165.295072 -357.375968) (xy 166.158672 -357.375968) (xy 166.185946 -357.37637)
			(xy 166.239941 -357.384129) (xy 166.292281 -357.399494) (xy 166.341901 -357.422152) (xy 166.387792 -357.451641)
			(xy 166.429019 -357.487361) (xy 166.464742 -357.528585) (xy 166.494235 -357.574474) (xy 166.516896 -357.624093)
			(xy 166.532265 -357.676432) (xy 166.540028 -357.730426) (xy 166.540028 -357.78497) (xy 168.022732 -357.78497)
			(xy 168.022732 -357.73043) (xy 168.030494 -357.676444) (xy 168.045861 -357.624113) (xy 168.068519 -357.574502)
			(xy 168.098007 -357.52862) (xy 168.133725 -357.487402) (xy 168.174946 -357.451688) (xy 168.22083 -357.422203)
			(xy 168.270443 -357.399549) (xy 168.322776 -357.384187) (xy 168.376762 -357.376429) (xy 168.404032 -357.375968)
			(xy 169.267632 -357.375968) (xy 169.294902 -357.376397) (xy 169.348886 -357.384163) (xy 169.401216 -357.399532)
			(xy 169.450826 -357.422192) (xy 169.496707 -357.451681) (xy 169.537924 -357.487399) (xy 169.573638 -357.528619)
			(xy 169.603124 -357.574502) (xy 169.625779 -357.624114) (xy 169.641144 -357.676445) (xy 169.648906 -357.73043)
			(xy 169.648906 -357.784967) (xy 171.131754 -357.784967) (xy 171.131754 -357.730433) (xy 171.139515 -357.676454)
			(xy 171.154879 -357.62413) (xy 171.177533 -357.574524) (xy 171.207016 -357.528647) (xy 171.242727 -357.487433)
			(xy 171.283941 -357.45172) (xy 171.329817 -357.422237) (xy 171.379422 -357.399582) (xy 171.431747 -357.384217)
			(xy 171.485725 -357.376455) (xy 171.512992 -357.375968) (xy 172.376592 -357.375968) (xy 172.403866 -357.376371)
			(xy 172.457857 -357.384133) (xy 172.510195 -357.3995) (xy 172.559813 -357.422159) (xy 172.605702 -357.451648)
			(xy 172.646926 -357.487368) (xy 172.682647 -357.528592) (xy 172.712138 -357.57448) (xy 172.734798 -357.624097)
			(xy 172.750165 -357.676435) (xy 172.757928 -357.730426) (xy 172.757928 -357.784965) (xy 174.240754 -357.784965)
			(xy 174.240754 -357.730435) (xy 174.248514 -357.67646) (xy 174.263876 -357.624138) (xy 174.286527 -357.574535)
			(xy 174.316006 -357.52866) (xy 174.351713 -357.487447) (xy 174.392922 -357.451735) (xy 174.438793 -357.42225)
			(xy 174.488393 -357.399593) (xy 174.540713 -357.384224) (xy 174.594687 -357.376458) (xy 174.621952 -357.375968)
			(xy 175.485552 -357.375968) (xy 175.512827 -357.376368) (xy 175.566824 -357.384125) (xy 175.619166 -357.399489)
			(xy 175.668789 -357.422145) (xy 175.714683 -357.451634) (xy 175.755912 -357.487354) (xy 175.791637 -357.528579)
			(xy 175.821132 -357.574468) (xy 175.843794 -357.624089) (xy 175.859164 -357.676429) (xy 175.866928 -357.730425)
			(xy 175.866928 -357.784969) (xy 177.349631 -357.784969) (xy 177.349631 -357.730431) (xy 177.357393 -357.676447)
			(xy 177.372759 -357.624117) (xy 177.395416 -357.574507) (xy 177.424902 -357.528627) (xy 177.460618 -357.487409)
			(xy 177.501836 -357.451695) (xy 177.547718 -357.42221) (xy 177.597329 -357.399555) (xy 177.649659 -357.384191)
			(xy 177.703643 -357.376431) (xy 177.730912 -357.375968) (xy 178.594512 -357.375968) (xy 178.621783 -357.376395)
			(xy 178.675769 -357.384159) (xy 178.728102 -357.399527) (xy 178.777714 -357.422185) (xy 178.823597 -357.451674)
			(xy 178.864817 -357.487392) (xy 178.900533 -357.528612) (xy 178.930021 -357.574496) (xy 178.952678 -357.62411)
			(xy 178.968044 -357.676442) (xy 178.975806 -357.730429) (xy 178.975806 -357.784966) (xy 180.458654 -357.784966)
			(xy 180.458654 -357.730434) (xy 180.466415 -357.676457) (xy 180.481777 -357.624134) (xy 180.50443 -357.57453)
			(xy 180.533911 -357.528654) (xy 180.56962 -357.48744) (xy 180.610831 -357.451727) (xy 180.656705 -357.422243)
			(xy 180.706308 -357.399587) (xy 180.75863 -357.384221) (xy 180.812606 -357.376456) (xy 180.839872 -357.375968)
			(xy 181.703472 -357.375968) (xy 181.730746 -357.37637) (xy 181.784741 -357.384129) (xy 181.837081 -357.399494)
			(xy 181.886701 -357.422152) (xy 181.932592 -357.451641) (xy 181.973819 -357.487361) (xy 182.009542 -357.528585)
			(xy 182.039035 -357.574474) (xy 182.061696 -357.624093) (xy 182.077065 -357.676432) (xy 182.084828 -357.730426)
			(xy 182.084828 -357.761176) (xy 183.567456 -357.761176) (xy 183.567456 -357.706624) (xy 183.57522 -357.652628)
			(xy 183.590589 -357.600287) (xy 183.613252 -357.550665) (xy 183.642746 -357.504775) (xy 183.678471 -357.463549)
			(xy 183.7197 -357.427827) (xy 183.765593 -357.398337) (xy 183.815217 -357.375678) (xy 183.867559 -357.360313)
			(xy 183.921556 -357.352553) (xy 183.948832 -357.352092) (xy 184.812432 -357.352092) (xy 184.839697 -357.352672)
			(xy 184.89367 -357.360437) (xy 184.94599 -357.375803) (xy 184.99559 -357.398458) (xy 185.041461 -357.427942)
			(xy 185.08267 -357.463653) (xy 185.118378 -357.504864) (xy 185.147857 -357.550738) (xy 185.170508 -357.60034)
			(xy 185.18587 -357.652661) (xy 185.19363 -357.706635) (xy 185.19363 -357.761165) (xy 185.193629 -357.761172)
			(xy 186.676479 -357.761172) (xy 186.676479 -357.706628) (xy 186.684241 -357.652638) (xy 186.699608 -357.600303)
			(xy 186.722266 -357.550688) (xy 186.751755 -357.504801) (xy 186.787473 -357.463579) (xy 186.828695 -357.42786)
			(xy 186.87458 -357.39837) (xy 186.924196 -357.37571) (xy 186.97653 -357.360343) (xy 187.03052 -357.352579)
			(xy 187.057792 -357.352092) (xy 187.921392 -357.352092) (xy 187.94866 -357.352647) (xy 188.002641 -357.360407)
			(xy 188.054969 -357.375771) (xy 188.104577 -357.398425) (xy 188.150456 -357.427909) (xy 188.191672 -357.463622)
			(xy 188.227386 -357.504838) (xy 188.256871 -357.550716) (xy 188.279526 -357.600324) (xy 188.294891 -357.652651)
			(xy 188.302653 -357.706632) (xy 188.302653 -357.761168) (xy 188.294891 -357.815149) (xy 188.279526 -357.867476)
			(xy 188.256871 -357.917084) (xy 188.227386 -357.962962) (xy 188.223925 -357.966956) (xy 245.50903 -357.966956)
			(xy 245.50903 -357.88226) (xy 245.517081 -357.797946) (xy 245.53311 -357.71478) (xy 245.556971 -357.633513)
			(xy 245.58845 -357.554883) (xy 245.627261 -357.479602) (xy 245.673051 -357.40835) (xy 245.725407 -357.341774)
			(xy 245.783855 -357.280476) (xy 245.847865 -357.225011) (xy 245.916857 -357.175882) (xy 245.990207 -357.133533)
			(xy 246.06725 -357.098349) (xy 246.147289 -357.070647) (xy 246.229598 -357.050679) (xy 246.313433 -357.038626)
			(xy 246.398034 -357.034596) (xy 246.482635 -357.038626) (xy 246.56647 -357.050679) (xy 246.648779 -357.070647)
			(xy 246.728818 -357.098349) (xy 246.805861 -357.133533) (xy 246.879211 -357.175882) (xy 246.948203 -357.225011)
			(xy 247.012213 -357.280476) (xy 247.070661 -357.341774) (xy 247.123017 -357.40835) (xy 247.168807 -357.479602)
			(xy 247.207618 -357.554883) (xy 247.239097 -357.633513) (xy 247.262958 -357.71478) (xy 247.276485 -357.784966)
			(xy 270.624854 -357.784966) (xy 270.624854 -357.730435) (xy 270.632614 -357.676458) (xy 270.647977 -357.624136)
			(xy 270.670628 -357.574532) (xy 270.700108 -357.528657) (xy 270.735817 -357.487443) (xy 270.777026 -357.451731)
			(xy 270.822899 -357.422246) (xy 270.8725 -357.39959) (xy 270.924821 -357.384222) (xy 270.978797 -357.376457)
			(xy 271.006062 -357.375968) (xy 271.869662 -357.375968) (xy 271.896937 -357.376369) (xy 271.950932 -357.384127)
			(xy 272.003273 -357.399491) (xy 272.052895 -357.422149) (xy 272.098787 -357.451638) (xy 272.140015 -357.487358)
			(xy 272.17574 -357.528582) (xy 272.205233 -357.574471) (xy 272.227895 -357.624091) (xy 272.243265 -357.676431)
			(xy 272.251028 -357.730425) (xy 272.251028 -357.78497) (xy 273.733731 -357.78497) (xy 273.733731 -357.73043)
			(xy 273.741494 -357.676446) (xy 273.75686 -357.624115) (xy 273.779517 -357.574505) (xy 273.809005 -357.528623)
			(xy 273.844722 -357.487406) (xy 273.885941 -357.451691) (xy 273.931824 -357.422207) (xy 273.981436 -357.399552)
			(xy 274.033767 -357.384189) (xy 274.087752 -357.37643) (xy 274.115022 -357.375968) (xy 274.978622 -357.375968)
			(xy 275.005892 -357.376396) (xy 275.059878 -357.384161) (xy 275.112209 -357.399529) (xy 275.16182 -357.422189)
			(xy 275.207702 -357.451677) (xy 275.24892 -357.487395) (xy 275.284636 -357.528616) (xy 275.314122 -357.574499)
			(xy 275.336778 -357.624112) (xy 275.352144 -357.676444) (xy 275.359906 -357.730429) (xy 275.359906 -357.784966)
			(xy 276.842754 -357.784966) (xy 276.842754 -357.730434) (xy 276.850515 -357.676456) (xy 276.865878 -357.624132)
			(xy 276.888531 -357.574527) (xy 276.918013 -357.52865) (xy 276.953724 -357.487436) (xy 276.994936 -357.451724)
			(xy 277.040811 -357.42224) (xy 277.090415 -357.399584) (xy 277.142738 -357.384219) (xy 277.196716 -357.376456)
			(xy 277.223982 -357.375968) (xy 278.087582 -357.375968) (xy 278.114856 -357.37637) (xy 278.168849 -357.384131)
			(xy 278.221188 -357.399497) (xy 278.270807 -357.422155) (xy 278.316697 -357.451645) (xy 278.357922 -357.487365)
			(xy 278.393644 -357.528589) (xy 278.423136 -357.574477) (xy 278.445797 -357.624095) (xy 278.461165 -357.676433)
			(xy 278.468928 -357.730426) (xy 278.468928 -357.784971) (xy 279.951632 -357.784971) (xy 279.951632 -357.730429)
			(xy 279.959394 -357.676443) (xy 279.974761 -357.624111) (xy 279.99742 -357.574499) (xy 280.026909 -357.528617)
			(xy 280.062629 -357.487399) (xy 280.103851 -357.451684) (xy 280.149736 -357.4222) (xy 280.19935 -357.399547)
			(xy 280.251684 -357.384185) (xy 280.305671 -357.376429) (xy 280.332942 -357.375968) (xy 281.196542 -357.375968)
			(xy 281.223812 -357.376397) (xy 281.277795 -357.384165) (xy 281.330123 -357.399535) (xy 281.379732 -357.422195)
			(xy 281.425611 -357.451684) (xy 281.466827 -357.487402) (xy 281.502541 -357.528622) (xy 281.532025 -357.574505)
			(xy 281.55468 -357.624116) (xy 281.570044 -357.676446) (xy 281.577806 -357.73043) (xy 281.577806 -357.784969)
			(xy 283.060631 -357.784969) (xy 283.060631 -357.730431) (xy 283.068393 -357.676448) (xy 283.083758 -357.62412)
			(xy 283.106414 -357.57451) (xy 283.1359 -357.52863) (xy 283.171614 -357.487413) (xy 283.212832 -357.451698)
			(xy 283.258712 -357.422213) (xy 283.308321 -357.399557) (xy 283.36065 -357.384193) (xy 283.414633 -357.376431)
			(xy 283.441902 -357.375968) (xy 284.305502 -357.375968) (xy 284.332773 -357.376395) (xy 284.386761 -357.384157)
			(xy 284.439094 -357.399524) (xy 284.488708 -357.422182) (xy 284.534593 -357.45167) (xy 284.575813 -357.487388)
			(xy 284.611531 -357.528609) (xy 284.641019 -357.574493) (xy 284.663677 -357.624107) (xy 284.679043 -357.676441)
			(xy 284.686806 -357.730429) (xy 284.686806 -357.784966) (xy 286.169654 -357.784966) (xy 286.169654 -357.730435)
			(xy 286.177414 -357.676458) (xy 286.192777 -357.624136) (xy 286.215428 -357.574532) (xy 286.244908 -357.528657)
			(xy 286.280617 -357.487443) (xy 286.321826 -357.451731) (xy 286.367699 -357.422246) (xy 286.4173 -357.39959)
			(xy 286.469621 -357.384222) (xy 286.523597 -357.376457) (xy 286.550862 -357.375968) (xy 287.414462 -357.375968)
			(xy 287.441737 -357.376369) (xy 287.495732 -357.384127) (xy 287.548073 -357.399491) (xy 287.597695 -357.422149)
			(xy 287.643587 -357.451638) (xy 287.684815 -357.487358) (xy 287.72054 -357.528582) (xy 287.750033 -357.574471)
			(xy 287.772695 -357.624091) (xy 287.788065 -357.676431) (xy 287.795828 -357.730425) (xy 287.795828 -357.78497)
			(xy 289.278531 -357.78497) (xy 289.278531 -357.73043) (xy 289.286294 -357.676446) (xy 289.30166 -357.624115)
			(xy 289.324317 -357.574505) (xy 289.353805 -357.528623) (xy 289.389522 -357.487406) (xy 289.430741 -357.451691)
			(xy 289.476624 -357.422207) (xy 289.526236 -357.399552) (xy 289.578567 -357.384189) (xy 289.632552 -357.37643)
			(xy 289.659822 -357.375968) (xy 290.523422 -357.375968) (xy 290.550692 -357.376396) (xy 290.604678 -357.384161)
			(xy 290.657009 -357.399529) (xy 290.70662 -357.422189) (xy 290.752502 -357.451677) (xy 290.79372 -357.487395)
			(xy 290.829436 -357.528616) (xy 290.858922 -357.574499) (xy 290.881578 -357.624112) (xy 290.896944 -357.676444)
			(xy 290.904706 -357.730429) (xy 290.904706 -357.784966) (xy 292.387554 -357.784966) (xy 292.387554 -357.730434)
			(xy 292.395315 -357.676456) (xy 292.410678 -357.624132) (xy 292.433331 -357.574527) (xy 292.462813 -357.52865)
			(xy 292.498524 -357.487436) (xy 292.539736 -357.451724) (xy 292.585611 -357.42224) (xy 292.635215 -357.399584)
			(xy 292.687538 -357.384219) (xy 292.741516 -357.376456) (xy 292.768782 -357.375968) (xy 293.632382 -357.375968)
			(xy 293.659656 -357.37637) (xy 293.713649 -357.384131) (xy 293.765988 -357.399497) (xy 293.815607 -357.422155)
			(xy 293.861497 -357.451645) (xy 293.902722 -357.487365) (xy 293.938444 -357.528589) (xy 293.967936 -357.574477)
			(xy 293.990597 -357.624095) (xy 294.005965 -357.676433) (xy 294.013728 -357.730426) (xy 294.013728 -357.784971)
			(xy 295.496432 -357.784971) (xy 295.496432 -357.730429) (xy 295.504194 -357.676443) (xy 295.519561 -357.624111)
			(xy 295.54222 -357.574499) (xy 295.571709 -357.528617) (xy 295.607429 -357.487399) (xy 295.648651 -357.451684)
			(xy 295.694536 -357.4222) (xy 295.74415 -357.399547) (xy 295.796484 -357.384185) (xy 295.850471 -357.376429)
			(xy 295.877742 -357.375968) (xy 296.741342 -357.375968) (xy 296.768612 -357.376397) (xy 296.822595 -357.384165)
			(xy 296.874923 -357.399535) (xy 296.924532 -357.422195) (xy 296.970411 -357.451684) (xy 297.011627 -357.487402)
			(xy 297.047341 -357.528622) (xy 297.076825 -357.574505) (xy 297.09948 -357.624116) (xy 297.114844 -357.676446)
			(xy 297.122606 -357.73043) (xy 297.122606 -357.784969) (xy 298.605431 -357.784969) (xy 298.605431 -357.730431)
			(xy 298.613193 -357.676448) (xy 298.628558 -357.62412) (xy 298.651214 -357.57451) (xy 298.6807 -357.52863)
			(xy 298.716414 -357.487413) (xy 298.757632 -357.451698) (xy 298.803512 -357.422213) (xy 298.853121 -357.399557)
			(xy 298.90545 -357.384193) (xy 298.959433 -357.376431) (xy 298.986702 -357.375968) (xy 299.850302 -357.375968)
			(xy 299.877573 -357.376395) (xy 299.931561 -357.384157) (xy 299.983894 -357.399524) (xy 300.033508 -357.422182)
			(xy 300.079393 -357.45167) (xy 300.120613 -357.487388) (xy 300.156331 -357.528609) (xy 300.185819 -357.574493)
			(xy 300.208477 -357.624107) (xy 300.223843 -357.676441) (xy 300.231606 -357.730429) (xy 300.231606 -357.784966)
			(xy 315.230554 -357.784966) (xy 315.230554 -357.730434) (xy 315.238314 -357.676458) (xy 315.253677 -357.624136)
			(xy 315.276328 -357.574532) (xy 315.305809 -357.528656) (xy 315.341517 -357.487443) (xy 315.382727 -357.45173)
			(xy 315.4286 -357.422246) (xy 315.478202 -357.399589) (xy 315.530523 -357.384222) (xy 315.584498 -357.376457)
			(xy 315.611764 -357.375968) (xy 316.475364 -357.375968) (xy 316.502639 -357.376369) (xy 316.556634 -357.384128)
			(xy 316.608975 -357.399492) (xy 316.658597 -357.422149) (xy 316.704488 -357.451638) (xy 316.745716 -357.487359)
			(xy 316.78144 -357.528583) (xy 316.810933 -357.574472) (xy 316.833595 -357.624091) (xy 316.848965 -357.676431)
			(xy 316.856728 -357.730425) (xy 316.856728 -357.78497) (xy 318.339431 -357.78497) (xy 318.339431 -357.73043)
			(xy 318.347194 -357.676445) (xy 318.36256 -357.624115) (xy 318.385217 -357.574504) (xy 318.414705 -357.528623)
			(xy 318.450422 -357.487405) (xy 318.491642 -357.451691) (xy 318.537525 -357.422206) (xy 318.587137 -357.399552)
			(xy 318.639469 -357.384189) (xy 318.693454 -357.37643) (xy 318.720724 -357.375968) (xy 319.584324 -357.375968)
			(xy 319.611594 -357.376396) (xy 319.66558 -357.384161) (xy 319.71791 -357.39953) (xy 319.767521 -357.422189)
			(xy 319.813403 -357.451678) (xy 319.854621 -357.487396) (xy 319.890336 -357.528616) (xy 319.919822 -357.5745)
			(xy 319.942479 -357.624112) (xy 319.957844 -357.676444) (xy 319.965606 -357.73043) (xy 319.965606 -357.784967)
			(xy 321.448454 -357.784967) (xy 321.448454 -357.730434) (xy 321.456215 -357.676456) (xy 321.471578 -357.624131)
			(xy 321.494232 -357.574526) (xy 321.523714 -357.52865) (xy 321.559424 -357.487436) (xy 321.600637 -357.451723)
			(xy 321.646512 -357.422239) (xy 321.696116 -357.399584) (xy 321.74844 -357.384218) (xy 321.802418 -357.376455)
			(xy 321.829684 -357.375968) (xy 322.693284 -357.375968) (xy 322.720558 -357.37637) (xy 322.774551 -357.384131)
			(xy 322.826889 -357.399497) (xy 322.876508 -357.422156) (xy 322.922398 -357.451645) (xy 322.963623 -357.487366)
			(xy 322.999345 -357.528589) (xy 323.028836 -357.574477) (xy 323.051497 -357.624096) (xy 323.066865 -357.676434)
			(xy 323.074628 -357.730426) (xy 323.074628 -357.784971) (xy 324.557332 -357.784971) (xy 324.557332 -357.730429)
			(xy 324.565094 -357.676443) (xy 324.580461 -357.624111) (xy 324.603121 -357.574498) (xy 324.63261 -357.528616)
			(xy 324.668329 -357.487398) (xy 324.709551 -357.451684) (xy 324.755437 -357.422199) (xy 324.805052 -357.399546)
			(xy 324.857386 -357.384185) (xy 324.911373 -357.376428) (xy 324.938644 -357.375968) (xy 325.802244 -357.375968)
			(xy 325.829513 -357.376398) (xy 325.883497 -357.384165) (xy 325.935825 -357.399535) (xy 325.985433 -357.422196)
			(xy 326.031312 -357.451685) (xy 326.072528 -357.487403) (xy 326.108241 -357.528623) (xy 326.137725 -357.574505)
			(xy 326.16038 -357.624116) (xy 326.175744 -357.676447) (xy 326.183506 -357.73043) (xy 326.183506 -357.784969)
			(xy 327.666331 -357.784969) (xy 327.666331 -357.730431) (xy 327.674093 -357.676448) (xy 327.689458 -357.624119)
			(xy 327.712114 -357.57451) (xy 327.7416 -357.528629) (xy 327.777315 -357.487412) (xy 327.818533 -357.451698)
			(xy 327.864413 -357.422212) (xy 327.914023 -357.399557) (xy 327.966352 -357.384192) (xy 328.020335 -357.376431)
			(xy 328.047604 -357.375968) (xy 328.911204 -357.375968) (xy 328.938475 -357.376395) (xy 328.992463 -357.384158)
			(xy 329.044796 -357.399524) (xy 329.094409 -357.422183) (xy 329.140293 -357.451671) (xy 329.181514 -357.487389)
			(xy 329.217231 -357.52861) (xy 329.246719 -357.574494) (xy 329.269377 -357.624108) (xy 329.284743 -357.676441)
			(xy 329.292506 -357.730429) (xy 329.292506 -357.784966) (xy 330.775354 -357.784966) (xy 330.775354 -357.730434)
			(xy 330.783114 -357.676458) (xy 330.798477 -357.624136) (xy 330.821128 -357.574532) (xy 330.850609 -357.528656)
			(xy 330.886317 -357.487443) (xy 330.927527 -357.45173) (xy 330.9734 -357.422246) (xy 331.023002 -357.399589)
			(xy 331.075323 -357.384222) (xy 331.129298 -357.376457) (xy 331.156564 -357.375968) (xy 332.020164 -357.375968)
			(xy 332.047439 -357.376369) (xy 332.101434 -357.384128) (xy 332.153775 -357.399492) (xy 332.203397 -357.422149)
			(xy 332.249288 -357.451638) (xy 332.290516 -357.487359) (xy 332.32624 -357.528583) (xy 332.355733 -357.574472)
			(xy 332.378395 -357.624091) (xy 332.393765 -357.676431) (xy 332.401528 -357.730425) (xy 332.401528 -357.78497)
			(xy 333.884231 -357.78497) (xy 333.884231 -357.73043) (xy 333.891994 -357.676445) (xy 333.90736 -357.624115)
			(xy 333.930017 -357.574504) (xy 333.959505 -357.528623) (xy 333.995222 -357.487405) (xy 334.036442 -357.451691)
			(xy 334.082325 -357.422206) (xy 334.131937 -357.399552) (xy 334.184269 -357.384189) (xy 334.238254 -357.37643)
			(xy 334.265524 -357.375968) (xy 335.129124 -357.375968) (xy 335.156394 -357.376396) (xy 335.21038 -357.384161)
			(xy 335.26271 -357.39953) (xy 335.312321 -357.422189) (xy 335.358203 -357.451678) (xy 335.399421 -357.487396)
			(xy 335.435136 -357.528616) (xy 335.464622 -357.5745) (xy 335.487279 -357.624112) (xy 335.502644 -357.676444)
			(xy 335.510406 -357.73043) (xy 335.510406 -357.784967) (xy 336.993254 -357.784967) (xy 336.993254 -357.730434)
			(xy 337.001015 -357.676456) (xy 337.016378 -357.624131) (xy 337.039032 -357.574526) (xy 337.068514 -357.52865)
			(xy 337.104224 -357.487436) (xy 337.145437 -357.451723) (xy 337.191312 -357.422239) (xy 337.240916 -357.399584)
			(xy 337.29324 -357.384218) (xy 337.347218 -357.376455) (xy 337.374484 -357.375968) (xy 338.238084 -357.375968)
			(xy 338.265358 -357.37637) (xy 338.319351 -357.384131) (xy 338.371689 -357.399497) (xy 338.421308 -357.422156)
			(xy 338.467198 -357.451645) (xy 338.508423 -357.487366) (xy 338.544145 -357.528589) (xy 338.573636 -357.574477)
			(xy 338.596297 -357.624096) (xy 338.611665 -357.676434) (xy 338.619428 -357.730426) (xy 338.619428 -357.784971)
			(xy 340.102132 -357.784971) (xy 340.102132 -357.730429) (xy 340.109894 -357.676443) (xy 340.125261 -357.624111)
			(xy 340.147921 -357.574498) (xy 340.17741 -357.528616) (xy 340.213129 -357.487398) (xy 340.254351 -357.451684)
			(xy 340.300237 -357.422199) (xy 340.349852 -357.399546) (xy 340.402186 -357.384185) (xy 340.456173 -357.376428)
			(xy 340.483444 -357.375968) (xy 341.347044 -357.375968) (xy 341.374313 -357.376398) (xy 341.428297 -357.384165)
			(xy 341.480625 -357.399535) (xy 341.530233 -357.422196) (xy 341.576112 -357.451685) (xy 341.617328 -357.487403)
			(xy 341.653041 -357.528623) (xy 341.682525 -357.574505) (xy 341.70518 -357.624116) (xy 341.720544 -357.676447)
			(xy 341.728306 -357.73043) (xy 341.728306 -357.784969) (xy 343.211131 -357.784969) (xy 343.211131 -357.730431)
			(xy 343.218893 -357.676448) (xy 343.234258 -357.624119) (xy 343.256914 -357.57451) (xy 343.2864 -357.528629)
			(xy 343.322115 -357.487412) (xy 343.363333 -357.451698) (xy 343.409213 -357.422212) (xy 343.458823 -357.399557)
			(xy 343.511152 -357.384192) (xy 343.565135 -357.376431) (xy 343.592404 -357.375968) (xy 344.456004 -357.375968)
			(xy 344.483275 -357.376395) (xy 344.537263 -357.384158) (xy 344.589596 -357.399524) (xy 344.639209 -357.422183)
			(xy 344.685093 -357.451671) (xy 344.726314 -357.487389) (xy 344.762031 -357.52861) (xy 344.791519 -357.574494)
			(xy 344.814177 -357.624108) (xy 344.829543 -357.676441) (xy 344.837306 -357.730429) (xy 344.837306 -357.784971)
			(xy 373.915632 -357.784971) (xy 373.915632 -357.730429) (xy 373.923394 -357.676443) (xy 373.938761 -357.624111)
			(xy 373.96142 -357.574499) (xy 373.990909 -357.528617) (xy 374.026628 -357.4874) (xy 374.06785 -357.451685)
			(xy 374.113735 -357.422201) (xy 374.163349 -357.399547) (xy 374.215682 -357.384186) (xy 374.269669 -357.376429)
			(xy 374.29694 -357.375968) (xy 375.16054 -357.375968) (xy 375.18781 -357.376397) (xy 375.241793 -357.384164)
			(xy 375.294122 -357.399534) (xy 375.343731 -357.422194) (xy 375.389611 -357.451684) (xy 375.430827 -357.487402)
			(xy 375.46654 -357.528622) (xy 375.496025 -357.574504) (xy 375.51868 -357.624116) (xy 375.534044 -357.676446)
			(xy 375.541806 -357.73043) (xy 375.541806 -357.784967) (xy 377.024654 -357.784967) (xy 377.024654 -357.730433)
			(xy 377.032415 -357.676453) (xy 377.04778 -357.624128) (xy 377.070434 -357.574522) (xy 377.099918 -357.528644)
			(xy 377.13563 -357.48743) (xy 377.176844 -357.451718) (xy 377.222722 -357.422234) (xy 377.272328 -357.39958)
			(xy 377.324653 -357.384215) (xy 377.378633 -357.376454) (xy 377.4059 -357.375968) (xy 378.2695 -357.375968)
			(xy 378.296772 -357.376395) (xy 378.350759 -357.384157) (xy 378.403093 -357.399523) (xy 378.452707 -357.422181)
			(xy 378.498592 -357.451669) (xy 378.539812 -357.487388) (xy 378.575531 -357.528608) (xy 378.605019 -357.574493)
			(xy 378.627677 -357.624107) (xy 378.643043 -357.676441) (xy 378.650805 -357.730428) (xy 378.650805 -357.784965)
			(xy 380.133654 -357.784965) (xy 380.133654 -357.730435) (xy 380.141414 -357.676459) (xy 380.156776 -357.624137)
			(xy 380.179428 -357.574533) (xy 380.208908 -357.528658) (xy 380.244616 -357.487444) (xy 380.285825 -357.451732)
			(xy 380.331698 -357.422247) (xy 380.381299 -357.39959) (xy 380.43362 -357.384223) (xy 380.487595 -357.376457)
			(xy 380.51486 -357.375968) (xy 381.37846 -357.375968) (xy 381.405735 -357.376369) (xy 381.45973 -357.384127)
			(xy 381.512072 -357.399491) (xy 381.561694 -357.422148) (xy 381.607586 -357.451637) (xy 381.648815 -357.487357)
			(xy 381.684539 -357.528582) (xy 381.714033 -357.574471) (xy 381.736695 -357.62409) (xy 381.752065 -357.67643)
			(xy 381.759828 -357.730425) (xy 381.759828 -357.78497) (xy 383.242531 -357.78497) (xy 383.242531 -357.73043)
			(xy 383.250294 -357.676446) (xy 383.26566 -357.624116) (xy 383.288317 -357.574505) (xy 383.317804 -357.528624)
			(xy 383.353521 -357.487407) (xy 383.39474 -357.451692) (xy 383.440623 -357.422207) (xy 383.490234 -357.399553)
			(xy 383.542565 -357.384189) (xy 383.59655 -357.37643) (xy 383.62382 -357.375968) (xy 384.48742 -357.375968)
			(xy 384.514691 -357.376396) (xy 384.568676 -357.38416) (xy 384.621007 -357.399529) (xy 384.670619 -357.422188)
			(xy 384.716501 -357.451677) (xy 384.75772 -357.487395) (xy 384.793435 -357.528615) (xy 384.822922 -357.574499)
			(xy 384.845578 -357.624111) (xy 384.860944 -357.676443) (xy 384.868706 -357.730429) (xy 384.868706 -357.784966)
			(xy 386.351554 -357.784966) (xy 386.351554 -357.730434) (xy 386.359315 -357.676456) (xy 386.374678 -357.624132)
			(xy 386.397331 -357.574527) (xy 386.426813 -357.528651) (xy 386.462523 -357.487437) (xy 386.503735 -357.451725)
			(xy 386.54961 -357.422241) (xy 386.599213 -357.399585) (xy 386.651537 -357.384219) (xy 386.705514 -357.376456)
			(xy 386.73278 -357.375968) (xy 387.59638 -357.375968) (xy 387.623654 -357.37637) (xy 387.677647 -357.384131)
			(xy 387.729987 -357.399496) (xy 387.779606 -357.422155) (xy 387.825496 -357.451644) (xy 387.866722 -357.487364)
			(xy 387.902444 -357.528588) (xy 387.931936 -357.574476) (xy 387.954597 -357.624095) (xy 387.969965 -357.676433)
			(xy 387.977728 -357.730426) (xy 387.977728 -357.784971) (xy 389.460432 -357.784971) (xy 389.460432 -357.730429)
			(xy 389.468194 -357.676443) (xy 389.483561 -357.624111) (xy 389.50622 -357.574499) (xy 389.535709 -357.528617)
			(xy 389.571428 -357.4874) (xy 389.61265 -357.451685) (xy 389.658535 -357.422201) (xy 389.708149 -357.399547)
			(xy 389.760482 -357.384186) (xy 389.814469 -357.376429) (xy 389.84174 -357.375968) (xy 390.70534 -357.375968)
			(xy 390.73261 -357.376397) (xy 390.786593 -357.384164) (xy 390.838922 -357.399534) (xy 390.888531 -357.422194)
			(xy 390.934411 -357.451684) (xy 390.975627 -357.487402) (xy 391.01134 -357.528622) (xy 391.040825 -357.574504)
			(xy 391.06348 -357.624116) (xy 391.078844 -357.676446) (xy 391.086606 -357.73043) (xy 391.086606 -357.784967)
			(xy 392.569454 -357.784967) (xy 392.569454 -357.730433) (xy 392.577215 -357.676453) (xy 392.59258 -357.624128)
			(xy 392.615234 -357.574522) (xy 392.644718 -357.528644) (xy 392.68043 -357.48743) (xy 392.721644 -357.451718)
			(xy 392.767522 -357.422234) (xy 392.817128 -357.39958) (xy 392.869453 -357.384215) (xy 392.923433 -357.376454)
			(xy 392.9507 -357.375968) (xy 393.8143 -357.375968) (xy 393.841572 -357.376395) (xy 393.895559 -357.384157)
			(xy 393.947893 -357.399523) (xy 393.997507 -357.422181) (xy 394.043392 -357.451669) (xy 394.084612 -357.487388)
			(xy 394.120331 -357.528608) (xy 394.149819 -357.574493) (xy 394.172477 -357.624107) (xy 394.187843 -357.676441)
			(xy 394.195605 -357.730428) (xy 394.195605 -357.784965) (xy 395.678454 -357.784965) (xy 395.678454 -357.730435)
			(xy 395.686214 -357.676459) (xy 395.701576 -357.624137) (xy 395.724228 -357.574533) (xy 395.753708 -357.528658)
			(xy 395.789416 -357.487444) (xy 395.830625 -357.451732) (xy 395.876498 -357.422247) (xy 395.926099 -357.39959)
			(xy 395.97842 -357.384223) (xy 396.032395 -357.376457) (xy 396.05966 -357.375968) (xy 396.92326 -357.375968)
			(xy 396.950535 -357.376369) (xy 397.00453 -357.384127) (xy 397.056872 -357.399491) (xy 397.106494 -357.422148)
			(xy 397.152386 -357.451637) (xy 397.193615 -357.487357) (xy 397.229339 -357.528582) (xy 397.258833 -357.574471)
			(xy 397.281495 -357.62409) (xy 397.296865 -357.67643) (xy 397.304628 -357.730425) (xy 397.304628 -357.78497)
			(xy 398.787331 -357.78497) (xy 398.787331 -357.73043) (xy 398.795094 -357.676446) (xy 398.81046 -357.624116)
			(xy 398.833117 -357.574505) (xy 398.862604 -357.528624) (xy 398.898321 -357.487407) (xy 398.93954 -357.451692)
			(xy 398.985423 -357.422207) (xy 399.035034 -357.399553) (xy 399.087365 -357.384189) (xy 399.14135 -357.37643)
			(xy 399.16862 -357.375968) (xy 400.03222 -357.375968) (xy 400.059491 -357.376396) (xy 400.113476 -357.38416)
			(xy 400.165807 -357.399529) (xy 400.215419 -357.422188) (xy 400.261301 -357.451677) (xy 400.30252 -357.487395)
			(xy 400.338235 -357.528615) (xy 400.367722 -357.574499) (xy 400.390378 -357.624111) (xy 400.405744 -357.676443)
			(xy 400.413506 -357.730429) (xy 400.413506 -357.784966) (xy 401.896354 -357.784966) (xy 401.896354 -357.730434)
			(xy 401.904115 -357.676456) (xy 401.919478 -357.624132) (xy 401.942131 -357.574527) (xy 401.971613 -357.528651)
			(xy 402.007323 -357.487437) (xy 402.048535 -357.451725) (xy 402.09441 -357.422241) (xy 402.144013 -357.399585)
			(xy 402.196337 -357.384219) (xy 402.250314 -357.376456) (xy 402.27758 -357.375968) (xy 403.14118 -357.375968)
			(xy 403.168454 -357.37637) (xy 403.222447 -357.384131) (xy 403.274787 -357.399496) (xy 403.324406 -357.422155)
			(xy 403.370296 -357.451644) (xy 403.411522 -357.487364) (xy 403.447244 -357.528588) (xy 403.476736 -357.574476)
			(xy 403.499397 -357.624095) (xy 403.514765 -357.676433) (xy 403.522528 -357.730426) (xy 403.522528 -357.784965)
			(xy 412.022854 -357.784965) (xy 412.022854 -357.730435) (xy 412.030614 -357.67646) (xy 412.045976 -357.624138)
			(xy 412.068627 -357.574535) (xy 412.098106 -357.52866) (xy 412.133813 -357.487447) (xy 412.175022 -357.451735)
			(xy 412.220893 -357.42225) (xy 412.270493 -357.399593) (xy 412.322813 -357.384224) (xy 412.376787 -357.376458)
			(xy 412.404052 -357.375968) (xy 413.267652 -357.375968) (xy 413.294927 -357.376368) (xy 413.348924 -357.384125)
			(xy 413.401266 -357.399489) (xy 413.450889 -357.422145) (xy 413.496783 -357.451634) (xy 413.538012 -357.487354)
			(xy 413.573737 -357.528579) (xy 413.603232 -357.574468) (xy 413.625894 -357.624089) (xy 413.641264 -357.676429)
			(xy 413.649028 -357.730425) (xy 413.649028 -357.784969) (xy 415.131731 -357.784969) (xy 415.131731 -357.730431)
			(xy 415.139493 -357.676447) (xy 415.154859 -357.624117) (xy 415.177516 -357.574507) (xy 415.207002 -357.528627)
			(xy 415.242718 -357.487409) (xy 415.283936 -357.451695) (xy 415.329818 -357.42221) (xy 415.379429 -357.399555)
			(xy 415.431759 -357.384191) (xy 415.485743 -357.376431) (xy 415.513012 -357.375968) (xy 416.376612 -357.375968)
			(xy 416.403883 -357.376395) (xy 416.457869 -357.384159) (xy 416.510202 -357.399527) (xy 416.559814 -357.422185)
			(xy 416.605697 -357.451674) (xy 416.646917 -357.487392) (xy 416.682633 -357.528612) (xy 416.712121 -357.574496)
			(xy 416.734778 -357.62411) (xy 416.750144 -357.676442) (xy 416.757906 -357.730429) (xy 416.757906 -357.784966)
			(xy 418.240754 -357.784966) (xy 418.240754 -357.730434) (xy 418.248515 -357.676457) (xy 418.263877 -357.624134)
			(xy 418.28653 -357.57453) (xy 418.316011 -357.528654) (xy 418.35172 -357.48744) (xy 418.392931 -357.451727)
			(xy 418.438805 -357.422243) (xy 418.488408 -357.399587) (xy 418.54073 -357.384221) (xy 418.594706 -357.376456)
			(xy 418.621972 -357.375968) (xy 419.485572 -357.375968) (xy 419.512846 -357.37637) (xy 419.566841 -357.384129)
			(xy 419.619181 -357.399494) (xy 419.668801 -357.422152) (xy 419.714692 -357.451641) (xy 419.755919 -357.487361)
			(xy 419.791642 -357.528585) (xy 419.821135 -357.574474) (xy 419.843796 -357.624093) (xy 419.859165 -357.676432)
			(xy 419.866928 -357.730426) (xy 419.866928 -357.78497) (xy 421.349632 -357.78497) (xy 421.349632 -357.73043)
			(xy 421.357394 -357.676444) (xy 421.372761 -357.624113) (xy 421.395419 -357.574502) (xy 421.424907 -357.52862)
			(xy 421.460625 -357.487402) (xy 421.501846 -357.451688) (xy 421.54773 -357.422203) (xy 421.597343 -357.399549)
			(xy 421.649676 -357.384187) (xy 421.703662 -357.376429) (xy 421.730932 -357.375968) (xy 422.594532 -357.375968)
			(xy 422.621802 -357.376397) (xy 422.675786 -357.384163) (xy 422.728116 -357.399532) (xy 422.777726 -357.422192)
			(xy 422.823607 -357.451681) (xy 422.864824 -357.487399) (xy 422.900538 -357.528619) (xy 422.930024 -357.574502)
			(xy 422.952679 -357.624114) (xy 422.968044 -357.676445) (xy 422.975806 -357.73043) (xy 422.975806 -357.784967)
			(xy 424.458654 -357.784967) (xy 424.458654 -357.730433) (xy 424.466415 -357.676454) (xy 424.481779 -357.62413)
			(xy 424.504433 -357.574524) (xy 424.533916 -357.528647) (xy 424.569627 -357.487433) (xy 424.610841 -357.45172)
			(xy 424.656717 -357.422237) (xy 424.706322 -357.399582) (xy 424.758647 -357.384217) (xy 424.812625 -357.376455)
			(xy 424.839892 -357.375968) (xy 425.703492 -357.375968) (xy 425.730766 -357.376371) (xy 425.784757 -357.384133)
			(xy 425.837095 -357.3995) (xy 425.886713 -357.422159) (xy 425.932602 -357.451648) (xy 425.973826 -357.487368)
			(xy 426.009547 -357.528592) (xy 426.039038 -357.57448) (xy 426.061698 -357.624097) (xy 426.077065 -357.676435)
			(xy 426.084828 -357.730426) (xy 426.084828 -357.784965) (xy 427.567654 -357.784965) (xy 427.567654 -357.730435)
			(xy 427.575414 -357.67646) (xy 427.590776 -357.624138) (xy 427.613427 -357.574535) (xy 427.642906 -357.52866)
			(xy 427.678613 -357.487447) (xy 427.719822 -357.451735) (xy 427.765693 -357.42225) (xy 427.815293 -357.399593)
			(xy 427.867613 -357.384224) (xy 427.921587 -357.376458) (xy 427.948852 -357.375968) (xy 428.812452 -357.375968)
			(xy 428.839727 -357.376368) (xy 428.893724 -357.384125) (xy 428.946066 -357.399489) (xy 428.995689 -357.422145)
			(xy 429.041583 -357.451634) (xy 429.082812 -357.487354) (xy 429.118537 -357.528579) (xy 429.148032 -357.574468)
			(xy 429.170694 -357.624089) (xy 429.186064 -357.676429) (xy 429.193828 -357.730425) (xy 429.193828 -357.784969)
			(xy 430.676531 -357.784969) (xy 430.676531 -357.730431) (xy 430.684293 -357.676447) (xy 430.699659 -357.624117)
			(xy 430.722316 -357.574507) (xy 430.751802 -357.528627) (xy 430.787518 -357.487409) (xy 430.828736 -357.451695)
			(xy 430.874618 -357.42221) (xy 430.924229 -357.399555) (xy 430.976559 -357.384191) (xy 431.030543 -357.376431)
			(xy 431.057812 -357.375968) (xy 431.921412 -357.375968) (xy 431.948683 -357.376395) (xy 432.002669 -357.384159)
			(xy 432.055002 -357.399527) (xy 432.104614 -357.422185) (xy 432.150497 -357.451674) (xy 432.191717 -357.487392)
			(xy 432.227433 -357.528612) (xy 432.256921 -357.574496) (xy 432.279578 -357.62411) (xy 432.294944 -357.676442)
			(xy 432.302706 -357.730429) (xy 432.302706 -357.784966) (xy 433.785554 -357.784966) (xy 433.785554 -357.730434)
			(xy 433.793315 -357.676457) (xy 433.808677 -357.624134) (xy 433.83133 -357.57453) (xy 433.860811 -357.528654)
			(xy 433.89652 -357.48744) (xy 433.937731 -357.451727) (xy 433.983605 -357.422243) (xy 434.033208 -357.399587)
			(xy 434.08553 -357.384221) (xy 434.139506 -357.376456) (xy 434.166772 -357.375968) (xy 435.030372 -357.375968)
			(xy 435.057646 -357.37637) (xy 435.111641 -357.384129) (xy 435.163981 -357.399494) (xy 435.213601 -357.422152)
			(xy 435.259492 -357.451641) (xy 435.300719 -357.487361) (xy 435.336442 -357.528585) (xy 435.365935 -357.574474)
			(xy 435.388596 -357.624093) (xy 435.403965 -357.676432) (xy 435.411728 -357.730426) (xy 435.411728 -357.78497)
			(xy 436.894432 -357.78497) (xy 436.894432 -357.73043) (xy 436.902194 -357.676444) (xy 436.917561 -357.624113)
			(xy 436.940219 -357.574502) (xy 436.969707 -357.52862) (xy 437.005425 -357.487402) (xy 437.046646 -357.451688)
			(xy 437.09253 -357.422203) (xy 437.142143 -357.399549) (xy 437.194476 -357.384187) (xy 437.248462 -357.376429)
			(xy 437.275732 -357.375968) (xy 438.139332 -357.375968) (xy 438.166602 -357.376397) (xy 438.220586 -357.384163)
			(xy 438.272916 -357.399532) (xy 438.322526 -357.422192) (xy 438.368407 -357.451681) (xy 438.409624 -357.487399)
			(xy 438.445338 -357.528619) (xy 438.474824 -357.574502) (xy 438.497479 -357.624114) (xy 438.512844 -357.676445)
			(xy 438.520606 -357.73043) (xy 438.520606 -357.784967) (xy 440.003454 -357.784967) (xy 440.003454 -357.730433)
			(xy 440.011215 -357.676454) (xy 440.026579 -357.62413) (xy 440.049233 -357.574524) (xy 440.078716 -357.528647)
			(xy 440.114427 -357.487433) (xy 440.155641 -357.45172) (xy 440.201517 -357.422237) (xy 440.251122 -357.399582)
			(xy 440.303447 -357.384217) (xy 440.357425 -357.376455) (xy 440.384692 -357.375968) (xy 441.248292 -357.375968)
			(xy 441.275566 -357.376371) (xy 441.329557 -357.384133) (xy 441.381895 -357.3995) (xy 441.431513 -357.422159)
			(xy 441.477402 -357.451648) (xy 441.518626 -357.487368) (xy 441.554347 -357.528592) (xy 441.583838 -357.57448)
			(xy 441.606498 -357.624097) (xy 441.621865 -357.676435) (xy 441.629628 -357.730426) (xy 441.629628 -357.784974)
			(xy 441.621865 -357.838965) (xy 441.606498 -357.891303) (xy 441.583838 -357.94092) (xy 441.554347 -357.986808)
			(xy 441.518626 -358.028032) (xy 441.477402 -358.063752) (xy 441.431513 -358.093241) (xy 441.381895 -358.1159)
			(xy 441.329557 -358.131267) (xy 441.275566 -358.139029) (xy 441.248292 -358.139492) (xy 440.384692 -358.139492)
			(xy 440.357425 -358.138945) (xy 440.303447 -358.131183) (xy 440.251122 -358.115818) (xy 440.201517 -358.093163)
			(xy 440.155641 -358.06368) (xy 440.114427 -358.027967) (xy 440.078716 -357.986753) (xy 440.049233 -357.940876)
			(xy 440.026579 -357.89127) (xy 440.011215 -357.838946) (xy 440.003454 -357.784967) (xy 438.520606 -357.784967)
			(xy 438.520606 -357.78497) (xy 438.512844 -357.838955) (xy 438.497479 -357.891286) (xy 438.474824 -357.940898)
			(xy 438.445338 -357.986781) (xy 438.409624 -358.028001) (xy 438.368407 -358.063719) (xy 438.322526 -358.093208)
			(xy 438.272916 -358.115868) (xy 438.220586 -358.131237) (xy 438.166602 -358.139003) (xy 438.139332 -358.139492)
			(xy 437.275732 -358.139492) (xy 437.248462 -358.138971) (xy 437.194476 -358.131213) (xy 437.142143 -358.115851)
			(xy 437.09253 -358.093197) (xy 437.046646 -358.063712) (xy 437.005425 -358.027998) (xy 436.969707 -357.98678)
			(xy 436.940219 -357.940898) (xy 436.917561 -357.891287) (xy 436.902194 -357.838956) (xy 436.894432 -357.78497)
			(xy 435.411728 -357.78497) (xy 435.411728 -357.784974) (xy 435.403965 -357.838968) (xy 435.388596 -357.891307)
			(xy 435.365935 -357.940926) (xy 435.336442 -357.986815) (xy 435.300719 -358.028039) (xy 435.259492 -358.063759)
			(xy 435.213601 -358.093248) (xy 435.163981 -358.115906) (xy 435.111641 -358.131271) (xy 435.057646 -358.13903)
			(xy 435.030372 -358.139492) (xy 434.166772 -358.139492) (xy 434.139506 -358.138944) (xy 434.08553 -358.131179)
			(xy 434.033208 -358.115813) (xy 433.983605 -358.093157) (xy 433.937731 -358.063673) (xy 433.89652 -358.02796)
			(xy 433.860811 -357.986746) (xy 433.83133 -357.94087) (xy 433.808677 -357.891266) (xy 433.793315 -357.838943)
			(xy 433.785554 -357.784966) (xy 432.302706 -357.784966) (xy 432.302706 -357.784971) (xy 432.294944 -357.838958)
			(xy 432.279578 -357.89129) (xy 432.256921 -357.940904) (xy 432.227433 -357.986788) (xy 432.191717 -358.028008)
			(xy 432.150497 -358.063726) (xy 432.104614 -358.093215) (xy 432.055002 -358.115873) (xy 432.002669 -358.131241)
			(xy 431.948683 -358.139005) (xy 431.921412 -358.139492) (xy 431.057812 -358.139492) (xy 431.030543 -358.138969)
			(xy 430.976559 -358.131209) (xy 430.924229 -358.115845) (xy 430.874618 -358.09319) (xy 430.828736 -358.063705)
			(xy 430.787518 -358.027991) (xy 430.751802 -357.986773) (xy 430.722316 -357.940893) (xy 430.699659 -357.891283)
			(xy 430.684293 -357.838953) (xy 430.676531 -357.784969) (xy 429.193828 -357.784969) (xy 429.193828 -357.784975)
			(xy 429.186064 -357.838971) (xy 429.170694 -357.891311) (xy 429.148032 -357.940932) (xy 429.118537 -357.986821)
			(xy 429.082812 -358.028046) (xy 429.041583 -358.063766) (xy 428.995689 -358.093255) (xy 428.946066 -358.115911)
			(xy 428.893724 -358.131275) (xy 428.839727 -358.139032) (xy 428.812452 -358.139492) (xy 427.948852 -358.139492)
			(xy 427.921587 -358.138942) (xy 427.867613 -358.131176) (xy 427.815293 -358.115807) (xy 427.765693 -358.09315)
			(xy 427.719822 -358.063665) (xy 427.678613 -358.027953) (xy 427.642906 -357.98674) (xy 427.613427 -357.940865)
			(xy 427.590776 -357.891262) (xy 427.575414 -357.83894) (xy 427.567654 -357.784965) (xy 426.084828 -357.784965)
			(xy 426.084828 -357.784974) (xy 426.077065 -357.838965) (xy 426.061698 -357.891303) (xy 426.039038 -357.94092)
			(xy 426.009547 -357.986808) (xy 425.973826 -358.028032) (xy 425.932602 -358.063752) (xy 425.886713 -358.093241)
			(xy 425.837095 -358.1159) (xy 425.784757 -358.131267) (xy 425.730766 -358.139029) (xy 425.703492 -358.139492)
			(xy 424.839892 -358.139492) (xy 424.812625 -358.138945) (xy 424.758647 -358.131183) (xy 424.706322 -358.115818)
			(xy 424.656717 -358.093163) (xy 424.610841 -358.06368) (xy 424.569627 -358.027967) (xy 424.533916 -357.986753)
			(xy 424.504433 -357.940876) (xy 424.481779 -357.89127) (xy 424.466415 -357.838946) (xy 424.458654 -357.784967)
			(xy 422.975806 -357.784967) (xy 422.975806 -357.78497) (xy 422.968044 -357.838955) (xy 422.952679 -357.891286)
			(xy 422.930024 -357.940898) (xy 422.900538 -357.986781) (xy 422.864824 -358.028001) (xy 422.823607 -358.063719)
			(xy 422.777726 -358.093208) (xy 422.728116 -358.115868) (xy 422.675786 -358.131237) (xy 422.621802 -358.139003)
			(xy 422.594532 -358.139492) (xy 421.730932 -358.139492) (xy 421.703662 -358.138971) (xy 421.649676 -358.131213)
			(xy 421.597343 -358.115851) (xy 421.54773 -358.093197) (xy 421.501846 -358.063712) (xy 421.460625 -358.027998)
			(xy 421.424907 -357.98678) (xy 421.395419 -357.940898) (xy 421.372761 -357.891287) (xy 421.357394 -357.838956)
			(xy 421.349632 -357.78497) (xy 419.866928 -357.78497) (xy 419.866928 -357.784974) (xy 419.859165 -357.838968)
			(xy 419.843796 -357.891307) (xy 419.821135 -357.940926) (xy 419.791642 -357.986815) (xy 419.755919 -358.028039)
			(xy 419.714692 -358.063759) (xy 419.668801 -358.093248) (xy 419.619181 -358.115906) (xy 419.566841 -358.131271)
			(xy 419.512846 -358.13903) (xy 419.485572 -358.139492) (xy 418.621972 -358.139492) (xy 418.594706 -358.138944)
			(xy 418.54073 -358.131179) (xy 418.488408 -358.115813) (xy 418.438805 -358.093157) (xy 418.392931 -358.063673)
			(xy 418.35172 -358.02796) (xy 418.316011 -357.986746) (xy 418.28653 -357.94087) (xy 418.263877 -357.891266)
			(xy 418.248515 -357.838943) (xy 418.240754 -357.784966) (xy 416.757906 -357.784966) (xy 416.757906 -357.784971)
			(xy 416.750144 -357.838958) (xy 416.734778 -357.89129) (xy 416.712121 -357.940904) (xy 416.682633 -357.986788)
			(xy 416.646917 -358.028008) (xy 416.605697 -358.063726) (xy 416.559814 -358.093215) (xy 416.510202 -358.115873)
			(xy 416.457869 -358.131241) (xy 416.403883 -358.139005) (xy 416.376612 -358.139492) (xy 415.513012 -358.139492)
			(xy 415.485743 -358.138969) (xy 415.431759 -358.131209) (xy 415.379429 -358.115845) (xy 415.329818 -358.09319)
			(xy 415.283936 -358.063705) (xy 415.242718 -358.027991) (xy 415.207002 -357.986773) (xy 415.177516 -357.940893)
			(xy 415.154859 -357.891283) (xy 415.139493 -357.838953) (xy 415.131731 -357.784969) (xy 413.649028 -357.784969)
			(xy 413.649028 -357.784975) (xy 413.641264 -357.838971) (xy 413.625894 -357.891311) (xy 413.603232 -357.940932)
			(xy 413.573737 -357.986821) (xy 413.538012 -358.028046) (xy 413.496783 -358.063766) (xy 413.450889 -358.093255)
			(xy 413.401266 -358.115911) (xy 413.348924 -358.131275) (xy 413.294927 -358.139032) (xy 413.267652 -358.139492)
			(xy 412.404052 -358.139492) (xy 412.376787 -358.138942) (xy 412.322813 -358.131176) (xy 412.270493 -358.115807)
			(xy 412.220893 -358.09315) (xy 412.175022 -358.063665) (xy 412.133813 -358.027953) (xy 412.098106 -357.98674)
			(xy 412.068627 -357.940865) (xy 412.045976 -357.891262) (xy 412.030614 -357.83894) (xy 412.022854 -357.784965)
			(xy 403.522528 -357.784965) (xy 403.522528 -357.784974) (xy 403.514765 -357.838967) (xy 403.499397 -357.891305)
			(xy 403.476736 -357.940924) (xy 403.447244 -357.986812) (xy 403.411522 -358.028036) (xy 403.370296 -358.063756)
			(xy 403.324406 -358.093245) (xy 403.274787 -358.115904) (xy 403.222447 -358.131269) (xy 403.168454 -358.13903)
			(xy 403.14118 -358.139492) (xy 402.27758 -358.139492) (xy 402.250314 -358.138944) (xy 402.196337 -358.131181)
			(xy 402.144013 -358.115815) (xy 402.09441 -358.093159) (xy 402.048535 -358.063675) (xy 402.007323 -358.027963)
			(xy 401.971613 -357.986749) (xy 401.942131 -357.940873) (xy 401.919478 -357.891268) (xy 401.904115 -357.838944)
			(xy 401.896354 -357.784966) (xy 400.413506 -357.784966) (xy 400.413506 -357.784971) (xy 400.405744 -357.838957)
			(xy 400.390378 -357.891289) (xy 400.367722 -357.940901) (xy 400.338235 -357.986785) (xy 400.30252 -358.028005)
			(xy 400.261301 -358.063723) (xy 400.215419 -358.093212) (xy 400.165807 -358.115871) (xy 400.113476 -358.13124)
			(xy 400.059491 -358.139004) (xy 400.03222 -358.139492) (xy 399.16862 -358.139492) (xy 399.14135 -358.13897)
			(xy 399.087365 -358.131211) (xy 399.035034 -358.115847) (xy 398.985423 -358.093193) (xy 398.93954 -358.063708)
			(xy 398.898321 -358.027993) (xy 398.862604 -357.986776) (xy 398.833117 -357.940895) (xy 398.81046 -357.891284)
			(xy 398.795094 -357.838954) (xy 398.787331 -357.78497) (xy 397.304628 -357.78497) (xy 397.304628 -357.784975)
			(xy 397.296865 -357.83897) (xy 397.281495 -357.89131) (xy 397.258833 -357.940929) (xy 397.229339 -357.986818)
			(xy 397.193615 -358.028043) (xy 397.152386 -358.063763) (xy 397.106494 -358.093252) (xy 397.056872 -358.115909)
			(xy 397.00453 -358.131273) (xy 396.950535 -358.139031) (xy 396.92326 -358.139492) (xy 396.05966 -358.139492)
			(xy 396.032395 -358.138943) (xy 395.97842 -358.131177) (xy 395.926099 -358.11581) (xy 395.876498 -358.093153)
			(xy 395.830625 -358.063668) (xy 395.789416 -358.027956) (xy 395.753708 -357.986742) (xy 395.724228 -357.940867)
			(xy 395.701576 -357.891263) (xy 395.686214 -357.838941) (xy 395.678454 -357.784965) (xy 394.195605 -357.784965)
			(xy 394.195605 -357.784972) (xy 394.187843 -357.838959) (xy 394.172477 -357.891293) (xy 394.149819 -357.940907)
			(xy 394.120331 -357.986792) (xy 394.084612 -358.028012) (xy 394.043392 -358.063731) (xy 393.997507 -358.093219)
			(xy 393.947893 -358.115877) (xy 393.895559 -358.131243) (xy 393.841572 -358.139005) (xy 393.8143 -358.139492)
			(xy 392.9507 -358.139492) (xy 392.923433 -358.138946) (xy 392.869453 -358.131185) (xy 392.817128 -358.11582)
			(xy 392.767522 -358.093166) (xy 392.721644 -358.063682) (xy 392.68043 -358.02797) (xy 392.644718 -357.986756)
			(xy 392.615234 -357.940878) (xy 392.59258 -357.891272) (xy 392.577215 -357.838947) (xy 392.569454 -357.784967)
			(xy 391.086606 -357.784967) (xy 391.086606 -357.78497) (xy 391.078844 -357.838954) (xy 391.06348 -357.891284)
			(xy 391.040825 -357.940896) (xy 391.01134 -357.986778) (xy 390.975627 -358.027998) (xy 390.934411 -358.063716)
			(xy 390.888531 -358.093206) (xy 390.838922 -358.115866) (xy 390.786593 -358.131236) (xy 390.73261 -358.139003)
			(xy 390.70534 -358.139492) (xy 389.84174 -358.139492) (xy 389.814469 -358.138971) (xy 389.760482 -358.131214)
			(xy 389.708149 -358.115853) (xy 389.658535 -358.093199) (xy 389.61265 -358.063715) (xy 389.571428 -358.028)
			(xy 389.535709 -357.986783) (xy 389.50622 -357.940901) (xy 389.483561 -357.891289) (xy 389.468194 -357.838957)
			(xy 389.460432 -357.784971) (xy 387.977728 -357.784971) (xy 387.977728 -357.784974) (xy 387.969965 -357.838967)
			(xy 387.954597 -357.891305) (xy 387.931936 -357.940924) (xy 387.902444 -357.986812) (xy 387.866722 -358.028036)
			(xy 387.825496 -358.063756) (xy 387.779606 -358.093245) (xy 387.729987 -358.115904) (xy 387.677647 -358.131269)
			(xy 387.623654 -358.13903) (xy 387.59638 -358.139492) (xy 386.73278 -358.139492) (xy 386.705514 -358.138944)
			(xy 386.651537 -358.131181) (xy 386.599213 -358.115815) (xy 386.54961 -358.093159) (xy 386.503735 -358.063675)
			(xy 386.462523 -358.027963) (xy 386.426813 -357.986749) (xy 386.397331 -357.940873) (xy 386.374678 -357.891268)
			(xy 386.359315 -357.838944) (xy 386.351554 -357.784966) (xy 384.868706 -357.784966) (xy 384.868706 -357.784971)
			(xy 384.860944 -357.838957) (xy 384.845578 -357.891289) (xy 384.822922 -357.940901) (xy 384.793435 -357.986785)
			(xy 384.75772 -358.028005) (xy 384.716501 -358.063723) (xy 384.670619 -358.093212) (xy 384.621007 -358.115871)
			(xy 384.568676 -358.13124) (xy 384.514691 -358.139004) (xy 384.48742 -358.139492) (xy 383.62382 -358.139492)
			(xy 383.59655 -358.13897) (xy 383.542565 -358.131211) (xy 383.490234 -358.115847) (xy 383.440623 -358.093193)
			(xy 383.39474 -358.063708) (xy 383.353521 -358.027993) (xy 383.317804 -357.986776) (xy 383.288317 -357.940895)
			(xy 383.26566 -357.891284) (xy 383.250294 -357.838954) (xy 383.242531 -357.78497) (xy 381.759828 -357.78497)
			(xy 381.759828 -357.784975) (xy 381.752065 -357.83897) (xy 381.736695 -357.89131) (xy 381.714033 -357.940929)
			(xy 381.684539 -357.986818) (xy 381.648815 -358.028043) (xy 381.607586 -358.063763) (xy 381.561694 -358.093252)
			(xy 381.512072 -358.115909) (xy 381.45973 -358.131273) (xy 381.405735 -358.139031) (xy 381.37846 -358.139492)
			(xy 380.51486 -358.139492) (xy 380.487595 -358.138943) (xy 380.43362 -358.131177) (xy 380.381299 -358.11581)
			(xy 380.331698 -358.093153) (xy 380.285825 -358.063668) (xy 380.244616 -358.027956) (xy 380.208908 -357.986742)
			(xy 380.179428 -357.940867) (xy 380.156776 -357.891263) (xy 380.141414 -357.838941) (xy 380.133654 -357.784965)
			(xy 378.650805 -357.784965) (xy 378.650805 -357.784972) (xy 378.643043 -357.838959) (xy 378.627677 -357.891293)
			(xy 378.605019 -357.940907) (xy 378.575531 -357.986792) (xy 378.539812 -358.028012) (xy 378.498592 -358.063731)
			(xy 378.452707 -358.093219) (xy 378.403093 -358.115877) (xy 378.350759 -358.131243) (xy 378.296772 -358.139005)
			(xy 378.2695 -358.139492) (xy 377.4059 -358.139492) (xy 377.378633 -358.138946) (xy 377.324653 -358.131185)
			(xy 377.272328 -358.11582) (xy 377.222722 -358.093166) (xy 377.176844 -358.063682) (xy 377.13563 -358.02797)
			(xy 377.099918 -357.986756) (xy 377.070434 -357.940878) (xy 377.04778 -357.891272) (xy 377.032415 -357.838947)
			(xy 377.024654 -357.784967) (xy 375.541806 -357.784967) (xy 375.541806 -357.78497) (xy 375.534044 -357.838954)
			(xy 375.51868 -357.891284) (xy 375.496025 -357.940896) (xy 375.46654 -357.986778) (xy 375.430827 -358.027998)
			(xy 375.389611 -358.063716) (xy 375.343731 -358.093206) (xy 375.294122 -358.115866) (xy 375.241793 -358.131236)
			(xy 375.18781 -358.139003) (xy 375.16054 -358.139492) (xy 374.29694 -358.139492) (xy 374.269669 -358.138971)
			(xy 374.215682 -358.131214) (xy 374.163349 -358.115853) (xy 374.113735 -358.093199) (xy 374.06785 -358.063715)
			(xy 374.026628 -358.028) (xy 373.990909 -357.986783) (xy 373.96142 -357.940901) (xy 373.938761 -357.891289)
			(xy 373.923394 -357.838957) (xy 373.915632 -357.784971) (xy 344.837306 -357.784971) (xy 344.829543 -357.838959)
			(xy 344.814177 -357.891292) (xy 344.791519 -357.940906) (xy 344.762031 -357.98679) (xy 344.726314 -358.028011)
			(xy 344.685093 -358.063729) (xy 344.639209 -358.093217) (xy 344.589596 -358.115876) (xy 344.537263 -358.131242)
			(xy 344.483275 -358.139005) (xy 344.456004 -358.139492) (xy 343.592404 -358.139492) (xy 343.565135 -358.138969)
			(xy 343.511152 -358.131208) (xy 343.458823 -358.115843) (xy 343.409213 -358.093188) (xy 343.363333 -358.063702)
			(xy 343.322115 -358.027988) (xy 343.2864 -357.986771) (xy 343.256914 -357.94089) (xy 343.234258 -357.891281)
			(xy 343.218893 -357.838952) (xy 343.211131 -357.784969) (xy 341.728306 -357.784969) (xy 341.728306 -357.78497)
			(xy 341.720544 -357.838953) (xy 341.70518 -357.891284) (xy 341.682525 -357.940895) (xy 341.653041 -357.986777)
			(xy 341.617328 -358.027997) (xy 341.576112 -358.063715) (xy 341.530233 -358.093204) (xy 341.480625 -358.115865)
			(xy 341.428297 -358.131235) (xy 341.374313 -358.139002) (xy 341.347044 -358.139492) (xy 340.483444 -358.139492)
			(xy 340.456173 -358.138972) (xy 340.402186 -358.131215) (xy 340.349852 -358.115854) (xy 340.300237 -358.093201)
			(xy 340.254351 -358.063716) (xy 340.213129 -358.028002) (xy 340.17741 -357.986784) (xy 340.147921 -357.940902)
			(xy 340.125261 -357.891289) (xy 340.109894 -357.838957) (xy 340.102132 -357.784971) (xy 338.619428 -357.784971)
			(xy 338.619428 -357.784974) (xy 338.611665 -357.838966) (xy 338.596297 -357.891304) (xy 338.573636 -357.940923)
			(xy 338.544145 -357.986811) (xy 338.508423 -358.028034) (xy 338.467198 -358.063755) (xy 338.421308 -358.093244)
			(xy 338.371689 -358.115903) (xy 338.319351 -358.131269) (xy 338.265358 -358.13903) (xy 338.238084 -358.139492)
			(xy 337.374484 -358.139492) (xy 337.347218 -358.138945) (xy 337.29324 -358.131182) (xy 337.240916 -358.115816)
			(xy 337.191312 -358.093161) (xy 337.145437 -358.063677) (xy 337.104224 -358.027964) (xy 337.068514 -357.98675)
			(xy 337.039032 -357.940874) (xy 337.016378 -357.891269) (xy 337.001015 -357.838944) (xy 336.993254 -357.784967)
			(xy 335.510406 -357.784967) (xy 335.510406 -357.78497) (xy 335.502644 -357.838956) (xy 335.487279 -357.891288)
			(xy 335.464622 -357.9409) (xy 335.435136 -357.986784) (xy 335.399421 -358.028004) (xy 335.358203 -358.063722)
			(xy 335.312321 -358.093211) (xy 335.26271 -358.11587) (xy 335.21038 -358.131239) (xy 335.156394 -358.139004)
			(xy 335.129124 -358.139492) (xy 334.265524 -358.139492) (xy 334.238254 -358.13897) (xy 334.184269 -358.131211)
			(xy 334.131937 -358.115848) (xy 334.082325 -358.093194) (xy 334.036442 -358.063709) (xy 333.995222 -358.027995)
			(xy 333.959505 -357.986777) (xy 333.930017 -357.940896) (xy 333.90736 -357.891285) (xy 333.891994 -357.838955)
			(xy 333.884231 -357.78497) (xy 332.401528 -357.78497) (xy 332.401528 -357.784975) (xy 332.393765 -357.838969)
			(xy 332.378395 -357.891309) (xy 332.355733 -357.940928) (xy 332.32624 -357.986817) (xy 332.290516 -358.028041)
			(xy 332.249288 -358.063762) (xy 332.203397 -358.093251) (xy 332.153775 -358.115908) (xy 332.101434 -358.131272)
			(xy 332.047439 -358.139031) (xy 332.020164 -358.139492) (xy 331.156564 -358.139492) (xy 331.129298 -358.138943)
			(xy 331.075323 -358.131178) (xy 331.023002 -358.115811) (xy 330.9734 -358.093154) (xy 330.927527 -358.06367)
			(xy 330.886317 -358.027957) (xy 330.850609 -357.986744) (xy 330.821128 -357.940868) (xy 330.798477 -357.891264)
			(xy 330.783114 -357.838942) (xy 330.775354 -357.784966) (xy 329.292506 -357.784966) (xy 329.292506 -357.784971)
			(xy 329.284743 -357.838959) (xy 329.269377 -357.891292) (xy 329.246719 -357.940906) (xy 329.217231 -357.98679)
			(xy 329.181514 -358.028011) (xy 329.140293 -358.063729) (xy 329.094409 -358.093217) (xy 329.044796 -358.115876)
			(xy 328.992463 -358.131242) (xy 328.938475 -358.139005) (xy 328.911204 -358.139492) (xy 328.047604 -358.139492)
			(xy 328.020335 -358.138969) (xy 327.966352 -358.131208) (xy 327.914023 -358.115843) (xy 327.864413 -358.093188)
			(xy 327.818533 -358.063702) (xy 327.777315 -358.027988) (xy 327.7416 -357.986771) (xy 327.712114 -357.94089)
			(xy 327.689458 -357.891281) (xy 327.674093 -357.838952) (xy 327.666331 -357.784969) (xy 326.183506 -357.784969)
			(xy 326.183506 -357.78497) (xy 326.175744 -357.838953) (xy 326.16038 -357.891284) (xy 326.137725 -357.940895)
			(xy 326.108241 -357.986777) (xy 326.072528 -358.027997) (xy 326.031312 -358.063715) (xy 325.985433 -358.093204)
			(xy 325.935825 -358.115865) (xy 325.883497 -358.131235) (xy 325.829513 -358.139002) (xy 325.802244 -358.139492)
			(xy 324.938644 -358.139492) (xy 324.911373 -358.138972) (xy 324.857386 -358.131215) (xy 324.805052 -358.115854)
			(xy 324.755437 -358.093201) (xy 324.709551 -358.063716) (xy 324.668329 -358.028002) (xy 324.63261 -357.986784)
			(xy 324.603121 -357.940902) (xy 324.580461 -357.891289) (xy 324.565094 -357.838957) (xy 324.557332 -357.784971)
			(xy 323.074628 -357.784971) (xy 323.074628 -357.784974) (xy 323.066865 -357.838966) (xy 323.051497 -357.891304)
			(xy 323.028836 -357.940923) (xy 322.999345 -357.986811) (xy 322.963623 -358.028034) (xy 322.922398 -358.063755)
			(xy 322.876508 -358.093244) (xy 322.826889 -358.115903) (xy 322.774551 -358.131269) (xy 322.720558 -358.13903)
			(xy 322.693284 -358.139492) (xy 321.829684 -358.139492) (xy 321.802418 -358.138945) (xy 321.74844 -358.131182)
			(xy 321.696116 -358.115816) (xy 321.646512 -358.093161) (xy 321.600637 -358.063677) (xy 321.559424 -358.027964)
			(xy 321.523714 -357.98675) (xy 321.494232 -357.940874) (xy 321.471578 -357.891269) (xy 321.456215 -357.838944)
			(xy 321.448454 -357.784967) (xy 319.965606 -357.784967) (xy 319.965606 -357.78497) (xy 319.957844 -357.838956)
			(xy 319.942479 -357.891288) (xy 319.919822 -357.9409) (xy 319.890336 -357.986784) (xy 319.854621 -358.028004)
			(xy 319.813403 -358.063722) (xy 319.767521 -358.093211) (xy 319.71791 -358.11587) (xy 319.66558 -358.131239)
			(xy 319.611594 -358.139004) (xy 319.584324 -358.139492) (xy 318.720724 -358.139492) (xy 318.693454 -358.13897)
			(xy 318.639469 -358.131211) (xy 318.587137 -358.115848) (xy 318.537525 -358.093194) (xy 318.491642 -358.063709)
			(xy 318.450422 -358.027995) (xy 318.414705 -357.986777) (xy 318.385217 -357.940896) (xy 318.36256 -357.891285)
			(xy 318.347194 -357.838955) (xy 318.339431 -357.78497) (xy 316.856728 -357.78497) (xy 316.856728 -357.784975)
			(xy 316.848965 -357.838969) (xy 316.833595 -357.891309) (xy 316.810933 -357.940928) (xy 316.78144 -357.986817)
			(xy 316.745716 -358.028041) (xy 316.704488 -358.063762) (xy 316.658597 -358.093251) (xy 316.608975 -358.115908)
			(xy 316.556634 -358.131272) (xy 316.502639 -358.139031) (xy 316.475364 -358.139492) (xy 315.611764 -358.139492)
			(xy 315.584498 -358.138943) (xy 315.530523 -358.131178) (xy 315.478202 -358.115811) (xy 315.4286 -358.093154)
			(xy 315.382727 -358.06367) (xy 315.341517 -358.027957) (xy 315.305809 -357.986744) (xy 315.276328 -357.940868)
			(xy 315.253677 -357.891264) (xy 315.238314 -357.838942) (xy 315.230554 -357.784966) (xy 300.231606 -357.784966)
			(xy 300.231606 -357.784971) (xy 300.223843 -357.838959) (xy 300.208477 -357.891293) (xy 300.185819 -357.940907)
			(xy 300.156331 -357.986791) (xy 300.120613 -358.028012) (xy 300.079393 -358.06373) (xy 300.033508 -358.093218)
			(xy 299.983894 -358.115876) (xy 299.931561 -358.131243) (xy 299.877573 -358.139005) (xy 299.850302 -358.139492)
			(xy 298.986702 -358.139492) (xy 298.959433 -358.138969) (xy 298.90545 -358.131207) (xy 298.853121 -358.115843)
			(xy 298.803512 -358.093187) (xy 298.757632 -358.063702) (xy 298.716414 -358.027987) (xy 298.6807 -357.98677)
			(xy 298.651214 -357.94089) (xy 298.628558 -357.89128) (xy 298.613193 -357.838952) (xy 298.605431 -357.784969)
			(xy 297.122606 -357.784969) (xy 297.122606 -357.78497) (xy 297.114844 -357.838954) (xy 297.09948 -357.891284)
			(xy 297.076825 -357.940895) (xy 297.047341 -357.986778) (xy 297.011627 -358.027998) (xy 296.970411 -358.063716)
			(xy 296.924532 -358.093205) (xy 296.874923 -358.115865) (xy 296.822595 -358.131235) (xy 296.768612 -358.139003)
			(xy 296.741342 -358.139492) (xy 295.877742 -358.139492) (xy 295.850471 -358.138971) (xy 295.796484 -358.131215)
			(xy 295.74415 -358.115853) (xy 295.694536 -358.0932) (xy 295.64865 -358.063716) (xy 295.607429 -358.028001)
			(xy 295.571709 -357.986783) (xy 295.54222 -357.940901) (xy 295.519561 -357.891289) (xy 295.504194 -357.838957)
			(xy 295.496432 -357.784971) (xy 294.013728 -357.784971) (xy 294.013728 -357.784974) (xy 294.005965 -357.838967)
			(xy 293.990597 -357.891305) (xy 293.967936 -357.940923) (xy 293.938444 -357.986811) (xy 293.902722 -358.028035)
			(xy 293.861497 -358.063755) (xy 293.815607 -358.093245) (xy 293.765988 -358.115903) (xy 293.713649 -358.131269)
			(xy 293.659656 -358.13903) (xy 293.632382 -358.139492) (xy 292.768782 -358.139492) (xy 292.741516 -358.138944)
			(xy 292.687538 -358.131181) (xy 292.635215 -358.115816) (xy 292.585611 -358.09316) (xy 292.539736 -358.063676)
			(xy 292.498524 -358.027964) (xy 292.462813 -357.98675) (xy 292.433331 -357.940873) (xy 292.410678 -357.891268)
			(xy 292.395315 -357.838944) (xy 292.387554 -357.784966) (xy 290.904706 -357.784966) (xy 290.904706 -357.784971)
			(xy 290.896944 -357.838956) (xy 290.881578 -357.891288) (xy 290.858922 -357.940901) (xy 290.829436 -357.986784)
			(xy 290.79372 -358.028005) (xy 290.752502 -358.063723) (xy 290.70662 -358.093211) (xy 290.657009 -358.115871)
			(xy 290.604678 -358.131239) (xy 290.550692 -358.139004) (xy 290.523422 -358.139492) (xy 289.659822 -358.139492)
			(xy 289.632552 -358.13897) (xy 289.578567 -358.131211) (xy 289.526236 -358.115848) (xy 289.476624 -358.093193)
			(xy 289.430741 -358.063709) (xy 289.389522 -358.027994) (xy 289.353805 -357.986777) (xy 289.324317 -357.940895)
			(xy 289.30166 -357.891285) (xy 289.286294 -357.838954) (xy 289.278531 -357.78497) (xy 287.795828 -357.78497)
			(xy 287.795828 -357.784975) (xy 287.788065 -357.838969) (xy 287.772695 -357.891309) (xy 287.750033 -357.940929)
			(xy 287.72054 -357.986818) (xy 287.684815 -358.028042) (xy 287.643587 -358.063762) (xy 287.597695 -358.093251)
			(xy 287.548073 -358.115908) (xy 287.495732 -358.131273) (xy 287.441737 -358.139031) (xy 287.414462 -358.139492)
			(xy 286.550862 -358.139492) (xy 286.523597 -358.138943) (xy 286.469621 -358.131178) (xy 286.4173 -358.11581)
			(xy 286.367699 -358.093154) (xy 286.321826 -358.063669) (xy 286.280617 -358.027957) (xy 286.244908 -357.986743)
			(xy 286.215428 -357.940868) (xy 286.192777 -357.891264) (xy 286.177414 -357.838942) (xy 286.169654 -357.784966)
			(xy 284.686806 -357.784966) (xy 284.686806 -357.784971) (xy 284.679043 -357.838959) (xy 284.663677 -357.891293)
			(xy 284.641019 -357.940907) (xy 284.611531 -357.986791) (xy 284.575813 -358.028012) (xy 284.534593 -358.06373)
			(xy 284.488708 -358.093218) (xy 284.439094 -358.115876) (xy 284.386761 -358.131243) (xy 284.332773 -358.139005)
			(xy 284.305502 -358.139492) (xy 283.441902 -358.139492) (xy 283.414633 -358.138969) (xy 283.36065 -358.131207)
			(xy 283.308321 -358.115843) (xy 283.258712 -358.093187) (xy 283.212832 -358.063702) (xy 283.171614 -358.027987)
			(xy 283.1359 -357.98677) (xy 283.106414 -357.94089) (xy 283.083758 -357.89128) (xy 283.068393 -357.838952)
			(xy 283.060631 -357.784969) (xy 281.577806 -357.784969) (xy 281.577806 -357.78497) (xy 281.570044 -357.838954)
			(xy 281.55468 -357.891284) (xy 281.532025 -357.940895) (xy 281.502541 -357.986778) (xy 281.466827 -358.027998)
			(xy 281.425611 -358.063716) (xy 281.379732 -358.093205) (xy 281.330123 -358.115865) (xy 281.277795 -358.131235)
			(xy 281.223812 -358.139003) (xy 281.196542 -358.139492) (xy 280.332942 -358.139492) (xy 280.305671 -358.138971)
			(xy 280.251684 -358.131215) (xy 280.19935 -358.115853) (xy 280.149736 -358.0932) (xy 280.10385 -358.063716)
			(xy 280.062629 -358.028001) (xy 280.026909 -357.986783) (xy 279.99742 -357.940901) (xy 279.974761 -357.891289)
			(xy 279.959394 -357.838957) (xy 279.951632 -357.784971) (xy 278.468928 -357.784971) (xy 278.468928 -357.784974)
			(xy 278.461165 -357.838967) (xy 278.445797 -357.891305) (xy 278.423136 -357.940923) (xy 278.393644 -357.986811)
			(xy 278.357922 -358.028035) (xy 278.316697 -358.063755) (xy 278.270807 -358.093245) (xy 278.221188 -358.115903)
			(xy 278.168849 -358.131269) (xy 278.114856 -358.13903) (xy 278.087582 -358.139492) (xy 277.223982 -358.139492)
			(xy 277.196716 -358.138944) (xy 277.142738 -358.131181) (xy 277.090415 -358.115816) (xy 277.040811 -358.09316)
			(xy 276.994936 -358.063676) (xy 276.953724 -358.027964) (xy 276.918013 -357.98675) (xy 276.888531 -357.940873)
			(xy 276.865878 -357.891268) (xy 276.850515 -357.838944) (xy 276.842754 -357.784966) (xy 275.359906 -357.784966)
			(xy 275.359906 -357.784971) (xy 275.352144 -357.838956) (xy 275.336778 -357.891288) (xy 275.314122 -357.940901)
			(xy 275.284636 -357.986784) (xy 275.24892 -358.028005) (xy 275.207702 -358.063723) (xy 275.16182 -358.093211)
			(xy 275.112209 -358.115871) (xy 275.059878 -358.131239) (xy 275.005892 -358.139004) (xy 274.978622 -358.139492)
			(xy 274.115022 -358.139492) (xy 274.087752 -358.13897) (xy 274.033767 -358.131211) (xy 273.981436 -358.115848)
			(xy 273.931824 -358.093193) (xy 273.885941 -358.063709) (xy 273.844722 -358.027994) (xy 273.809005 -357.986777)
			(xy 273.779517 -357.940895) (xy 273.75686 -357.891285) (xy 273.741494 -357.838954) (xy 273.733731 -357.78497)
			(xy 272.251028 -357.78497) (xy 272.251028 -357.784975) (xy 272.243265 -357.838969) (xy 272.227895 -357.891309)
			(xy 272.205233 -357.940929) (xy 272.17574 -357.986818) (xy 272.140015 -358.028042) (xy 272.098787 -358.063762)
			(xy 272.052895 -358.093251) (xy 272.003273 -358.115908) (xy 271.950932 -358.131273) (xy 271.896937 -358.139031)
			(xy 271.869662 -358.139492) (xy 271.006062 -358.139492) (xy 270.978797 -358.138943) (xy 270.924821 -358.131178)
			(xy 270.8725 -358.11581) (xy 270.822899 -358.093154) (xy 270.777026 -358.063669) (xy 270.735817 -358.027957)
			(xy 270.700108 -357.986743) (xy 270.670628 -357.940868) (xy 270.647977 -357.891264) (xy 270.632614 -357.838942)
			(xy 270.624854 -357.784966) (xy 247.276485 -357.784966) (xy 247.278987 -357.797946) (xy 247.287038 -357.88226)
			(xy 247.287542 -357.924608) (xy 247.287038 -357.966956) (xy 247.278987 -358.05127) (xy 247.262958 -358.134436)
			(xy 247.239097 -358.215703) (xy 247.207618 -358.294333) (xy 247.168807 -358.369614) (xy 247.123017 -358.440866)
			(xy 247.070661 -358.507442) (xy 247.012213 -358.56874) (xy 246.948203 -358.624205) (xy 246.879211 -358.673334)
			(xy 246.805861 -358.715683) (xy 246.728818 -358.750867) (xy 246.648779 -358.778569) (xy 246.56647 -358.798537)
			(xy 246.482635 -358.81059) (xy 246.398034 -358.814621) (xy 246.313433 -358.81059) (xy 246.229598 -358.798537)
			(xy 246.147289 -358.778569) (xy 246.06725 -358.750867) (xy 245.990207 -358.715683) (xy 245.916857 -358.673334)
			(xy 245.847865 -358.624205) (xy 245.783855 -358.56874) (xy 245.725407 -358.507442) (xy 245.673051 -358.440866)
			(xy 245.627261 -358.369614) (xy 245.58845 -358.294333) (xy 245.556971 -358.215703) (xy 245.53311 -358.134436)
			(xy 245.517081 -358.05127) (xy 245.50903 -357.966956) (xy 188.223925 -357.966956) (xy 188.191672 -358.004178)
			(xy 188.150456 -358.039891) (xy 188.104577 -358.069375) (xy 188.054969 -358.092029) (xy 188.002641 -358.107393)
			(xy 187.94866 -358.115153) (xy 187.921392 -358.115616) (xy 187.057792 -358.115616) (xy 187.03052 -358.115221)
			(xy 186.97653 -358.107457) (xy 186.924196 -358.092089) (xy 186.87458 -358.06943) (xy 186.828695 -358.03994)
			(xy 186.787473 -358.004221) (xy 186.751755 -357.962999) (xy 186.722266 -357.917112) (xy 186.699608 -357.867497)
			(xy 186.684241 -357.815162) (xy 186.676479 -357.761172) (xy 185.193629 -357.761172) (xy 185.18587 -357.815139)
			(xy 185.170508 -357.86746) (xy 185.147857 -357.917062) (xy 185.118378 -357.962936) (xy 185.08267 -358.004147)
			(xy 185.041461 -358.039858) (xy 184.99559 -358.069342) (xy 184.94599 -358.091997) (xy 184.89367 -358.107363)
			(xy 184.839697 -358.115128) (xy 184.812432 -358.115616) (xy 183.948832 -358.115616) (xy 183.921556 -358.115247)
			(xy 183.867559 -358.107487) (xy 183.815217 -358.092122) (xy 183.765593 -358.069463) (xy 183.7197 -358.039973)
			(xy 183.678471 -358.004251) (xy 183.642746 -357.963025) (xy 183.613252 -357.917135) (xy 183.590589 -357.867513)
			(xy 183.57522 -357.815172) (xy 183.567456 -357.761176) (xy 182.084828 -357.761176) (xy 182.084828 -357.784974)
			(xy 182.077065 -357.838968) (xy 182.061696 -357.891307) (xy 182.039035 -357.940926) (xy 182.009542 -357.986815)
			(xy 181.973819 -358.028039) (xy 181.932592 -358.063759) (xy 181.886701 -358.093248) (xy 181.837081 -358.115906)
			(xy 181.784741 -358.131271) (xy 181.730746 -358.13903) (xy 181.703472 -358.139492) (xy 180.839872 -358.139492)
			(xy 180.812606 -358.138944) (xy 180.75863 -358.131179) (xy 180.706308 -358.115813) (xy 180.656705 -358.093157)
			(xy 180.610831 -358.063673) (xy 180.56962 -358.02796) (xy 180.533911 -357.986746) (xy 180.50443 -357.94087)
			(xy 180.481777 -357.891266) (xy 180.466415 -357.838943) (xy 180.458654 -357.784966) (xy 178.975806 -357.784966)
			(xy 178.975806 -357.784971) (xy 178.968044 -357.838958) (xy 178.952678 -357.89129) (xy 178.930021 -357.940904)
			(xy 178.900533 -357.986788) (xy 178.864817 -358.028008) (xy 178.823597 -358.063726) (xy 178.777714 -358.093215)
			(xy 178.728102 -358.115873) (xy 178.675769 -358.131241) (xy 178.621783 -358.139005) (xy 178.594512 -358.139492)
			(xy 177.730912 -358.139492) (xy 177.703643 -358.138969) (xy 177.649659 -358.131209) (xy 177.597329 -358.115845)
			(xy 177.547718 -358.09319) (xy 177.501836 -358.063705) (xy 177.460618 -358.027991) (xy 177.424902 -357.986773)
			(xy 177.395416 -357.940893) (xy 177.372759 -357.891283) (xy 177.357393 -357.838953) (xy 177.349631 -357.784969)
			(xy 175.866928 -357.784969) (xy 175.866928 -357.784975) (xy 175.859164 -357.838971) (xy 175.843794 -357.891311)
			(xy 175.821132 -357.940932) (xy 175.791637 -357.986821) (xy 175.755912 -358.028046) (xy 175.714683 -358.063766)
			(xy 175.668789 -358.093255) (xy 175.619166 -358.115911) (xy 175.566824 -358.131275) (xy 175.512827 -358.139032)
			(xy 175.485552 -358.139492) (xy 174.621952 -358.139492) (xy 174.594687 -358.138942) (xy 174.540713 -358.131176)
			(xy 174.488393 -358.115807) (xy 174.438793 -358.09315) (xy 174.392922 -358.063665) (xy 174.351713 -358.027953)
			(xy 174.316006 -357.98674) (xy 174.286527 -357.940865) (xy 174.263876 -357.891262) (xy 174.248514 -357.83894)
			(xy 174.240754 -357.784965) (xy 172.757928 -357.784965) (xy 172.757928 -357.784974) (xy 172.750165 -357.838965)
			(xy 172.734798 -357.891303) (xy 172.712138 -357.94092) (xy 172.682647 -357.986808) (xy 172.646926 -358.028032)
			(xy 172.605702 -358.063752) (xy 172.559813 -358.093241) (xy 172.510195 -358.1159) (xy 172.457857 -358.131267)
			(xy 172.403866 -358.139029) (xy 172.376592 -358.139492) (xy 171.512992 -358.139492) (xy 171.485725 -358.138945)
			(xy 171.431747 -358.131183) (xy 171.379422 -358.115818) (xy 171.329817 -358.093163) (xy 171.283941 -358.06368)
			(xy 171.242727 -358.027967) (xy 171.207016 -357.986753) (xy 171.177533 -357.940876) (xy 171.154879 -357.89127)
			(xy 171.139515 -357.838946) (xy 171.131754 -357.784967) (xy 169.648906 -357.784967) (xy 169.648906 -357.78497)
			(xy 169.641144 -357.838955) (xy 169.625779 -357.891286) (xy 169.603124 -357.940898) (xy 169.573638 -357.986781)
			(xy 169.537924 -358.028001) (xy 169.496707 -358.063719) (xy 169.450826 -358.093208) (xy 169.401216 -358.115868)
			(xy 169.348886 -358.131237) (xy 169.294902 -358.139003) (xy 169.267632 -358.139492) (xy 168.404032 -358.139492)
			(xy 168.376762 -358.138971) (xy 168.322776 -358.131213) (xy 168.270443 -358.115851) (xy 168.22083 -358.093197)
			(xy 168.174946 -358.063712) (xy 168.133725 -358.027998) (xy 168.098007 -357.98678) (xy 168.068519 -357.940898)
			(xy 168.045861 -357.891287) (xy 168.030494 -357.838956) (xy 168.022732 -357.78497) (xy 166.540028 -357.78497)
			(xy 166.540028 -357.784974) (xy 166.532265 -357.838968) (xy 166.516896 -357.891307) (xy 166.494235 -357.940926)
			(xy 166.464742 -357.986815) (xy 166.429019 -358.028039) (xy 166.387792 -358.063759) (xy 166.341901 -358.093248)
			(xy 166.292281 -358.115906) (xy 166.239941 -358.131271) (xy 166.185946 -358.13903) (xy 166.158672 -358.139492)
			(xy 165.295072 -358.139492) (xy 165.267806 -358.138944) (xy 165.21383 -358.131179) (xy 165.161508 -358.115813)
			(xy 165.111905 -358.093157) (xy 165.066031 -358.063673) (xy 165.02482 -358.02796) (xy 164.989111 -357.986746)
			(xy 164.95963 -357.94087) (xy 164.936977 -357.891266) (xy 164.921615 -357.838943) (xy 164.913854 -357.784966)
			(xy 163.431006 -357.784966) (xy 163.431006 -357.784971) (xy 163.423244 -357.838958) (xy 163.407878 -357.89129)
			(xy 163.385221 -357.940904) (xy 163.355733 -357.986788) (xy 163.320017 -358.028008) (xy 163.278797 -358.063726)
			(xy 163.232914 -358.093215) (xy 163.183302 -358.115873) (xy 163.130969 -358.131241) (xy 163.076983 -358.139005)
			(xy 163.049712 -358.139492) (xy 162.186112 -358.139492) (xy 162.158843 -358.138969) (xy 162.104859 -358.131209)
			(xy 162.052529 -358.115845) (xy 162.002918 -358.09319) (xy 161.957036 -358.063705) (xy 161.915818 -358.027991)
			(xy 161.880102 -357.986773) (xy 161.850616 -357.940893) (xy 161.827959 -357.891283) (xy 161.812593 -357.838953)
			(xy 161.804831 -357.784969) (xy 160.322128 -357.784969) (xy 160.322128 -357.784975) (xy 160.314364 -357.838971)
			(xy 160.298994 -357.891311) (xy 160.276332 -357.940932) (xy 160.246837 -357.986821) (xy 160.211112 -358.028046)
			(xy 160.169883 -358.063766) (xy 160.123989 -358.093255) (xy 160.074366 -358.115911) (xy 160.022024 -358.131275)
			(xy 159.968027 -358.139032) (xy 159.940752 -358.139492) (xy 159.077152 -358.139492) (xy 159.049887 -358.138942)
			(xy 158.995913 -358.131176) (xy 158.943593 -358.115807) (xy 158.893993 -358.09315) (xy 158.848122 -358.063665)
			(xy 158.806913 -358.027953) (xy 158.771206 -357.98674) (xy 158.741727 -357.940865) (xy 158.719076 -357.891262)
			(xy 158.703714 -357.83894) (xy 158.695954 -357.784965) (xy 144.196606 -357.784965) (xy 144.196606 -357.784971)
			(xy 144.188843 -357.838958) (xy 144.173477 -357.891291) (xy 144.15082 -357.940905) (xy 144.121332 -357.986789)
			(xy 144.085615 -358.02801) (xy 144.044395 -358.063728) (xy 143.998512 -358.093216) (xy 143.948899 -358.115875)
			(xy 143.896566 -358.131242) (xy 143.842579 -358.139005) (xy 143.815308 -358.139492) (xy 142.951708 -358.139492)
			(xy 142.924439 -358.138969) (xy 142.870455 -358.131209) (xy 142.818126 -358.115844) (xy 142.768515 -358.093189)
			(xy 142.722634 -358.063704) (xy 142.681417 -358.027989) (xy 142.645701 -357.986772) (xy 142.616215 -357.940892)
			(xy 142.593559 -357.891282) (xy 142.578193 -357.838953) (xy 142.570431 -357.784969) (xy 141.087606 -357.784969)
			(xy 141.079845 -357.838953) (xy 141.06448 -357.891283) (xy 141.041826 -357.940894) (xy 141.012342 -357.986776)
			(xy 140.976629 -358.027995) (xy 140.935414 -358.063713) (xy 140.889536 -358.093203) (xy 140.839928 -358.115864)
			(xy 140.7876 -358.131234) (xy 140.733617 -358.139002) (xy 140.706348 -358.139492) (xy 139.842748 -358.139492)
			(xy 139.815477 -358.138972) (xy 139.761489 -358.131216) (xy 139.709155 -358.115855) (xy 139.659539 -358.093202)
			(xy 139.613653 -358.063718) (xy 139.572431 -358.028003) (xy 139.536711 -357.986785) (xy 139.507221 -357.940903)
			(xy 139.484562 -357.89129) (xy 139.469194 -357.838958) (xy 139.461432 -357.784971) (xy 137.978728 -357.784971)
			(xy 137.978728 -357.784974) (xy 137.970965 -357.838966) (xy 137.955597 -357.891304) (xy 137.932937 -357.940921)
			(xy 137.903446 -357.986809) (xy 137.867724 -358.028033) (xy 137.8265 -358.063753) (xy 137.780611 -358.093243)
			(xy 137.730992 -358.115901) (xy 137.678654 -358.131268) (xy 137.624662 -358.139029) (xy 137.597388 -358.139492)
			(xy 136.733788 -358.139492) (xy 136.706521 -358.138945) (xy 136.652543 -358.131182) (xy 136.600219 -358.115817)
			(xy 136.550615 -358.093162) (xy 136.504739 -358.063678) (xy 136.463526 -358.027966) (xy 136.427815 -357.986752)
			(xy 136.398332 -357.940875) (xy 136.375679 -357.891269) (xy 136.360315 -357.838945) (xy 136.352554 -357.784967)
			(xy 134.869706 -357.784967) (xy 134.869706 -357.78497) (xy 134.861944 -357.838956) (xy 134.846579 -357.891287)
			(xy 134.823923 -357.940899) (xy 134.794437 -357.986782) (xy 134.758722 -358.028003) (xy 134.717505 -358.063721)
			(xy 134.671624 -358.09321) (xy 134.622013 -358.115869) (xy 134.569683 -358.131238) (xy 134.515698 -358.139004)
			(xy 134.488428 -358.139492) (xy 133.624828 -358.139492) (xy 133.597558 -358.13897) (xy 133.543572 -358.131212)
			(xy 133.49124 -358.11585) (xy 133.441627 -358.093195) (xy 133.395744 -358.063711) (xy 133.354524 -358.027996)
			(xy 133.318806 -357.986779) (xy 133.289318 -357.940897) (xy 133.26666 -357.891286) (xy 133.251294 -357.838955)
			(xy 133.243531 -357.78497) (xy 131.760828 -357.78497) (xy 131.760828 -357.784975) (xy 131.753065 -357.838969)
			(xy 131.737696 -357.891308) (xy 131.715034 -357.940927) (xy 131.685541 -357.986816) (xy 131.649817 -358.02804)
			(xy 131.60859 -358.06376) (xy 131.562699 -358.093249) (xy 131.513078 -358.115907) (xy 131.460737 -358.131272)
			(xy 131.406743 -358.139031) (xy 131.379468 -358.139492) (xy 130.515868 -358.139492) (xy 130.488602 -358.138943)
			(xy 130.434626 -358.131179) (xy 130.382305 -358.115812) (xy 130.332703 -358.093156) (xy 130.286829 -358.063671)
			(xy 130.245619 -358.027959) (xy 130.20991 -357.986745) (xy 130.180429 -357.940869) (xy 130.157777 -357.891265)
			(xy 130.142414 -357.838942) (xy 130.134654 -357.784966) (xy 128.651806 -357.784966) (xy 128.651806 -357.784971)
			(xy 128.644043 -357.838958) (xy 128.628677 -357.891291) (xy 128.60602 -357.940905) (xy 128.576532 -357.986789)
			(xy 128.540815 -358.02801) (xy 128.499595 -358.063728) (xy 128.453712 -358.093216) (xy 128.404099 -358.115875)
			(xy 128.351766 -358.131242) (xy 128.297779 -358.139005) (xy 128.270508 -358.139492) (xy 127.406908 -358.139492)
			(xy 127.379639 -358.138969) (xy 127.325655 -358.131209) (xy 127.273326 -358.115844) (xy 127.223715 -358.093189)
			(xy 127.177834 -358.063704) (xy 127.136617 -358.027989) (xy 127.100901 -357.986772) (xy 127.071415 -357.940892)
			(xy 127.048759 -357.891282) (xy 127.033393 -357.838953) (xy 127.025631 -357.784969) (xy 125.542806 -357.784969)
			(xy 125.535045 -357.838953) (xy 125.51968 -357.891283) (xy 125.497026 -357.940894) (xy 125.467542 -357.986776)
			(xy 125.431829 -358.027995) (xy 125.390614 -358.063713) (xy 125.344736 -358.093203) (xy 125.295128 -358.115864)
			(xy 125.2428 -358.131234) (xy 125.188817 -358.139002) (xy 125.161548 -358.139492) (xy 124.297948 -358.139492)
			(xy 124.270677 -358.138972) (xy 124.216689 -358.131216) (xy 124.164355 -358.115855) (xy 124.114739 -358.093202)
			(xy 124.068853 -358.063718) (xy 124.027631 -358.028003) (xy 123.991911 -357.986785) (xy 123.962421 -357.940903)
			(xy 123.939762 -357.89129) (xy 123.924394 -357.838958) (xy 123.916632 -357.784971) (xy 122.433928 -357.784971)
			(xy 122.433928 -357.784974) (xy 122.426165 -357.838966) (xy 122.410797 -357.891304) (xy 122.388137 -357.940921)
			(xy 122.358646 -357.986809) (xy 122.322924 -358.028033) (xy 122.2817 -358.063753) (xy 122.235811 -358.093243)
			(xy 122.186192 -358.115901) (xy 122.133854 -358.131268) (xy 122.079862 -358.139029) (xy 122.052588 -358.139492)
			(xy 121.188988 -358.139492) (xy 121.161721 -358.138945) (xy 121.107743 -358.131182) (xy 121.055419 -358.115817)
			(xy 121.005815 -358.093162) (xy 120.959939 -358.063678) (xy 120.918726 -358.027966) (xy 120.883015 -357.986752)
			(xy 120.853532 -357.940875) (xy 120.830879 -357.891269) (xy 120.815515 -357.838945) (xy 120.807754 -357.784967)
			(xy 119.324906 -357.784967) (xy 119.324906 -357.78497) (xy 119.317144 -357.838956) (xy 119.301779 -357.891287)
			(xy 119.279123 -357.940899) (xy 119.249637 -357.986782) (xy 119.213922 -358.028003) (xy 119.172705 -358.063721)
			(xy 119.126824 -358.09321) (xy 119.077213 -358.115869) (xy 119.024883 -358.131238) (xy 118.970898 -358.139004)
			(xy 118.943628 -358.139492) (xy 118.080028 -358.139492) (xy 118.052758 -358.13897) (xy 117.998772 -358.131212)
			(xy 117.94644 -358.11585) (xy 117.896827 -358.093195) (xy 117.850944 -358.063711) (xy 117.809724 -358.027996)
			(xy 117.774006 -357.986779) (xy 117.744518 -357.940897) (xy 117.72186 -357.891286) (xy 117.706494 -357.838955)
			(xy 117.698731 -357.78497) (xy 116.216028 -357.78497) (xy 116.216028 -357.784975) (xy 116.208265 -357.838969)
			(xy 116.192896 -357.891308) (xy 116.170234 -357.940927) (xy 116.140741 -357.986816) (xy 116.105017 -358.02804)
			(xy 116.06379 -358.06376) (xy 116.017899 -358.093249) (xy 115.968278 -358.115907) (xy 115.915937 -358.131272)
			(xy 115.861943 -358.139031) (xy 115.834668 -358.139492) (xy 114.971068 -358.139492) (xy 114.943802 -358.138943)
			(xy 114.889826 -358.131179) (xy 114.837505 -358.115812) (xy 114.787903 -358.093156) (xy 114.742029 -358.063671)
			(xy 114.700819 -358.027959) (xy 114.66511 -357.986745) (xy 114.635629 -357.940869) (xy 114.612977 -357.891265)
			(xy 114.597614 -357.838942) (xy 114.589854 -357.784966) (xy 93.706706 -357.784966) (xy 93.706706 -357.78497)
			(xy 93.698944 -357.838954) (xy 93.68358 -357.891284) (xy 93.660925 -357.940895) (xy 93.631441 -357.986778)
			(xy 93.595727 -358.027998) (xy 93.554511 -358.063716) (xy 93.508632 -358.093205) (xy 93.459023 -358.115865)
			(xy 93.406695 -358.131235) (xy 93.352712 -358.139003) (xy 93.325442 -358.139492) (xy 92.461842 -358.139492)
			(xy 92.434571 -358.138971) (xy 92.380584 -358.131215) (xy 92.32825 -358.115853) (xy 92.278636 -358.0932)
			(xy 92.23275 -358.063716) (xy 92.191529 -358.028001) (xy 92.155809 -357.986783) (xy 92.12632 -357.940901)
			(xy 92.103661 -357.891289) (xy 92.088294 -357.838957) (xy 92.080532 -357.784971) (xy 90.597828 -357.784971)
			(xy 90.597828 -357.784974) (xy 90.590065 -357.838967) (xy 90.574697 -357.891305) (xy 90.552036 -357.940923)
			(xy 90.522544 -357.986811) (xy 90.486822 -358.028035) (xy 90.445597 -358.063755) (xy 90.399707 -358.093245)
			(xy 90.350088 -358.115903) (xy 90.297749 -358.131269) (xy 90.243756 -358.13903) (xy 90.216482 -358.139492)
			(xy 89.352882 -358.139492) (xy 89.325616 -358.138944) (xy 89.271638 -358.131181) (xy 89.219315 -358.115816)
			(xy 89.169711 -358.09316) (xy 89.123836 -358.063676) (xy 89.082624 -358.027964) (xy 89.046913 -357.98675)
			(xy 89.017431 -357.940873) (xy 88.994778 -357.891268) (xy 88.979415 -357.838944) (xy 88.971654 -357.784966)
			(xy 87.488806 -357.784966) (xy 87.488806 -357.784971) (xy 87.481044 -357.838956) (xy 87.465678 -357.891288)
			(xy 87.443022 -357.940901) (xy 87.413536 -357.986784) (xy 87.37782 -358.028005) (xy 87.336602 -358.063723)
			(xy 87.29072 -358.093211) (xy 87.241109 -358.115871) (xy 87.188778 -358.131239) (xy 87.134792 -358.139004)
			(xy 87.107522 -358.139492) (xy 86.243922 -358.139492) (xy 86.216652 -358.13897) (xy 86.162667 -358.131211)
			(xy 86.110336 -358.115848) (xy 86.060724 -358.093193) (xy 86.014841 -358.063709) (xy 85.973622 -358.027994)
			(xy 85.937905 -357.986777) (xy 85.908417 -357.940895) (xy 85.88576 -357.891285) (xy 85.870394 -357.838954)
			(xy 85.862631 -357.78497) (xy 84.379928 -357.78497) (xy 84.379928 -357.784975) (xy 84.372165 -357.838969)
			(xy 84.356795 -357.891309) (xy 84.334133 -357.940929) (xy 84.30464 -357.986818) (xy 84.268915 -358.028042)
			(xy 84.227687 -358.063762) (xy 84.181795 -358.093251) (xy 84.132173 -358.115908) (xy 84.079832 -358.131273)
			(xy 84.025837 -358.139031) (xy 83.998562 -358.139492) (xy 83.134962 -358.139492) (xy 83.107697 -358.138943)
			(xy 83.053721 -358.131178) (xy 83.0014 -358.11581) (xy 82.951799 -358.093154) (xy 82.905926 -358.063669)
			(xy 82.864717 -358.027957) (xy 82.829008 -357.986743) (xy 82.799528 -357.940868) (xy 82.776877 -357.891264)
			(xy 82.761514 -357.838942) (xy 82.753754 -357.784966) (xy 81.270906 -357.784966) (xy 81.270906 -357.784971)
			(xy 81.263143 -357.838959) (xy 81.247777 -357.891293) (xy 81.225119 -357.940907) (xy 81.195631 -357.986791)
			(xy 81.159913 -358.028012) (xy 81.118693 -358.06373) (xy 81.072808 -358.093218) (xy 81.023194 -358.115876)
			(xy 80.970861 -358.131243) (xy 80.916873 -358.139005) (xy 80.889602 -358.139492) (xy 80.026002 -358.139492)
			(xy 79.998733 -358.138969) (xy 79.94475 -358.131207) (xy 79.892421 -358.115843) (xy 79.842812 -358.093187)
			(xy 79.796932 -358.063702) (xy 79.755714 -358.027987) (xy 79.72 -357.98677) (xy 79.690514 -357.94089)
			(xy 79.667858 -357.89128) (xy 79.652493 -357.838952) (xy 79.644731 -357.784969) (xy 78.161906 -357.784969)
			(xy 78.161906 -357.78497) (xy 78.154144 -357.838954) (xy 78.13878 -357.891284) (xy 78.116125 -357.940895)
			(xy 78.086641 -357.986778) (xy 78.050927 -358.027998) (xy 78.009711 -358.063716) (xy 77.963832 -358.093205)
			(xy 77.914223 -358.115865) (xy 77.861895 -358.131235) (xy 77.807912 -358.139003) (xy 77.780642 -358.139492)
			(xy 76.917042 -358.139492) (xy 76.889771 -358.138971) (xy 76.835784 -358.131215) (xy 76.78345 -358.115853)
			(xy 76.733836 -358.0932) (xy 76.68795 -358.063716) (xy 76.646729 -358.028001) (xy 76.611009 -357.986783)
			(xy 76.58152 -357.940901) (xy 76.558861 -357.891289) (xy 76.543494 -357.838957) (xy 76.535732 -357.784971)
			(xy 75.053028 -357.784971) (xy 75.053028 -357.784974) (xy 75.045265 -357.838967) (xy 75.029897 -357.891305)
			(xy 75.007236 -357.940923) (xy 74.977744 -357.986811) (xy 74.942022 -358.028035) (xy 74.900797 -358.063755)
			(xy 74.854907 -358.093245) (xy 74.805288 -358.115903) (xy 74.752949 -358.131269) (xy 74.698956 -358.13903)
			(xy 74.671682 -358.139492) (xy 73.808082 -358.139492) (xy 73.780816 -358.138944) (xy 73.726838 -358.131181)
			(xy 73.674515 -358.115816) (xy 73.624911 -358.09316) (xy 73.579036 -358.063676) (xy 73.537824 -358.027964)
			(xy 73.502113 -357.98675) (xy 73.472631 -357.940873) (xy 73.449978 -357.891268) (xy 73.434615 -357.838944)
			(xy 73.426854 -357.784966) (xy 71.944006 -357.784966) (xy 71.944006 -357.784971) (xy 71.936244 -357.838956)
			(xy 71.920878 -357.891288) (xy 71.898222 -357.940901) (xy 71.868736 -357.986784) (xy 71.83302 -358.028005)
			(xy 71.791802 -358.063723) (xy 71.74592 -358.093211) (xy 71.696309 -358.115871) (xy 71.643978 -358.131239)
			(xy 71.589992 -358.139004) (xy 71.562722 -358.139492) (xy 70.699122 -358.139492) (xy 70.671852 -358.13897)
			(xy 70.617867 -358.131211) (xy 70.565536 -358.115848) (xy 70.515924 -358.093193) (xy 70.470041 -358.063709)
			(xy 70.428822 -358.027994) (xy 70.393105 -357.986777) (xy 70.363617 -357.940895) (xy 70.34096 -357.891285)
			(xy 70.325594 -357.838954) (xy 70.317831 -357.78497) (xy 68.835128 -357.78497) (xy 68.835128 -357.784975)
			(xy 68.827365 -357.838969) (xy 68.811995 -357.891309) (xy 68.789333 -357.940929) (xy 68.75984 -357.986818)
			(xy 68.724115 -358.028042) (xy 68.682887 -358.063762) (xy 68.636995 -358.093251) (xy 68.587373 -358.115908)
			(xy 68.535032 -358.131273) (xy 68.481037 -358.139031) (xy 68.453762 -358.139492) (xy 67.590162 -358.139492)
			(xy 67.562897 -358.138943) (xy 67.508921 -358.131178) (xy 67.4566 -358.11581) (xy 67.406999 -358.093154)
			(xy 67.361126 -358.063669) (xy 67.319917 -358.027957) (xy 67.284208 -357.986743) (xy 67.254728 -357.940868)
			(xy 67.232077 -357.891264) (xy 67.216714 -357.838942) (xy 67.208954 -357.784966) (xy 65.726106 -357.784966)
			(xy 65.726106 -357.784971) (xy 65.718343 -357.838959) (xy 65.702977 -357.891293) (xy 65.680319 -357.940907)
			(xy 65.650831 -357.986791) (xy 65.615113 -358.028012) (xy 65.573893 -358.06373) (xy 65.528008 -358.093218)
			(xy 65.478394 -358.115876) (xy 65.426061 -358.131243) (xy 65.372073 -358.139005) (xy 65.344802 -358.139492)
			(xy 64.481202 -358.139492) (xy 64.453933 -358.138969) (xy 64.39995 -358.131207) (xy 64.347621 -358.115843)
			(xy 64.298012 -358.093187) (xy 64.252132 -358.063702) (xy 64.210914 -358.027987) (xy 64.1752 -357.98677)
			(xy 64.145714 -357.94089) (xy 64.123058 -357.89128) (xy 64.107693 -357.838952) (xy 64.099931 -357.784969)
			(xy 51.666906 -357.784969) (xy 51.659145 -357.838953) (xy 51.64378 -357.891283) (xy 51.621126 -357.940894)
			(xy 51.591642 -357.986776) (xy 51.555929 -358.027995) (xy 51.514714 -358.063713) (xy 51.468836 -358.093203)
			(xy 51.419228 -358.115864) (xy 51.3669 -358.131234) (xy 51.312917 -358.139002) (xy 51.285648 -358.139492)
			(xy 50.422048 -358.139492) (xy 50.394777 -358.138972) (xy 50.340789 -358.131216) (xy 50.288455 -358.115855)
			(xy 50.238839 -358.093202) (xy 50.192953 -358.063718) (xy 50.151731 -358.028003) (xy 50.116011 -357.986785)
			(xy 50.086521 -357.940903) (xy 50.063862 -357.89129) (xy 50.048494 -357.838958) (xy 50.040732 -357.784971)
			(xy 48.558028 -357.784971) (xy 48.558028 -357.784974) (xy 48.550265 -357.838966) (xy 48.534897 -357.891304)
			(xy 48.512237 -357.940921) (xy 48.482746 -357.986809) (xy 48.447024 -358.028033) (xy 48.4058 -358.063753)
			(xy 48.359911 -358.093243) (xy 48.310292 -358.115901) (xy 48.257954 -358.131268) (xy 48.203962 -358.139029)
			(xy 48.176688 -358.139492) (xy 47.313088 -358.139492) (xy 47.285821 -358.138945) (xy 47.231843 -358.131182)
			(xy 47.179519 -358.115817) (xy 47.129915 -358.093162) (xy 47.084039 -358.063678) (xy 47.042826 -358.027966)
			(xy 47.007115 -357.986752) (xy 46.977632 -357.940875) (xy 46.954979 -357.891269) (xy 46.939615 -357.838945)
			(xy 46.931854 -357.784967) (xy 45.449006 -357.784967) (xy 45.449006 -357.78497) (xy 45.441244 -357.838956)
			(xy 45.425879 -357.891287) (xy 45.403223 -357.940899) (xy 45.373737 -357.986782) (xy 45.338022 -358.028003)
			(xy 45.296805 -358.063721) (xy 45.250924 -358.09321) (xy 45.201313 -358.115869) (xy 45.148983 -358.131238)
			(xy 45.094998 -358.139004) (xy 45.067728 -358.139492) (xy 44.204128 -358.139492) (xy 44.176858 -358.13897)
			(xy 44.122872 -358.131212) (xy 44.07054 -358.11585) (xy 44.020927 -358.093195) (xy 43.975044 -358.063711)
			(xy 43.933824 -358.027996) (xy 43.898106 -357.986779) (xy 43.868618 -357.940897) (xy 43.84596 -357.891286)
			(xy 43.830594 -357.838955) (xy 43.822831 -357.78497) (xy 42.340128 -357.78497) (xy 42.340128 -357.784975)
			(xy 42.332365 -357.838969) (xy 42.316996 -357.891308) (xy 42.294334 -357.940927) (xy 42.264841 -357.986816)
			(xy 42.229117 -358.02804) (xy 42.18789 -358.06376) (xy 42.141999 -358.093249) (xy 42.092378 -358.115907)
			(xy 42.040037 -358.131272) (xy 41.986043 -358.139031) (xy 41.958768 -358.139492) (xy 41.095168 -358.139492)
			(xy 41.067902 -358.138943) (xy 41.013926 -358.131179) (xy 40.961605 -358.115812) (xy 40.912003 -358.093156)
			(xy 40.866129 -358.063671) (xy 40.824919 -358.027959) (xy 40.78921 -357.986745) (xy 40.759729 -357.940869)
			(xy 40.737077 -357.891265) (xy 40.721714 -357.838942) (xy 40.713954 -357.784966) (xy 39.231106 -357.784966)
			(xy 39.231106 -357.784971) (xy 39.223343 -357.838958) (xy 39.207977 -357.891291) (xy 39.18532 -357.940905)
			(xy 39.155832 -357.986789) (xy 39.120115 -358.02801) (xy 39.078895 -358.063728) (xy 39.033012 -358.093216)
			(xy 38.983399 -358.115875) (xy 38.931066 -358.131242) (xy 38.877079 -358.139005) (xy 38.849808 -358.139492)
			(xy 37.986208 -358.139492) (xy 37.958939 -358.138969) (xy 37.904955 -358.131209) (xy 37.852626 -358.115844)
			(xy 37.803015 -358.093189) (xy 37.757134 -358.063704) (xy 37.715917 -358.027989) (xy 37.680201 -357.986772)
			(xy 37.650715 -357.940892) (xy 37.628059 -357.891282) (xy 37.612693 -357.838953) (xy 37.604931 -357.784969)
			(xy 36.122106 -357.784969) (xy 36.114345 -357.838953) (xy 36.09898 -357.891283) (xy 36.076326 -357.940894)
			(xy 36.046842 -357.986776) (xy 36.011129 -358.027995) (xy 35.969914 -358.063713) (xy 35.924036 -358.093203)
			(xy 35.874428 -358.115864) (xy 35.8221 -358.131234) (xy 35.768117 -358.139002) (xy 35.740848 -358.139492)
			(xy 34.877248 -358.139492) (xy 34.849977 -358.138972) (xy 34.795989 -358.131216) (xy 34.743655 -358.115855)
			(xy 34.694039 -358.093202) (xy 34.648153 -358.063718) (xy 34.606931 -358.028003) (xy 34.571211 -357.986785)
			(xy 34.541721 -357.940903) (xy 34.519062 -357.89129) (xy 34.503694 -357.838958) (xy 34.495932 -357.784971)
			(xy 33.013228 -357.784971) (xy 33.013228 -357.784974) (xy 33.005465 -357.838966) (xy 32.990097 -357.891304)
			(xy 32.967437 -357.940921) (xy 32.937946 -357.986809) (xy 32.902224 -358.028033) (xy 32.861 -358.063753)
			(xy 32.815111 -358.093243) (xy 32.765492 -358.115901) (xy 32.713154 -358.131268) (xy 32.659162 -358.139029)
			(xy 32.631888 -358.139492) (xy 31.768288 -358.139492) (xy 31.741021 -358.138945) (xy 31.687043 -358.131182)
			(xy 31.634719 -358.115817) (xy 31.585115 -358.093162) (xy 31.539239 -358.063678) (xy 31.498026 -358.027966)
			(xy 31.462315 -357.986752) (xy 31.432832 -357.940875) (xy 31.410179 -357.891269) (xy 31.394815 -357.838945)
			(xy 31.387054 -357.784967) (xy 29.904206 -357.784967) (xy 29.904206 -357.78497) (xy 29.896444 -357.838956)
			(xy 29.881079 -357.891287) (xy 29.858423 -357.940899) (xy 29.828937 -357.986782) (xy 29.793222 -358.028003)
			(xy 29.752005 -358.063721) (xy 29.706124 -358.09321) (xy 29.656513 -358.115869) (xy 29.604183 -358.131238)
			(xy 29.550198 -358.139004) (xy 29.522928 -358.139492) (xy 28.659328 -358.139492) (xy 28.632058 -358.13897)
			(xy 28.578072 -358.131212) (xy 28.52574 -358.11585) (xy 28.476127 -358.093195) (xy 28.430244 -358.063711)
			(xy 28.389024 -358.027996) (xy 28.353306 -357.986779) (xy 28.323818 -357.940897) (xy 28.30116 -357.891286)
			(xy 28.285794 -357.838955) (xy 28.278031 -357.78497) (xy 26.795328 -357.78497) (xy 26.795328 -357.784975)
			(xy 26.787565 -357.838969) (xy 26.772196 -357.891308) (xy 26.749534 -357.940927) (xy 26.720041 -357.986816)
			(xy 26.684317 -358.02804) (xy 26.64309 -358.06376) (xy 26.597199 -358.093249) (xy 26.547578 -358.115907)
			(xy 26.495237 -358.131272) (xy 26.441243 -358.139031) (xy 26.413968 -358.139492) (xy 25.550368 -358.139492)
			(xy 25.523102 -358.138943) (xy 25.469126 -358.131179) (xy 25.416805 -358.115812) (xy 25.367203 -358.093156)
			(xy 25.321329 -358.063671) (xy 25.280119 -358.027959) (xy 25.24441 -357.986745) (xy 25.214929 -357.940869)
			(xy 25.192277 -357.891265) (xy 25.176914 -357.838942) (xy 25.169154 -357.784966) (xy 23.686306 -357.784966)
			(xy 23.686306 -357.784971) (xy 23.678543 -357.838958) (xy 23.663177 -357.891291) (xy 23.64052 -357.940905)
			(xy 23.611032 -357.986789) (xy 23.575315 -358.02801) (xy 23.534095 -358.063728) (xy 23.488212 -358.093216)
			(xy 23.438599 -358.115875) (xy 23.386266 -358.131242) (xy 23.332279 -358.139005) (xy 23.305008 -358.139492)
			(xy 22.441408 -358.139492) (xy 22.414139 -358.138969) (xy 22.360155 -358.131209) (xy 22.307826 -358.115844)
			(xy 22.258215 -358.093189) (xy 22.212334 -358.063704) (xy 22.171117 -358.027989) (xy 22.135401 -357.986772)
			(xy 22.105915 -357.940892) (xy 22.083259 -357.891282) (xy 22.067893 -357.838953) (xy 22.060131 -357.784969)
			(xy 1.524 -357.784969) (xy 1.524 -360.017783) (xy 101.774757 -360.017783) (xy 101.774757 -359.957817)
			(xy 101.782584 -359.898365) (xy 101.798104 -359.840443) (xy 101.821052 -359.785042) (xy 101.851035 -359.733111)
			(xy 101.88754 -359.685538) (xy 101.929942 -359.643136) (xy 101.977516 -359.606632) (xy 102.029448 -359.57665)
			(xy 102.084849 -359.553703) (xy 102.142771 -359.538183) (xy 102.202223 -359.530357) (xy 102.232206 -359.529888)
			(xy 103.095806 -359.529888) (xy 103.125793 -359.530279) (xy 103.185255 -359.538108) (xy 103.243186 -359.553631)
			(xy 103.298595 -359.576583) (xy 103.350534 -359.60657) (xy 103.398115 -359.643081) (xy 103.440523 -359.68549)
			(xy 103.477033 -359.733071) (xy 103.50702 -359.785011) (xy 103.529971 -359.84042) (xy 103.545494 -359.898351)
			(xy 103.553322 -359.957813) (xy 103.553322 -360.017787) (xy 103.545494 -360.077249) (xy 103.529971 -360.13518)
			(xy 103.50702 -360.190589) (xy 103.477033 -360.242529) (xy 103.440523 -360.29011) (xy 103.398115 -360.332519)
			(xy 103.350534 -360.36903) (xy 103.298595 -360.399017) (xy 103.243186 -360.421969) (xy 103.185255 -360.437492)
			(xy 103.125793 -360.445321) (xy 103.095806 -360.445812) (xy 102.232206 -360.445812) (xy 102.202223 -360.445243)
			(xy 102.142771 -360.437417) (xy 102.084849 -360.421897) (xy 102.029448 -360.39895) (xy 101.977516 -360.368968)
			(xy 101.929942 -360.332464) (xy 101.88754 -360.290062) (xy 101.851035 -360.242489) (xy 101.821052 -360.190558)
			(xy 101.798104 -360.135157) (xy 101.782584 -360.077235) (xy 101.774757 -360.017783) (xy 1.524 -360.017783)
			(xy 1.524 -363.334808) (xy 54.890416 -363.334808) (xy 54.890416 -362.471208) (xy 54.890906 -362.441224)
			(xy 54.898734 -362.381768) (xy 54.914255 -362.323843) (xy 54.937204 -362.268439) (xy 54.967188 -362.216505)
			(xy 55.003694 -362.168929) (xy 55.046099 -362.126524) (xy 55.093675 -362.090018) (xy 55.145609 -362.060034)
			(xy 55.201013 -362.037085) (xy 55.258938 -362.021564) (xy 55.318394 -362.013736) (xy 55.378362 -362.013736)
			(xy 55.437818 -362.021564) (xy 55.495743 -362.037085) (xy 55.551147 -362.060034) (xy 55.603081 -362.090018)
			(xy 55.650657 -362.126524) (xy 55.693062 -362.168929) (xy 55.729568 -362.216505) (xy 55.759552 -362.268439)
			(xy 55.782501 -362.323843) (xy 55.798022 -362.381768) (xy 55.80585 -362.441224) (xy 55.80634 -362.471208)
			(xy 55.80634 -363.334808) (xy 55.80585 -363.364792) (xy 55.798022 -363.424248) (xy 55.782501 -363.482173)
			(xy 55.759552 -363.537577) (xy 55.729568 -363.589511) (xy 55.693062 -363.637087) (xy 55.650657 -363.679492)
			(xy 55.603081 -363.715998) (xy 55.551147 -363.745982) (xy 55.495743 -363.768931) (xy 55.437818 -363.784452)
			(xy 55.378362 -363.79228) (xy 55.318394 -363.79228) (xy 55.258938 -363.784452) (xy 55.201013 -363.768931)
			(xy 55.145609 -363.745982) (xy 55.093675 -363.715998) (xy 55.046099 -363.679492) (xy 55.003694 -363.637087)
			(xy 54.967188 -363.589511) (xy 54.937204 -363.537577) (xy 54.914255 -363.482173) (xy 54.898734 -363.424248)
			(xy 54.890906 -363.364792) (xy 54.890416 -363.334808) (xy 1.524 -363.334808) (xy 1.524 -365.797384)
			(xy 54.438294 -365.797384) (xy 54.438294 -365.737416) (xy 54.446121 -365.67796) (xy 54.461641 -365.620034)
			(xy 54.484589 -365.564629) (xy 54.514571 -365.512694) (xy 54.551076 -365.465115) (xy 54.593478 -365.422709)
			(xy 54.641052 -365.386199) (xy 54.692984 -365.356211) (xy 54.748387 -365.333257) (xy 54.806311 -365.317731)
			(xy 54.865766 -365.309897) (xy 54.89575 -365.309404) (xy 55.75935 -365.309404) (xy 55.789336 -365.309938)
			(xy 55.848794 -365.31776) (xy 55.906723 -365.333276) (xy 55.962131 -365.356222) (xy 56.01407 -365.386203)
			(xy 56.06165 -365.422708) (xy 56.104059 -365.465112) (xy 56.140569 -365.512689) (xy 56.170556 -365.564624)
			(xy 56.193508 -365.620029) (xy 56.20903 -365.677957) (xy 56.216859 -365.737414) (xy 56.216859 -365.797386)
			(xy 56.20903 -365.856843) (xy 56.193508 -365.914771) (xy 56.170556 -365.970176) (xy 56.140569 -366.022112)
			(xy 56.104059 -366.069688) (xy 56.06165 -366.112092) (xy 56.01407 -366.148597) (xy 55.962131 -366.178578)
			(xy 55.906723 -366.201524) (xy 55.848794 -366.21704) (xy 55.789336 -366.224862) (xy 55.75935 -366.225328)
			(xy 54.89575 -366.225328) (xy 54.865766 -366.224903) (xy 54.806311 -366.217069) (xy 54.748386 -366.201543)
			(xy 54.692984 -366.178589) (xy 54.641052 -366.148601) (xy 54.593478 -366.112091) (xy 54.551076 -366.069685)
			(xy 54.514571 -366.022106) (xy 54.484589 -365.970171) (xy 54.461641 -365.914766) (xy 54.446121 -365.85684)
			(xy 54.438294 -365.797384) (xy 1.524 -365.797384) (xy 1.524 -367.89868) (xy 1.524416 -367.908704)
			(xy 1.532082 -367.927228) (xy 1.546255 -367.941406) (xy 1.564776 -367.94908) (xy 1.5748 -367.94948)
			(xy 5.720842 -367.94948) (xy 5.7531 -367.937796) (xy 5.775978 -367.919717) (xy 5.82614 -367.889994)
			(xy 5.880243 -367.868254) (xy 5.937025 -367.855004) (xy 5.995162 -367.850553) (xy 6.053299 -367.855004)
			(xy 6.110081 -367.868254) (xy 6.164184 -367.889994) (xy 6.214346 -367.919717) (xy 6.237224 -367.937796)
			(xy 6.269482 -367.94948) (xy 53.915564 -367.94948) (xy 53.925589 -367.949066) (xy 53.944114 -367.941402)
			(xy 53.958293 -367.927228) (xy 53.965963 -367.908704) (xy 53.966364 -367.89868) (xy 53.966364 -367.653062)
			(xy 53.96685 -367.625793) (xy 53.974612 -367.571809) (xy 53.989977 -367.519479) (xy 54.012634 -367.469869)
			(xy 54.04212 -367.423988) (xy 54.077835 -367.382771) (xy 54.119052 -367.347056) (xy 54.164933 -367.31757)
			(xy 54.214543 -367.294913) (xy 54.266873 -367.279548) (xy 54.320857 -367.271786) (xy 54.375395 -367.271786)
			(xy 54.429379 -367.279548) (xy 54.481709 -367.294913) (xy 54.531319 -367.31757) (xy 54.5772 -367.347056)
			(xy 54.618417 -367.382771) (xy 54.654132 -367.423988) (xy 54.683618 -367.469869) (xy 54.706275 -367.519479)
			(xy 54.72164 -367.571809) (xy 54.729402 -367.625793) (xy 54.729888 -367.653062) (xy 54.729888 -367.89868)
			(xy 54.730304 -367.908705) (xy 54.73797 -367.927231) (xy 54.752142 -367.941412) (xy 54.770663 -367.94909)
			(xy 54.780688 -367.94948) (xy 57.288684 -367.94948) (xy 57.298706 -367.949063) (xy 57.317225 -367.941395)
			(xy 57.331397 -367.927221) (xy 57.339063 -367.908702) (xy 57.339484 -367.89868) (xy 57.339484 -367.653062)
			(xy 57.33997 -367.625793) (xy 57.347732 -367.571809) (xy 57.363097 -367.519479) (xy 57.385754 -367.469869)
			(xy 57.41524 -367.423988) (xy 57.450955 -367.382771) (xy 57.492172 -367.347056) (xy 57.538053 -367.31757)
			(xy 57.587663 -367.294913) (xy 57.639993 -367.279548) (xy 57.693977 -367.271786) (xy 57.748515 -367.271786)
			(xy 57.802499 -367.279548) (xy 57.854829 -367.294913) (xy 57.904439 -367.31757) (xy 57.95032 -367.347056)
			(xy 57.991537 -367.382771) (xy 58.027252 -367.423988) (xy 58.056738 -367.469869) (xy 58.079395 -367.519479)
			(xy 58.09476 -367.571809) (xy 58.102522 -367.625793) (xy 58.103008 -367.653062) (xy 58.103008 -367.89868)
			(xy 58.103424 -367.908703) (xy 58.111091 -367.927226) (xy 58.125264 -367.941402) (xy 58.143785 -367.949074)
			(xy 58.153808 -367.94948) (xy 100.418392 -367.94948) (xy 100.426774 -367.946432) (xy 100.457938 -367.935988)
			(xy 100.522691 -367.924755) (xy 100.555552 -367.92408) (xy 100.58841 -367.924772) (xy 100.653157 -367.936019)
			(xy 100.68433 -367.946432) (xy 100.692712 -367.94948) (xy 103.35514 -367.94948) (xy 103.386636 -367.938304)
			(xy 103.40928 -367.920932) (xy 103.458706 -367.892403) (xy 103.511831 -367.871556) (xy 103.56747 -367.85886)
			(xy 103.62438 -367.854596) (xy 103.68129 -367.85886) (xy 103.736929 -367.871556) (xy 103.790054 -367.892403)
			(xy 103.83948 -367.920932) (xy 103.862124 -367.938304) (xy 103.89362 -367.94948) (xy 202.57135 -367.94948)
			(xy 202.580783 -367.948986) (xy 202.598343 -367.94207) (xy 202.612234 -367.929294) (xy 202.616816 -367.921032)
			(xy 202.616816 -367.920778) (xy 202.628817 -367.896844) (xy 202.658526 -367.852301) (xy 202.694175 -367.812353)
			(xy 202.735062 -367.777786) (xy 202.780383 -367.749279) (xy 202.829247 -367.727393) (xy 202.880693 -367.712558)
			(xy 202.933707 -367.705068) (xy 202.987249 -367.705068) (xy 203.040263 -367.712558) (xy 203.091709 -367.727393)
			(xy 203.140573 -367.749279) (xy 203.185894 -367.777786) (xy 203.226781 -367.812353) (xy 203.26243 -367.852301)
			(xy 203.292139 -367.896844) (xy 203.30414 -367.920778) (xy 203.30414 -367.921032) (xy 203.308629 -367.929365)
			(xy 203.322531 -367.94219) (xy 203.340149 -367.949074) (xy 203.349606 -367.94948) (xy 203.58735 -367.94948)
			(xy 203.596783 -367.948986) (xy 203.614343 -367.94207) (xy 203.628234 -367.929294) (xy 203.632816 -367.921032)
			(xy 203.632816 -367.920778) (xy 203.644817 -367.896844) (xy 203.674527 -367.852302) (xy 203.710177 -367.812354)
			(xy 203.751064 -367.777786) (xy 203.796385 -367.749279) (xy 203.845248 -367.727391) (xy 203.896693 -367.712555)
			(xy 203.949707 -367.705062) (xy 203.976478 -367.704624) (xy 203.985876 -367.704624) (xy 203.996036 -367.704878)
			(xy 204.015086 -367.697512) (xy 204.074776 -367.6396) (xy 204.081725 -367.632175) (xy 204.089587 -367.613439)
			(xy 204.090016 -367.603278) (xy 204.090016 -367.26876) (xy 204.0905 -367.243808) (xy 204.098296 -367.194518)
			(xy 204.113706 -367.147053) (xy 204.13635 -367.102583) (xy 204.16567 -367.062201) (xy 204.18298 -367.044224)
			(xy 204.446632 -366.780572) (xy 204.464629 -366.763285) (xy 204.50501 -366.733969) (xy 204.549476 -366.711323)
			(xy 204.596934 -366.695902) (xy 204.646218 -366.688086) (xy 204.671168 -366.687608) (xy 208.09839 -366.687608)
			(xy 208.123342 -366.688071) (xy 208.17263 -366.695876) (xy 208.220091 -366.711296) (xy 208.264556 -366.733951)
			(xy 208.304928 -366.763283) (xy 208.322926 -366.780572) (xy 208.566512 -367.024158) (xy 208.583794 -367.042158)
			(xy 208.613098 -367.082542) (xy 208.635735 -367.127008) (xy 208.651147 -367.174465) (xy 208.658958 -367.223746)
			(xy 208.659476 -367.248694) (xy 208.659476 -369.788186) (xy 208.659961 -369.798197) (xy 208.667617 -369.816698)
			(xy 208.68177 -369.830861) (xy 208.700265 -369.838531) (xy 208.710276 -369.838986) (xy 208.785968 -369.838986)
			(xy 208.810918 -369.839473) (xy 208.860205 -369.847274) (xy 208.907665 -369.862689) (xy 208.95213 -369.885339)
			(xy 208.992503 -369.914666) (xy 209.010504 -369.93195) (xy 209.67573 -370.597176) (xy 209.683129 -370.60402)
			(xy 209.701727 -370.611748) (xy 209.711798 -370.612162) (xy 210.06562 -370.612162) (xy 210.090572 -370.612645)
			(xy 210.139863 -370.620439) (xy 210.187329 -370.635848) (xy 210.231799 -370.658493) (xy 210.27218 -370.687815)
			(xy 210.290156 -370.705126) (xy 210.516978 -370.931948) (xy 210.534262 -370.949947) (xy 210.563571 -370.99033)
			(xy 210.586211 -371.034796) (xy 210.601627 -371.082253) (xy 210.60944 -371.131535) (xy 210.609942 -371.156484)
			(xy 210.609942 -371.380512) (xy 210.610364 -371.390529) (xy 210.618038 -371.409034) (xy 210.632211 -371.423192)
			(xy 210.650725 -371.430846) (xy 210.660742 -371.431312) (xy 216.45245 -371.431312) (xy 216.462516 -371.43088)
			(xy 216.481109 -371.423154) (xy 216.488518 -371.416326) (xy 217.302334 -370.60251) (xy 217.309189 -370.595115)
			(xy 217.316938 -370.576517) (xy 217.31732 -370.566442) (xy 217.31732 -367.318036) (xy 217.317806 -367.293085)
			(xy 217.325606 -367.243796) (xy 217.341018 -367.196334) (xy 217.363664 -367.151867) (xy 217.392987 -367.111488)
			(xy 217.410284 -367.0935) (xy 217.733118 -366.770666) (xy 217.751115 -366.753378) (xy 217.791496 -366.724062)
			(xy 217.835962 -366.701414) (xy 217.883419 -366.685991) (xy 217.932704 -366.678172) (xy 217.957654 -366.677702)
			(xy 221.342458 -366.677702) (xy 221.367411 -366.678163) (xy 221.416702 -366.685963) (xy 221.464166 -366.701379)
			(xy 221.508634 -366.724031) (xy 221.549011 -366.753361) (xy 221.566994 -366.770666) (xy 221.81058 -367.014252)
			(xy 221.827864 -367.032251) (xy 221.857172 -367.072634) (xy 221.879811 -367.1171) (xy 221.895227 -367.164557)
			(xy 221.903039 -367.213839) (xy 221.903544 -367.238788) (xy 221.903544 -370.592604) (xy 221.903969 -370.602673)
			(xy 221.91169 -370.621272) (xy 221.91853 -370.628672) (xy 222.004382 -370.714524) (xy 222.021667 -370.732522)
			(xy 222.050979 -370.772905) (xy 222.073622 -370.817371) (xy 222.089041 -370.864828) (xy 222.096858 -370.914111)
			(xy 222.097346 -370.93906) (xy 222.097346 -373.42191) (xy 222.097772 -373.431978) (xy 222.105494 -373.450576)
			(xy 222.112332 -373.457978) (xy 223.764602 -375.110248) (xy 223.771998 -375.1171) (xy 223.790597 -375.124842)
			(xy 223.80067 -375.125234) (xy 225.416872 -375.125234) (xy 225.426935 -375.124796) (xy 225.445514 -375.117056)
			(xy 225.45294 -375.110248) (xy 226.51339 -374.049798) (xy 226.520237 -374.0424) (xy 226.527972 -374.023802)
			(xy 226.528376 -374.01373) (xy 226.528376 -372.656862) (xy 226.528835 -372.631909) (xy 226.536633 -372.582615)
			(xy 226.552045 -372.535148) (xy 226.574694 -372.490677) (xy 226.60402 -372.450296) (xy 226.62134 -372.432326)
			(xy 227.816156 -371.23751) (xy 227.823009 -371.230114) (xy 227.830754 -371.211516) (xy 227.831142 -371.201442)
			(xy 227.831142 -370.936012) (xy 227.83163 -370.911062) (xy 227.839433 -370.861776) (xy 227.854849 -370.814316)
			(xy 227.877499 -370.769853) (xy 227.906824 -370.729479) (xy 227.924106 -370.711476) (xy 228.003608 -370.631974)
			(xy 228.010449 -370.624574) (xy 228.018173 -370.605976) (xy 228.018594 -370.595906) (xy 228.018594 -367.245138)
			(xy 228.019055 -367.220185) (xy 228.026856 -367.170894) (xy 228.042272 -367.12343) (xy 228.064924 -367.078962)
			(xy 228.094253 -367.038585) (xy 228.111558 -367.020602) (xy 228.364796 -366.767364) (xy 228.382793 -366.750075)
			(xy 228.423173 -366.720756) (xy 228.467638 -366.698105) (xy 228.515096 -366.682679) (xy 228.564381 -366.674857)
			(xy 228.589332 -366.6744) (xy 232.007156 -366.6744) (xy 232.032109 -366.67486) (xy 232.0814 -366.682661)
			(xy 232.128865 -366.698077) (xy 232.173333 -366.720728) (xy 232.213711 -366.750057) (xy 232.231692 -366.767364)
			(xy 232.48493 -367.020602) (xy 232.502219 -367.038599) (xy 232.531538 -367.078979) (xy 232.554188 -367.123444)
			(xy 232.569613 -367.170902) (xy 232.577435 -367.220187) (xy 232.577894 -367.245138) (xy 232.577894 -370.60251)
			(xy 232.578319 -370.61258) (xy 232.586035 -370.631182) (xy 232.59288 -370.638578) (xy 232.652824 -370.698522)
			(xy 232.670112 -370.716519) (xy 232.699429 -370.7569) (xy 232.722077 -370.801365) (xy 232.737499 -370.848823)
			(xy 232.745318 -370.898108) (xy 232.745788 -370.923058) (xy 232.745788 -371.05971) (xy 232.746212 -371.06978)
			(xy 232.753928 -371.088383) (xy 232.760774 -371.095778) (xy 233.402886 -371.73789) (xy 233.420167 -371.75589)
			(xy 233.44947 -371.796274) (xy 233.472104 -371.840741) (xy 233.487513 -371.888197) (xy 233.495319 -371.937478)
			(xy 233.49585 -371.962426) (xy 233.49585 -375.346214) (xy 233.496277 -375.356282) (xy 233.504001 -375.374878)
			(xy 233.510836 -375.382282) (xy 237.245652 -379.117098) (xy 237.253053 -379.123937) (xy 237.271651 -379.131652)
			(xy 237.28172 -379.132084) (xy 239.621314 -379.132084) (xy 239.631383 -379.131658) (xy 239.649982 -379.123938)
			(xy 239.657382 -379.117098) (xy 240.207292 -378.567188) (xy 240.225293 -378.549908) (xy 240.265678 -378.520608)
			(xy 240.310144 -378.497976) (xy 240.3576 -378.482569) (xy 240.406881 -378.474763) (xy 240.431828 -378.474224)
			(xy 262.084058 -378.474224) (xy 262.109009 -378.47471) (xy 262.158298 -378.482508) (xy 262.205761 -378.49792)
			(xy 262.250229 -378.520566) (xy 262.290608 -378.549888) (xy 262.308594 -378.567188) (xy 262.441436 -378.70003)
			(xy 266.644636 -378.70003) (xy 266.648637 -378.494991) (xy 266.660635 -378.290263) (xy 266.680612 -378.08616)
			(xy 266.708537 -377.882992) (xy 266.744367 -377.681068) (xy 266.788049 -377.480695) (xy 266.839515 -377.28218)
			(xy 266.898687 -377.085823) (xy 266.965475 -376.891925) (xy 267.039777 -376.70078) (xy 267.12148 -376.51268)
			(xy 267.210461 -376.327911) (xy 267.306582 -376.146754) (xy 267.409698 -375.969485) (xy 267.519652 -375.796375)
			(xy 267.636277 -375.627686) (xy 267.759394 -375.463676) (xy 267.888817 -375.304594) (xy 268.024347 -375.150683)
			(xy 268.16578 -375.002177) (xy 268.312899 -374.859302) (xy 268.46548 -374.722277) (xy 268.623292 -374.591308)
			(xy 268.786093 -374.466597) (xy 268.953636 -374.348332) (xy 269.125665 -374.236694) (xy 269.30192 -374.131853)
			(xy 269.48213 -374.033969) (xy 269.666022 -373.94319) (xy 269.853317 -373.859656) (xy 270.043727 -373.783492)
			(xy 270.236965 -373.714815) (xy 270.432735 -373.65373) (xy 270.630739 -373.60033) (xy 270.830675 -373.554696)
			(xy 271.03224 -373.516897) (xy 271.235126 -373.486991) (xy 271.439025 -373.465024) (xy 271.643625 -373.451029)
			(xy 271.848616 -373.445028) (xy 272.053685 -373.447028) (xy 272.258519 -373.457029) (xy 272.462807 -373.475013)
			(xy 272.666239 -373.500955) (xy 272.868503 -373.534813) (xy 273.069292 -373.576538) (xy 273.2683 -373.626064)
			(xy 273.465224 -373.683318) (xy 273.659765 -373.748211) (xy 273.851626 -373.820645) (xy 274.040514 -373.900509)
			(xy 274.226143 -373.987683) (xy 274.408229 -374.082032) (xy 274.586495 -374.183414) (xy 274.76067 -374.291674)
			(xy 274.930489 -374.406647) (xy 274.953921 -374.423882) (xy 286.928731 -374.423882) (xy 286.928735 -374.356454)
			(xy 286.936815 -374.289512) (xy 286.952857 -374.22402) (xy 286.976628 -374.160921) (xy 287.007787 -374.101124)
			(xy 287.045884 -374.04549) (xy 287.067752 -374.019826) (xy 287.073569 -374.012695) (xy 287.08007 -373.995494)
			(xy 287.080452 -373.986298) (xy 287.080452 -373.828818) (xy 287.080942 -373.818691) (xy 287.088666 -373.799968)
			(xy 287.102951 -373.785611) (xy 287.121636 -373.777793) (xy 287.13176 -373.777256) (xy 287.84804 -373.777256)
			(xy 287.858191 -373.777688) (xy 287.876936 -373.785489) (xy 287.891256 -373.799881) (xy 287.898963 -373.818665)
			(xy 287.899348 -373.828818) (xy 287.899348 -373.986298) (xy 287.899771 -373.995484) (xy 287.906277 -374.012667)
			(xy 287.912048 -374.019826) (xy 287.933873 -374.045524) (xy 287.971966 -374.101153) (xy 288.003121 -374.160944)
			(xy 288.02689 -374.224037) (xy 288.04293 -374.289522) (xy 288.05101 -374.356458) (xy 288.051014 -374.423823)
			(xy 291.32905 -374.423823) (xy 291.329054 -374.356514) (xy 291.337102 -374.289689) (xy 291.35308 -374.224304)
			(xy 291.376757 -374.161298) (xy 291.407796 -374.101573) (xy 291.44575 -374.045986) (xy 291.46754 -374.020334)
			(xy 291.473352 -374.0132) (xy 291.479857 -373.996001) (xy 291.48024 -373.986806) (xy 291.48024 -373.828818)
			(xy 291.480678 -373.818647) (xy 291.488458 -373.799853) (xy 291.502839 -373.785467) (xy 291.521631 -373.777682)
			(xy 291.531802 -373.777256) (xy 292.248082 -373.777256) (xy 292.258255 -373.777679) (xy 292.277053 -373.785461)
			(xy 292.291439 -373.799847) (xy 292.299221 -373.818645) (xy 292.299644 -373.828818) (xy 292.299644 -373.986806)
			(xy 292.300064 -373.995992) (xy 292.306572 -374.013176) (xy 292.312344 -374.020334) (xy 292.334091 -374.04602)
			(xy 292.372042 -374.101601) (xy 292.403078 -374.16132) (xy 292.426754 -374.22432) (xy 292.44273 -374.289698)
			(xy 292.450778 -374.356517) (xy 292.450782 -374.423819) (xy 292.450774 -374.423882) (xy 295.728819 -374.423882)
			(xy 295.728822 -374.356455) (xy 295.736903 -374.289513) (xy 295.752944 -374.224021) (xy 295.776715 -374.160922)
			(xy 295.807872 -374.101125) (xy 295.845968 -374.045491) (xy 295.867836 -374.019826) (xy 295.873651 -374.012694)
			(xy 295.880154 -373.995493) (xy 295.880536 -373.986298) (xy 295.880536 -373.828818) (xy 295.881041 -373.818693)
			(xy 295.888762 -373.799973) (xy 295.903043 -373.785616) (xy 295.921722 -373.777796) (xy 295.931844 -373.777256)
			(xy 296.648124 -373.777256) (xy 296.658274 -373.777701) (xy 296.677019 -373.785496) (xy 296.69134 -373.799885)
			(xy 296.699046 -373.818666) (xy 296.699432 -373.828818) (xy 296.699432 -373.986298) (xy 296.699858 -373.995483)
			(xy 296.706362 -374.012667) (xy 296.712132 -374.019826) (xy 296.733954 -374.045526) (xy 296.772041 -374.101156)
			(xy 296.803192 -374.160948) (xy 296.826957 -374.22404) (xy 296.842995 -374.289525) (xy 296.851073 -374.356459)
			(xy 296.851077 -374.423878) (xy 296.851077 -374.423882) (xy 300.12861 -374.423882) (xy 300.128613 -374.356455)
			(xy 300.136694 -374.289513) (xy 300.152734 -374.224021) (xy 300.176504 -374.160923) (xy 300.207661 -374.101126)
			(xy 300.245757 -374.045491) (xy 300.267624 -374.019826) (xy 300.273437 -374.012693) (xy 300.279941 -373.995493)
			(xy 300.280324 -373.986298) (xy 300.280324 -373.828818) (xy 300.280841 -373.818694) (xy 300.28856 -373.799977)
			(xy 300.302837 -373.78562) (xy 300.321511 -373.777798) (xy 300.331632 -373.777256) (xy 301.047912 -373.777256)
			(xy 301.058061 -373.777711) (xy 301.076806 -373.785502) (xy 301.091127 -373.799888) (xy 301.098834 -373.818667)
			(xy 301.09922 -373.828818) (xy 301.09922 -373.986298) (xy 301.099627 -373.995486) (xy 301.106142 -374.01267)
			(xy 301.11192 -374.019826) (xy 301.133742 -374.045526) (xy 301.171831 -374.101156) (xy 301.202982 -374.160947)
			(xy 301.226748 -374.22404) (xy 301.242785 -374.289524) (xy 301.250864 -374.356458) (xy 301.250868 -374.423823)
			(xy 330.929168 -374.423823) (xy 330.929172 -374.356514) (xy 330.937221 -374.289688) (xy 330.953199 -374.224303)
			(xy 330.976878 -374.161297) (xy 331.007917 -374.101572) (xy 331.045873 -374.045986) (xy 331.067664 -374.020334)
			(xy 331.073479 -374.013202) (xy 331.079981 -373.996001) (xy 331.080364 -373.986806) (xy 331.080364 -373.828818)
			(xy 331.080779 -373.818644) (xy 331.088563 -373.799845) (xy 331.102952 -373.785458) (xy 331.121752 -373.777677)
			(xy 331.131926 -373.777256) (xy 331.848206 -373.777256) (xy 331.85838 -373.777659) (xy 331.877178 -373.78545)
			(xy 331.891564 -373.799842) (xy 331.899345 -373.818644) (xy 331.899768 -373.828818) (xy 331.899768 -373.986806)
			(xy 331.900182 -373.995993) (xy 331.906694 -374.013177) (xy 331.912468 -374.020334) (xy 331.934214 -374.04602)
			(xy 331.972164 -374.101602) (xy 332.003198 -374.161321) (xy 332.026873 -374.224321) (xy 332.042849 -374.289699)
			(xy 332.050896 -374.356518) (xy 332.0509 -374.423819) (xy 332.050892 -374.423882) (xy 335.328961 -374.423882)
			(xy 335.328965 -374.356455) (xy 335.337045 -374.289515) (xy 335.353083 -374.224024) (xy 335.37685 -374.160926)
			(xy 335.408004 -374.101128) (xy 335.446095 -374.045492) (xy 335.46796 -374.019826) (xy 335.473778 -374.012696)
			(xy 335.480278 -373.995494) (xy 335.48066 -373.986298) (xy 335.48066 -373.828818) (xy 335.481142 -373.81869)
			(xy 335.488867 -373.799965) (xy 335.503156 -373.785608) (xy 335.521842 -373.777791) (xy 335.531968 -373.777256)
			(xy 336.248248 -373.777256) (xy 336.2584 -373.777682) (xy 336.277145 -373.785485) (xy 336.291465 -373.799879)
			(xy 336.299171 -373.818664) (xy 336.299556 -373.828818) (xy 336.299556 -373.986298) (xy 336.299977 -373.995484)
			(xy 336.306484 -374.012668) (xy 336.312256 -374.019826) (xy 336.33408 -374.045525) (xy 336.372173 -374.101153)
			(xy 336.403328 -374.160944) (xy 336.427097 -374.224037) (xy 336.443136 -374.289523) (xy 336.451216 -374.356458)
			(xy 336.45122 -374.423823) (xy 339.729256 -374.423823) (xy 339.72926 -374.356514) (xy 339.737309 -374.289689)
			(xy 339.753286 -374.224304) (xy 339.776964 -374.161298) (xy 339.808003 -374.101573) (xy 339.845957 -374.045986)
			(xy 339.867748 -374.020334) (xy 339.873561 -374.013201) (xy 339.880065 -373.996001) (xy 339.880448 -373.986806)
			(xy 339.880448 -373.828818) (xy 339.880879 -373.818646) (xy 339.88866 -373.79985) (xy 339.903043 -373.785464)
			(xy 339.921838 -373.77768) (xy 339.93201 -373.777256) (xy 340.64829 -373.777256) (xy 340.658463 -373.777672)
			(xy 340.677261 -373.785457) (xy 340.691647 -373.799846) (xy 340.699429 -373.818645) (xy 340.699852 -373.828818)
			(xy 340.699852 -373.986806) (xy 340.70027 -373.995992) (xy 340.706779 -374.013176) (xy 340.712552 -374.020334)
			(xy 340.734299 -374.04602) (xy 340.772249 -374.101601) (xy 340.803285 -374.16132) (xy 340.82696 -374.22432)
			(xy 340.842936 -374.289699) (xy 340.850984 -374.356517) (xy 340.850988 -374.423819) (xy 340.850988 -374.423823)
			(xy 344.129047 -374.423823) (xy 344.129051 -374.356514) (xy 344.137099 -374.289689) (xy 344.153077 -374.224304)
			(xy 344.176754 -374.161298) (xy 344.207792 -374.101573) (xy 344.245746 -374.045986) (xy 344.267536 -374.020334)
			(xy 344.273348 -374.0132) (xy 344.279852 -373.996001) (xy 344.280236 -373.986806) (xy 344.280236 -373.828818)
			(xy 344.280678 -373.818648) (xy 344.288457 -373.799854) (xy 344.302837 -373.785468) (xy 344.321628 -373.777682)
			(xy 344.331798 -373.777256) (xy 345.048078 -373.777256) (xy 345.05825 -373.777683) (xy 345.077048 -373.785464)
			(xy 345.091434 -373.799849) (xy 345.099217 -373.818646) (xy 345.09964 -373.828818) (xy 345.09964 -373.986806)
			(xy 345.100061 -373.995992) (xy 345.106569 -374.013175) (xy 345.11234 -374.020334) (xy 345.134087 -374.04602)
			(xy 345.172038 -374.101601) (xy 345.203075 -374.16132) (xy 345.226751 -374.22432) (xy 345.242727 -374.289698)
			(xy 345.250775 -374.356517) (xy 345.250779 -374.423819) (xy 345.250779 -374.423823) (xy 374.929078 -374.423823)
			(xy 374.929081 -374.356514) (xy 374.93713 -374.289688) (xy 374.953109 -374.224303) (xy 374.976788 -374.161296)
			(xy 375.007828 -374.101572) (xy 375.045784 -374.045985) (xy 375.067576 -374.020334) (xy 375.07338 -374.013194)
			(xy 375.079891 -373.996) (xy 375.080276 -373.986806) (xy 375.080276 -373.828818) (xy 375.080679 -373.818643)
			(xy 375.088465 -373.799841) (xy 375.102858 -373.785454) (xy 375.121663 -373.777675) (xy 375.131838 -373.777256)
			(xy 375.848118 -373.777256) (xy 375.858279 -373.777719) (xy 375.877052 -373.785503) (xy 375.891418 -373.799878)
			(xy 375.899188 -373.818656) (xy 375.89968 -373.828818) (xy 375.89968 -373.986806) (xy 375.900092 -373.995993)
			(xy 375.906605 -374.013177) (xy 375.91238 -374.020334) (xy 375.934126 -374.046021) (xy 375.972074 -374.101603)
			(xy 376.003108 -374.161322) (xy 376.026783 -374.224321) (xy 376.042758 -374.289699) (xy 376.050805 -374.356518)
			(xy 376.050809 -374.423819) (xy 376.050801 -374.423882) (xy 379.32887 -374.423882) (xy 379.328874 -374.356455)
			(xy 379.336954 -374.289515) (xy 379.352993 -374.224024) (xy 379.376761 -374.160925) (xy 379.407915 -374.101127)
			(xy 379.446007 -374.045492) (xy 379.467872 -374.019826) (xy 379.473691 -374.012697) (xy 379.48019 -373.995494)
			(xy 379.480572 -373.986298) (xy 379.480572 -373.828818) (xy 379.481042 -373.818688) (xy 379.48877 -373.799962)
			(xy 379.503062 -373.785604) (xy 379.521753 -373.777789) (xy 379.53188 -373.777256) (xy 380.24816 -373.777256)
			(xy 380.258306 -373.777754) (xy 380.277049 -373.785528) (xy 380.291372 -373.799901) (xy 380.299081 -373.818671)
			(xy 380.299468 -373.828818) (xy 380.299468 -373.986298) (xy 380.299886 -373.995484) (xy 380.306395 -374.012668)
			(xy 380.312168 -374.019826) (xy 380.333992 -374.045525) (xy 380.372084 -374.101154) (xy 380.403238 -374.160945)
			(xy 380.427006 -374.224038) (xy 380.443046 -374.289523) (xy 380.451125 -374.356458) (xy 380.451129 -374.423823)
			(xy 383.729165 -374.423823) (xy 383.729169 -374.356514) (xy 383.737218 -374.289688) (xy 383.753196 -374.224303)
			(xy 383.776874 -374.161297) (xy 383.807914 -374.101572) (xy 383.845869 -374.045986) (xy 383.86766 -374.020334)
			(xy 383.873474 -374.013202) (xy 383.879977 -373.996001) (xy 383.88036 -373.986806) (xy 383.88036 -373.828818)
			(xy 383.880779 -373.818645) (xy 383.888562 -373.799846) (xy 383.90295 -373.78546) (xy 383.921749 -373.777678)
			(xy 383.931922 -373.777256) (xy 384.648202 -373.777256) (xy 384.658376 -373.777663) (xy 384.677174 -373.785452)
			(xy 384.69156 -373.799843) (xy 384.699341 -373.818644) (xy 384.699764 -373.828818) (xy 384.699764 -373.986806)
			(xy 384.700179 -373.995992) (xy 384.70669 -374.013176) (xy 384.712464 -374.020334) (xy 384.73421 -374.04602)
			(xy 384.77216 -374.101602) (xy 384.803195 -374.161321) (xy 384.82687 -374.224321) (xy 384.842846 -374.289699)
			(xy 384.850893 -374.356518) (xy 384.850897 -374.423819) (xy 384.850897 -374.423823) (xy 388.128956 -374.423823)
			(xy 388.12896 -374.356514) (xy 388.137009 -374.289689) (xy 388.152986 -374.224304) (xy 388.176664 -374.161298)
			(xy 388.207703 -374.101573) (xy 388.245657 -374.045986) (xy 388.267448 -374.020334) (xy 388.273261 -374.013201)
			(xy 388.279765 -373.996001) (xy 388.280148 -373.986806) (xy 388.280148 -373.828818) (xy 388.280579 -373.818646)
			(xy 388.28836 -373.79985) (xy 388.302743 -373.785464) (xy 388.321538 -373.77768) (xy 388.33171 -373.777256)
			(xy 389.04799 -373.777256) (xy 389.058163 -373.777672) (xy 389.076961 -373.785457) (xy 389.091347 -373.799846)
			(xy 389.099129 -373.818645) (xy 389.099552 -373.828818) (xy 389.099552 -373.986806) (xy 389.09997 -373.995992)
			(xy 389.106479 -374.013176) (xy 389.112252 -374.020334) (xy 389.133999 -374.04602) (xy 389.171949 -374.101601)
			(xy 389.202985 -374.16132) (xy 389.22666 -374.22432) (xy 389.242636 -374.289699) (xy 389.250684 -374.356517)
			(xy 389.250688 -374.423819) (xy 389.250688 -374.423823) (xy 418.928987 -374.423823) (xy 418.928991 -374.356514)
			(xy 418.93704 -374.289688) (xy 418.953019 -374.224302) (xy 418.976698 -374.161296) (xy 419.007739 -374.101572)
			(xy 419.045696 -374.045986) (xy 419.067488 -374.020334) (xy 419.073294 -374.013195) (xy 419.079803 -373.996)
			(xy 419.080188 -373.986806) (xy 419.080188 -373.828818) (xy 419.08058 -373.818641) (xy 419.088368 -373.799837)
			(xy 419.102764 -373.78545) (xy 419.121573 -373.777673) (xy 419.13175 -373.777256) (xy 419.84803 -373.777256)
			(xy 419.858192 -373.777709) (xy 419.876965 -373.785497) (xy 419.89133 -373.799875) (xy 419.8991 -373.818656)
			(xy 419.899592 -373.828818) (xy 419.899592 -373.986806) (xy 419.900001 -373.995993) (xy 419.906516 -374.013177)
			(xy 419.912292 -374.020334) (xy 419.934038 -374.04602) (xy 419.971986 -374.101603) (xy 420.003019 -374.161322)
			(xy 420.026693 -374.224322) (xy 420.042668 -374.2897) (xy 420.050715 -374.356518) (xy 420.050719 -374.423819)
			(xy 420.050711 -374.423882) (xy 423.328779 -374.423882) (xy 423.328783 -374.356455) (xy 423.336863 -374.289514)
			(xy 423.352903 -374.224023) (xy 423.376671 -374.160925) (xy 423.407825 -374.101127) (xy 423.445918 -374.045492)
			(xy 423.467784 -374.019826) (xy 423.473593 -374.012689) (xy 423.480101 -373.995492) (xy 423.480484 -373.986298)
			(xy 423.480484 -373.828818) (xy 423.480942 -373.818687) (xy 423.488672 -373.799958) (xy 423.502968 -373.785599)
			(xy 423.521663 -373.777787) (xy 423.531792 -373.777256) (xy 424.248072 -373.777256) (xy 424.258219 -373.777743)
			(xy 424.276962 -373.785522) (xy 424.291285 -373.799898) (xy 424.298994 -373.81867) (xy 424.29938 -373.828818)
			(xy 424.29938 -373.986298) (xy 424.299795 -373.995485) (xy 424.306306 -374.012669) (xy 424.31208 -374.019826)
			(xy 424.333903 -374.045525) (xy 424.371995 -374.101154) (xy 424.403148 -374.160946) (xy 424.426916 -374.224038)
			(xy 424.442955 -374.289523) (xy 424.451034 -374.356458) (xy 424.451038 -374.423823) (xy 427.729074 -374.423823)
			(xy 427.729078 -374.356514) (xy 427.737127 -374.289688) (xy 427.753106 -374.224303) (xy 427.776784 -374.161296)
			(xy 427.807824 -374.101572) (xy 427.84578 -374.045986) (xy 427.867572 -374.020334) (xy 427.873388 -374.013203)
			(xy 427.879889 -373.996001) (xy 427.880272 -373.986806) (xy 427.880272 -373.828818) (xy 427.880679 -373.818643)
			(xy 427.888465 -373.799842) (xy 427.902856 -373.785456) (xy 427.921659 -373.777676) (xy 427.931834 -373.777256)
			(xy 428.648114 -373.777256) (xy 428.658289 -373.777653) (xy 428.677087 -373.785446) (xy 428.691472 -373.79984)
			(xy 428.699253 -373.818643) (xy 428.699676 -373.828818) (xy 428.699676 -373.986806) (xy 428.700088 -373.995993)
			(xy 428.706601 -374.013177) (xy 428.712376 -374.020334) (xy 428.734122 -374.04602) (xy 428.772071 -374.101602)
			(xy 428.803105 -374.161321) (xy 428.82678 -374.224321) (xy 428.842755 -374.289699) (xy 428.850802 -374.356518)
			(xy 428.850806 -374.423819) (xy 428.850806 -374.423823) (xy 432.128865 -374.423823) (xy 432.128869 -374.356514)
			(xy 432.136918 -374.289688) (xy 432.152896 -374.224303) (xy 432.176574 -374.161297) (xy 432.207614 -374.101572)
			(xy 432.245569 -374.045986) (xy 432.26736 -374.020334) (xy 432.273174 -374.013202) (xy 432.279677 -373.996001)
			(xy 432.28006 -373.986806) (xy 432.28006 -373.828818) (xy 432.280479 -373.818645) (xy 432.288262 -373.799846)
			(xy 432.30265 -373.78546) (xy 432.321449 -373.777678) (xy 432.331622 -373.777256) (xy 433.047902 -373.777256)
			(xy 433.058076 -373.777663) (xy 433.076874 -373.785452) (xy 433.09126 -373.799843) (xy 433.099041 -373.818644)
			(xy 433.099464 -373.828818) (xy 433.099464 -373.986806) (xy 433.099879 -373.995992) (xy 433.10639 -374.013176)
			(xy 433.112164 -374.020334) (xy 433.13391 -374.04602) (xy 433.17186 -374.101602) (xy 433.202895 -374.161321)
			(xy 433.22657 -374.224321) (xy 433.242546 -374.289699) (xy 433.250593 -374.356518) (xy 433.250597 -374.423819)
			(xy 433.242557 -374.490639) (xy 433.226589 -374.556019) (xy 433.202921 -374.619021) (xy 433.171892 -374.678744)
			(xy 433.133949 -374.73433) (xy 433.112164 -374.759982) (xy 433.106346 -374.767112) (xy 433.099845 -374.784314)
			(xy 433.099464 -374.79351) (xy 433.099464 -375.286778) (xy 433.099893 -375.295963) (xy 433.106394 -375.313147)
			(xy 433.112164 -375.320306) (xy 433.133981 -375.345934) (xy 433.171929 -375.401524) (xy 433.202961 -375.461251)
			(xy 433.226632 -375.524259) (xy 433.242603 -375.589644) (xy 433.250644 -375.656469) (xy 433.250642 -375.723776)
			(xy 433.242594 -375.790601) (xy 433.226618 -375.855985) (xy 433.202942 -375.91899) (xy 433.171906 -375.978715)
			(xy 433.133954 -376.034302) (xy 433.112164 -376.059954) (xy 433.106357 -376.067092) (xy 433.09985 -376.084288)
			(xy 433.099464 -376.093482) (xy 433.099464 -376.25147) (xy 433.099011 -376.261639) (xy 433.091237 -376.280433)
			(xy 433.07686 -376.294819) (xy 433.058071 -376.302605) (xy 433.047902 -376.303032) (xy 432.331622 -376.303032)
			(xy 432.321448 -376.302617) (xy 432.302648 -376.294834) (xy 432.288262 -376.280445) (xy 432.280481 -376.261644)
			(xy 432.28006 -376.25147) (xy 432.28006 -376.093482) (xy 432.279645 -376.084296) (xy 432.273133 -376.067112)
			(xy 432.26736 -376.059954) (xy 432.245601 -376.034278) (xy 432.20765 -375.978695) (xy 432.176614 -375.918975)
			(xy 432.152939 -375.855974) (xy 432.136963 -375.790594) (xy 432.128917 -375.723774) (xy 432.128914 -375.656471)
			(xy 432.136955 -375.58965) (xy 432.152926 -375.524269) (xy 432.176596 -375.461266) (xy 432.207627 -375.401543)
			(xy 432.245574 -375.345958) (xy 432.26736 -375.320306) (xy 432.273144 -375.313152) (xy 432.279664 -375.295968)
			(xy 432.28006 -375.286778) (xy 432.28006 -374.79351) (xy 432.279632 -374.784325) (xy 432.273129 -374.767141)
			(xy 432.26736 -374.759982) (xy 432.24553 -374.734364) (xy 432.207581 -374.678773) (xy 432.176549 -374.619045)
			(xy 432.152877 -374.556036) (xy 432.136907 -374.49065) (xy 432.128865 -374.423823) (xy 428.850806 -374.423823)
			(xy 428.842766 -374.490639) (xy 428.826798 -374.556018) (xy 428.803131 -374.619021) (xy 428.772103 -374.678743)
			(xy 428.73416 -374.734329) (xy 428.712376 -374.759982) (xy 428.706559 -374.767113) (xy 428.700057 -374.784314)
			(xy 428.699676 -374.79351) (xy 428.699676 -375.286778) (xy 428.700102 -375.295963) (xy 428.706605 -375.313148)
			(xy 428.712376 -375.320306) (xy 428.734193 -375.345934) (xy 428.77214 -375.401524) (xy 428.803171 -375.461251)
			(xy 428.826841 -375.524259) (xy 428.842812 -375.589644) (xy 428.850853 -375.656469) (xy 428.850851 -375.723776)
			(xy 428.842804 -375.790601) (xy 428.826828 -375.855984) (xy 428.803152 -375.91899) (xy 428.772117 -375.978714)
			(xy 428.734165 -376.034302) (xy 428.712376 -376.059954) (xy 428.706571 -376.067093) (xy 428.700062 -376.084288)
			(xy 428.699676 -376.093482) (xy 428.699676 -376.25147) (xy 428.699212 -376.261638) (xy 428.691439 -376.280429)
			(xy 428.677066 -376.294815) (xy 428.658282 -376.302603) (xy 428.648114 -376.303032) (xy 427.931834 -376.303032)
			(xy 427.921661 -376.302607) (xy 427.902861 -376.294828) (xy 427.888474 -376.280442) (xy 427.880693 -376.261643)
			(xy 427.880272 -376.25147) (xy 427.880272 -376.093482) (xy 427.879877 -376.084293) (xy 427.873353 -376.067109)
			(xy 427.867572 -376.059954) (xy 427.845813 -376.034278) (xy 427.807861 -375.978696) (xy 427.776825 -375.918976)
			(xy 427.753149 -375.855974) (xy 427.737173 -375.790595) (xy 427.729126 -375.723774) (xy 427.729123 -375.656471)
			(xy 427.737165 -375.58965) (xy 427.753135 -375.524269) (xy 427.776806 -375.461266) (xy 427.807838 -375.401543)
			(xy 427.845785 -375.345958) (xy 427.867572 -375.320306) (xy 427.873357 -375.313153) (xy 427.879877 -375.295968)
			(xy 427.880272 -375.286778) (xy 427.880272 -374.79351) (xy 427.879863 -374.784323) (xy 427.873349 -374.767138)
			(xy 427.867572 -374.759982) (xy 427.845742 -374.734364) (xy 427.807792 -374.678774) (xy 427.776759 -374.619046)
			(xy 427.753087 -374.556037) (xy 427.737116 -374.49065) (xy 427.729074 -374.423823) (xy 424.451038 -374.423823)
			(xy 424.451038 -374.423879) (xy 424.442966 -374.490815) (xy 424.426934 -374.556302) (xy 424.403174 -374.619397)
			(xy 424.372027 -374.679192) (xy 424.333942 -374.734825) (xy 424.31208 -374.76049) (xy 424.30626 -374.767619)
			(xy 424.29976 -374.784822) (xy 424.29938 -374.794018) (xy 424.29938 -375.28627) (xy 424.299809 -375.295455)
			(xy 424.30631 -375.312639) (xy 424.31208 -375.319798) (xy 424.333974 -375.345439) (xy 424.372063 -375.401076)
			(xy 424.403214 -375.460876) (xy 424.426977 -375.523976) (xy 424.443011 -375.589468) (xy 424.451085 -375.656409)
			(xy 424.451082 -375.723836) (xy 424.443003 -375.790776) (xy 424.426964 -375.856267) (xy 424.403195 -375.919366)
			(xy 424.37204 -375.979163) (xy 424.333946 -376.034797) (xy 424.31208 -376.060462) (xy 424.306272 -376.067599)
			(xy 424.299765 -376.084796) (xy 424.29938 -376.09399) (xy 424.29938 -376.25147) (xy 424.29885 -376.261592)
			(xy 424.291135 -376.280309) (xy 424.276863 -376.294666) (xy 424.258191 -376.30249) (xy 424.248072 -376.303032)
			(xy 423.531792 -376.303032) (xy 423.521641 -376.302585) (xy 423.502895 -376.294793) (xy 423.488573 -376.280405)
			(xy 423.480868 -376.261622) (xy 423.480484 -376.25147) (xy 423.480484 -376.09399) (xy 423.480082 -376.084802)
			(xy 423.473563 -376.067617) (xy 423.467784 -376.060462) (xy 423.44595 -376.034772) (xy 423.407862 -375.979141)
			(xy 423.37671 -375.919348) (xy 423.352945 -375.856254) (xy 423.336908 -375.790768) (xy 423.32883 -375.723833)
			(xy 423.328827 -375.656412) (xy 423.3369 -375.589476) (xy 423.352932 -375.523989) (xy 423.376692 -375.460893)
			(xy 423.407838 -375.401098) (xy 423.445922 -375.345463) (xy 423.467784 -375.319798) (xy 423.473562 -375.31264)
			(xy 423.480088 -375.295459) (xy 423.480484 -375.28627) (xy 423.480484 -374.794018) (xy 423.480069 -374.784831)
			(xy 423.473559 -374.767647) (xy 423.467784 -374.76049) (xy 423.445879 -374.734859) (xy 423.407793 -374.679219)
			(xy 423.376645 -374.619418) (xy 423.352884 -374.556317) (xy 423.336852 -374.490824) (xy 423.328779 -374.423882)
			(xy 420.050711 -374.423882) (xy 420.042679 -374.490638) (xy 420.026712 -374.556018) (xy 420.003045 -374.61902)
			(xy 419.972018 -374.678743) (xy 419.934076 -374.73433) (xy 419.912292 -374.759982) (xy 419.906477 -374.767114)
			(xy 419.899974 -374.784315) (xy 419.899592 -374.79351) (xy 419.899592 -375.286778) (xy 419.900015 -375.295964)
			(xy 419.90652 -375.313148) (xy 419.912292 -375.320306) (xy 419.934108 -375.345934) (xy 419.972054 -375.401525)
			(xy 420.003084 -375.461252) (xy 420.026754 -375.52426) (xy 420.042724 -375.589644) (xy 420.050765 -375.656469)
			(xy 420.050763 -375.723776) (xy 420.042716 -375.7906) (xy 420.026741 -375.855984) (xy 420.003066 -375.918989)
			(xy 419.972031 -375.978714) (xy 419.934081 -376.034301) (xy 419.912292 -376.059954) (xy 419.906489 -376.067095)
			(xy 419.899978 -376.084289) (xy 419.899592 -376.093482) (xy 419.899592 -376.25147) (xy 419.899043 -376.261622)
			(xy 419.891284 -376.280385) (xy 419.876935 -376.29475) (xy 419.858182 -376.302531) (xy 419.84803 -376.303032)
			(xy 419.13175 -376.303032) (xy 419.121578 -376.302595) (xy 419.102779 -376.29482) (xy 419.088391 -376.280438)
			(xy 419.080609 -376.261642) (xy 419.080188 -376.25147) (xy 419.080188 -376.093482) (xy 419.079789 -376.084294)
			(xy 419.073268 -376.067109) (xy 419.067488 -376.059954) (xy 419.045728 -376.034278) (xy 419.007775 -375.978696)
			(xy 418.976738 -375.918976) (xy 418.953061 -375.855975) (xy 418.937085 -375.790595) (xy 418.929038 -375.723774)
			(xy 418.929035 -375.656471) (xy 418.937077 -375.589649) (xy 418.953048 -375.524268) (xy 418.97672 -375.461265)
			(xy 419.007752 -375.401542) (xy 419.045701 -375.345957) (xy 419.067488 -375.320306) (xy 419.073263 -375.313145)
			(xy 419.079791 -375.295967) (xy 419.080188 -375.286778) (xy 419.080188 -374.79351) (xy 419.079776 -374.784323)
			(xy 419.073264 -374.767138) (xy 419.067488 -374.759982) (xy 419.045658 -374.734364) (xy 419.007707 -374.678774)
			(xy 418.976673 -374.619046) (xy 418.953 -374.556037) (xy 418.937029 -374.49065) (xy 418.928987 -374.423823)
			(xy 389.250688 -374.423823) (xy 389.242648 -374.490639) (xy 389.226679 -374.556019) (xy 389.203011 -374.619022)
			(xy 389.171982 -374.678744) (xy 389.134037 -374.73433) (xy 389.112252 -374.759982) (xy 389.106432 -374.76711)
			(xy 389.099933 -374.784314) (xy 389.099552 -374.79351) (xy 389.099552 -375.286778) (xy 389.099983 -375.295963)
			(xy 389.106483 -375.313147) (xy 389.112252 -375.320306) (xy 389.13407 -375.345934) (xy 389.172018 -375.401523)
			(xy 389.203051 -375.46125) (xy 389.226722 -375.524258) (xy 389.242693 -375.589643) (xy 389.250735 -375.656469)
			(xy 389.250732 -375.723776) (xy 389.242685 -375.790601) (xy 389.226709 -375.855985) (xy 389.203032 -375.918991)
			(xy 389.171995 -375.978715) (xy 389.134042 -376.034302) (xy 389.112252 -376.059954) (xy 389.106444 -376.067091)
			(xy 389.099937 -376.084288) (xy 389.099552 -376.093482) (xy 389.099552 -376.25147) (xy 389.099111 -376.261641)
			(xy 389.091334 -376.280437) (xy 389.076954 -376.294823) (xy 389.058161 -376.302607) (xy 389.04799 -376.303032)
			(xy 388.33171 -376.303032) (xy 388.321535 -376.302627) (xy 388.302735 -376.29484) (xy 388.288349 -376.280448)
			(xy 388.280569 -376.261645) (xy 388.280148 -376.25147) (xy 388.280148 -376.093482) (xy 388.279736 -376.084295)
			(xy 388.273222 -376.067111) (xy 388.267448 -376.059954) (xy 388.24569 -376.034278) (xy 388.207739 -375.978695)
			(xy 388.176704 -375.918975) (xy 388.153029 -375.855973) (xy 388.137054 -375.790594) (xy 388.129007 -375.723774)
			(xy 388.129005 -375.656471) (xy 388.137046 -375.58965) (xy 388.153016 -375.52427) (xy 388.176686 -375.461267)
			(xy 388.207716 -375.401544) (xy 388.245662 -375.345958) (xy 388.267448 -375.320306) (xy 388.273231 -375.313151)
			(xy 388.279752 -375.295968) (xy 388.280148 -375.286778) (xy 388.280148 -374.79351) (xy 388.279722 -374.784325)
			(xy 388.273218 -374.767141) (xy 388.267448 -374.759982) (xy 388.245619 -374.734364) (xy 388.20767 -374.678773)
			(xy 388.176638 -374.619045) (xy 388.152968 -374.556036) (xy 388.136997 -374.490649) (xy 388.128956 -374.423823)
			(xy 384.850897 -374.423823) (xy 384.842857 -374.490639) (xy 384.826889 -374.556019) (xy 384.803221 -374.619021)
			(xy 384.772192 -374.678744) (xy 384.734249 -374.73433) (xy 384.712464 -374.759982) (xy 384.706646 -374.767112)
			(xy 384.700145 -374.784314) (xy 384.699764 -374.79351) (xy 384.699764 -375.286778) (xy 384.700193 -375.295963)
			(xy 384.706694 -375.313147) (xy 384.712464 -375.320306) (xy 384.734281 -375.345934) (xy 384.772229 -375.401524)
			(xy 384.803261 -375.461251) (xy 384.826932 -375.524259) (xy 384.842903 -375.589644) (xy 384.850944 -375.656469)
			(xy 384.850942 -375.723776) (xy 384.842894 -375.790601) (xy 384.826918 -375.855985) (xy 384.803242 -375.91899)
			(xy 384.772206 -375.978715) (xy 384.734254 -376.034302) (xy 384.712464 -376.059954) (xy 384.706657 -376.067092)
			(xy 384.70015 -376.084288) (xy 384.699764 -376.093482) (xy 384.699764 -376.25147) (xy 384.699311 -376.261639)
			(xy 384.691537 -376.280433) (xy 384.67716 -376.294819) (xy 384.658371 -376.302605) (xy 384.648202 -376.303032)
			(xy 383.931922 -376.303032) (xy 383.921748 -376.302617) (xy 383.902948 -376.294834) (xy 383.888562 -376.280445)
			(xy 383.880781 -376.261644) (xy 383.88036 -376.25147) (xy 383.88036 -376.093482) (xy 383.879945 -376.084296)
			(xy 383.873433 -376.067112) (xy 383.86766 -376.059954) (xy 383.845901 -376.034278) (xy 383.80795 -375.978695)
			(xy 383.776914 -375.918975) (xy 383.753239 -375.855974) (xy 383.737263 -375.790594) (xy 383.729217 -375.723774)
			(xy 383.729214 -375.656471) (xy 383.737255 -375.58965) (xy 383.753226 -375.524269) (xy 383.776896 -375.461266)
			(xy 383.807927 -375.401543) (xy 383.845874 -375.345958) (xy 383.86766 -375.320306) (xy 383.873444 -375.313152)
			(xy 383.879964 -375.295968) (xy 383.88036 -375.286778) (xy 383.88036 -374.79351) (xy 383.879932 -374.784325)
			(xy 383.873429 -374.767141) (xy 383.86766 -374.759982) (xy 383.84583 -374.734364) (xy 383.807881 -374.678773)
			(xy 383.776849 -374.619045) (xy 383.753177 -374.556036) (xy 383.737207 -374.49065) (xy 383.729165 -374.423823)
			(xy 380.451129 -374.423823) (xy 380.451129 -374.423879) (xy 380.443057 -374.490815) (xy 380.427025 -374.556302)
			(xy 380.403264 -374.619397) (xy 380.372116 -374.679192) (xy 380.334031 -374.734825) (xy 380.312168 -374.76049)
			(xy 380.306347 -374.767617) (xy 380.299847 -374.784822) (xy 380.299468 -374.794018) (xy 380.299468 -375.28627)
			(xy 380.2999 -375.295455) (xy 380.306399 -375.312639) (xy 380.312168 -375.319798) (xy 380.334063 -375.345438)
			(xy 380.372152 -375.401076) (xy 380.403304 -375.460875) (xy 380.427068 -375.523975) (xy 380.443102 -375.589468)
			(xy 380.451176 -375.656409) (xy 380.451173 -375.723836) (xy 380.443094 -375.790777) (xy 380.427054 -375.856268)
			(xy 380.403285 -375.919366) (xy 380.372129 -375.979163) (xy 380.334035 -376.034797) (xy 380.312168 -376.060462)
			(xy 380.306358 -376.067598) (xy 380.299852 -376.084796) (xy 380.299468 -376.09399) (xy 380.299468 -376.25147)
			(xy 380.298949 -376.261594) (xy 380.291233 -376.280313) (xy 380.276956 -376.29467) (xy 380.258281 -376.302492)
			(xy 380.24816 -376.303032) (xy 379.53188 -376.303032) (xy 379.521729 -376.302596) (xy 379.502982 -376.294799)
			(xy 379.48866 -376.280408) (xy 379.480955 -376.261623) (xy 379.480572 -376.25147) (xy 379.480572 -376.09399)
			(xy 379.480173 -376.084802) (xy 379.473652 -376.067617) (xy 379.467872 -376.060462) (xy 379.446038 -376.034772)
			(xy 379.407951 -375.97914) (xy 379.3768 -375.919347) (xy 379.353036 -375.856254) (xy 379.336999 -375.790768)
			(xy 379.328921 -375.723833) (xy 379.328918 -375.656412) (xy 379.336991 -375.589476) (xy 379.353022 -375.523989)
			(xy 379.376782 -375.460894) (xy 379.407928 -375.401098) (xy 379.446011 -375.345464) (xy 379.467872 -375.319798)
			(xy 379.473661 -375.312648) (xy 379.480178 -375.295461) (xy 379.480572 -375.28627) (xy 379.480572 -374.794018)
			(xy 379.48016 -374.784831) (xy 379.473648 -374.767646) (xy 379.467872 -374.76049) (xy 379.445968 -374.734858)
			(xy 379.407882 -374.679218) (xy 379.376735 -374.619417) (xy 379.352974 -374.556316) (xy 379.336943 -374.490823)
			(xy 379.32887 -374.423882) (xy 376.050801 -374.423882) (xy 376.042769 -374.490638) (xy 376.026801 -374.556018)
			(xy 376.003134 -374.619021) (xy 375.972107 -374.678743) (xy 375.934164 -374.734329) (xy 375.91238 -374.759982)
			(xy 375.906564 -374.767113) (xy 375.900062 -374.784315) (xy 375.89968 -374.79351) (xy 375.89968 -375.286778)
			(xy 375.900105 -375.295963) (xy 375.906609 -375.313148) (xy 375.91238 -375.320306) (xy 375.934197 -375.345934)
			(xy 375.972143 -375.401524) (xy 376.003174 -375.461252) (xy 376.026845 -375.524259) (xy 376.042815 -375.589644)
			(xy 376.050856 -375.656469) (xy 376.050854 -375.723776) (xy 376.042807 -375.7906) (xy 376.026831 -375.855984)
			(xy 376.003156 -375.91899) (xy 375.97212 -375.978714) (xy 375.934169 -376.034302) (xy 375.91238 -376.059954)
			(xy 375.906576 -376.067094) (xy 375.900066 -376.084288) (xy 375.89968 -376.093482) (xy 375.89968 -376.25147)
			(xy 375.899212 -376.261637) (xy 375.89144 -376.280428) (xy 375.877068 -376.294813) (xy 375.858285 -376.302602)
			(xy 375.848118 -376.303032) (xy 375.131838 -376.303032) (xy 375.121665 -376.302604) (xy 375.102866 -376.294826)
			(xy 375.088478 -376.280441) (xy 375.080697 -376.261643) (xy 375.080276 -376.25147) (xy 375.080276 -376.093482)
			(xy 375.07988 -376.084293) (xy 375.073357 -376.067109) (xy 375.067576 -376.059954) (xy 375.045817 -376.034278)
			(xy 375.007865 -375.978696) (xy 374.976828 -375.918976) (xy 374.953152 -375.855974) (xy 374.937176 -375.790595)
			(xy 374.929129 -375.723774) (xy 374.929126 -375.656471) (xy 374.937168 -375.58965) (xy 374.953138 -375.524269)
			(xy 374.97681 -375.461265) (xy 375.007841 -375.401543) (xy 375.045789 -375.345958) (xy 375.067576 -375.320306)
			(xy 375.07335 -375.313144) (xy 375.079879 -375.295967) (xy 375.080276 -375.286778) (xy 375.080276 -374.79351)
			(xy 375.079866 -374.784323) (xy 375.073353 -374.767138) (xy 375.067576 -374.759982) (xy 375.045746 -374.734365)
			(xy 375.007796 -374.678774) (xy 374.976762 -374.619046) (xy 374.95309 -374.556037) (xy 374.937119 -374.49065)
			(xy 374.929078 -374.423823) (xy 345.250779 -374.423823) (xy 345.242739 -374.49064) (xy 345.226769 -374.55602)
			(xy 345.2031 -374.619022) (xy 345.172071 -374.678745) (xy 345.134126 -374.73433) (xy 345.11234 -374.759982)
			(xy 345.106519 -374.767109) (xy 345.10002 -374.784314) (xy 345.09964 -374.79351) (xy 345.09964 -375.286778)
			(xy 345.100074 -375.295962) (xy 345.106573 -375.313146) (xy 345.11234 -375.320306) (xy 345.134158 -375.345933)
			(xy 345.172107 -375.401523) (xy 345.203141 -375.46125) (xy 345.226813 -375.524258) (xy 345.242784 -375.589643)
			(xy 345.250826 -375.656469) (xy 345.250823 -375.723776) (xy 345.242776 -375.790602) (xy 345.226799 -375.855986)
			(xy 345.203122 -375.918992) (xy 345.172084 -375.978716) (xy 345.13413 -376.034302) (xy 345.11234 -376.059954)
			(xy 345.106531 -376.06709) (xy 345.100025 -376.084288) (xy 345.09964 -376.093482) (xy 345.09964 -376.25147)
			(xy 345.099211 -376.261642) (xy 345.091432 -376.280441) (xy 345.077047 -376.294827) (xy 345.05825 -376.302609)
			(xy 345.048078 -376.303032) (xy 344.331798 -376.303032) (xy 344.321623 -376.302637) (xy 344.302822 -376.294846)
			(xy 344.288436 -376.280451) (xy 344.280657 -376.261646) (xy 344.280236 -376.25147) (xy 344.280236 -376.093482)
			(xy 344.279826 -376.084295) (xy 344.273311 -376.067111) (xy 344.267536 -376.059954) (xy 344.245778 -376.034277)
			(xy 344.207829 -375.978694) (xy 344.176794 -375.918974) (xy 344.15312 -375.855973) (xy 344.137145 -375.790594)
			(xy 344.129098 -375.723774) (xy 344.129096 -375.656471) (xy 344.137137 -375.589651) (xy 344.153106 -375.52427)
			(xy 344.176776 -375.461267) (xy 344.207805 -375.401544) (xy 344.24575 -375.345958) (xy 344.267536 -375.320306)
			(xy 344.273317 -375.31315) (xy 344.27984 -375.295968) (xy 344.280236 -375.286778) (xy 344.280236 -374.79351)
			(xy 344.279813 -374.784324) (xy 344.273308 -374.76714) (xy 344.267536 -374.759982) (xy 344.245707 -374.734364)
			(xy 344.20776 -374.678772) (xy 344.176728 -374.619044) (xy 344.153058 -374.556035) (xy 344.137088 -374.490649)
			(xy 344.129047 -374.423823) (xy 340.850988 -374.423823) (xy 340.842948 -374.490639) (xy 340.826979 -374.556019)
			(xy 340.803311 -374.619022) (xy 340.772282 -374.678744) (xy 340.734337 -374.73433) (xy 340.712552 -374.759982)
			(xy 340.706732 -374.76711) (xy 340.700233 -374.784314) (xy 340.699852 -374.79351) (xy 340.699852 -375.286778)
			(xy 340.700283 -375.295963) (xy 340.706783 -375.313147) (xy 340.712552 -375.320306) (xy 340.73437 -375.345934)
			(xy 340.772318 -375.401523) (xy 340.803351 -375.46125) (xy 340.827022 -375.524258) (xy 340.842993 -375.589643)
			(xy 340.851035 -375.656469) (xy 340.851032 -375.723776) (xy 340.842985 -375.790601) (xy 340.827009 -375.855985)
			(xy 340.803332 -375.918991) (xy 340.772295 -375.978715) (xy 340.734342 -376.034302) (xy 340.712552 -376.059954)
			(xy 340.706744 -376.067091) (xy 340.700237 -376.084288) (xy 340.699852 -376.093482) (xy 340.699852 -376.25147)
			(xy 340.699411 -376.261641) (xy 340.691634 -376.280437) (xy 340.677254 -376.294823) (xy 340.658461 -376.302607)
			(xy 340.64829 -376.303032) (xy 339.93201 -376.303032) (xy 339.921835 -376.302627) (xy 339.903035 -376.29484)
			(xy 339.888649 -376.280448) (xy 339.880869 -376.261645) (xy 339.880448 -376.25147) (xy 339.880448 -376.093482)
			(xy 339.880036 -376.084295) (xy 339.873522 -376.067111) (xy 339.867748 -376.059954) (xy 339.84599 -376.034278)
			(xy 339.808039 -375.978695) (xy 339.777004 -375.918975) (xy 339.753329 -375.855973) (xy 339.737354 -375.790594)
			(xy 339.729307 -375.723774) (xy 339.729305 -375.656471) (xy 339.737346 -375.58965) (xy 339.753316 -375.52427)
			(xy 339.776986 -375.461267) (xy 339.808016 -375.401544) (xy 339.845962 -375.345958) (xy 339.867748 -375.320306)
			(xy 339.873531 -375.313151) (xy 339.880052 -375.295968) (xy 339.880448 -375.286778) (xy 339.880448 -374.79351)
			(xy 339.880022 -374.784325) (xy 339.873518 -374.767141) (xy 339.867748 -374.759982) (xy 339.845919 -374.734364)
			(xy 339.80797 -374.678773) (xy 339.776938 -374.619045) (xy 339.753268 -374.556036) (xy 339.737297 -374.490649)
			(xy 339.729256 -374.423823) (xy 336.45122 -374.423823) (xy 336.45122 -374.423879) (xy 336.443148 -374.490815)
			(xy 336.427115 -374.556303) (xy 336.403354 -374.619398) (xy 336.372206 -374.679193) (xy 336.334119 -374.734826)
			(xy 336.312256 -374.76049) (xy 336.306433 -374.767616) (xy 336.299935 -374.784821) (xy 336.299556 -374.794018)
			(xy 336.299556 -375.28627) (xy 336.29999 -375.295454) (xy 336.306488 -375.312639) (xy 336.312256 -375.319798)
			(xy 336.334151 -375.345438) (xy 336.372242 -375.401075) (xy 336.403394 -375.460875) (xy 336.427158 -375.523975)
			(xy 336.443193 -375.589467) (xy 336.451267 -375.656409) (xy 336.451264 -375.723836) (xy 336.443185 -375.790777)
			(xy 336.427145 -375.856268) (xy 336.403375 -375.919367) (xy 336.372218 -375.979163) (xy 336.334123 -376.034797)
			(xy 336.312256 -376.060462) (xy 336.306445 -376.067597) (xy 336.29994 -376.084795) (xy 336.299556 -376.09399)
			(xy 336.299556 -376.25147) (xy 336.299049 -376.261595) (xy 336.29133 -376.280317) (xy 336.27705 -376.294674)
			(xy 336.258371 -376.302494) (xy 336.248248 -376.303032) (xy 335.531968 -376.303032) (xy 335.521816 -376.302605)
			(xy 335.503069 -376.294805) (xy 335.488748 -376.280411) (xy 335.481043 -376.261624) (xy 335.48066 -376.25147)
			(xy 335.48066 -376.09399) (xy 335.480241 -376.084804) (xy 335.473732 -376.06762) (xy 335.46796 -376.060462)
			(xy 335.446127 -376.034772) (xy 335.40804 -375.97914) (xy 335.37689 -375.919347) (xy 335.353126 -375.856253)
			(xy 335.33709 -375.790768) (xy 335.329012 -375.723833) (xy 335.329009 -375.656412) (xy 335.337082 -375.589477)
			(xy 335.353113 -375.52399) (xy 335.376872 -375.460894) (xy 335.408017 -375.401099) (xy 335.446099 -375.345464)
			(xy 335.46796 -375.319798) (xy 335.473747 -375.312647) (xy 335.480266 -375.295461) (xy 335.48066 -375.28627)
			(xy 335.48066 -374.794018) (xy 335.480228 -374.784833) (xy 335.473728 -374.76765) (xy 335.46796 -374.76049)
			(xy 335.446056 -374.734858) (xy 335.407971 -374.679218) (xy 335.376825 -374.619417) (xy 335.353065 -374.556316)
			(xy 335.337033 -374.490823) (xy 335.328961 -374.423882) (xy 332.050892 -374.423882) (xy 332.04286 -374.490639)
			(xy 332.026892 -374.556019) (xy 332.003224 -374.619021) (xy 331.972196 -374.678744) (xy 331.934253 -374.73433)
			(xy 331.912468 -374.759982) (xy 331.90665 -374.767112) (xy 331.900149 -374.784314) (xy 331.899768 -374.79351)
			(xy 331.899768 -375.286778) (xy 331.900196 -375.295963) (xy 331.906698 -375.313147) (xy 331.912468 -375.320306)
			(xy 331.934285 -375.345934) (xy 331.972233 -375.401524) (xy 332.003264 -375.461251) (xy 332.026935 -375.524259)
			(xy 332.042906 -375.589644) (xy 332.050947 -375.656469) (xy 332.050945 -375.723776) (xy 332.042898 -375.790601)
			(xy 332.026922 -375.855985) (xy 332.003246 -375.91899) (xy 331.972209 -375.978715) (xy 331.934257 -376.034302)
			(xy 331.912468 -376.059954) (xy 331.906662 -376.067092) (xy 331.900154 -376.084288) (xy 331.899768 -376.093482)
			(xy 331.899768 -376.25147) (xy 331.899312 -376.261639) (xy 331.891538 -376.280432) (xy 331.877162 -376.294817)
			(xy 331.858375 -376.302604) (xy 331.848206 -376.303032) (xy 331.131926 -376.303032) (xy 331.121752 -376.302614)
			(xy 331.102953 -376.294832) (xy 331.088566 -376.280444) (xy 331.080785 -376.261644) (xy 331.080364 -376.25147)
			(xy 331.080364 -376.093482) (xy 331.079948 -376.084296) (xy 331.073437 -376.067112) (xy 331.067664 -376.059954)
			(xy 331.045905 -376.034278) (xy 331.007954 -375.978695) (xy 330.976918 -375.918975) (xy 330.953242 -375.855974)
			(xy 330.937266 -375.790594) (xy 330.92922 -375.723774) (xy 330.929217 -375.656471) (xy 330.937258 -375.58965)
			(xy 330.953229 -375.524269) (xy 330.976899 -375.461266) (xy 331.007931 -375.401543) (xy 331.045877 -375.345958)
			(xy 331.067664 -375.320306) (xy 331.073448 -375.313152) (xy 331.079969 -375.295968) (xy 331.080364 -375.286778)
			(xy 331.080364 -374.79351) (xy 331.079935 -374.784325) (xy 331.073433 -374.767141) (xy 331.067664 -374.759982)
			(xy 331.045834 -374.734364) (xy 331.007885 -374.678773) (xy 330.976852 -374.619045) (xy 330.95318 -374.556036)
			(xy 330.93721 -374.49065) (xy 330.929168 -374.423823) (xy 301.250868 -374.423823) (xy 301.250868 -374.423878)
			(xy 301.242797 -374.490814) (xy 301.226766 -374.5563) (xy 301.203008 -374.619395) (xy 301.171863 -374.67919)
			(xy 301.133781 -374.734824) (xy 301.11192 -374.76049) (xy 301.106105 -374.767622) (xy 301.099601 -374.784823)
			(xy 301.09922 -374.794018) (xy 301.09922 -375.28627) (xy 301.09964 -375.295456) (xy 301.106146 -375.312641)
			(xy 301.11192 -375.319798) (xy 301.133813 -375.345439) (xy 301.171899 -375.401078) (xy 301.203048 -375.460877)
			(xy 301.226809 -375.523977) (xy 301.242842 -375.589469) (xy 301.250915 -375.65641) (xy 301.250912 -375.723835)
			(xy 301.242834 -375.790775) (xy 301.226796 -375.856266) (xy 301.203029 -375.919364) (xy 301.171876 -375.979161)
			(xy 301.133785 -376.034796) (xy 301.11192 -376.060462) (xy 301.106117 -376.067603) (xy 301.099605 -376.084797)
			(xy 301.09922 -376.09399) (xy 301.09922 -376.25147) (xy 301.098748 -376.2616) (xy 301.091023 -376.280328)
			(xy 301.076731 -376.294687) (xy 301.058039 -376.3025) (xy 301.047912 -376.303032) (xy 300.331632 -376.303032)
			(xy 300.321484 -376.302553) (xy 300.302738 -376.294774) (xy 300.288415 -376.280395) (xy 300.280708 -376.26162)
			(xy 300.280324 -376.25147) (xy 300.280324 -376.09399) (xy 300.279913 -376.084803) (xy 300.2734 -376.067619)
			(xy 300.267624 -376.060462) (xy 300.245789 -376.034773) (xy 300.207697 -375.979142) (xy 300.176544 -375.91935)
			(xy 300.152777 -375.856256) (xy 300.136739 -375.790769) (xy 300.12866 -375.723833) (xy 300.128658 -375.656412)
			(xy 300.136731 -375.589475) (xy 300.152764 -375.523987) (xy 300.176526 -375.460892) (xy 300.207674 -375.401096)
			(xy 300.245761 -375.345463) (xy 300.267624 -375.319798) (xy 300.273407 -375.312643) (xy 300.279929 -375.29546)
			(xy 300.280324 -375.28627) (xy 300.280324 -374.794018) (xy 300.2799 -374.784832) (xy 300.273395 -374.767648)
			(xy 300.267624 -374.76049) (xy 300.245718 -374.734859) (xy 300.207629 -374.67922) (xy 300.176479 -374.61942)
			(xy 300.152716 -374.556318) (xy 300.136683 -374.490825) (xy 300.12861 -374.423882) (xy 296.851077 -374.423882)
			(xy 296.843006 -374.490813) (xy 296.826976 -374.556299) (xy 296.803218 -374.619394) (xy 296.772074 -374.67919)
			(xy 296.733992 -374.734824) (xy 296.712132 -374.76049) (xy 296.706306 -374.767614) (xy 296.699811 -374.784821)
			(xy 296.699432 -374.794018) (xy 296.699432 -375.28627) (xy 296.699872 -375.295454) (xy 296.706366 -375.312638)
			(xy 296.712132 -375.319798) (xy 296.734024 -375.345439) (xy 296.77211 -375.401078) (xy 296.803258 -375.460878)
			(xy 296.827019 -375.523978) (xy 296.843051 -375.589469) (xy 296.851124 -375.65641) (xy 296.851121 -375.723835)
			(xy 296.843043 -375.790775) (xy 296.827005 -375.856265) (xy 296.803239 -375.919363) (xy 296.772087 -375.979161)
			(xy 296.733997 -376.034796) (xy 296.712132 -376.060462) (xy 296.706318 -376.067595) (xy 296.699816 -376.084795)
			(xy 296.699432 -376.09399) (xy 296.699432 -376.25147) (xy 296.698948 -376.261598) (xy 296.691225 -376.280324)
			(xy 296.676937 -376.294683) (xy 296.65825 -376.302498) (xy 296.648124 -376.303032) (xy 295.931844 -376.303032)
			(xy 295.921697 -376.302543) (xy 295.902951 -376.294768) (xy 295.888628 -376.280392) (xy 295.880921 -376.261619)
			(xy 295.880536 -376.25147) (xy 295.880536 -376.09399) (xy 295.880123 -376.084803) (xy 295.87361 -376.067619)
			(xy 295.867836 -376.060462) (xy 295.846 -376.034773) (xy 295.807908 -375.979143) (xy 295.776754 -375.91935)
			(xy 295.752987 -375.856256) (xy 295.736948 -375.79077) (xy 295.728869 -375.723834) (xy 295.728867 -375.656412)
			(xy 295.73694 -375.589475) (xy 295.752973 -375.523987) (xy 295.776736 -375.460891) (xy 295.807885 -375.401096)
			(xy 295.845973 -375.345463) (xy 295.867836 -375.319798) (xy 295.873621 -375.312644) (xy 295.880142 -375.29546)
			(xy 295.880536 -375.28627) (xy 295.880536 -374.794018) (xy 295.880109 -374.784833) (xy 295.873606 -374.767649)
			(xy 295.867836 -374.76049) (xy 295.84593 -374.734859) (xy 295.80784 -374.679221) (xy 295.776689 -374.61942)
			(xy 295.752925 -374.556319) (xy 295.736892 -374.490825) (xy 295.728819 -374.423882) (xy 292.450774 -374.423882)
			(xy 292.442742 -374.490639) (xy 292.426773 -374.55602) (xy 292.403104 -374.619022) (xy 292.372075 -374.678745)
			(xy 292.33413 -374.73433) (xy 292.312344 -374.759982) (xy 292.306523 -374.76711) (xy 292.300025 -374.784314)
			(xy 292.299644 -374.79351) (xy 292.299644 -375.286778) (xy 292.300077 -375.295962) (xy 292.306576 -375.313146)
			(xy 292.312344 -375.320306) (xy 292.334162 -375.345934) (xy 292.372111 -375.401523) (xy 292.403144 -375.46125)
			(xy 292.426816 -375.524258) (xy 292.442787 -375.589643) (xy 292.450829 -375.656469) (xy 292.450826 -375.723776)
			(xy 292.442779 -375.790601) (xy 292.426802 -375.855985) (xy 292.403125 -375.918991) (xy 292.372088 -375.978716)
			(xy 292.334134 -376.034302) (xy 292.312344 -376.059954) (xy 292.306535 -376.06709) (xy 292.300029 -376.084288)
			(xy 292.299644 -376.093482) (xy 292.299644 -376.25147) (xy 292.299211 -376.261642) (xy 292.291433 -376.280439)
			(xy 292.277049 -376.294826) (xy 292.258254 -376.302609) (xy 292.248082 -376.303032) (xy 291.531802 -376.303032)
			(xy 291.521627 -376.302634) (xy 291.502826 -376.294844) (xy 291.48844 -376.28045) (xy 291.480661 -376.261645)
			(xy 291.48024 -376.25147) (xy 291.48024 -376.093482) (xy 291.47983 -376.084295) (xy 291.473315 -376.067111)
			(xy 291.46754 -376.059954) (xy 291.445782 -376.034277) (xy 291.407832 -375.978695) (xy 291.376798 -375.918974)
			(xy 291.353123 -375.855973) (xy 291.337148 -375.790594) (xy 291.329101 -375.723774) (xy 291.329099 -375.656471)
			(xy 291.33714 -375.589651) (xy 291.35311 -375.52427) (xy 291.376779 -375.461267) (xy 291.407809 -375.401544)
			(xy 291.445754 -375.345958) (xy 291.46754 -375.320306) (xy 291.473322 -375.31315) (xy 291.479844 -375.295968)
			(xy 291.48024 -375.286778) (xy 291.48024 -374.79351) (xy 291.479816 -374.784324) (xy 291.473311 -374.76714)
			(xy 291.46754 -374.759982) (xy 291.445711 -374.734364) (xy 291.407763 -374.678773) (xy 291.376732 -374.619044)
			(xy 291.353061 -374.556035) (xy 291.337091 -374.490649) (xy 291.32905 -374.423823) (xy 288.051014 -374.423823)
			(xy 288.051014 -374.423879) (xy 288.042941 -374.490816) (xy 288.026909 -374.556303) (xy 288.003147 -374.619398)
			(xy 287.971998 -374.679193) (xy 287.933911 -374.734826) (xy 287.912048 -374.76049) (xy 287.906224 -374.767616)
			(xy 287.899727 -374.784821) (xy 287.899348 -374.794018) (xy 287.899348 -375.28627) (xy 287.899784 -375.295454)
			(xy 287.906281 -375.312638) (xy 287.912048 -375.319798) (xy 287.933943 -375.345438) (xy 287.972035 -375.401075)
			(xy 288.003187 -375.460874) (xy 288.026952 -375.523974) (xy 288.042987 -375.589467) (xy 288.051061 -375.656409)
			(xy 288.051058 -375.723836) (xy 288.042978 -375.790777) (xy 288.026938 -375.856269) (xy 288.003168 -375.919367)
			(xy 287.972011 -375.979164) (xy 287.933916 -376.034798) (xy 287.912048 -376.060462) (xy 287.906236 -376.067596)
			(xy 287.899732 -376.084795) (xy 287.899348 -376.09399) (xy 287.899348 -376.25147) (xy 287.898849 -376.261596)
			(xy 287.891129 -376.280319) (xy 287.876846 -376.294677) (xy 287.858164 -376.302495) (xy 287.84804 -376.303032)
			(xy 287.13176 -376.303032) (xy 287.121607 -376.302612) (xy 287.10286 -376.294809) (xy 287.088539 -376.280413)
			(xy 287.080835 -376.261625) (xy 287.080452 -376.25147) (xy 287.080452 -376.09399) (xy 287.080035 -376.084804)
			(xy 287.073525 -376.06762) (xy 287.067752 -376.060462) (xy 287.045916 -376.034773) (xy 287.007823 -375.979143)
			(xy 286.976668 -375.919351) (xy 286.9529 -375.856257) (xy 286.93686 -375.79077) (xy 286.928781 -375.723834)
			(xy 286.928779 -375.656411) (xy 286.936852 -375.589474) (xy 286.952886 -375.523986) (xy 286.976649 -375.46089)
			(xy 287.007799 -375.401095) (xy 287.045888 -375.345462) (xy 287.067752 -375.319798) (xy 287.073538 -375.312646)
			(xy 287.080058 -375.29546) (xy 287.080452 -375.28627) (xy 287.080452 -374.794018) (xy 287.080022 -374.784833)
			(xy 287.073521 -374.767649) (xy 287.067752 -374.76049) (xy 287.045845 -374.73486) (xy 287.007754 -374.679221)
			(xy 286.976602 -374.619421) (xy 286.952838 -374.556319) (xy 286.936804 -374.490825) (xy 286.928731 -374.423882)
			(xy 274.953921 -374.423882) (xy 275.095692 -374.528158) (xy 275.256029 -374.656022) (xy 275.411255 -374.790045)
			(xy 275.561134 -374.930022) (xy 275.705437 -375.07574) (xy 275.843945 -375.226977) (xy 275.976447 -375.383504)
			(xy 276.102741 -375.54508) (xy 276.222634 -375.711461) (xy 276.335945 -375.882393) (xy 276.442501 -376.057616)
			(xy 276.542138 -376.236863) (xy 276.634707 -376.419861) (xy 276.720065 -376.606332) (xy 276.798083 -376.79599)
			(xy 276.808294 -376.823856) (xy 289.128922 -376.823856) (xy 289.128922 -376.75655) (xy 289.136967 -376.689727)
			(xy 289.152941 -376.624344) (xy 289.176615 -376.56134) (xy 289.207651 -376.501617) (xy 289.245603 -376.446031)
			(xy 289.267392 -376.42038) (xy 289.273179 -376.413228) (xy 289.2797 -376.396043) (xy 289.280092 -376.386852)
			(xy 289.280092 -375.893584) (xy 289.279691 -375.884396) (xy 289.273171 -375.867212) (xy 289.267392 -375.860056)
			(xy 289.245634 -375.834379) (xy 289.207681 -375.778797) (xy 289.176643 -375.719078) (xy 289.152966 -375.656076)
			(xy 289.13699 -375.590696) (xy 289.128942 -375.523876) (xy 289.128939 -375.456572) (xy 289.136981 -375.389751)
			(xy 289.152952 -375.32437) (xy 289.176624 -375.261367) (xy 289.207656 -375.201644) (xy 289.245605 -375.146059)
			(xy 289.267392 -375.120408) (xy 289.273167 -375.113247) (xy 289.279695 -375.096069) (xy 289.280092 -375.08688)
			(xy 289.280092 -374.928638) (xy 289.280664 -374.918488) (xy 289.288417 -374.899729) (xy 289.302758 -374.885364)
			(xy 289.321505 -374.87758) (xy 289.331654 -374.877076) (xy 290.047934 -374.877076) (xy 290.058113 -374.877437)
			(xy 290.076915 -374.88524) (xy 290.0913 -374.899645) (xy 290.099077 -374.918459) (xy 290.099496 -374.928638)
			(xy 290.099496 -375.08688) (xy 290.099917 -375.096066) (xy 290.106423 -375.11325) (xy 290.112196 -375.120408)
			(xy 290.134014 -375.146035) (xy 290.17196 -375.201626) (xy 290.20299 -375.261353) (xy 290.226659 -375.324361)
			(xy 290.242629 -375.389746) (xy 290.25067 -375.456571) (xy 290.250667 -375.523878) (xy 290.24262 -375.590702)
			(xy 290.226645 -375.656085) (xy 290.20297 -375.719091) (xy 290.171935 -375.778816) (xy 290.133985 -375.834403)
			(xy 290.112196 -375.860056) (xy 290.106393 -375.867196) (xy 290.099882 -375.884391) (xy 290.099496 -375.893584)
			(xy 290.099496 -376.386852) (xy 290.09993 -376.396037) (xy 290.106427 -376.413221) (xy 290.112196 -376.42038)
			(xy 290.133987 -376.446029) (xy 290.171933 -376.501617) (xy 290.202964 -376.561341) (xy 290.226635 -376.624346)
			(xy 290.242607 -376.689728) (xy 290.25065 -376.756551) (xy 290.25065 -376.823855) (xy 290.250643 -376.823915)
			(xy 293.528715 -376.823915) (xy 293.528715 -376.756491) (xy 293.53679 -376.689554) (xy 293.552824 -376.624065)
			(xy 293.576588 -376.560968) (xy 293.607737 -376.501172) (xy 293.645825 -376.445537) (xy 293.667688 -376.419872)
			(xy 293.673478 -376.412722) (xy 293.679997 -376.395535) (xy 293.680388 -376.386344) (xy 293.680388 -375.894092)
			(xy 293.679984 -375.884904) (xy 293.673466 -375.86772) (xy 293.667688 -375.860564) (xy 293.645856 -375.834873)
			(xy 293.607767 -375.779242) (xy 293.576616 -375.719449) (xy 293.55285 -375.656355) (xy 293.536813 -375.59087)
			(xy 293.528735 -375.523934) (xy 293.528732 -375.456514) (xy 293.536804 -375.389578) (xy 293.552836 -375.324091)
			(xy 293.576596 -375.260995) (xy 293.607742 -375.2012) (xy 293.645826 -375.145565) (xy 293.667688 -375.1199)
			(xy 293.673466 -375.112741) (xy 293.679992 -375.095561) (xy 293.680388 -375.086372) (xy 293.680388 -374.928638)
			(xy 293.680956 -374.91852) (xy 293.688662 -374.89981) (xy 293.702923 -374.885454) (xy 293.721582 -374.877624)
			(xy 293.731696 -374.877076) (xy 294.447976 -374.877076) (xy 294.458126 -374.877541) (xy 294.476873 -374.885324)
			(xy 294.491196 -374.899707) (xy 294.498901 -374.918487) (xy 294.499284 -374.928638) (xy 294.499284 -375.086372)
			(xy 294.499711 -375.095557) (xy 294.506214 -375.112742) (xy 294.511984 -375.1199) (xy 294.53388 -375.145539)
			(xy 294.571969 -375.201177) (xy 294.603119 -375.260977) (xy 294.626882 -375.324077) (xy 294.642916 -375.389569)
			(xy 294.650989 -375.456511) (xy 294.650986 -375.523937) (xy 294.642907 -375.590878) (xy 294.626868 -375.656369)
			(xy 294.603099 -375.719467) (xy 294.571944 -375.779264) (xy 294.53385 -375.834899) (xy 294.511984 -375.860564)
			(xy 294.506176 -375.867701) (xy 294.499669 -375.884898) (xy 294.499284 -375.894092) (xy 294.499284 -376.386344)
			(xy 294.499677 -376.395533) (xy 294.506203 -376.412717) (xy 294.511984 -376.419872) (xy 294.533852 -376.445534)
			(xy 294.571942 -376.501168) (xy 294.603094 -376.560965) (xy 294.626858 -376.624062) (xy 294.642894 -376.689552)
			(xy 294.65097 -376.756491) (xy 294.650969 -376.823856) (xy 297.92901 -376.823856) (xy 297.92901 -376.75655)
			(xy 297.937054 -376.689727) (xy 297.953028 -376.624345) (xy 297.976702 -376.56134) (xy 298.007737 -376.501617)
			(xy 298.045687 -376.446032) (xy 298.067476 -376.42038) (xy 298.073261 -376.413226) (xy 298.079783 -376.396042)
			(xy 298.080176 -376.386852) (xy 298.080176 -375.893584) (xy 298.079779 -375.884395) (xy 298.073257 -375.867211)
			(xy 298.067476 -375.860056) (xy 298.045719 -375.834378) (xy 298.007766 -375.778797) (xy 297.97673 -375.719077)
			(xy 297.953054 -375.656076) (xy 297.937077 -375.590696) (xy 297.92903 -375.523876) (xy 297.929027 -375.456572)
			(xy 297.937069 -375.389751) (xy 297.953039 -375.324371) (xy 297.97671 -375.261367) (xy 298.007742 -375.201645)
			(xy 298.045689 -375.14606) (xy 298.067476 -375.120408) (xy 298.073249 -375.113246) (xy 298.079778 -375.096068)
			(xy 298.080176 -375.08688) (xy 298.080176 -374.928638) (xy 298.080596 -374.918464) (xy 298.088376 -374.899663)
			(xy 298.102763 -374.885276) (xy 298.121564 -374.877496) (xy 298.131738 -374.877076) (xy 298.848018 -374.877076)
			(xy 298.858195 -374.87745) (xy 298.876998 -374.885248) (xy 298.891383 -374.899649) (xy 298.899161 -374.91846)
			(xy 298.89958 -374.928638) (xy 298.89958 -375.08688) (xy 298.900004 -375.096066) (xy 298.906509 -375.11325)
			(xy 298.91228 -375.120408) (xy 298.934099 -375.146035) (xy 298.972045 -375.201625) (xy 299.003076 -375.261352)
			(xy 299.026746 -375.32436) (xy 299.042716 -375.389745) (xy 299.050758 -375.45657) (xy 299.050755 -375.523878)
			(xy 299.042708 -375.590702) (xy 299.026732 -375.656086) (xy 299.003056 -375.719092) (xy 298.972021 -375.778816)
			(xy 298.934069 -375.834404) (xy 298.91228 -375.860056) (xy 298.906475 -375.867195) (xy 298.899966 -375.88439)
			(xy 298.89958 -375.893584) (xy 298.89958 -376.386852) (xy 298.900018 -376.396036) (xy 298.906513 -376.413221)
			(xy 298.91228 -376.42038) (xy 298.934071 -376.446029) (xy 298.972019 -376.501616) (xy 299.003051 -376.561341)
			(xy 299.026722 -376.624345) (xy 299.042695 -376.689728) (xy 299.050731 -376.756492) (xy 302.328802 -376.756492)
			(xy 302.336877 -376.689554) (xy 302.352912 -376.624066) (xy 302.376674 -376.560969) (xy 302.407823 -376.501173)
			(xy 302.445909 -376.445538) (xy 302.467772 -376.419872) (xy 302.473572 -376.412729) (xy 302.480082 -376.395537)
			(xy 302.480472 -376.386344) (xy 302.480472 -375.894092) (xy 302.480072 -375.884904) (xy 302.473552 -375.867719)
			(xy 302.467772 -375.860564) (xy 302.44594 -375.834872) (xy 302.407853 -375.779241) (xy 302.376702 -375.719448)
			(xy 302.352937 -375.656355) (xy 302.336901 -375.590869) (xy 302.328823 -375.523934) (xy 302.32882 -375.456514)
			(xy 302.336892 -375.389578) (xy 302.352923 -375.324091) (xy 302.376682 -375.260996) (xy 302.407828 -375.2012)
			(xy 302.445911 -375.145566) (xy 302.467772 -375.1199) (xy 302.47356 -375.112749) (xy 302.480078 -375.095563)
			(xy 302.480472 -375.086372) (xy 302.480472 -374.928638) (xy 302.480959 -374.91851) (xy 302.48868 -374.899784)
			(xy 302.502967 -374.885425) (xy 302.521654 -374.87761) (xy 302.53178 -374.877076) (xy 303.24806 -374.877076)
			(xy 303.258209 -374.877554) (xy 303.276955 -374.885332) (xy 303.291279 -374.899711) (xy 303.298985 -374.918488)
			(xy 303.299368 -374.928638) (xy 303.299368 -375.086372) (xy 303.299799 -375.095557) (xy 303.306299 -375.112741)
			(xy 303.312068 -375.1199) (xy 303.333965 -375.145539) (xy 303.372054 -375.201176) (xy 303.403205 -375.260976)
			(xy 303.426969 -375.324076) (xy 303.443004 -375.389569) (xy 303.451077 -375.456511) (xy 303.451074 -375.523937)
			(xy 303.442995 -375.590878) (xy 303.426955 -375.65637) (xy 303.403186 -375.719468) (xy 303.37203 -375.779265)
			(xy 303.333935 -375.834899) (xy 303.312068 -375.860564) (xy 303.306258 -375.867699) (xy 303.299752 -375.884898)
			(xy 303.299368 -375.894092) (xy 303.299368 -376.386344) (xy 303.299764 -376.395533) (xy 303.306288 -376.412716)
			(xy 303.312068 -376.419872) (xy 303.333937 -376.445533) (xy 303.372028 -376.501168) (xy 303.40318 -376.560964)
			(xy 303.426945 -376.624062) (xy 303.442982 -376.689551) (xy 303.451058 -376.756491) (xy 303.451057 -376.823915)
			(xy 333.128833 -376.823915) (xy 333.128833 -376.756491) (xy 333.136908 -376.689553) (xy 333.152944 -376.624064)
			(xy 333.176708 -376.560967) (xy 333.207859 -376.501171) (xy 333.245948 -376.445537) (xy 333.267812 -376.419872)
			(xy 333.273604 -376.412724) (xy 333.280121 -376.395536) (xy 333.280512 -376.386344) (xy 333.280512 -375.894092)
			(xy 333.280103 -375.884905) (xy 333.273588 -375.86772) (xy 333.267812 -375.860564) (xy 333.245979 -375.834873)
			(xy 333.207889 -375.779242) (xy 333.176736 -375.71945) (xy 333.152969 -375.656356) (xy 333.136931 -375.59087)
			(xy 333.128853 -375.523935) (xy 333.12885 -375.456513) (xy 333.136923 -375.389577) (xy 333.152955 -375.32409)
			(xy 333.176716 -375.260994) (xy 333.207864 -375.201199) (xy 333.24595 -375.145565) (xy 333.267812 -375.1199)
			(xy 333.273592 -375.112743) (xy 333.280116 -375.095562) (xy 333.280512 -375.086372) (xy 333.280512 -374.928638)
			(xy 333.281057 -374.918517) (xy 333.288767 -374.899802) (xy 333.303035 -374.885446) (xy 333.321702 -374.87762)
			(xy 333.33182 -374.877076) (xy 334.0481 -374.877076) (xy 334.058251 -374.877521) (xy 334.076999 -374.885312)
			(xy 334.091321 -374.899701) (xy 334.099025 -374.918485) (xy 334.099408 -374.928638) (xy 334.099408 -375.086372)
			(xy 334.09983 -375.095558) (xy 334.106335 -375.112743) (xy 334.112108 -375.1199) (xy 334.134003 -375.145539)
			(xy 334.17209 -375.201178) (xy 334.203239 -375.260978) (xy 334.227001 -375.324078) (xy 334.243034 -375.38957)
			(xy 334.251107 -375.456511) (xy 334.251105 -375.523937) (xy 334.243026 -375.590877) (xy 334.226987 -375.656368)
			(xy 334.20322 -375.719466) (xy 334.172066 -375.779263) (xy 334.133974 -375.834899) (xy 334.112108 -375.860564)
			(xy 334.106303 -375.867703) (xy 334.099793 -375.884898) (xy 334.099408 -375.894092) (xy 334.099408 -376.386344)
			(xy 334.099795 -376.395534) (xy 334.106324 -376.412718) (xy 334.112108 -376.419872) (xy 334.133976 -376.445534)
			(xy 334.172064 -376.501169) (xy 334.203214 -376.560966) (xy 334.226977 -376.624063) (xy 334.243012 -376.689553)
			(xy 334.251088 -376.756491) (xy 334.251087 -376.823855) (xy 337.529152 -376.823855) (xy 337.529152 -376.756551)
			(xy 337.537195 -376.689729) (xy 337.553167 -376.624348) (xy 337.576837 -376.561344) (xy 337.607868 -376.50162)
			(xy 337.645814 -376.446033) (xy 337.6676 -376.42038) (xy 337.673388 -376.413228) (xy 337.679908 -376.396043)
			(xy 337.6803 -376.386852) (xy 337.6803 -375.893584) (xy 337.679897 -375.884396) (xy 337.673378 -375.867212)
			(xy 337.6676 -375.860056) (xy 337.645845 -375.834377) (xy 337.607898 -375.778794) (xy 337.576865 -375.719074)
			(xy 337.553192 -375.656073) (xy 337.537218 -375.590694) (xy 337.529172 -375.523875) (xy 337.529169 -375.456573)
			(xy 337.53721 -375.389753) (xy 337.553178 -375.324373) (xy 337.576846 -375.26137) (xy 337.607873 -375.201647)
			(xy 337.645815 -375.146061) (xy 337.6676 -375.120408) (xy 337.673376 -375.113248) (xy 337.679903 -375.096069)
			(xy 337.6803 -375.08688) (xy 337.6803 -374.928638) (xy 337.680864 -374.918487) (xy 337.688619 -374.899726)
			(xy 337.702963 -374.885361) (xy 337.721712 -374.877579) (xy 337.731862 -374.877076) (xy 338.448142 -374.877076)
			(xy 338.458307 -374.8775) (xy 338.477085 -374.885295) (xy 338.49145 -374.899683) (xy 338.499216 -374.918472)
			(xy 338.499704 -374.928638) (xy 338.499704 -375.08688) (xy 338.500123 -375.096066) (xy 338.50663 -375.113251)
			(xy 338.512404 -375.120408) (xy 338.534222 -375.146035) (xy 338.572167 -375.201626) (xy 338.603196 -375.261353)
			(xy 338.626865 -375.324361) (xy 338.642835 -375.389746) (xy 338.650876 -375.456571) (xy 338.650873 -375.523877)
			(xy 338.642826 -375.590701) (xy 338.626851 -375.656085) (xy 338.603177 -375.719091) (xy 338.572142 -375.778815)
			(xy 338.534192 -375.834403) (xy 338.512404 -375.860056) (xy 338.506602 -375.867197) (xy 338.50009 -375.884391)
			(xy 338.499704 -375.893584) (xy 338.499704 -376.386852) (xy 338.500136 -376.396037) (xy 338.506634 -376.413222)
			(xy 338.512404 -376.42038) (xy 338.534194 -376.44603) (xy 338.57214 -376.501617) (xy 338.603171 -376.561342)
			(xy 338.626842 -376.624346) (xy 338.642813 -376.689729) (xy 338.650856 -376.756551) (xy 338.650856 -376.823855)
			(xy 338.650849 -376.823915) (xy 341.928921 -376.823915) (xy 341.928921 -376.756491) (xy 341.936996 -376.689553)
			(xy 341.953031 -376.624065) (xy 341.976794 -376.560968) (xy 342.007944 -376.501172) (xy 342.046032 -376.445537)
			(xy 342.067896 -376.419872) (xy 342.073686 -376.412722) (xy 342.080205 -376.395535) (xy 342.080596 -376.386344)
			(xy 342.080596 -375.894092) (xy 342.08019 -375.884904) (xy 342.073674 -375.86772) (xy 342.067896 -375.860564)
			(xy 342.046064 -375.834873) (xy 342.007974 -375.779242) (xy 341.976822 -375.719449) (xy 341.953057 -375.656356)
			(xy 341.937019 -375.59087) (xy 341.928941 -375.523935) (xy 341.928938 -375.456513) (xy 341.93701 -375.389577)
			(xy 341.953042 -375.32409) (xy 341.976803 -375.260995) (xy 342.007949 -375.201199) (xy 342.046034 -375.145565)
			(xy 342.067896 -375.1199) (xy 342.073675 -375.112742) (xy 342.0802 -375.095561) (xy 342.080596 -375.086372)
			(xy 342.080596 -374.928638) (xy 342.081157 -374.918519) (xy 342.088864 -374.899807) (xy 342.103127 -374.885451)
			(xy 342.121789 -374.877623) (xy 342.131904 -374.877076) (xy 342.848184 -374.877076) (xy 342.858334 -374.877534)
			(xy 342.877082 -374.88532) (xy 342.891405 -374.899705) (xy 342.899109 -374.918486) (xy 342.899492 -374.928638)
			(xy 342.899492 -375.086372) (xy 342.899917 -375.095558) (xy 342.906421 -375.112742) (xy 342.912192 -375.1199)
			(xy 342.934088 -375.145539) (xy 342.972176 -375.201177) (xy 343.003326 -375.260977) (xy 343.027088 -375.324077)
			(xy 343.043122 -375.38957) (xy 343.051195 -375.456511) (xy 343.051193 -375.523937) (xy 343.043113 -375.590878)
			(xy 343.027074 -375.656369) (xy 343.003306 -375.719467) (xy 342.972151 -375.779264) (xy 342.934058 -375.834899)
			(xy 342.912192 -375.860564) (xy 342.906385 -375.867702) (xy 342.899877 -375.884898) (xy 342.899492 -375.894092)
			(xy 342.899492 -376.386344) (xy 342.899883 -376.395533) (xy 342.90641 -376.412717) (xy 342.912192 -376.419872)
			(xy 342.93406 -376.445534) (xy 342.972149 -376.501169) (xy 343.0033 -376.560965) (xy 343.027065 -376.624063)
			(xy 343.0431 -376.689552) (xy 343.051176 -376.756491) (xy 343.051175 -376.823856) (xy 346.329216 -376.823856)
			(xy 346.329216 -376.75655) (xy 346.33726 -376.689727) (xy 346.353234 -376.624345) (xy 346.376909 -376.56134)
			(xy 346.407944 -376.501617) (xy 346.445895 -376.446032) (xy 346.467684 -376.42038) (xy 346.47347 -376.413227)
			(xy 346.479991 -376.396043) (xy 346.480384 -376.386852) (xy 346.480384 -375.893584) (xy 346.479985 -375.884396)
			(xy 346.473464 -375.867211) (xy 346.467684 -375.860056) (xy 346.445926 -375.834379) (xy 346.407974 -375.778797)
			(xy 346.376937 -375.719077) (xy 346.35326 -375.656076) (xy 346.337283 -375.590696) (xy 346.329236 -375.523876)
			(xy 346.329233 -375.456572) (xy 346.337275 -375.389751) (xy 346.353246 -375.32437) (xy 346.376917 -375.261367)
			(xy 346.407949 -375.201645) (xy 346.445897 -375.14606) (xy 346.467684 -375.120408) (xy 346.473458 -375.113247)
			(xy 346.479987 -375.096069) (xy 346.480384 -375.08688) (xy 346.480384 -374.928638) (xy 346.480796 -374.918463)
			(xy 346.488577 -374.899661) (xy 346.502967 -374.885273) (xy 346.521771 -374.877495) (xy 346.531946 -374.877076)
			(xy 347.248226 -374.877076) (xy 347.258404 -374.877443) (xy 347.277207 -374.885244) (xy 347.291592 -374.899647)
			(xy 347.299369 -374.918459) (xy 347.299788 -374.928638) (xy 347.299788 -375.08688) (xy 347.300211 -375.096066)
			(xy 347.306716 -375.11325) (xy 347.312488 -375.120408) (xy 347.334306 -375.146035) (xy 347.372252 -375.201625)
			(xy 347.403283 -375.261353) (xy 347.426953 -375.324361) (xy 347.442923 -375.389746) (xy 347.450964 -375.456571)
			(xy 347.450961 -375.523878) (xy 347.442914 -375.590702) (xy 347.426938 -375.656086) (xy 347.403263 -375.719091)
			(xy 347.372228 -375.778816) (xy 347.334277 -375.834403) (xy 347.312488 -375.860056) (xy 347.306684 -375.867196)
			(xy 347.300174 -375.88439) (xy 347.299788 -375.893584) (xy 347.299788 -376.386852) (xy 347.300224 -376.396036)
			(xy 347.30672 -376.413221) (xy 347.312488 -376.42038) (xy 347.334279 -376.446029) (xy 347.372226 -376.501617)
			(xy 347.403257 -376.561341) (xy 347.426929 -376.624346) (xy 347.442901 -376.689728) (xy 347.450944 -376.756551)
			(xy 347.450944 -376.823855) (xy 347.450937 -376.823915) (xy 377.128742 -376.823915) (xy 377.128742 -376.756491)
			(xy 377.136817 -376.689553) (xy 377.152853 -376.624064) (xy 377.176618 -376.560967) (xy 377.20777 -376.501171)
			(xy 377.245859 -376.445537) (xy 377.267724 -376.419872) (xy 377.273518 -376.412725) (xy 377.280033 -376.395536)
			(xy 377.280424 -376.386344) (xy 377.280424 -375.894092) (xy 377.280012 -375.884905) (xy 377.273499 -375.867721)
			(xy 377.267724 -375.860564) (xy 377.245891 -375.834873) (xy 377.207799 -375.779243) (xy 377.176646 -375.71945)
			(xy 377.152879 -375.656357) (xy 377.136841 -375.590871) (xy 377.128762 -375.523935) (xy 377.128759 -375.456513)
			(xy 377.136832 -375.389577) (xy 377.152865 -375.324089) (xy 377.176626 -375.260993) (xy 377.207775 -375.201198)
			(xy 377.245861 -375.145565) (xy 377.267724 -375.1199) (xy 377.273506 -375.112744) (xy 377.280029 -375.095562)
			(xy 377.280424 -375.086372) (xy 377.280424 -374.928638) (xy 377.280957 -374.918516) (xy 377.28867 -374.899799)
			(xy 377.302942 -374.885442) (xy 377.321613 -374.877618) (xy 377.331732 -374.877076) (xy 378.048012 -374.877076)
			(xy 378.058164 -374.877511) (xy 378.076912 -374.885306) (xy 378.091234 -374.899698) (xy 378.098938 -374.918484)
			(xy 378.09932 -374.928638) (xy 378.09932 -375.086372) (xy 378.099739 -375.095558) (xy 378.106246 -375.112743)
			(xy 378.11202 -375.1199) (xy 378.133915 -375.14554) (xy 378.172001 -375.201178) (xy 378.203149 -375.260978)
			(xy 378.226911 -375.324078) (xy 378.242943 -375.38957) (xy 378.251016 -375.456511) (xy 378.251014 -375.523937)
			(xy 378.242935 -375.590877) (xy 378.226897 -375.656368) (xy 378.20313 -375.719466) (xy 378.171976 -375.779263)
			(xy 378.133885 -375.834898) (xy 378.11202 -375.860564) (xy 378.106216 -375.867704) (xy 378.099705 -375.884898)
			(xy 378.09932 -375.894092) (xy 378.09932 -376.386344) (xy 378.099704 -376.395534) (xy 378.106235 -376.412718)
			(xy 378.11202 -376.419872) (xy 378.133887 -376.445534) (xy 378.171974 -376.50117) (xy 378.203124 -376.560967)
			(xy 378.226887 -376.624064) (xy 378.242922 -376.689553) (xy 378.250997 -376.756491) (xy 378.250997 -376.756551)
			(xy 381.529061 -376.756551) (xy 381.537105 -376.689729) (xy 381.553076 -376.624347) (xy 381.576747 -376.561343)
			(xy 381.607779 -376.501619) (xy 381.645725 -376.446032) (xy 381.667512 -376.42038) (xy 381.673301 -376.413229)
			(xy 381.67982 -376.396043) (xy 381.680212 -376.386852) (xy 381.680212 -375.893584) (xy 381.679807 -375.884396)
			(xy 381.67329 -375.867212) (xy 381.667512 -375.860056) (xy 381.645756 -375.834378) (xy 381.607808 -375.778794)
			(xy 381.576775 -375.719074) (xy 381.553102 -375.656073) (xy 381.537127 -375.590694) (xy 381.529081 -375.523875)
			(xy 381.529078 -375.456573) (xy 381.537119 -375.389753) (xy 381.553088 -375.324373) (xy 381.576756 -375.26137)
			(xy 381.607784 -375.201647) (xy 381.645727 -375.14606) (xy 381.667512 -375.120408) (xy 381.673289 -375.113249)
			(xy 381.679815 -375.096069) (xy 381.680212 -375.08688) (xy 381.680212 -374.928638) (xy 381.680694 -374.918472)
			(xy 381.688462 -374.899683) (xy 381.702829 -374.885298) (xy 381.721609 -374.877507) (xy 381.731774 -374.877076)
			(xy 382.448054 -374.877076) (xy 382.458227 -374.877502) (xy 382.477028 -374.885279) (xy 382.491416 -374.899665)
			(xy 382.499196 -374.918465) (xy 382.499616 -374.928638) (xy 382.499616 -375.08688) (xy 382.500032 -375.096067)
			(xy 382.506541 -375.113251) (xy 382.512316 -375.120408) (xy 382.534136 -375.146034) (xy 382.572087 -375.201623)
			(xy 382.603122 -375.26135) (xy 382.626795 -375.324358) (xy 382.642767 -375.389744) (xy 382.650809 -375.45657)
			(xy 382.650806 -375.523878) (xy 382.642758 -375.590704) (xy 382.62678 -375.656088) (xy 382.603102 -375.719094)
			(xy 382.572063 -375.778818) (xy 382.534107 -375.834404) (xy 382.512316 -375.860056) (xy 382.506515 -375.867198)
			(xy 382.500002 -375.884391) (xy 382.499616 -375.893584) (xy 382.499616 -376.386852) (xy 382.500045 -376.396037)
			(xy 382.506545 -376.413222) (xy 382.512316 -376.42038) (xy 382.534109 -376.446028) (xy 382.572061 -376.501614)
			(xy 382.603096 -376.561338) (xy 382.626771 -376.624343) (xy 382.642745 -376.689726) (xy 382.650789 -376.75655)
			(xy 382.650789 -376.823856) (xy 382.650782 -376.823915) (xy 385.92883 -376.823915) (xy 385.92883 -376.756491)
			(xy 385.936905 -376.689553) (xy 385.95294 -376.624064) (xy 385.976705 -376.560967) (xy 386.007855 -376.501171)
			(xy 386.045944 -376.445537) (xy 386.067808 -376.419872) (xy 386.0736 -376.412724) (xy 386.080117 -376.395535)
			(xy 386.080508 -376.386344) (xy 386.080508 -375.894092) (xy 386.0801 -375.884905) (xy 386.073584 -375.867721)
			(xy 386.067808 -375.860564) (xy 386.045975 -375.834873) (xy 386.007885 -375.779242) (xy 385.976732 -375.71945)
			(xy 385.952966 -375.656356) (xy 385.936928 -375.59087) (xy 385.92885 -375.523935) (xy 385.928847 -375.456513)
			(xy 385.93692 -375.389577) (xy 385.952952 -375.32409) (xy 385.976713 -375.260994) (xy 386.00786 -375.201199)
			(xy 386.045946 -375.145565) (xy 386.067808 -375.1199) (xy 386.073588 -375.112743) (xy 386.080112 -375.095562)
			(xy 386.080508 -375.086372) (xy 386.080508 -374.928638) (xy 386.081057 -374.918518) (xy 386.088766 -374.899804)
			(xy 386.103033 -374.885447) (xy 386.121699 -374.877621) (xy 386.131816 -374.877076) (xy 386.848096 -374.877076)
			(xy 386.858247 -374.877524) (xy 386.876995 -374.885314) (xy 386.891317 -374.899702) (xy 386.899021 -374.918485)
			(xy 386.899404 -374.928638) (xy 386.899404 -375.086372) (xy 386.899827 -375.095558) (xy 386.906332 -375.112742)
			(xy 386.912104 -375.1199) (xy 386.933999 -375.145539) (xy 386.972087 -375.201178) (xy 387.003236 -375.260978)
			(xy 387.026998 -375.324078) (xy 387.043031 -375.38957) (xy 387.051104 -375.456511) (xy 387.051102 -375.523937)
			(xy 387.043023 -375.590877) (xy 387.026984 -375.656368) (xy 387.003216 -375.719466) (xy 386.972062 -375.779264)
			(xy 386.93397 -375.834899) (xy 386.912104 -375.860564) (xy 386.906298 -375.867703) (xy 386.899789 -375.884898)
			(xy 386.899404 -375.894092) (xy 386.899404 -376.386344) (xy 386.899792 -376.395534) (xy 386.906321 -376.412718)
			(xy 386.912104 -376.419872) (xy 386.933972 -376.445534) (xy 386.97206 -376.501169) (xy 387.00321 -376.560966)
			(xy 387.026974 -376.624063) (xy 387.043009 -376.689552) (xy 387.051085 -376.756491) (xy 387.051084 -376.823855)
			(xy 390.329149 -376.823855) (xy 390.329149 -376.756551) (xy 390.337192 -376.689729) (xy 390.353163 -376.624348)
			(xy 390.376834 -376.561344) (xy 390.407864 -376.50162) (xy 390.44581 -376.446033) (xy 390.467596 -376.42038)
			(xy 390.473383 -376.413228) (xy 390.479904 -376.396043) (xy 390.480296 -376.386852) (xy 390.480296 -375.893584)
			(xy 390.479894 -375.884396) (xy 390.473375 -375.867212) (xy 390.467596 -375.860056) (xy 390.445841 -375.834377)
			(xy 390.407894 -375.778794) (xy 390.376862 -375.719073) (xy 390.353189 -375.656072) (xy 390.337215 -375.590694)
			(xy 390.329169 -375.523875) (xy 390.329166 -375.456573) (xy 390.337207 -375.389754) (xy 390.353175 -375.324374)
			(xy 390.376842 -375.261371) (xy 390.407869 -375.201648) (xy 390.445812 -375.146061) (xy 390.467596 -375.120408)
			(xy 390.473371 -375.113248) (xy 390.479899 -375.096069) (xy 390.480296 -375.08688) (xy 390.480296 -374.928638)
			(xy 390.480864 -374.918488) (xy 390.488618 -374.899728) (xy 390.502961 -374.885363) (xy 390.521709 -374.877579)
			(xy 390.531858 -374.877076) (xy 391.248138 -374.877076) (xy 391.258303 -374.877503) (xy 391.27708 -374.885297)
			(xy 391.291445 -374.899684) (xy 391.299212 -374.918472) (xy 391.2997 -374.928638) (xy 391.2997 -375.08688)
			(xy 391.30012 -375.096066) (xy 391.306627 -375.113251) (xy 391.3124 -375.120408) (xy 391.334218 -375.146035)
			(xy 391.372163 -375.201626) (xy 391.403193 -375.261353) (xy 391.426862 -375.324361) (xy 391.442832 -375.389746)
			(xy 391.450873 -375.456571) (xy 391.45087 -375.523877) (xy 391.442823 -375.590702) (xy 391.426848 -375.656085)
			(xy 391.403173 -375.719091) (xy 391.372139 -375.778816) (xy 391.334188 -375.834403) (xy 391.3124 -375.860056)
			(xy 391.306597 -375.867197) (xy 391.300086 -375.884391) (xy 391.2997 -375.893584) (xy 391.2997 -376.386852)
			(xy 391.300133 -376.396037) (xy 391.306631 -376.413221) (xy 391.3124 -376.42038) (xy 391.33419 -376.446029)
			(xy 391.372137 -376.501617) (xy 391.403168 -376.561342) (xy 391.426838 -376.624346) (xy 391.44281 -376.689728)
			(xy 391.450853 -376.756551) (xy 391.450853 -376.823855) (xy 391.450846 -376.823915) (xy 421.128651 -376.823915)
			(xy 421.128651 -376.756491) (xy 421.136727 -376.689552) (xy 421.152763 -376.624063) (xy 421.176528 -376.560966)
			(xy 421.20768 -376.50117) (xy 421.245771 -376.445537) (xy 421.267636 -376.419872) (xy 421.273432 -376.412726)
			(xy 421.279946 -376.395536) (xy 421.280336 -376.386344) (xy 421.280336 -375.894092) (xy 421.279922 -375.884905)
			(xy 421.27341 -375.867721) (xy 421.267636 -375.860564) (xy 421.245802 -375.834873) (xy 421.20771 -375.779243)
			(xy 421.176556 -375.719451) (xy 421.152788 -375.656357) (xy 421.13675 -375.590871) (xy 421.128671 -375.523935)
			(xy 421.128668 -375.456513) (xy 421.136741 -375.389576) (xy 421.152774 -375.324089) (xy 421.176536 -375.260993)
			(xy 421.207685 -375.201198) (xy 421.245773 -375.145565) (xy 421.267636 -375.1199) (xy 421.27342 -375.112746)
			(xy 421.279941 -375.095562) (xy 421.280336 -375.086372) (xy 421.280336 -374.928638) (xy 421.280858 -374.918514)
			(xy 421.288572 -374.899795) (xy 421.302848 -374.885437) (xy 421.321523 -374.877616) (xy 421.331644 -374.877076)
			(xy 422.047924 -374.877076) (xy 422.058077 -374.877501) (xy 422.076825 -374.8853) (xy 422.091147 -374.899695)
			(xy 422.09885 -374.918483) (xy 422.099232 -374.928638) (xy 422.099232 -375.086372) (xy 422.099671 -375.095556)
			(xy 422.106166 -375.11274) (xy 422.111932 -375.1199) (xy 422.133826 -375.14554) (xy 422.171912 -375.201179)
			(xy 422.203059 -375.260979) (xy 422.22682 -375.324079) (xy 422.242853 -375.389571) (xy 422.250926 -375.456511)
			(xy 422.250923 -375.523937) (xy 422.242844 -375.590877) (xy 422.226806 -375.656367) (xy 422.20304 -375.719465)
			(xy 422.171887 -375.779263) (xy 422.133797 -375.834898) (xy 422.111932 -375.860564) (xy 422.106117 -375.867696)
			(xy 422.099615 -375.884897) (xy 422.099232 -375.894092) (xy 422.099232 -376.386344) (xy 422.099636 -376.395532)
			(xy 422.106156 -376.412715) (xy 422.111932 -376.419872) (xy 422.133799 -376.445535) (xy 422.171885 -376.50117)
			(xy 422.203034 -376.560967) (xy 422.226797 -376.624064) (xy 422.242831 -376.689553) (xy 422.250906 -376.756491)
			(xy 422.250906 -376.756551) (xy 425.52897 -376.756551) (xy 425.537014 -376.689729) (xy 425.552986 -376.624347)
			(xy 425.576658 -376.561343) (xy 425.607689 -376.501619) (xy 425.645637 -376.446032) (xy 425.667424 -376.42038)
			(xy 425.673214 -376.413231) (xy 425.679732 -376.396043) (xy 425.680124 -376.386852) (xy 425.680124 -375.893584)
			(xy 425.679716 -375.884397) (xy 425.6732 -375.867213) (xy 425.667424 -375.860056) (xy 425.645668 -375.834378)
			(xy 425.60772 -375.778795) (xy 425.576686 -375.719074) (xy 425.553012 -375.656073) (xy 425.537037 -375.590695)
			(xy 425.528991 -375.523875) (xy 425.528988 -375.456573) (xy 425.537029 -375.389753) (xy 425.552998 -375.324373)
			(xy 425.576666 -375.26137) (xy 425.607695 -375.201647) (xy 425.645639 -375.146061) (xy 425.667424 -375.120408)
			(xy 425.673202 -375.11325) (xy 425.679727 -375.096069) (xy 425.680124 -375.08688) (xy 425.680124 -374.928638)
			(xy 425.680595 -374.918471) (xy 425.688365 -374.899679) (xy 425.702736 -374.885294) (xy 425.721519 -374.877505)
			(xy 425.731686 -374.877076) (xy 426.447966 -374.877076) (xy 426.45814 -374.877493) (xy 426.476941 -374.885274)
			(xy 426.491329 -374.899662) (xy 426.499108 -374.918464) (xy 426.499528 -374.928638) (xy 426.499528 -375.08688)
			(xy 426.499941 -375.096067) (xy 426.506452 -375.113252) (xy 426.512228 -375.120408) (xy 426.534048 -375.146034)
			(xy 426.571998 -375.201623) (xy 426.603032 -375.26135) (xy 426.626705 -375.324358) (xy 426.642676 -375.389744)
			(xy 426.650718 -375.45657) (xy 426.650716 -375.523878) (xy 426.642668 -375.590704) (xy 426.62669 -375.656088)
			(xy 426.603013 -375.719094) (xy 426.571974 -375.778818) (xy 426.534019 -375.834404) (xy 426.512228 -375.860056)
			(xy 426.506416 -375.86719) (xy 426.499913 -375.884389) (xy 426.499528 -375.893584) (xy 426.499528 -376.386852)
			(xy 426.499955 -376.396037) (xy 426.506456 -376.413222) (xy 426.512228 -376.42038) (xy 426.534021 -376.446029)
			(xy 426.571971 -376.501615) (xy 426.603006 -376.561338) (xy 426.62668 -376.624344) (xy 426.642654 -376.689727)
			(xy 426.650698 -376.75655) (xy 426.650698 -376.823856) (xy 426.650691 -376.823915) (xy 429.928739 -376.823915)
			(xy 429.928739 -376.756491) (xy 429.936814 -376.689553) (xy 429.95285 -376.624064) (xy 429.976615 -376.560967)
			(xy 430.007766 -376.501171) (xy 430.045856 -376.445537) (xy 430.06772 -376.419872) (xy 430.073513 -376.412725)
			(xy 430.080029 -376.395536) (xy 430.08042 -376.386344) (xy 430.08042 -375.894092) (xy 430.080009 -375.884905)
			(xy 430.073496 -375.867721) (xy 430.06772 -375.860564) (xy 430.045887 -375.834873) (xy 430.007796 -375.779243)
			(xy 429.976643 -375.71945) (xy 429.952876 -375.656357) (xy 429.936837 -375.590871) (xy 429.928759 -375.523935)
			(xy 429.928756 -375.456513) (xy 429.936829 -375.389577) (xy 429.952861 -375.324089) (xy 429.976623 -375.260994)
			(xy 430.007771 -375.201199) (xy 430.045857 -375.145565) (xy 430.06772 -375.1199) (xy 430.073501 -375.112744)
			(xy 430.080024 -375.095562) (xy 430.08042 -375.086372) (xy 430.08042 -374.928638) (xy 430.080957 -374.918516)
			(xy 430.088669 -374.8998) (xy 430.10294 -374.885443) (xy 430.121609 -374.877619) (xy 430.131728 -374.877076)
			(xy 430.848008 -374.877076) (xy 430.85816 -374.877515) (xy 430.876907 -374.885308) (xy 430.89123 -374.899699)
			(xy 430.898933 -374.918484) (xy 430.899316 -374.928638) (xy 430.899316 -375.086372) (xy 430.899736 -375.095558)
			(xy 430.906242 -375.112743) (xy 430.912016 -375.1199) (xy 430.933911 -375.14554) (xy 430.971998 -375.201178)
			(xy 431.003146 -375.260978) (xy 431.026908 -375.324078) (xy 431.04294 -375.38957) (xy 431.051013 -375.456511)
			(xy 431.051011 -375.523937) (xy 431.042932 -375.590877) (xy 431.026893 -375.656368) (xy 431.003126 -375.719466)
			(xy 430.971973 -375.779263) (xy 430.933881 -375.834898) (xy 430.912016 -375.860564) (xy 430.906212 -375.867704)
			(xy 430.899701 -375.884898) (xy 430.899316 -375.894092) (xy 430.899316 -376.386344) (xy 430.899701 -376.395534)
			(xy 430.906232 -376.412718) (xy 430.912016 -376.419872) (xy 430.933883 -376.445534) (xy 430.971971 -376.50117)
			(xy 431.003121 -376.560966) (xy 431.026884 -376.624064) (xy 431.042918 -376.689553) (xy 431.050994 -376.756491)
			(xy 431.050994 -376.756551) (xy 434.329058 -376.756551) (xy 434.337101 -376.689729) (xy 434.353073 -376.624348)
			(xy 434.376744 -376.561343) (xy 434.407775 -376.50162) (xy 434.445721 -376.446033) (xy 434.467508 -376.42038)
			(xy 434.473296 -376.413229) (xy 434.479816 -376.396043) (xy 434.480208 -376.386852) (xy 434.480208 -375.893584)
			(xy 434.479804 -375.884396) (xy 434.473286 -375.867212) (xy 434.467508 -375.860056) (xy 434.445753 -375.834378)
			(xy 434.407805 -375.778794) (xy 434.376772 -375.719074) (xy 434.353099 -375.656073) (xy 434.337124 -375.590694)
			(xy 434.329078 -375.523875) (xy 434.329075 -375.456573) (xy 434.337116 -375.389753) (xy 434.353084 -375.324373)
			(xy 434.376752 -375.26137) (xy 434.40778 -375.201647) (xy 434.445723 -375.146061) (xy 434.467508 -375.120408)
			(xy 434.473285 -375.113249) (xy 434.479811 -375.096069) (xy 434.480208 -375.08688) (xy 434.480208 -374.928638)
			(xy 434.480694 -374.918473) (xy 434.488461 -374.899684) (xy 434.502827 -374.885299) (xy 434.521605 -374.877508)
			(xy 434.53177 -374.877076) (xy 435.24805 -374.877076) (xy 435.258223 -374.877506) (xy 435.277024 -374.885281)
			(xy 435.291412 -374.899666) (xy 435.299192 -374.918465) (xy 435.299612 -374.928638) (xy 435.299612 -375.08688)
			(xy 435.300029 -375.096067) (xy 435.306538 -375.113251) (xy 435.312312 -375.120408) (xy 435.334133 -375.146034)
			(xy 435.372084 -375.201623) (xy 435.403118 -375.26135) (xy 435.426791 -375.324358) (xy 435.442764 -375.389744)
			(xy 435.450806 -375.45657) (xy 435.450803 -375.523878) (xy 435.442755 -375.590704) (xy 435.426777 -375.656088)
			(xy 435.403099 -375.719094) (xy 435.372059 -375.778819) (xy 435.334103 -375.834404) (xy 435.312312 -375.860056)
			(xy 435.306511 -375.867198) (xy 435.299998 -375.884391) (xy 435.299612 -375.893584) (xy 435.299612 -376.386852)
			(xy 435.300042 -376.396037) (xy 435.306542 -376.413222) (xy 435.312312 -376.42038) (xy 435.334105 -376.446028)
			(xy 435.372057 -376.501614) (xy 435.403093 -376.561338) (xy 435.426768 -376.624343) (xy 435.442742 -376.689726)
			(xy 435.450786 -376.75655) (xy 435.450786 -376.823856) (xy 435.442741 -376.89068) (xy 435.426766 -376.956063)
			(xy 435.40309 -377.019068) (xy 435.372054 -377.078791) (xy 435.334101 -377.134376) (xy 435.312312 -377.160028)
			(xy 435.306522 -377.167178) (xy 435.300003 -377.184365) (xy 435.299612 -377.193556) (xy 435.299612 -377.35129)
			(xy 435.299227 -377.361467) (xy 435.291436 -377.380271) (xy 435.277038 -377.394658) (xy 435.258228 -377.402435)
			(xy 435.24805 -377.402852) (xy 434.53177 -377.402852) (xy 434.521609 -377.402391) (xy 434.502837 -377.394605)
			(xy 434.488473 -377.380229) (xy 434.480701 -377.361451) (xy 434.480208 -377.35129) (xy 434.480208 -377.193556)
			(xy 434.479817 -377.184367) (xy 434.47329 -377.167183) (xy 434.467508 -377.160028) (xy 434.445725 -377.134372)
			(xy 434.407778 -377.078786) (xy 434.376746 -377.019062) (xy 434.353075 -376.956058) (xy 434.337103 -376.890677)
			(xy 434.329059 -376.823855) (xy 434.329058 -376.756551) (xy 431.050994 -376.756551) (xy 431.050993 -376.823915)
			(xy 431.042917 -376.890853) (xy 431.026882 -376.956342) (xy 431.003118 -377.019439) (xy 430.971968 -377.079236)
			(xy 430.93388 -377.13487) (xy 430.912016 -377.160536) (xy 430.906223 -377.167684) (xy 430.899706 -377.184872)
			(xy 430.899316 -377.194064) (xy 430.899316 -377.35129) (xy 430.898864 -377.361421) (xy 430.891131 -377.380151)
			(xy 430.876834 -377.394509) (xy 430.858137 -377.402321) (xy 430.848008 -377.402852) (xy 430.131728 -377.402852)
			(xy 430.121582 -377.402357) (xy 430.10284 -377.39458) (xy 430.088518 -377.380207) (xy 430.080808 -377.361437)
			(xy 430.08042 -377.35129) (xy 430.08042 -377.194064) (xy 430.080023 -377.184876) (xy 430.0735 -377.167692)
			(xy 430.06772 -377.160536) (xy 430.045859 -377.134868) (xy 430.007769 -377.079234) (xy 429.976617 -377.019439)
			(xy 429.952852 -376.956342) (xy 429.936815 -376.890853) (xy 429.928739 -376.823915) (xy 426.650691 -376.823915)
			(xy 426.642653 -376.890679) (xy 426.626679 -376.956062) (xy 426.603004 -377.019067) (xy 426.571968 -377.07879)
			(xy 426.534017 -377.134376) (xy 426.512228 -377.160028) (xy 426.506428 -377.167171) (xy 426.499918 -377.184363)
			(xy 426.499528 -377.193556) (xy 426.499528 -377.35129) (xy 426.499127 -377.361465) (xy 426.491339 -377.380266)
			(xy 426.476946 -377.394653) (xy 426.458141 -377.402432) (xy 426.447966 -377.402852) (xy 425.731686 -377.402852)
			(xy 425.721526 -377.402378) (xy 425.702755 -377.394597) (xy 425.68839 -377.380225) (xy 425.680618 -377.36145)
			(xy 425.680124 -377.35129) (xy 425.680124 -377.193556) (xy 425.67973 -377.184367) (xy 425.673204 -377.167183)
			(xy 425.667424 -377.160028) (xy 425.645641 -377.134372) (xy 425.607693 -377.078786) (xy 425.57666 -377.019063)
			(xy 425.552988 -376.956059) (xy 425.537015 -376.890677) (xy 425.528971 -376.823855) (xy 425.52897 -376.756551)
			(xy 422.250906 -376.756551) (xy 422.250905 -376.823915) (xy 422.24283 -376.890853) (xy 422.226795 -376.956342)
			(xy 422.203032 -377.019438) (xy 422.171882 -377.079235) (xy 422.133795 -377.13487) (xy 422.111932 -377.160536)
			(xy 422.106129 -377.167677) (xy 422.09962 -377.184871) (xy 422.099232 -377.194064) (xy 422.099232 -377.35129)
			(xy 422.098764 -377.36142) (xy 422.091035 -377.380146) (xy 422.076742 -377.394503) (xy 422.058051 -377.402318)
			(xy 422.047924 -377.402852) (xy 421.331644 -377.402852) (xy 421.321499 -377.402343) (xy 421.302758 -377.394572)
			(xy 421.288435 -377.380202) (xy 421.280724 -377.361436) (xy 421.280336 -377.35129) (xy 421.280336 -377.194064)
			(xy 421.279935 -377.184876) (xy 421.273414 -377.167692) (xy 421.267636 -377.160536) (xy 421.245775 -377.134868)
			(xy 421.207684 -377.079235) (xy 421.176531 -377.019439) (xy 421.152765 -376.956343) (xy 421.136728 -376.890854)
			(xy 421.128651 -376.823915) (xy 391.450846 -376.823915) (xy 391.442809 -376.890678) (xy 391.426837 -376.956059)
			(xy 391.403165 -377.019064) (xy 391.372134 -377.078788) (xy 391.334187 -377.134375) (xy 391.3124 -377.160028)
			(xy 391.306609 -377.167177) (xy 391.300091 -377.184365) (xy 391.2997 -377.193556) (xy 391.2997 -377.35129)
			(xy 391.299159 -377.361442) (xy 391.291395 -377.380204) (xy 391.277044 -377.394568) (xy 391.25829 -377.40235)
			(xy 391.248138 -377.402852) (xy 390.531858 -377.402852) (xy 390.521696 -377.402401) (xy 390.502924 -377.394611)
			(xy 390.48856 -377.380232) (xy 390.480789 -377.361452) (xy 390.480296 -377.35129) (xy 390.480296 -377.193556)
			(xy 390.479908 -377.184366) (xy 390.473379 -377.167182) (xy 390.467596 -377.160028) (xy 390.445814 -377.134372)
			(xy 390.407867 -377.078785) (xy 390.376836 -377.019062) (xy 390.353165 -376.956058) (xy 390.337193 -376.890676)
			(xy 390.329149 -376.823855) (xy 387.051084 -376.823855) (xy 387.051084 -376.823915) (xy 387.043008 -376.890853)
			(xy 387.026972 -376.956343) (xy 387.003208 -377.01944) (xy 386.972057 -377.079236) (xy 386.933968 -377.134871)
			(xy 386.912104 -377.160536) (xy 386.90631 -377.167683) (xy 386.899794 -377.184872) (xy 386.899404 -377.194064)
			(xy 386.899404 -377.35129) (xy 386.898867 -377.361411) (xy 386.89115 -377.380123) (xy 386.87688 -377.394478)
			(xy 386.858214 -377.402306) (xy 386.848096 -377.402852) (xy 386.131816 -377.402852) (xy 386.121669 -377.402366)
			(xy 386.102927 -377.394586) (xy 386.088605 -377.380209) (xy 386.080896 -377.361438) (xy 386.080508 -377.35129)
			(xy 386.080508 -377.194064) (xy 386.080114 -377.184875) (xy 386.073589 -377.167691) (xy 386.067808 -377.160536)
			(xy 386.045948 -377.134868) (xy 386.007858 -377.079234) (xy 385.976707 -377.019438) (xy 385.952942 -376.956342)
			(xy 385.936906 -376.890853) (xy 385.92883 -376.823915) (xy 382.650782 -376.823915) (xy 382.642744 -376.89068)
			(xy 382.626769 -376.956063) (xy 382.603094 -377.019068) (xy 382.572058 -377.078791) (xy 382.534105 -377.134376)
			(xy 382.512316 -377.160028) (xy 382.506527 -377.167179) (xy 382.500007 -377.184365) (xy 382.499616 -377.193556)
			(xy 382.499616 -377.35129) (xy 382.499227 -377.361467) (xy 382.491437 -377.38027) (xy 382.47704 -377.394657)
			(xy 382.458231 -377.402434) (xy 382.448054 -377.402852) (xy 381.731774 -377.402852) (xy 381.721613 -377.402388)
			(xy 381.702842 -377.394603) (xy 381.688477 -377.380228) (xy 381.680705 -377.361451) (xy 381.680212 -377.35129)
			(xy 381.680212 -377.193556) (xy 381.67982 -377.184367) (xy 381.673294 -377.167183) (xy 381.667512 -377.160028)
			(xy 381.645729 -377.134372) (xy 381.607782 -377.078786) (xy 381.57675 -377.019062) (xy 381.553078 -376.956058)
			(xy 381.537106 -376.890677) (xy 381.529062 -376.823855) (xy 381.529061 -376.756551) (xy 378.250997 -376.756551)
			(xy 378.250996 -376.823915) (xy 378.24292 -376.890853) (xy 378.226885 -376.956342) (xy 378.203121 -377.019439)
			(xy 378.171971 -377.079235) (xy 378.133884 -377.13487) (xy 378.11202 -377.160536) (xy 378.106228 -377.167685)
			(xy 378.09971 -377.184872) (xy 378.09932 -377.194064) (xy 378.09932 -377.35129) (xy 378.098864 -377.361421)
			(xy 378.091132 -377.38015) (xy 378.076836 -377.394508) (xy 378.058141 -377.40232) (xy 378.048012 -377.402852)
			(xy 377.331732 -377.402852) (xy 377.321586 -377.402353) (xy 377.302845 -377.394578) (xy 377.288522 -377.380206)
			(xy 377.280812 -377.361437) (xy 377.280424 -377.35129) (xy 377.280424 -377.194064) (xy 377.280026 -377.184876)
			(xy 377.273503 -377.167692) (xy 377.267724 -377.160536) (xy 377.245863 -377.134868) (xy 377.207773 -377.079234)
			(xy 377.17662 -377.019439) (xy 377.152855 -376.956342) (xy 377.136819 -376.890853) (xy 377.128742 -376.823915)
			(xy 347.450937 -376.823915) (xy 347.4429 -376.890678) (xy 347.426927 -376.95606) (xy 347.403255 -377.019065)
			(xy 347.372223 -377.078788) (xy 347.334275 -377.134376) (xy 347.312488 -377.160028) (xy 347.306696 -377.167176)
			(xy 347.300179 -377.184364) (xy 347.299788 -377.193556) (xy 347.299788 -377.35129) (xy 347.299259 -377.361444)
			(xy 347.291493 -377.380208) (xy 347.277138 -377.394573) (xy 347.25838 -377.402352) (xy 347.248226 -377.402852)
			(xy 346.531946 -377.402852) (xy 346.521776 -377.402398) (xy 346.502981 -377.394627) (xy 346.488594 -377.38025)
			(xy 346.480809 -377.36146) (xy 346.480384 -377.35129) (xy 346.480384 -377.193556) (xy 346.479999 -377.184366)
			(xy 346.473468 -377.167182) (xy 346.467684 -377.160028) (xy 346.445899 -377.134373) (xy 346.407947 -377.078788)
			(xy 346.376911 -377.019065) (xy 346.353236 -376.956061) (xy 346.337262 -376.890679) (xy 346.329216 -376.823856)
			(xy 343.051175 -376.823856) (xy 343.051175 -376.823915) (xy 343.043099 -376.890854) (xy 343.027063 -376.956343)
			(xy 343.003298 -377.01944) (xy 342.972146 -377.079236) (xy 342.934056 -377.134871) (xy 342.912192 -377.160536)
			(xy 342.906397 -377.167682) (xy 342.899882 -377.184872) (xy 342.899492 -377.194064) (xy 342.899492 -377.35129)
			(xy 342.898966 -377.361412) (xy 342.891248 -377.380127) (xy 342.876974 -377.394483) (xy 342.858303 -377.402308)
			(xy 342.848184 -377.402852) (xy 342.131904 -377.402852) (xy 342.121757 -377.402376) (xy 342.103014 -377.394592)
			(xy 342.088693 -377.380212) (xy 342.080984 -377.361439) (xy 342.080596 -377.35129) (xy 342.080596 -377.194064)
			(xy 342.080204 -377.184875) (xy 342.073678 -377.167691) (xy 342.067896 -377.160536) (xy 342.046036 -377.134867)
			(xy 342.007948 -377.079233) (xy 341.976797 -377.019438) (xy 341.953033 -376.956341) (xy 341.936997 -376.890852)
			(xy 341.928921 -376.823915) (xy 338.650849 -376.823915) (xy 338.642812 -376.890677) (xy 338.62684 -376.956059)
			(xy 338.603168 -377.019064) (xy 338.572137 -377.078788) (xy 338.534191 -377.134375) (xy 338.512404 -377.160028)
			(xy 338.506614 -377.167178) (xy 338.500095 -377.184365) (xy 338.499704 -377.193556) (xy 338.499704 -377.35129)
			(xy 338.49916 -377.361442) (xy 338.491396 -377.380203) (xy 338.477047 -377.394567) (xy 338.458293 -377.402349)
			(xy 338.448142 -377.402852) (xy 337.731862 -377.402852) (xy 337.721701 -377.402397) (xy 337.702929 -377.394609)
			(xy 337.688564 -377.380231) (xy 337.680793 -377.361452) (xy 337.6803 -377.35129) (xy 337.6803 -377.193556)
			(xy 337.679911 -377.184367) (xy 337.673383 -377.167182) (xy 337.6676 -377.160028) (xy 337.645817 -377.134372)
			(xy 337.607871 -377.078785) (xy 337.57684 -377.019062) (xy 337.553168 -376.956058) (xy 337.537196 -376.890677)
			(xy 337.529152 -376.823855) (xy 334.251087 -376.823855) (xy 334.251087 -376.823915) (xy 334.243011 -376.890853)
			(xy 334.226976 -376.956342) (xy 334.203211 -377.019439) (xy 334.172061 -377.079236) (xy 334.133972 -377.134871)
			(xy 334.112108 -377.160536) (xy 334.106315 -377.167684) (xy 334.099798 -377.184872) (xy 334.099408 -377.194064)
			(xy 334.099408 -377.35129) (xy 334.098867 -377.36141) (xy 334.091151 -377.380122) (xy 334.076882 -377.394477)
			(xy 334.058217 -377.402305) (xy 334.0481 -377.402852) (xy 333.33182 -377.402852) (xy 333.321674 -377.402363)
			(xy 333.302932 -377.394584) (xy 333.288609 -377.380209) (xy 333.2809 -377.361438) (xy 333.280512 -377.35129)
			(xy 333.280512 -377.194064) (xy 333.280117 -377.184875) (xy 333.273592 -377.167691) (xy 333.267812 -377.160536)
			(xy 333.245952 -377.134868) (xy 333.207862 -377.079234) (xy 333.17671 -377.019438) (xy 333.152945 -376.956342)
			(xy 333.136909 -376.890853) (xy 333.128833 -376.823915) (xy 303.451057 -376.823915) (xy 303.44298 -376.890854)
			(xy 303.426944 -376.956344) (xy 303.403178 -377.019441) (xy 303.372025 -377.079237) (xy 303.333933 -377.134871)
			(xy 303.312068 -377.160536) (xy 303.30627 -377.16768) (xy 303.299757 -377.184871) (xy 303.299368 -377.194064)
			(xy 303.299368 -377.35129) (xy 303.298865 -377.361415) (xy 303.291142 -377.380135) (xy 303.276861 -377.394491)
			(xy 303.258182 -377.402312) (xy 303.24806 -377.402852) (xy 302.53178 -377.402852) (xy 302.521631 -377.402396)
			(xy 302.502888 -377.394604) (xy 302.488567 -377.380218) (xy 302.480859 -377.361441) (xy 302.480472 -377.35129)
			(xy 302.480472 -377.194064) (xy 302.480085 -377.184874) (xy 302.473556 -377.16769) (xy 302.467772 -377.160536)
			(xy 302.445913 -377.134867) (xy 302.407826 -377.079232) (xy 302.376677 -377.019436) (xy 302.352913 -376.95634)
			(xy 302.336879 -376.890852) (xy 302.328803 -376.823914) (xy 302.328802 -376.756492) (xy 299.050731 -376.756492)
			(xy 299.050738 -376.756551) (xy 299.050738 -376.823856) (xy 299.042693 -376.890678) (xy 299.026721 -376.95606)
			(xy 299.003048 -377.019065) (xy 298.972016 -377.078789) (xy 298.934067 -377.134376) (xy 298.91228 -377.160028)
			(xy 298.906487 -377.167175) (xy 298.899971 -377.184364) (xy 298.89958 -377.193556) (xy 298.89958 -377.35129)
			(xy 298.899059 -377.361445) (xy 298.891291 -377.38021) (xy 298.876934 -377.394575) (xy 298.858173 -377.402353)
			(xy 298.848018 -377.402852) (xy 298.131738 -377.402852) (xy 298.121568 -377.402405) (xy 298.102772 -377.39463)
			(xy 298.088385 -377.380252) (xy 298.080601 -377.36146) (xy 298.080176 -377.35129) (xy 298.080176 -377.193556)
			(xy 298.079792 -377.184366) (xy 298.073261 -377.167182) (xy 298.067476 -377.160028) (xy 298.045691 -377.134373)
			(xy 298.00774 -377.078788) (xy 297.976704 -377.019065) (xy 297.95303 -376.956061) (xy 297.937055 -376.890679)
			(xy 297.92901 -376.823856) (xy 294.650969 -376.823856) (xy 294.650969 -376.823915) (xy 294.642893 -376.890854)
			(xy 294.626856 -376.956343) (xy 294.603091 -377.019441) (xy 294.571939 -377.079237) (xy 294.533849 -377.134871)
			(xy 294.511984 -377.160536) (xy 294.506188 -377.167681) (xy 294.499673 -377.184872) (xy 294.499284 -377.194064)
			(xy 294.499284 -377.35129) (xy 294.498766 -377.361413) (xy 294.491046 -377.38013) (xy 294.47677 -377.394485)
			(xy 294.458096 -377.402309) (xy 294.447976 -377.402852) (xy 293.731696 -377.402852) (xy 293.721548 -377.402383)
			(xy 293.702806 -377.394595) (xy 293.688484 -377.380214) (xy 293.680776 -377.36144) (xy 293.680388 -377.35129)
			(xy 293.680388 -377.194064) (xy 293.679998 -377.184875) (xy 293.673471 -377.16769) (xy 293.667688 -377.160536)
			(xy 293.645828 -377.134867) (xy 293.60774 -377.079233) (xy 293.57659 -377.019437) (xy 293.552826 -376.956341)
			(xy 293.536791 -376.890852) (xy 293.528715 -376.823915) (xy 290.250643 -376.823915) (xy 290.242606 -376.890678)
			(xy 290.226633 -376.95606) (xy 290.202962 -377.019064) (xy 290.17193 -377.078788) (xy 290.133983 -377.134375)
			(xy 290.112196 -377.160028) (xy 290.106405 -377.167177) (xy 290.099887 -377.184365) (xy 290.099496 -377.193556)
			(xy 290.099496 -377.35129) (xy 290.098959 -377.361443) (xy 290.091194 -377.380205) (xy 290.076842 -377.39457)
			(xy 290.058087 -377.402351) (xy 290.047934 -377.402852) (xy 289.331654 -377.402852) (xy 289.321492 -377.402404)
			(xy 289.30272 -377.394613) (xy 289.288356 -377.380233) (xy 289.280585 -377.361452) (xy 289.280092 -377.35129)
			(xy 289.280092 -377.193556) (xy 289.279705 -377.184366) (xy 289.273176 -377.167182) (xy 289.267392 -377.160028)
			(xy 289.245607 -377.134373) (xy 289.207654 -377.078788) (xy 289.176618 -377.019066) (xy 289.152942 -376.956061)
			(xy 289.136968 -376.890679) (xy 289.128922 -376.823856) (xy 276.808294 -376.823856) (xy 276.868641 -376.988548)
			(xy 276.931633 -377.183713) (xy 276.986963 -377.381187) (xy 277.034546 -377.580669) (xy 277.074309 -377.781855)
			(xy 277.106193 -377.98444) (xy 277.130148 -378.188114) (xy 277.14076 -378.323794) (xy 286.928742 -378.323794)
			(xy 286.928744 -378.256367) (xy 286.936824 -378.189426) (xy 286.952863 -378.123935) (xy 286.976633 -378.060837)
			(xy 287.007789 -378.00104) (xy 287.045885 -377.945406) (xy 287.067752 -377.919742) (xy 287.073562 -377.912607)
			(xy 287.080067 -377.895408) (xy 287.080452 -377.886214) (xy 287.080452 -377.728734) (xy 287.080955 -377.718608)
			(xy 287.088674 -377.699885) (xy 287.102955 -377.685528) (xy 287.121637 -377.677709) (xy 287.13176 -377.677172)
			(xy 287.84804 -377.677172) (xy 287.858193 -377.677588) (xy 287.876941 -377.685392) (xy 287.891262 -377.699789)
			(xy 287.898965 -377.718579) (xy 287.899348 -377.728734) (xy 287.899348 -377.886214) (xy 287.899763 -377.8954)
			(xy 287.906275 -377.912584) (xy 287.912048 -377.919742) (xy 287.933888 -377.945427) (xy 287.971981 -378.001058)
			(xy 288.003136 -378.060851) (xy 288.026904 -378.123945) (xy 288.042943 -378.189432) (xy 288.051021 -378.256369)
			(xy 288.051024 -378.323734) (xy 291.329062 -378.323734) (xy 291.329064 -378.256427) (xy 291.337111 -378.189602)
			(xy 291.353086 -378.124219) (xy 291.376762 -378.061213) (xy 291.407799 -378.001489) (xy 291.445751 -377.945902)
			(xy 291.46754 -377.92025) (xy 291.473345 -377.913111) (xy 291.479854 -377.895916) (xy 291.48024 -377.886722)
			(xy 291.48024 -377.728734) (xy 291.480692 -377.718564) (xy 291.488466 -377.69977) (xy 291.502843 -377.685384)
			(xy 291.521633 -377.677598) (xy 291.531802 -377.677172) (xy 292.248082 -377.677172) (xy 292.258257 -377.677579)
			(xy 292.277058 -377.685365) (xy 292.291444 -377.699756) (xy 292.299224 -377.718559) (xy 292.299644 -377.728734)
			(xy 292.299644 -377.886722) (xy 292.300056 -377.895909) (xy 292.30657 -377.913092) (xy 292.312344 -377.92025)
			(xy 292.334107 -377.945923) (xy 292.372057 -378.001506) (xy 292.403093 -378.061227) (xy 292.426768 -378.124228)
			(xy 292.442743 -378.189608) (xy 292.450789 -378.256429) (xy 292.450792 -378.323732) (xy 292.450785 -378.323794)
			(xy 295.72883 -378.323794) (xy 295.728832 -378.256367) (xy 295.736911 -378.189427) (xy 295.752951 -378.123936)
			(xy 295.776719 -378.060837) (xy 295.807875 -378.001041) (xy 295.845969 -377.945407) (xy 295.867836 -377.919742)
			(xy 295.873644 -377.912605) (xy 295.880151 -377.895408) (xy 295.880536 -377.886214) (xy 295.880536 -377.728734)
			(xy 295.881055 -377.71861) (xy 295.88877 -377.69989) (xy 295.903047 -377.685533) (xy 295.921723 -377.677712)
			(xy 295.931844 -377.677172) (xy 296.648124 -377.677172) (xy 296.658276 -377.677601) (xy 296.677024 -377.6854)
			(xy 296.691345 -377.699793) (xy 296.699049 -377.71858) (xy 296.699432 -377.728734) (xy 296.699432 -377.886214)
			(xy 296.699851 -377.8954) (xy 296.70636 -377.912584) (xy 296.712132 -377.919742) (xy 296.733969 -377.945429)
			(xy 296.772057 -378.001061) (xy 296.803207 -378.060855) (xy 296.826971 -378.123949) (xy 296.843007 -378.189435)
			(xy 296.851085 -378.25637) (xy 296.851087 -378.323791) (xy 296.851087 -378.323794) (xy 300.128621 -378.323794)
			(xy 300.128623 -378.256367) (xy 300.136702 -378.189427) (xy 300.152741 -378.123936) (xy 300.176509 -378.060838)
			(xy 300.207664 -378.001041) (xy 300.245758 -377.945407) (xy 300.267624 -377.919742) (xy 300.27343 -377.912604)
			(xy 300.279938 -377.895408) (xy 300.280324 -377.886214) (xy 300.280324 -377.728734) (xy 300.280854 -377.718611)
			(xy 300.288568 -377.699894) (xy 300.302841 -377.685537) (xy 300.321512 -377.677714) (xy 300.331632 -377.677172)
			(xy 301.047912 -377.677172) (xy 301.058063 -377.677611) (xy 301.076811 -377.685405) (xy 301.091133 -377.699796)
			(xy 301.098837 -377.718581) (xy 301.09922 -377.728734) (xy 301.09922 -377.886214) (xy 301.099619 -377.895402)
			(xy 301.10614 -377.912587) (xy 301.11192 -377.919742) (xy 301.133758 -377.945429) (xy 301.171846 -378.001061)
			(xy 301.202997 -378.060854) (xy 301.226761 -378.123948) (xy 301.242798 -378.189434) (xy 301.250876 -378.25637)
			(xy 301.250878 -378.323734) (xy 330.92918 -378.323734) (xy 330.929182 -378.256427) (xy 330.937229 -378.189602)
			(xy 330.953206 -378.124218) (xy 330.976882 -378.061212) (xy 331.00792 -378.001488) (xy 331.045874 -377.945902)
			(xy 331.067664 -377.92025) (xy 331.073472 -377.913113) (xy 331.079978 -377.895916) (xy 331.080364 -377.886722)
			(xy 331.080364 -377.728734) (xy 331.080792 -377.718561) (xy 331.088571 -377.699763) (xy 331.102956 -377.685376)
			(xy 331.121753 -377.677594) (xy 331.131926 -377.677172) (xy 331.848206 -377.677172) (xy 331.858382 -377.67756)
			(xy 331.877184 -377.685353) (xy 331.891569 -377.69975) (xy 331.899348 -377.718557) (xy 331.899768 -377.728734)
			(xy 331.899768 -377.886722) (xy 331.900175 -377.895909) (xy 331.906692 -377.913093) (xy 331.912468 -377.92025)
			(xy 331.93423 -377.945923) (xy 331.972179 -378.001507) (xy 332.003213 -378.061228) (xy 332.026887 -378.124229)
			(xy 332.042861 -378.189609) (xy 332.050907 -378.256429) (xy 332.05091 -378.323732) (xy 332.050903 -378.323793)
			(xy 335.328973 -378.323793) (xy 335.328975 -378.256368) (xy 335.337053 -378.189429) (xy 335.35309 -378.123939)
			(xy 335.376855 -378.060841) (xy 335.408007 -378.001044) (xy 335.446096 -377.945408) (xy 335.46796 -377.919742)
			(xy 335.473771 -377.912607) (xy 335.480275 -377.895409) (xy 335.48066 -377.886214) (xy 335.48066 -377.728734)
			(xy 335.481155 -377.718607) (xy 335.488875 -377.699883) (xy 335.50316 -377.685525) (xy 335.521844 -377.677708)
			(xy 335.531968 -377.677172) (xy 336.248248 -377.677172) (xy 336.258402 -377.677582) (xy 336.27715 -377.685388)
			(xy 336.29147 -377.699787) (xy 336.299173 -377.718578) (xy 336.299556 -377.728734) (xy 336.299556 -377.886214)
			(xy 336.299969 -377.895401) (xy 336.306482 -377.912585) (xy 336.312256 -377.919742) (xy 336.334096 -377.945428)
			(xy 336.372188 -378.001058) (xy 336.403343 -378.060851) (xy 336.42711 -378.123945) (xy 336.443149 -378.189433)
			(xy 336.451227 -378.256369) (xy 336.45123 -378.323734) (xy 339.729268 -378.323734) (xy 339.72927 -378.256427)
			(xy 339.737317 -378.189602) (xy 339.753293 -378.124218) (xy 339.776969 -378.061213) (xy 339.808006 -378.001489)
			(xy 339.845958 -377.945902) (xy 339.867748 -377.92025) (xy 339.873554 -377.913112) (xy 339.880062 -377.895916)
			(xy 339.880448 -377.886722) (xy 339.880448 -377.728734) (xy 339.880892 -377.718563) (xy 339.888668 -377.699768)
			(xy 339.903047 -377.685381) (xy 339.92184 -377.677597) (xy 339.93201 -377.677172) (xy 340.64829 -377.677172)
			(xy 340.658465 -377.677573) (xy 340.677266 -377.685361) (xy 340.691653 -377.699754) (xy 340.699432 -377.718559)
			(xy 340.699852 -377.728734) (xy 340.699852 -377.886722) (xy 340.700262 -377.895909) (xy 340.706777 -377.913093)
			(xy 340.712552 -377.92025) (xy 340.734314 -377.945923) (xy 340.772264 -378.001506) (xy 340.803299 -378.061227)
			(xy 340.826974 -378.124229) (xy 340.842949 -378.189608) (xy 340.850995 -378.256429) (xy 340.850998 -378.323732)
			(xy 340.850998 -378.323734) (xy 344.129059 -378.323734) (xy 344.129061 -378.256427) (xy 344.137108 -378.189603)
			(xy 344.153083 -378.124219) (xy 344.176759 -378.061213) (xy 344.207795 -378.001489) (xy 344.245747 -377.945902)
			(xy 344.267536 -377.92025) (xy 344.273341 -377.913111) (xy 344.27985 -377.895916) (xy 344.280236 -377.886722)
			(xy 344.280236 -377.728734) (xy 344.280692 -377.718565) (xy 344.288465 -377.699771) (xy 344.302841 -377.685385)
			(xy 344.321629 -377.677599) (xy 344.331798 -377.677172) (xy 345.048078 -377.677172) (xy 345.058252 -377.677583)
			(xy 345.077053 -377.685367) (xy 345.09144 -377.699757) (xy 345.099219 -377.71856) (xy 345.09964 -377.728734)
			(xy 345.09964 -377.886722) (xy 345.100053 -377.895909) (xy 345.106566 -377.913092) (xy 345.11234 -377.92025)
			(xy 345.134103 -377.945923) (xy 345.172054 -378.001506) (xy 345.203089 -378.061226) (xy 345.226764 -378.124228)
			(xy 345.24274 -378.189608) (xy 345.250786 -378.256429) (xy 345.250789 -378.323732) (xy 345.250789 -378.323734)
			(xy 374.929089 -378.323734) (xy 374.929092 -378.256427) (xy 374.937139 -378.189602) (xy 374.953116 -378.124218)
			(xy 374.976793 -378.061212) (xy 375.007831 -378.001488) (xy 375.045786 -377.945902) (xy 375.067576 -377.92025)
			(xy 375.073374 -377.913105) (xy 375.079888 -377.895915) (xy 375.080276 -377.886722) (xy 375.080276 -377.728734)
			(xy 375.080693 -377.71856) (xy 375.088474 -377.699759) (xy 375.102862 -377.685371) (xy 375.121664 -377.677592)
			(xy 375.131838 -377.677172) (xy 375.848118 -377.677172) (xy 375.858295 -377.67755) (xy 375.877097 -377.685347)
			(xy 375.891482 -377.699747) (xy 375.89926 -377.718557) (xy 375.89968 -377.728734) (xy 375.89968 -377.886722)
			(xy 375.900084 -377.89591) (xy 375.906602 -377.913094) (xy 375.91238 -377.92025) (xy 375.934142 -377.945923)
			(xy 375.97209 -378.001507) (xy 376.003123 -378.061228) (xy 376.026797 -378.12423) (xy 376.042771 -378.189609)
			(xy 376.050817 -378.256429) (xy 376.050819 -378.323732) (xy 376.050812 -378.323793) (xy 379.328882 -378.323793)
			(xy 379.328884 -378.256368) (xy 379.336962 -378.189428) (xy 379.352999 -378.123938) (xy 379.376765 -378.06084)
			(xy 379.407917 -378.001043) (xy 379.446007 -377.945408) (xy 379.467872 -377.919742) (xy 379.473684 -377.912608)
			(xy 379.480188 -377.895409) (xy 379.480572 -377.886214) (xy 379.480572 -377.728734) (xy 379.481056 -377.718606)
			(xy 379.488778 -377.699879) (xy 379.503066 -377.685521) (xy 379.521754 -377.677706) (xy 379.53188 -377.677172)
			(xy 380.24816 -377.677172) (xy 380.258308 -377.677654) (xy 380.277054 -377.685431) (xy 380.291378 -377.699809)
			(xy 380.299084 -377.718584) (xy 380.299468 -377.728734) (xy 380.299468 -377.886214) (xy 380.299878 -377.895401)
			(xy 380.306393 -377.912585) (xy 380.312168 -377.919742) (xy 380.334008 -377.945428) (xy 380.372099 -378.001059)
			(xy 380.403253 -378.060852) (xy 380.42702 -378.123946) (xy 380.443058 -378.189433) (xy 380.451137 -378.256369)
			(xy 380.451139 -378.323734) (xy 383.729177 -378.323734) (xy 383.729179 -378.256427) (xy 383.737226 -378.189602)
			(xy 383.753202 -378.124218) (xy 383.776879 -378.061212) (xy 383.807917 -378.001488) (xy 383.84587 -377.945902)
			(xy 383.86766 -377.92025) (xy 383.873468 -377.913113) (xy 383.879974 -377.895916) (xy 383.88036 -377.886722)
			(xy 383.88036 -377.728734) (xy 383.880792 -377.718562) (xy 383.88857 -377.699764) (xy 383.902954 -377.685377)
			(xy 383.92175 -377.677595) (xy 383.931922 -377.677172) (xy 384.648202 -377.677172) (xy 384.658378 -377.677563)
			(xy 384.677179 -377.685355) (xy 384.691565 -377.699751) (xy 384.699344 -377.718558) (xy 384.699764 -377.728734)
			(xy 384.699764 -377.886722) (xy 384.700172 -377.895909) (xy 384.706688 -377.913093) (xy 384.712464 -377.92025)
			(xy 384.734226 -377.945923) (xy 384.772175 -378.001507) (xy 384.803209 -378.061228) (xy 384.826884 -378.124229)
			(xy 384.842858 -378.189609) (xy 384.850904 -378.256429) (xy 384.850907 -378.323732) (xy 384.850907 -378.323734)
			(xy 388.128968 -378.323734) (xy 388.12897 -378.256427) (xy 388.137017 -378.189602) (xy 388.152993 -378.124218)
			(xy 388.176669 -378.061213) (xy 388.207706 -378.001489) (xy 388.245658 -377.945902) (xy 388.267448 -377.92025)
			(xy 388.273254 -377.913112) (xy 388.279762 -377.895916) (xy 388.280148 -377.886722) (xy 388.280148 -377.728734)
			(xy 388.280592 -377.718563) (xy 388.288368 -377.699768) (xy 388.302747 -377.685381) (xy 388.32154 -377.677597)
			(xy 388.33171 -377.677172) (xy 389.04799 -377.677172) (xy 389.058165 -377.677573) (xy 389.076966 -377.685361)
			(xy 389.091353 -377.699754) (xy 389.099132 -377.718559) (xy 389.099552 -377.728734) (xy 389.099552 -377.886722)
			(xy 389.099962 -377.895909) (xy 389.106477 -377.913093) (xy 389.112252 -377.92025) (xy 389.134014 -377.945923)
			(xy 389.171964 -378.001506) (xy 389.202999 -378.061227) (xy 389.226674 -378.124229) (xy 389.242649 -378.189608)
			(xy 389.250695 -378.256429) (xy 389.250698 -378.323732) (xy 389.250698 -378.323734) (xy 418.928998 -378.323734)
			(xy 418.929001 -378.256426) (xy 418.937048 -378.189601) (xy 418.953025 -378.124217) (xy 418.976703 -378.061211)
			(xy 419.007742 -378.001487) (xy 419.045697 -377.945902) (xy 419.067488 -377.92025) (xy 419.073287 -377.913106)
			(xy 419.079801 -377.895915) (xy 419.080188 -377.886722) (xy 419.080188 -377.728734) (xy 419.080593 -377.718558)
			(xy 419.088376 -377.699755) (xy 419.102768 -377.685367) (xy 419.121574 -377.67759) (xy 419.13175 -377.677172)
			(xy 419.84803 -377.677172) (xy 419.858208 -377.67754) (xy 419.87701 -377.685341) (xy 419.891395 -377.699744)
			(xy 419.899173 -377.718556) (xy 419.899592 -377.728734) (xy 419.899592 -377.886722) (xy 419.899993 -377.89591)
			(xy 419.906513 -377.913094) (xy 419.912292 -377.92025) (xy 419.934053 -377.945924) (xy 419.972001 -378.001508)
			(xy 420.003034 -378.061229) (xy 420.026706 -378.12423) (xy 420.04268 -378.189609) (xy 420.050726 -378.256429)
			(xy 420.050728 -378.323732) (xy 420.050721 -378.323793) (xy 423.328791 -378.323793) (xy 423.328793 -378.256368)
			(xy 423.336871 -378.189428) (xy 423.352909 -378.123938) (xy 423.376675 -378.06084) (xy 423.407828 -378.001043)
			(xy 423.445919 -377.945408) (xy 423.467784 -377.919742) (xy 423.473586 -377.9126) (xy 423.480098 -377.895407)
			(xy 423.480484 -377.886214) (xy 423.480484 -377.728734) (xy 423.480956 -377.718604) (xy 423.488681 -377.699875)
			(xy 423.502972 -377.685516) (xy 423.521664 -377.677704) (xy 423.531792 -377.677172) (xy 424.248072 -377.677172)
			(xy 424.258221 -377.677644) (xy 424.276967 -377.685425) (xy 424.291291 -377.699806) (xy 424.298996 -377.718584)
			(xy 424.29938 -377.728734) (xy 424.29938 -377.886214) (xy 424.299788 -377.895401) (xy 424.306303 -377.912585)
			(xy 424.31208 -377.919742) (xy 424.333919 -377.945428) (xy 424.37201 -378.001059) (xy 424.403163 -378.060852)
			(xy 424.426929 -378.123946) (xy 424.442967 -378.189433) (xy 424.451046 -378.256369) (xy 424.451048 -378.323734)
			(xy 427.729086 -378.323734) (xy 427.729089 -378.256427) (xy 427.737136 -378.189602) (xy 427.753113 -378.124218)
			(xy 427.77679 -378.061212) (xy 427.807828 -378.001488) (xy 427.845782 -377.945902) (xy 427.867572 -377.92025)
			(xy 427.873381 -377.913114) (xy 427.879886 -377.895916) (xy 427.880272 -377.886722) (xy 427.880272 -377.728734)
			(xy 427.880693 -377.71856) (xy 427.888473 -377.69976) (xy 427.90286 -377.685373) (xy 427.92166 -377.677593)
			(xy 427.931834 -377.677172) (xy 428.648114 -377.677172) (xy 428.658291 -377.677553) (xy 428.677092 -377.685349)
			(xy 428.691478 -377.699748) (xy 428.699256 -377.718557) (xy 428.699676 -377.728734) (xy 428.699676 -377.886722)
			(xy 428.700081 -377.89591) (xy 428.706599 -377.913094) (xy 428.712376 -377.92025) (xy 428.734137 -377.945924)
			(xy 428.772086 -378.001507) (xy 428.80312 -378.061228) (xy 428.826793 -378.12423) (xy 428.842767 -378.189609)
			(xy 428.850813 -378.256429) (xy 428.850816 -378.323732) (xy 428.850816 -378.323734) (xy 432.128877 -378.323734)
			(xy 432.128879 -378.256427) (xy 432.136926 -378.189602) (xy 432.152902 -378.124218) (xy 432.176579 -378.061212)
			(xy 432.207617 -378.001488) (xy 432.24557 -377.945902) (xy 432.26736 -377.92025) (xy 432.273168 -377.913113)
			(xy 432.279674 -377.895916) (xy 432.28006 -377.886722) (xy 432.28006 -377.728734) (xy 432.280492 -377.718562)
			(xy 432.28827 -377.699764) (xy 432.302654 -377.685377) (xy 432.32145 -377.677595) (xy 432.331622 -377.677172)
			(xy 433.047902 -377.677172) (xy 433.058078 -377.677563) (xy 433.076879 -377.685355) (xy 433.091265 -377.699751)
			(xy 433.099044 -377.718558) (xy 433.099464 -377.728734) (xy 433.099464 -377.886722) (xy 433.099872 -377.895909)
			(xy 433.106388 -377.913093) (xy 433.112164 -377.92025) (xy 433.133926 -377.945923) (xy 433.171875 -378.001507)
			(xy 433.202909 -378.061228) (xy 433.226584 -378.124229) (xy 433.242558 -378.189609) (xy 433.250604 -378.256429)
			(xy 433.250607 -378.323732) (xy 433.242565 -378.390553) (xy 433.226595 -378.455933) (xy 433.202925 -378.518937)
			(xy 433.171895 -378.57866) (xy 433.13395 -378.634246) (xy 433.112164 -378.659898) (xy 433.106381 -378.667053)
			(xy 433.099859 -378.684236) (xy 433.099464 -378.693426) (xy 433.099464 -379.186694) (xy 433.099885 -379.19588)
			(xy 433.106392 -379.213064) (xy 433.112164 -379.220222) (xy 433.133997 -379.245837) (xy 433.171944 -379.301429)
			(xy 433.202975 -379.361158) (xy 433.226645 -379.424167) (xy 433.242615 -379.489554) (xy 433.250655 -379.55638)
			(xy 433.250651 -379.623689) (xy 433.242603 -379.690515) (xy 433.226625 -379.755899) (xy 433.202947 -379.818906)
			(xy 433.171909 -379.878631) (xy 433.133955 -379.934218) (xy 433.112164 -379.95987) (xy 433.106351 -379.967003)
			(xy 433.099847 -379.984203) (xy 433.099464 -379.993398) (xy 433.099464 -380.151386) (xy 433.099025 -380.161556)
			(xy 433.091245 -380.180351) (xy 433.076864 -380.194736) (xy 433.058072 -380.202522) (xy 433.047902 -380.202948)
			(xy 432.331622 -380.202948) (xy 432.32145 -380.202518) (xy 432.302653 -380.194737) (xy 432.288267 -380.180353)
			(xy 432.280484 -380.161558) (xy 432.28006 -380.151386) (xy 432.28006 -379.993398) (xy 432.279637 -379.984212)
			(xy 432.273131 -379.967029) (xy 432.26736 -379.95987) (xy 432.245617 -379.934181) (xy 432.207665 -379.8786)
			(xy 432.176629 -379.818882) (xy 432.152953 -379.755882) (xy 432.136976 -379.690504) (xy 432.128928 -379.623685)
			(xy 432.128924 -379.556384) (xy 432.136964 -379.489564) (xy 432.152932 -379.424184) (xy 432.176601 -379.361181)
			(xy 432.20763 -379.301459) (xy 432.245575 -379.245874) (xy 432.26736 -379.220222) (xy 432.27318 -379.213093)
			(xy 432.279679 -379.19589) (xy 432.28006 -379.186694) (xy 432.28006 -378.693426) (xy 432.279624 -378.684242)
			(xy 432.273127 -378.667058) (xy 432.26736 -378.659898) (xy 432.245546 -378.634267) (xy 432.207596 -378.578678)
			(xy 432.176563 -378.518952) (xy 432.152891 -378.455945) (xy 432.136919 -378.39056) (xy 432.128877 -378.323734)
			(xy 428.850816 -378.323734) (xy 428.842774 -378.390552) (xy 428.826805 -378.455933) (xy 428.803136 -378.518936)
			(xy 428.772106 -378.578659) (xy 428.734161 -378.634245) (xy 428.712376 -378.659898) (xy 428.706595 -378.667054)
			(xy 428.700072 -378.684236) (xy 428.699676 -378.693426) (xy 428.699676 -379.186694) (xy 428.700094 -379.19588)
			(xy 428.706603 -379.213064) (xy 428.712376 -379.220222) (xy 428.734209 -379.245837) (xy 428.772155 -379.301429)
			(xy 428.803185 -379.361158) (xy 428.826855 -379.424167) (xy 428.842824 -379.489554) (xy 428.850865 -379.55638)
			(xy 428.85086 -379.623689) (xy 428.842812 -379.690514) (xy 428.826835 -379.755899) (xy 428.803157 -379.818905)
			(xy 428.772119 -379.87863) (xy 428.734166 -379.934218) (xy 428.712376 -379.95987) (xy 428.706564 -379.967004)
			(xy 428.70006 -379.984203) (xy 428.699676 -379.993398) (xy 428.699676 -380.151386) (xy 428.699156 -380.161541)
			(xy 428.691388 -380.180307) (xy 428.677031 -380.194673) (xy 428.658269 -380.20245) (xy 428.648114 -380.202948)
			(xy 427.931834 -380.202948) (xy 427.921663 -380.202508) (xy 427.902866 -380.194731) (xy 427.88848 -380.180351)
			(xy 427.880696 -380.161557) (xy 427.880272 -380.151386) (xy 427.880272 -379.993398) (xy 427.879869 -379.98421)
			(xy 427.873351 -379.967025) (xy 427.867572 -379.95987) (xy 427.845829 -379.934181) (xy 427.807876 -379.878601)
			(xy 427.776839 -379.818882) (xy 427.753162 -379.755883) (xy 427.737185 -379.690505) (xy 427.729137 -379.623686)
			(xy 427.729133 -379.556384) (xy 427.737173 -379.489564) (xy 427.753142 -379.424183) (xy 427.776811 -379.361181)
			(xy 427.807841 -379.301459) (xy 427.845786 -379.245874) (xy 427.867572 -379.220222) (xy 427.873393 -379.213094)
			(xy 427.879891 -379.19589) (xy 427.880272 -379.186694) (xy 427.880272 -378.693426) (xy 427.879856 -378.684239)
			(xy 427.873347 -378.667055) (xy 427.867572 -378.659898) (xy 427.845758 -378.634267) (xy 427.807808 -378.578678)
			(xy 427.776774 -378.518952) (xy 427.753101 -378.455945) (xy 427.737129 -378.39056) (xy 427.729086 -378.323734)
			(xy 424.451048 -378.323734) (xy 424.451048 -378.323791) (xy 424.442974 -378.390728) (xy 424.426941 -378.456216)
			(xy 424.403179 -378.519312) (xy 424.37203 -378.579107) (xy 424.333943 -378.634741) (xy 424.31208 -378.660406)
			(xy 424.306296 -378.66756) (xy 424.299775 -378.684744) (xy 424.29938 -378.693934) (xy 424.29938 -379.186186)
			(xy 424.299802 -379.195372) (xy 424.306308 -379.212556) (xy 424.31208 -379.219714) (xy 424.33399 -379.245342)
			(xy 424.372079 -379.300981) (xy 424.403228 -379.360782) (xy 424.426991 -379.423884) (xy 424.443024 -379.489378)
			(xy 424.451096 -379.556321) (xy 424.451092 -379.623748) (xy 424.443011 -379.69069) (xy 424.42697 -379.756182)
			(xy 424.4032 -379.819281) (xy 424.372043 -379.879078) (xy 424.333947 -379.934713) (xy 424.31208 -379.960378)
			(xy 424.306266 -379.96751) (xy 424.299762 -379.984711) (xy 424.29938 -379.993906) (xy 424.29938 -380.151386)
			(xy 424.298863 -380.161509) (xy 424.291143 -380.180226) (xy 424.276866 -380.194583) (xy 424.258193 -380.202406)
			(xy 424.248072 -380.202948) (xy 423.531792 -380.202948) (xy 423.521643 -380.202486) (xy 423.5029 -380.194697)
			(xy 423.488579 -380.180313) (xy 423.480871 -380.161536) (xy 423.480484 -380.151386) (xy 423.480484 -379.993906)
			(xy 423.480075 -379.984719) (xy 423.473561 -379.967534) (xy 423.467784 -379.960378) (xy 423.445966 -379.934675)
			(xy 423.407877 -379.879046) (xy 423.376725 -379.819255) (xy 423.352959 -379.756163) (xy 423.336921 -379.690678)
			(xy 423.328841 -379.623744) (xy 423.328837 -379.556325) (xy 423.336908 -379.48939) (xy 423.352938 -379.423904)
			(xy 423.376697 -379.360809) (xy 423.407841 -379.301014) (xy 423.445923 -379.245379) (xy 423.467784 -379.219714)
			(xy 423.473598 -379.212581) (xy 423.480103 -379.195381) (xy 423.480484 -379.186186) (xy 423.480484 -378.693934)
			(xy 423.480061 -378.684748) (xy 423.473557 -378.667563) (xy 423.467784 -378.660406) (xy 423.445895 -378.634762)
			(xy 423.407808 -378.579124) (xy 423.376659 -378.519324) (xy 423.352897 -378.456225) (xy 423.336864 -378.390733)
			(xy 423.328791 -378.323793) (xy 420.050721 -378.323793) (xy 420.042687 -378.390552) (xy 420.026718 -378.455932)
			(xy 420.003049 -378.518936) (xy 419.972021 -378.578659) (xy 419.934077 -378.634245) (xy 419.912292 -378.659898)
			(xy 419.906513 -378.667056) (xy 419.899988 -378.684237) (xy 419.899592 -378.693426) (xy 419.899592 -379.186694)
			(xy 419.900007 -379.195881) (xy 419.906518 -379.213065) (xy 419.912292 -379.220222) (xy 419.934124 -379.245837)
			(xy 419.972069 -379.30143) (xy 420.003099 -379.361159) (xy 420.026768 -379.424168) (xy 420.042737 -379.489554)
			(xy 420.050777 -379.556381) (xy 420.050772 -379.623689) (xy 420.042724 -379.690514) (xy 420.026747 -379.755898)
			(xy 420.003071 -379.818905) (xy 419.972034 -379.87863) (xy 419.934082 -379.934217) (xy 419.912292 -379.95987)
			(xy 419.906482 -379.967006) (xy 419.899976 -379.984204) (xy 419.899592 -379.993398) (xy 419.899592 -380.151386)
			(xy 419.899056 -380.161539) (xy 419.891292 -380.180302) (xy 419.876939 -380.194667) (xy 419.858183 -380.202447)
			(xy 419.84803 -380.202948) (xy 419.13175 -380.202948) (xy 419.12158 -380.202495) (xy 419.102784 -380.194724)
			(xy 419.088396 -380.180347) (xy 419.080612 -380.161556) (xy 419.080188 -380.151386) (xy 419.080188 -379.993398)
			(xy 419.079781 -379.98421) (xy 419.073266 -379.967026) (xy 419.067488 -379.95987) (xy 419.045744 -379.934181)
			(xy 419.007791 -379.878601) (xy 418.976753 -379.818883) (xy 418.953075 -379.755883) (xy 418.937097 -379.690505)
			(xy 418.929049 -379.623686) (xy 418.929045 -379.556383) (xy 418.937085 -379.489563) (xy 418.953055 -379.424183)
			(xy 418.976724 -379.36118) (xy 419.007755 -379.301458) (xy 419.045702 -379.245873) (xy 419.067488 -379.220222)
			(xy 419.073299 -379.213087) (xy 419.079805 -379.195889) (xy 419.080188 -379.186694) (xy 419.080188 -378.693426)
			(xy 419.079768 -378.68424) (xy 419.073262 -378.667055) (xy 419.067488 -378.659898) (xy 419.045673 -378.634268)
			(xy 419.007722 -378.578679) (xy 418.976687 -378.518953) (xy 418.953014 -378.455946) (xy 418.937041 -378.39056)
			(xy 418.928998 -378.323734) (xy 389.250698 -378.323734) (xy 389.242656 -378.390553) (xy 389.226686 -378.455934)
			(xy 389.203015 -378.518937) (xy 389.171985 -378.57866) (xy 389.134038 -378.634246) (xy 389.112252 -378.659898)
			(xy 389.106468 -378.667052) (xy 389.099947 -378.684236) (xy 389.099552 -378.693426) (xy 389.099552 -379.186694)
			(xy 389.099976 -379.19588) (xy 389.106481 -379.213063) (xy 389.112252 -379.220222) (xy 389.134085 -379.245837)
			(xy 389.172033 -379.301428) (xy 389.203065 -379.361157) (xy 389.226736 -379.424166) (xy 389.242706 -379.489553)
			(xy 389.250746 -379.55638) (xy 389.250742 -379.623689) (xy 389.242693 -379.690515) (xy 389.226715 -379.7559)
			(xy 389.203037 -379.818906) (xy 389.171998 -379.878631) (xy 389.134043 -379.934218) (xy 389.112252 -379.95987)
			(xy 389.106437 -379.967002) (xy 389.099935 -379.984203) (xy 389.099552 -379.993398) (xy 389.099552 -380.151386)
			(xy 389.099125 -380.161558) (xy 389.091342 -380.180354) (xy 389.076958 -380.19474) (xy 389.058162 -380.202524)
			(xy 389.04799 -380.202948) (xy 388.33171 -380.202948) (xy 388.321537 -380.202528) (xy 388.30274 -380.194743)
			(xy 388.288354 -380.180357) (xy 388.280571 -380.161559) (xy 388.280148 -380.151386) (xy 388.280148 -379.993398)
			(xy 388.279728 -379.984212) (xy 388.27322 -379.967028) (xy 388.267448 -379.95987) (xy 388.245705 -379.934181)
			(xy 388.207755 -379.8786) (xy 388.176719 -379.818881) (xy 388.153043 -379.755882) (xy 388.137067 -379.690504)
			(xy 388.129019 -379.623685) (xy 388.129015 -379.556384) (xy 388.137054 -379.489564) (xy 388.153023 -379.424184)
			(xy 388.176691 -379.361182) (xy 388.207719 -379.30146) (xy 388.245663 -379.245874) (xy 388.267448 -379.220222)
			(xy 388.273266 -379.213092) (xy 388.279767 -379.19589) (xy 388.280148 -379.186694) (xy 388.280148 -378.693426)
			(xy 388.279715 -378.684241) (xy 388.273216 -378.667057) (xy 388.267448 -378.659898) (xy 388.245634 -378.634267)
			(xy 388.207686 -378.578678) (xy 388.176653 -378.518951) (xy 388.152981 -378.455944) (xy 388.13701 -378.390559)
			(xy 388.128968 -378.323734) (xy 384.850907 -378.323734) (xy 384.842865 -378.390553) (xy 384.826895 -378.455933)
			(xy 384.803225 -378.518937) (xy 384.772195 -378.57866) (xy 384.73425 -378.634246) (xy 384.712464 -378.659898)
			(xy 384.706681 -378.667053) (xy 384.700159 -378.684236) (xy 384.699764 -378.693426) (xy 384.699764 -379.186694)
			(xy 384.700185 -379.19588) (xy 384.706692 -379.213064) (xy 384.712464 -379.220222) (xy 384.734297 -379.245837)
			(xy 384.772244 -379.301429) (xy 384.803275 -379.361158) (xy 384.826945 -379.424167) (xy 384.842915 -379.489554)
			(xy 384.850955 -379.55638) (xy 384.850951 -379.623689) (xy 384.842903 -379.690515) (xy 384.826925 -379.755899)
			(xy 384.803247 -379.818906) (xy 384.772209 -379.878631) (xy 384.734255 -379.934218) (xy 384.712464 -379.95987)
			(xy 384.706651 -379.967003) (xy 384.700147 -379.984203) (xy 384.699764 -379.993398) (xy 384.699764 -380.151386)
			(xy 384.699325 -380.161556) (xy 384.691545 -380.180351) (xy 384.677164 -380.194736) (xy 384.658372 -380.202522)
			(xy 384.648202 -380.202948) (xy 383.931922 -380.202948) (xy 383.92175 -380.202518) (xy 383.902953 -380.194737)
			(xy 383.888567 -380.180353) (xy 383.880784 -380.161558) (xy 383.88036 -380.151386) (xy 383.88036 -379.993398)
			(xy 383.879937 -379.984212) (xy 383.873431 -379.967029) (xy 383.86766 -379.95987) (xy 383.845917 -379.934181)
			(xy 383.807965 -379.8786) (xy 383.776929 -379.818882) (xy 383.753253 -379.755882) (xy 383.737276 -379.690504)
			(xy 383.729228 -379.623685) (xy 383.729224 -379.556384) (xy 383.737264 -379.489564) (xy 383.753232 -379.424184)
			(xy 383.776901 -379.361181) (xy 383.80793 -379.301459) (xy 383.845875 -379.245874) (xy 383.86766 -379.220222)
			(xy 383.87348 -379.213093) (xy 383.879979 -379.19589) (xy 383.88036 -379.186694) (xy 383.88036 -378.693426)
			(xy 383.879924 -378.684242) (xy 383.873427 -378.667058) (xy 383.86766 -378.659898) (xy 383.845846 -378.634267)
			(xy 383.807896 -378.578678) (xy 383.776863 -378.518952) (xy 383.753191 -378.455945) (xy 383.737219 -378.39056)
			(xy 383.729177 -378.323734) (xy 380.451139 -378.323734) (xy 380.451139 -378.323792) (xy 380.443065 -378.390729)
			(xy 380.427031 -378.456217) (xy 380.403269 -378.519313) (xy 380.372119 -378.579108) (xy 380.334032 -378.634741)
			(xy 380.312168 -378.660406) (xy 380.306382 -378.667559) (xy 380.299862 -378.684744) (xy 380.299468 -378.693934)
			(xy 380.299468 -379.186186) (xy 380.299892 -379.195372) (xy 380.306397 -379.212556) (xy 380.312168 -379.219714)
			(xy 380.334078 -379.245341) (xy 380.372168 -379.300981) (xy 380.403318 -379.360782) (xy 380.427081 -379.423884)
			(xy 380.443114 -379.489378) (xy 380.451187 -379.556321) (xy 380.451183 -379.623749) (xy 380.443102 -379.69069)
			(xy 380.427061 -379.756182) (xy 380.40329 -379.819281) (xy 380.372132 -379.879079) (xy 380.334036 -379.934713)
			(xy 380.312168 -379.960378) (xy 380.306352 -379.967509) (xy 380.29985 -379.984711) (xy 380.299468 -379.993906)
			(xy 380.299468 -380.151386) (xy 380.298962 -380.161511) (xy 380.291241 -380.18023) (xy 380.27696 -380.194587)
			(xy 380.258282 -380.202408) (xy 380.24816 -380.202948) (xy 379.53188 -380.202948) (xy 379.521731 -380.202496)
			(xy 379.502987 -380.194703) (xy 379.488666 -380.180316) (xy 379.480958 -380.161537) (xy 379.480572 -380.151386)
			(xy 379.480572 -379.993906) (xy 379.480165 -379.984718) (xy 379.47365 -379.967534) (xy 379.467872 -379.960378)
			(xy 379.446054 -379.934675) (xy 379.407966 -379.879045) (xy 379.376815 -379.819254) (xy 379.353049 -379.756162)
			(xy 379.337011 -379.690678) (xy 379.328932 -379.623744) (xy 379.328928 -379.556325) (xy 379.336999 -379.48939)
			(xy 379.353029 -379.423904) (xy 379.376787 -379.360809) (xy 379.40793 -379.301014) (xy 379.446012 -379.24538)
			(xy 379.467872 -379.219714) (xy 379.473696 -379.212589) (xy 379.480192 -379.195383) (xy 379.480572 -379.186186)
			(xy 379.480572 -378.693934) (xy 379.480152 -378.684748) (xy 379.473646 -378.667563) (xy 379.467872 -378.660406)
			(xy 379.445983 -378.634761) (xy 379.407897 -378.579123) (xy 379.376749 -378.519324) (xy 379.352988 -378.456224)
			(xy 379.336955 -378.390733) (xy 379.328882 -378.323793) (xy 376.050812 -378.323793) (xy 376.042778 -378.390552)
			(xy 376.026808 -378.455933) (xy 376.003139 -378.518936) (xy 375.97211 -378.578659) (xy 375.934166 -378.634246)
			(xy 375.91238 -378.659898) (xy 375.906599 -378.667054) (xy 375.900076 -378.684236) (xy 375.89968 -378.693426)
			(xy 375.89968 -379.186694) (xy 375.900098 -379.19588) (xy 375.906607 -379.213064) (xy 375.91238 -379.220222)
			(xy 375.934212 -379.245837) (xy 375.972159 -379.301429) (xy 376.003189 -379.361158) (xy 376.026858 -379.424168)
			(xy 376.042827 -379.489554) (xy 376.050868 -379.55638) (xy 376.050863 -379.623689) (xy 376.042815 -379.690514)
			(xy 376.026838 -379.755899) (xy 376.003161 -379.818905) (xy 375.972123 -379.87863) (xy 375.93417 -379.934218)
			(xy 375.91238 -379.95987) (xy 375.906569 -379.967005) (xy 375.900064 -379.984203) (xy 375.89968 -379.993398)
			(xy 375.89968 -380.151386) (xy 375.899156 -380.161541) (xy 375.891389 -380.180306) (xy 375.877033 -380.194671)
			(xy 375.858272 -380.202449) (xy 375.848118 -380.202948) (xy 375.131838 -380.202948) (xy 375.121667 -380.202505)
			(xy 375.102871 -380.19473) (xy 375.088484 -380.18035) (xy 375.0807 -380.161557) (xy 375.080276 -380.151386)
			(xy 375.080276 -379.993398) (xy 375.079872 -379.98421) (xy 375.073355 -379.967025) (xy 375.067576 -379.95987)
			(xy 375.045832 -379.934181) (xy 375.00788 -379.878601) (xy 374.976842 -379.818883) (xy 374.953165 -379.755883)
			(xy 374.937188 -379.690505) (xy 374.92914 -379.623686) (xy 374.929136 -379.556384) (xy 374.937176 -379.489563)
			(xy 374.953145 -379.424183) (xy 374.976814 -379.361181) (xy 375.007844 -379.301459) (xy 375.04579 -379.245874)
			(xy 375.067576 -379.220222) (xy 375.073385 -379.213086) (xy 375.079893 -379.195889) (xy 375.080276 -379.186694)
			(xy 375.080276 -378.693426) (xy 375.079859 -378.684239) (xy 375.073351 -378.667055) (xy 375.067576 -378.659898)
			(xy 375.045762 -378.634267) (xy 375.007811 -378.578679) (xy 374.976777 -378.518952) (xy 374.953104 -378.455945)
			(xy 374.937132 -378.39056) (xy 374.929089 -378.323734) (xy 345.250789 -378.323734) (xy 345.242747 -378.390553)
			(xy 345.226776 -378.455934) (xy 345.203105 -378.518938) (xy 345.172074 -378.57866) (xy 345.134127 -378.634246)
			(xy 345.11234 -378.659898) (xy 345.106554 -378.667051) (xy 345.100035 -378.684236) (xy 345.09964 -378.693426)
			(xy 345.09964 -379.186694) (xy 345.100066 -379.195879) (xy 345.10657 -379.213063) (xy 345.11234 -379.220222)
			(xy 345.134174 -379.245837) (xy 345.172123 -379.301428) (xy 345.203155 -379.361156) (xy 345.226826 -379.424166)
			(xy 345.242797 -379.489553) (xy 345.250837 -379.55638) (xy 345.250833 -379.623689) (xy 345.242784 -379.690515)
			(xy 345.226806 -379.7559) (xy 345.203127 -379.818907) (xy 345.172087 -379.878632) (xy 345.134131 -379.934218)
			(xy 345.11234 -379.95987) (xy 345.106524 -379.967001) (xy 345.100023 -379.984203) (xy 345.09964 -379.993398)
			(xy 345.09964 -380.151386) (xy 345.099224 -380.161559) (xy 345.09144 -380.180358) (xy 345.077051 -380.194744)
			(xy 345.058252 -380.202526) (xy 345.048078 -380.202948) (xy 344.331798 -380.202948) (xy 344.321625 -380.202537)
			(xy 344.302827 -380.194749) (xy 344.288442 -380.180359) (xy 344.280659 -380.16156) (xy 344.280236 -380.151386)
			(xy 344.280236 -379.993398) (xy 344.279819 -379.984212) (xy 344.273309 -379.967028) (xy 344.267536 -379.95987)
			(xy 344.245794 -379.93418) (xy 344.207844 -379.878599) (xy 344.176809 -379.818881) (xy 344.153133 -379.755881)
			(xy 344.137157 -379.690504) (xy 344.12911 -379.623685) (xy 344.129106 -379.556384) (xy 344.137145 -379.489565)
			(xy 344.153113 -379.424185) (xy 344.17678 -379.361182) (xy 344.207808 -379.30146) (xy 344.245751 -379.245874)
			(xy 344.267536 -379.220222) (xy 344.273353 -379.213091) (xy 344.279855 -379.19589) (xy 344.280236 -379.186694)
			(xy 344.280236 -378.693426) (xy 344.279805 -378.684241) (xy 344.273305 -378.667057) (xy 344.267536 -378.659898)
			(xy 344.245723 -378.634267) (xy 344.207775 -378.578677) (xy 344.176743 -378.518951) (xy 344.153072 -378.455944)
			(xy 344.137101 -378.390559) (xy 344.129059 -378.323734) (xy 340.850998 -378.323734) (xy 340.842956 -378.390553)
			(xy 340.826986 -378.455934) (xy 340.803315 -378.518937) (xy 340.772285 -378.57866) (xy 340.734338 -378.634246)
			(xy 340.712552 -378.659898) (xy 340.706768 -378.667052) (xy 340.700247 -378.684236) (xy 340.699852 -378.693426)
			(xy 340.699852 -379.186694) (xy 340.700276 -379.19588) (xy 340.706781 -379.213063) (xy 340.712552 -379.220222)
			(xy 340.734385 -379.245837) (xy 340.772333 -379.301428) (xy 340.803365 -379.361157) (xy 340.827036 -379.424166)
			(xy 340.843006 -379.489553) (xy 340.851046 -379.55638) (xy 340.851042 -379.623689) (xy 340.842993 -379.690515)
			(xy 340.827015 -379.7559) (xy 340.803337 -379.818906) (xy 340.772298 -379.878631) (xy 340.734343 -379.934218)
			(xy 340.712552 -379.95987) (xy 340.706737 -379.967002) (xy 340.700235 -379.984203) (xy 340.699852 -379.993398)
			(xy 340.699852 -380.151386) (xy 340.699425 -380.161558) (xy 340.691642 -380.180354) (xy 340.677258 -380.19474)
			(xy 340.658462 -380.202524) (xy 340.64829 -380.202948) (xy 339.93201 -380.202948) (xy 339.921837 -380.202528)
			(xy 339.90304 -380.194743) (xy 339.888654 -380.180357) (xy 339.880871 -380.161559) (xy 339.880448 -380.151386)
			(xy 339.880448 -379.993398) (xy 339.880028 -379.984212) (xy 339.87352 -379.967028) (xy 339.867748 -379.95987)
			(xy 339.846005 -379.934181) (xy 339.808055 -379.8786) (xy 339.777019 -379.818881) (xy 339.753343 -379.755882)
			(xy 339.737367 -379.690504) (xy 339.729319 -379.623685) (xy 339.729315 -379.556384) (xy 339.737354 -379.489564)
			(xy 339.753323 -379.424184) (xy 339.776991 -379.361182) (xy 339.808019 -379.30146) (xy 339.845963 -379.245874)
			(xy 339.867748 -379.220222) (xy 339.873566 -379.213092) (xy 339.880067 -379.19589) (xy 339.880448 -379.186694)
			(xy 339.880448 -378.693426) (xy 339.880015 -378.684241) (xy 339.873516 -378.667057) (xy 339.867748 -378.659898)
			(xy 339.845934 -378.634267) (xy 339.807986 -378.578678) (xy 339.776953 -378.518951) (xy 339.753281 -378.455944)
			(xy 339.73731 -378.390559) (xy 339.729268 -378.323734) (xy 336.45123 -378.323734) (xy 336.45123 -378.323792)
			(xy 336.443156 -378.390729) (xy 336.427122 -378.456217) (xy 336.403359 -378.519313) (xy 336.372208 -378.579108)
			(xy 336.33412 -378.634742) (xy 336.312256 -378.660406) (xy 336.306469 -378.667558) (xy 336.29995 -378.684743)
			(xy 336.299556 -378.693934) (xy 336.299556 -379.186186) (xy 336.299983 -379.195371) (xy 336.306486 -379.212555)
			(xy 336.312256 -379.219714) (xy 336.334167 -379.245341) (xy 336.372257 -379.30098) (xy 336.403408 -379.360781)
			(xy 336.427172 -379.423883) (xy 336.443205 -379.489377) (xy 336.451278 -379.55632) (xy 336.451274 -379.623749)
			(xy 336.443193 -379.690691) (xy 336.427151 -379.756183) (xy 336.40338 -379.819282) (xy 336.372221 -379.879079)
			(xy 336.334124 -379.934713) (xy 336.312256 -379.960378) (xy 336.306438 -379.967508) (xy 336.299937 -379.98471)
			(xy 336.299556 -379.993906) (xy 336.299556 -380.151386) (xy 336.299062 -380.161512) (xy 336.291338 -380.180234)
			(xy 336.277054 -380.194591) (xy 336.258372 -380.20241) (xy 336.248248 -380.202948) (xy 335.531968 -380.202948)
			(xy 335.521818 -380.202506) (xy 335.503074 -380.194708) (xy 335.488753 -380.180319) (xy 335.481046 -380.161538)
			(xy 335.48066 -380.151386) (xy 335.48066 -379.993906) (xy 335.480234 -379.984721) (xy 335.47373 -379.967537)
			(xy 335.46796 -379.960378) (xy 335.446143 -379.934675) (xy 335.408055 -379.879045) (xy 335.376905 -379.819253)
			(xy 335.35314 -379.756162) (xy 335.337102 -379.690678) (xy 335.329023 -379.623744) (xy 335.329019 -379.556325)
			(xy 335.33709 -379.48939) (xy 335.353119 -379.423904) (xy 335.376876 -379.36081) (xy 335.40802 -379.301015)
			(xy 335.4461 -379.24538) (xy 335.46796 -379.219714) (xy 335.473783 -379.212588) (xy 335.48028 -379.195382)
			(xy 335.48066 -379.186186) (xy 335.48066 -378.693934) (xy 335.48022 -378.68475) (xy 335.473726 -378.667566)
			(xy 335.46796 -378.660406) (xy 335.446072 -378.634761) (xy 335.407987 -378.579123) (xy 335.376839 -378.519323)
			(xy 335.353078 -378.456224) (xy 335.337046 -378.390733) (xy 335.328973 -378.323793) (xy 332.050903 -378.323793)
			(xy 332.042868 -378.390553) (xy 332.026898 -378.455933) (xy 332.003229 -378.518937) (xy 331.972199 -378.578659)
			(xy 331.934254 -378.634246) (xy 331.912468 -378.659898) (xy 331.906686 -378.667053) (xy 331.900163 -378.684236)
			(xy 331.899768 -378.693426) (xy 331.899768 -379.186694) (xy 331.900188 -379.19588) (xy 331.906696 -379.213064)
			(xy 331.912468 -379.220222) (xy 331.934301 -379.245837) (xy 331.972248 -379.301429) (xy 332.003279 -379.361158)
			(xy 332.026949 -379.424167) (xy 332.042918 -379.489554) (xy 332.050958 -379.55638) (xy 332.050954 -379.623689)
			(xy 332.042906 -379.690514) (xy 332.026928 -379.755899) (xy 332.00325 -379.818906) (xy 331.972212 -379.878631)
			(xy 331.934258 -379.934218) (xy 331.912468 -379.95987) (xy 331.906655 -379.967003) (xy 331.900151 -379.984203)
			(xy 331.899768 -379.993398) (xy 331.899768 -380.151386) (xy 331.899325 -380.161556) (xy 331.891546 -380.180349)
			(xy 331.877166 -380.194734) (xy 331.858376 -380.202521) (xy 331.848206 -380.202948) (xy 331.131926 -380.202948)
			(xy 331.121754 -380.202514) (xy 331.102958 -380.194735) (xy 331.088571 -380.180352) (xy 331.080788 -380.161558)
			(xy 331.080364 -380.151386) (xy 331.080364 -379.993398) (xy 331.07994 -379.984213) (xy 331.073434 -379.967029)
			(xy 331.067664 -379.95987) (xy 331.045921 -379.934181) (xy 331.007969 -379.8786) (xy 330.976932 -379.818882)
			(xy 330.953256 -379.755882) (xy 330.937279 -379.690504) (xy 330.929231 -379.623686) (xy 330.929227 -379.556384)
			(xy 330.937267 -379.489564) (xy 330.953235 -379.424184) (xy 330.976904 -379.361181) (xy 331.007933 -379.301459)
			(xy 331.045878 -379.245874) (xy 331.067664 -379.220222) (xy 331.073484 -379.213094) (xy 331.079983 -379.19589)
			(xy 331.080364 -379.186694) (xy 331.080364 -378.693426) (xy 331.079927 -378.684242) (xy 331.07343 -378.667058)
			(xy 331.067664 -378.659898) (xy 331.04585 -378.634267) (xy 331.0079 -378.578678) (xy 330.976866 -378.518952)
			(xy 330.953194 -378.455945) (xy 330.937222 -378.39056) (xy 330.92918 -378.323734) (xy 301.250878 -378.323734)
			(xy 301.250878 -378.323791) (xy 301.242805 -378.390727) (xy 301.226773 -378.456215) (xy 301.203013 -378.51931)
			(xy 301.171866 -378.579106) (xy 301.133782 -378.63474) (xy 301.11192 -378.660406) (xy 301.106141 -378.667564)
			(xy 301.099615 -378.684745) (xy 301.09922 -378.693934) (xy 301.09922 -379.186186) (xy 301.099632 -379.195373)
			(xy 301.106144 -379.212558) (xy 301.11192 -379.219714) (xy 301.133828 -379.245342) (xy 301.171914 -379.300983)
			(xy 301.203062 -379.360784) (xy 301.226823 -379.423886) (xy 301.242854 -379.489379) (xy 301.250926 -379.556321)
			(xy 301.250922 -379.623748) (xy 301.242842 -379.690689) (xy 301.226802 -379.75618) (xy 301.203034 -379.819279)
			(xy 301.171879 -379.879077) (xy 301.133786 -379.934712) (xy 301.11192 -379.960378) (xy 301.10611 -379.967514)
			(xy 301.099603 -379.984711) (xy 301.09922 -379.993906) (xy 301.09922 -380.151386) (xy 301.098761 -380.161517)
			(xy 301.09103 -380.180245) (xy 301.076735 -380.194603) (xy 301.058041 -380.202416) (xy 301.047912 -380.202948)
			(xy 300.331632 -380.202948) (xy 300.321486 -380.202453) (xy 300.302743 -380.194677) (xy 300.28842 -380.180304)
			(xy 300.280711 -380.161534) (xy 300.280324 -380.151386) (xy 300.280324 -379.993906) (xy 300.279906 -379.98472)
			(xy 300.273397 -379.967536) (xy 300.267624 -379.960378) (xy 300.245804 -379.934676) (xy 300.207713 -379.879047)
			(xy 300.176559 -379.819256) (xy 300.152791 -379.756164) (xy 300.136751 -379.690679) (xy 300.128672 -379.623745)
			(xy 300.128667 -379.556324) (xy 300.136739 -379.489389) (xy 300.15277 -379.423902) (xy 300.17653 -379.360807)
			(xy 300.207677 -379.301012) (xy 300.245762 -379.245379) (xy 300.267624 -379.219714) (xy 300.273442 -379.212584)
			(xy 300.279943 -379.195382) (xy 300.280324 -379.186186) (xy 300.280324 -378.693934) (xy 300.279892 -378.684749)
			(xy 300.273393 -378.667565) (xy 300.267624 -378.660406) (xy 300.245734 -378.634762) (xy 300.207644 -378.579125)
			(xy 300.176493 -378.519326) (xy 300.152729 -378.456227) (xy 300.136695 -378.390735) (xy 300.128621 -378.323794)
			(xy 296.851087 -378.323794) (xy 296.843014 -378.390727) (xy 296.826983 -378.456214) (xy 296.803223 -378.51931)
			(xy 296.772077 -378.579105) (xy 296.733993 -378.63474) (xy 296.712132 -378.660406) (xy 296.706342 -378.667556)
			(xy 296.699825 -378.684743) (xy 296.699432 -378.693934) (xy 296.699432 -379.186186) (xy 296.699864 -379.195371)
			(xy 296.706364 -379.212554) (xy 296.712132 -379.219714) (xy 296.73404 -379.245342) (xy 296.772125 -379.300983)
			(xy 296.803272 -379.360785) (xy 296.827032 -379.423886) (xy 296.843064 -379.489379) (xy 296.851135 -379.556321)
			(xy 296.851131 -379.623748) (xy 296.843051 -379.690689) (xy 296.827012 -379.75618) (xy 296.803244 -379.819279)
			(xy 296.77209 -379.879076) (xy 296.733998 -379.934712) (xy 296.712132 -379.960378) (xy 296.706312 -379.967506)
			(xy 296.699813 -379.98471) (xy 296.699432 -379.993906) (xy 296.699432 -380.151386) (xy 296.698961 -380.161515)
			(xy 296.691233 -380.180241) (xy 296.676941 -380.194599) (xy 296.658251 -380.202414) (xy 296.648124 -380.202948)
			(xy 295.931844 -380.202948) (xy 295.921699 -380.202443) (xy 295.902957 -380.194671) (xy 295.888633 -380.1803)
			(xy 295.880924 -380.161533) (xy 295.880536 -380.151386) (xy 295.880536 -379.993906) (xy 295.880115 -379.98472)
			(xy 295.873608 -379.967536) (xy 295.867836 -379.960378) (xy 295.846016 -379.934676) (xy 295.807924 -379.879048)
			(xy 295.776769 -379.819257) (xy 295.753 -379.756165) (xy 295.736961 -379.69068) (xy 295.728881 -379.623745)
			(xy 295.728876 -379.556324) (xy 295.736948 -379.489388) (xy 295.75298 -379.423901) (xy 295.776741 -379.360806)
			(xy 295.807888 -379.301012) (xy 295.845974 -379.245379) (xy 295.867836 -379.219714) (xy 295.873656 -379.212586)
			(xy 295.880156 -379.195382) (xy 295.880536 -379.186186) (xy 295.880536 -378.693934) (xy 295.880101 -378.68475)
			(xy 295.873604 -378.667565) (xy 295.867836 -378.660406) (xy 295.845945 -378.634762) (xy 295.807855 -378.579126)
			(xy 295.776703 -378.519327) (xy 295.752939 -378.456227) (xy 295.736904 -378.390735) (xy 295.72883 -378.323794)
			(xy 292.450785 -378.323794) (xy 292.44275 -378.390553) (xy 292.426779 -378.455934) (xy 292.403109 -378.518938)
			(xy 292.372077 -378.57866) (xy 292.334131 -378.634246) (xy 292.312344 -378.659898) (xy 292.306559 -378.667051)
			(xy 292.300039 -378.684236) (xy 292.299644 -378.693426) (xy 292.299644 -379.186694) (xy 292.30007 -379.195879)
			(xy 292.306574 -379.213063) (xy 292.312344 -379.220222) (xy 292.334178 -379.245837) (xy 292.372126 -379.301428)
			(xy 292.403158 -379.361157) (xy 292.426829 -379.424166) (xy 292.4428 -379.489553) (xy 292.45084 -379.55638)
			(xy 292.450836 -379.623689) (xy 292.442787 -379.690515) (xy 292.426809 -379.7559) (xy 292.40313 -379.818907)
			(xy 292.372091 -379.878631) (xy 292.334135 -379.934218) (xy 292.312344 -379.95987) (xy 292.306528 -379.967001)
			(xy 292.300027 -379.984203) (xy 292.299644 -379.993398) (xy 292.299644 -380.151386) (xy 292.299224 -380.161559)
			(xy 292.291441 -380.180357) (xy 292.277054 -380.194743) (xy 292.258255 -380.202525) (xy 292.248082 -380.202948)
			(xy 291.531802 -380.202948) (xy 291.521629 -380.202534) (xy 291.502831 -380.194747) (xy 291.488446 -380.180358)
			(xy 291.480663 -380.161559) (xy 291.48024 -380.151386) (xy 291.48024 -379.993398) (xy 291.479822 -379.984212)
			(xy 291.473313 -379.967028) (xy 291.46754 -379.95987) (xy 291.445798 -379.934181) (xy 291.407847 -379.878599)
			(xy 291.376812 -379.818881) (xy 291.353137 -379.755881) (xy 291.337161 -379.690504) (xy 291.329113 -379.623685)
			(xy 291.329109 -379.556384) (xy 291.337148 -379.489564) (xy 291.353116 -379.424185) (xy 291.376784 -379.361182)
			(xy 291.407812 -379.30146) (xy 291.445755 -379.245874) (xy 291.46754 -379.220222) (xy 291.473357 -379.213092)
			(xy 291.479859 -379.19589) (xy 291.48024 -379.186694) (xy 291.48024 -378.693426) (xy 291.479809 -378.684241)
			(xy 291.473309 -378.667057) (xy 291.46754 -378.659898) (xy 291.445727 -378.634267) (xy 291.407778 -378.578678)
			(xy 291.376746 -378.518951) (xy 291.353075 -378.455944) (xy 291.337104 -378.390559) (xy 291.329062 -378.323734)
			(xy 288.051024 -378.323734) (xy 288.051024 -378.323792) (xy 288.04295 -378.390729) (xy 288.026915 -378.456218)
			(xy 288.003152 -378.519314) (xy 287.972001 -378.579109) (xy 287.933912 -378.634742) (xy 287.912048 -378.660406)
			(xy 287.90626 -378.667557) (xy 287.899742 -378.684743) (xy 287.899348 -378.693934) (xy 287.899348 -379.186186)
			(xy 287.899776 -379.195371) (xy 287.906279 -379.212555) (xy 287.912048 -379.219714) (xy 287.933959 -379.245341)
			(xy 287.97205 -379.30098) (xy 288.003201 -379.360781) (xy 288.026965 -379.423883) (xy 288.042999 -379.489377)
			(xy 288.051072 -379.55632) (xy 288.051068 -379.623749) (xy 288.042987 -379.690691) (xy 288.026945 -379.756183)
			(xy 288.003173 -379.819282) (xy 287.972014 -379.879079) (xy 287.933917 -379.934714) (xy 287.912048 -379.960378)
			(xy 287.906229 -379.967507) (xy 287.899729 -379.98471) (xy 287.899348 -379.993906) (xy 287.899348 -380.151386)
			(xy 287.898862 -380.161513) (xy 287.891136 -380.180236) (xy 287.87685 -380.194594) (xy 287.858165 -380.202411)
			(xy 287.84804 -380.202948) (xy 287.13176 -380.202948) (xy 287.121609 -380.202512) (xy 287.102865 -380.194712)
			(xy 287.088545 -380.180321) (xy 287.080838 -380.161539) (xy 287.080452 -380.151386) (xy 287.080452 -379.993906)
			(xy 287.080027 -379.984721) (xy 287.073523 -379.967537) (xy 287.067752 -379.960378) (xy 287.045931 -379.934676)
			(xy 287.007838 -379.879048) (xy 286.976682 -379.819258) (xy 286.952913 -379.756165) (xy 286.936873 -379.69068)
			(xy 286.928793 -379.623745) (xy 286.928788 -379.556324) (xy 286.936861 -379.489388) (xy 286.952893 -379.423901)
			(xy 286.976654 -379.360806) (xy 287.007802 -379.301011) (xy 287.045889 -379.245378) (xy 287.067752 -379.219714)
			(xy 287.073574 -379.212587) (xy 287.080072 -379.195382) (xy 287.080452 -379.186186) (xy 287.080452 -378.693934)
			(xy 287.080014 -378.68475) (xy 287.073519 -378.667566) (xy 287.067752 -378.660406) (xy 287.045861 -378.634763)
			(xy 287.007769 -378.579126) (xy 286.976617 -378.519328) (xy 286.952852 -378.456228) (xy 286.936817 -378.390735)
			(xy 286.928742 -378.323794) (xy 277.14076 -378.323794) (xy 277.146139 -378.392568) (xy 277.15414 -378.597491)
			(xy 277.15464 -378.70003) (xy 277.15414 -378.802569) (xy 277.146139 -379.007492) (xy 277.130148 -379.211946)
			(xy 277.106193 -379.41562) (xy 277.074309 -379.618205) (xy 277.034546 -379.819391) (xy 276.986963 -380.018873)
			(xy 276.931633 -380.216347) (xy 276.868641 -380.411512) (xy 276.798083 -380.60407) (xy 276.776531 -380.656463)
			(xy 289.128932 -380.656463) (xy 289.136975 -380.589641) (xy 289.152947 -380.524259) (xy 289.17662 -380.461255)
			(xy 289.207654 -380.401532) (xy 289.245604 -380.345947) (xy 289.267392 -380.320296) (xy 289.273172 -380.313139)
			(xy 289.279697 -380.295958) (xy 289.280092 -380.286768) (xy 289.280092 -379.7935) (xy 289.279684 -379.784313)
			(xy 289.273169 -379.767128) (xy 289.267392 -379.759972) (xy 289.24565 -379.734282) (xy 289.207696 -379.678702)
			(xy 289.176658 -379.618984) (xy 289.15298 -379.555985) (xy 289.137002 -379.490606) (xy 289.128953 -379.423787)
			(xy 289.128949 -379.356485) (xy 289.136989 -379.289665) (xy 289.152959 -379.224284) (xy 289.176628 -379.161282)
			(xy 289.207659 -379.10156) (xy 289.245606 -379.045975) (xy 289.267392 -379.020324) (xy 289.273202 -379.013189)
			(xy 289.279709 -378.995991) (xy 289.280092 -378.986796) (xy 289.280092 -378.828554) (xy 289.280595 -378.818399)
			(xy 289.288376 -378.799638) (xy 289.302738 -378.785276) (xy 289.321499 -378.777495) (xy 289.331654 -378.776992)
			(xy 290.047934 -378.776992) (xy 290.058088 -378.777504) (xy 290.076849 -378.785281) (xy 290.091212 -378.799641)
			(xy 290.098993 -378.8184) (xy 290.099496 -378.828554) (xy 290.099496 -378.986796) (xy 290.099909 -378.995983)
			(xy 290.106421 -379.013167) (xy 290.112196 -379.020324) (xy 290.13403 -379.045938) (xy 290.171975 -379.101531)
			(xy 290.203004 -379.16126) (xy 290.226673 -379.224269) (xy 290.242641 -379.289656) (xy 290.250681 -379.356482)
			(xy 290.250677 -379.42379) (xy 290.242628 -379.490615) (xy 290.226651 -379.556) (xy 290.202975 -379.619006)
			(xy 290.171938 -379.678731) (xy 290.133986 -379.734319) (xy 290.112196 -379.759972) (xy 290.106386 -379.767108)
			(xy 290.099879 -379.784305) (xy 290.099496 -379.7935) (xy 290.099496 -380.286768) (xy 290.099922 -380.295953)
			(xy 290.106425 -380.313138) (xy 290.112196 -380.320296) (xy 290.134002 -380.345932) (xy 290.171948 -380.401522)
			(xy 290.202979 -380.461248) (xy 290.226649 -380.524255) (xy 290.242619 -380.589638) (xy 290.250654 -380.656404)
			(xy 293.528724 -380.656404) (xy 293.536798 -380.589467) (xy 293.552831 -380.52398) (xy 293.576592 -380.460884)
			(xy 293.60774 -380.401088) (xy 293.645826 -380.345453) (xy 293.667688 -380.319788) (xy 293.673471 -380.312633)
			(xy 293.679994 -380.29545) (xy 293.680388 -380.28626) (xy 293.680388 -379.794008) (xy 293.679977 -379.784821)
			(xy 293.673464 -379.767636) (xy 293.667688 -379.76048) (xy 293.645872 -379.734776) (xy 293.607782 -379.679146)
			(xy 293.57663 -379.619356) (xy 293.552864 -379.556264) (xy 293.536825 -379.49078) (xy 293.528746 -379.423846)
			(xy 293.528741 -379.356426) (xy 293.536812 -379.289491) (xy 293.552842 -379.224005) (xy 293.576601 -379.16091)
			(xy 293.607745 -379.101115) (xy 293.645827 -379.045481) (xy 293.667688 -379.019816) (xy 293.673501 -379.012683)
			(xy 293.680006 -378.995483) (xy 293.680388 -378.986288) (xy 293.680388 -378.828554) (xy 293.680887 -378.818431)
			(xy 293.688621 -378.799718) (xy 293.702902 -378.785366) (xy 293.721575 -378.777539) (xy 293.731696 -378.776992)
			(xy 294.447976 -378.776992) (xy 294.458128 -378.777441) (xy 294.476878 -378.785227) (xy 294.491202 -378.799615)
			(xy 294.498904 -378.818401) (xy 294.499284 -378.828554) (xy 294.499284 -378.986288) (xy 294.499704 -378.995474)
			(xy 294.506211 -379.012658) (xy 294.511984 -379.019816) (xy 294.533896 -379.045442) (xy 294.571984 -379.101082)
			(xy 294.603134 -379.160883) (xy 294.626896 -379.223985) (xy 294.642928 -379.289479) (xy 294.651001 -379.356422)
			(xy 294.650996 -379.42385) (xy 294.642915 -379.490792) (xy 294.626874 -379.556284) (xy 294.603104 -379.619383)
			(xy 294.571947 -379.67918) (xy 294.533851 -379.734815) (xy 294.511984 -379.76048) (xy 294.506169 -379.767612)
			(xy 294.499666 -379.784813) (xy 294.499284 -379.794008) (xy 294.499284 -380.28626) (xy 294.499717 -380.295445)
			(xy 294.506215 -380.312629) (xy 294.511984 -380.319788) (xy 294.533868 -380.345437) (xy 294.571957 -380.401073)
			(xy 294.603108 -380.460872) (xy 294.626872 -380.523971) (xy 294.642906 -380.589462) (xy 294.650981 -380.656402)
			(xy 294.650981 -380.656463) (xy 297.92902 -380.656463) (xy 297.937062 -380.589641) (xy 297.953034 -380.52426)
			(xy 297.976707 -380.461256) (xy 298.00774 -380.401533) (xy 298.045688 -380.345948) (xy 298.067476 -380.320296)
			(xy 298.073254 -380.313137) (xy 298.079781 -380.295957) (xy 298.080176 -380.286768) (xy 298.080176 -379.7935)
			(xy 298.079771 -379.784312) (xy 298.073254 -379.767128) (xy 298.067476 -379.759972) (xy 298.045734 -379.734282)
			(xy 298.007782 -379.678701) (xy 297.976744 -379.618984) (xy 297.953067 -379.555984) (xy 297.93709 -379.490606)
			(xy 297.929041 -379.423787) (xy 297.929037 -379.356485) (xy 297.937077 -379.289665) (xy 297.953046 -379.224285)
			(xy 297.976715 -379.161283) (xy 298.007745 -379.101561) (xy 298.04569 -379.045976) (xy 298.067476 -379.020324)
			(xy 298.073285 -379.013187) (xy 298.079793 -378.99599) (xy 298.080176 -378.986796) (xy 298.080176 -378.828554)
			(xy 298.080597 -378.818389) (xy 298.088393 -378.799611) (xy 298.102782 -378.785246) (xy 298.121572 -378.77748)
			(xy 298.131738 -378.776992) (xy 298.848018 -378.776992) (xy 298.858171 -378.777517) (xy 298.876932 -378.785289)
			(xy 298.891295 -378.799644) (xy 298.899077 -378.818401) (xy 298.89958 -378.828554) (xy 298.89958 -378.986796)
			(xy 298.899996 -378.995982) (xy 298.906506 -379.013167) (xy 298.91228 -379.020324) (xy 298.934114 -379.045938)
			(xy 298.972061 -379.10153) (xy 299.003091 -379.161259) (xy 299.02676 -379.224269) (xy 299.042729 -379.289655)
			(xy 299.050769 -379.356482) (xy 299.050765 -379.42379) (xy 299.042716 -379.490616) (xy 299.026739 -379.556)
			(xy 299.003061 -379.619007) (xy 298.972023 -379.678732) (xy 298.93407 -379.73432) (xy 298.91228 -379.759972)
			(xy 298.906468 -379.767106) (xy 298.899963 -379.784305) (xy 298.89958 -379.7935) (xy 298.89958 -380.286768)
			(xy 298.90001 -380.295953) (xy 298.90651 -380.313137) (xy 298.91228 -380.320296) (xy 298.934087 -380.345932)
			(xy 298.972034 -380.401521) (xy 299.003065 -380.461247) (xy 299.026736 -380.524254) (xy 299.042707 -380.589638)
			(xy 299.050742 -380.656404) (xy 302.328812 -380.656404) (xy 302.336886 -380.589468) (xy 302.352918 -380.52398)
			(xy 302.376679 -380.460884) (xy 302.407826 -380.401089) (xy 302.44591 -380.345454) (xy 302.467772 -380.319788)
			(xy 302.473565 -380.312641) (xy 302.48008 -380.295451) (xy 302.480472 -380.28626) (xy 302.480472 -379.794008)
			(xy 302.480064 -379.78482) (xy 302.47355 -379.767636) (xy 302.467772 -379.76048) (xy 302.445956 -379.734775)
			(xy 302.407868 -379.679146) (xy 302.376717 -379.619355) (xy 302.352951 -379.556263) (xy 302.336913 -379.490779)
			(xy 302.328834 -379.423846) (xy 302.328829 -379.356426) (xy 302.3369 -379.289492) (xy 302.35293 -379.224006)
			(xy 302.376687 -379.160911) (xy 302.407831 -379.101116) (xy 302.445912 -379.045482) (xy 302.467772 -379.019816)
			(xy 302.473595 -379.01269) (xy 302.480092 -378.995485) (xy 302.480472 -378.986288) (xy 302.480472 -378.828554)
			(xy 302.48089 -378.81842) (xy 302.488639 -378.799692) (xy 302.502946 -378.785336) (xy 302.521648 -378.777525)
			(xy 302.53178 -378.776992) (xy 303.24806 -378.776992) (xy 303.258211 -378.777454) (xy 303.27696 -378.785235)
			(xy 303.291285 -378.79962) (xy 303.298987 -378.818402) (xy 303.299368 -378.828554) (xy 303.299368 -378.986288)
			(xy 303.299791 -378.995474) (xy 303.306296 -379.012658) (xy 303.312068 -379.019816) (xy 303.33398 -379.045442)
			(xy 303.37207 -379.101081) (xy 303.40322 -379.160883) (xy 303.426983 -379.223985) (xy 303.443016 -379.289479)
			(xy 303.451089 -379.356422) (xy 303.451084 -379.42385) (xy 303.443003 -379.490792) (xy 303.426962 -379.556284)
			(xy 303.403191 -379.619383) (xy 303.372032 -379.679181) (xy 303.333936 -379.734815) (xy 303.312068 -379.76048)
			(xy 303.306251 -379.76761) (xy 303.299749 -379.784812) (xy 303.299368 -379.794008) (xy 303.299368 -380.28626)
			(xy 303.299805 -380.295444) (xy 303.306301 -380.312628) (xy 303.312068 -380.319788) (xy 303.333953 -380.345436)
			(xy 303.372043 -380.401073) (xy 303.403195 -380.460871) (xy 303.426959 -380.52397) (xy 303.442994 -380.589461)
			(xy 303.451069 -380.656402) (xy 303.451069 -380.656404) (xy 333.128842 -380.656404) (xy 333.136916 -380.589467)
			(xy 333.15295 -380.523979) (xy 333.176713 -380.460883) (xy 333.207862 -380.401087) (xy 333.245949 -380.345453)
			(xy 333.267812 -380.319788) (xy 333.273598 -380.312635) (xy 333.280118 -380.29545) (xy 333.280512 -380.28626)
			(xy 333.280512 -379.794008) (xy 333.280095 -379.784822) (xy 333.273586 -379.767637) (xy 333.267812 -379.76048)
			(xy 333.245995 -379.734776) (xy 333.207904 -379.679147) (xy 333.17675 -379.619357) (xy 333.152983 -379.556265)
			(xy 333.136944 -379.49078) (xy 333.128864 -379.423846) (xy 333.12886 -379.356426) (xy 333.136931 -379.289491)
			(xy 333.152962 -379.224004) (xy 333.176721 -379.160909) (xy 333.207867 -379.101115) (xy 333.24595 -379.045481)
			(xy 333.267812 -379.019816) (xy 333.273628 -379.012685) (xy 333.280131 -378.995483) (xy 333.280512 -378.986288)
			(xy 333.280512 -378.828554) (xy 333.280988 -378.818428) (xy 333.288726 -378.799711) (xy 333.303015 -378.785357)
			(xy 333.321696 -378.777535) (xy 333.33182 -378.776992) (xy 334.0481 -378.776992) (xy 334.058253 -378.777422)
			(xy 334.077004 -378.785216) (xy 334.091327 -378.79961) (xy 334.099028 -378.818399) (xy 334.099408 -378.828554)
			(xy 334.099408 -378.986288) (xy 334.099822 -378.995475) (xy 334.106333 -379.012659) (xy 334.112108 -379.019816)
			(xy 334.134019 -379.045442) (xy 334.172106 -379.101083) (xy 334.203254 -379.160884) (xy 334.227015 -379.223986)
			(xy 334.243047 -379.28948) (xy 334.251119 -379.356422) (xy 334.251114 -379.42385) (xy 334.243034 -379.490791)
			(xy 334.226994 -379.556283) (xy 334.203224 -379.619382) (xy 334.172068 -379.679179) (xy 334.133975 -379.734815)
			(xy 334.112108 -379.76048) (xy 334.106296 -379.767614) (xy 334.09979 -379.784813) (xy 334.099408 -379.794008)
			(xy 334.099408 -380.28626) (xy 334.099836 -380.295445) (xy 334.106337 -380.31263) (xy 334.112108 -380.319788)
			(xy 334.133991 -380.345437) (xy 334.172079 -380.401074) (xy 334.203228 -380.460873) (xy 334.226991 -380.523972)
			(xy 334.243025 -380.589463) (xy 334.251099 -380.656402) (xy 334.251099 -380.656464) (xy 337.529162 -380.656464)
			(xy 337.537203 -380.589643) (xy 337.553173 -380.524262) (xy 337.576842 -380.461259) (xy 337.607871 -380.401536)
			(xy 337.645815 -380.345949) (xy 337.6676 -380.320296) (xy 337.673381 -380.31314) (xy 337.679905 -380.295958)
			(xy 337.6803 -380.286768) (xy 337.6803 -379.7935) (xy 337.67989 -379.784313) (xy 337.673376 -379.767129)
			(xy 337.6676 -379.759972) (xy 337.645861 -379.734281) (xy 337.607913 -379.678699) (xy 337.57688 -379.61898)
			(xy 337.553206 -379.555981) (xy 337.537231 -379.490604) (xy 337.529183 -379.423786) (xy 337.529179 -379.356486)
			(xy 337.537218 -379.289667) (xy 337.553185 -379.224288) (xy 337.57685 -379.161286) (xy 337.607876 -379.101563)
			(xy 337.645816 -379.045977) (xy 337.6676 -379.020324) (xy 337.673411 -379.013189) (xy 337.679917 -378.995991)
			(xy 337.6803 -378.986796) (xy 337.6803 -378.828554) (xy 337.680795 -378.818398) (xy 337.688577 -378.799635)
			(xy 337.702942 -378.785273) (xy 337.721706 -378.777493) (xy 337.731862 -378.776992) (xy 338.448142 -378.776992)
			(xy 338.458297 -378.777498) (xy 338.477058 -378.785278) (xy 338.49142 -378.799639) (xy 338.499201 -378.818399)
			(xy 338.499704 -378.828554) (xy 338.499704 -378.986796) (xy 338.500115 -378.995983) (xy 338.506628 -379.013167)
			(xy 338.512404 -379.020324) (xy 338.534237 -379.045938) (xy 338.572182 -379.101531) (xy 338.603211 -379.16126)
			(xy 338.626879 -379.22427) (xy 338.642847 -379.289656) (xy 338.650887 -379.356482) (xy 338.650883 -379.42379)
			(xy 338.642834 -379.490615) (xy 338.626858 -379.556) (xy 338.603181 -379.619006) (xy 338.572145 -379.678731)
			(xy 338.534193 -379.734319) (xy 338.512404 -379.759972) (xy 338.506595 -379.767108) (xy 338.500088 -379.784306)
			(xy 338.499704 -379.7935) (xy 338.499704 -380.286768) (xy 338.500129 -380.295954) (xy 338.506632 -380.313138)
			(xy 338.512404 -380.320296) (xy 338.53421 -380.345933) (xy 338.572155 -380.401522) (xy 338.603185 -380.461248)
			(xy 338.626855 -380.524255) (xy 338.642826 -380.589639) (xy 338.65086 -380.656404) (xy 341.92893 -380.656404)
			(xy 341.937004 -380.589467) (xy 341.953037 -380.523979) (xy 341.976799 -380.460883) (xy 342.007947 -380.401088)
			(xy 342.046033 -380.345453) (xy 342.067896 -380.319788) (xy 342.07368 -380.312634) (xy 342.080202 -380.29545)
			(xy 342.080596 -380.28626) (xy 342.080596 -379.794008) (xy 342.080183 -379.784821) (xy 342.073671 -379.767637)
			(xy 342.067896 -379.76048) (xy 342.046079 -379.734776) (xy 342.007989 -379.679147) (xy 341.976837 -379.619356)
			(xy 341.95307 -379.556264) (xy 341.937032 -379.49078) (xy 341.928952 -379.423846) (xy 341.928948 -379.356426)
			(xy 341.937019 -379.289491) (xy 341.953049 -379.224005) (xy 341.976807 -379.16091) (xy 342.007952 -379.101115)
			(xy 342.046035 -379.045481) (xy 342.067896 -379.019816) (xy 342.07371 -379.012683) (xy 342.080215 -378.995483)
			(xy 342.080596 -378.986288) (xy 342.080596 -378.828554) (xy 342.081088 -378.81843) (xy 342.088822 -378.799716)
			(xy 342.103106 -378.785363) (xy 342.121782 -378.777538) (xy 342.131904 -378.776992) (xy 342.848184 -378.776992)
			(xy 342.858336 -378.777434) (xy 342.877087 -378.785223) (xy 342.89141 -378.799614) (xy 342.899112 -378.8184)
			(xy 342.899492 -378.828554) (xy 342.899492 -378.986288) (xy 342.89991 -378.995474) (xy 342.906418 -379.012659)
			(xy 342.912192 -379.019816) (xy 342.934103 -379.045442) (xy 342.972191 -379.101082) (xy 343.00334 -379.160884)
			(xy 343.027102 -379.223986) (xy 343.043135 -379.28948) (xy 343.051207 -379.356422) (xy 343.051202 -379.42385)
			(xy 343.043122 -379.490792) (xy 343.027081 -379.556283) (xy 343.003311 -379.619382) (xy 342.972154 -379.67918)
			(xy 342.934059 -379.734815) (xy 342.912192 -379.76048) (xy 342.906378 -379.767613) (xy 342.899874 -379.784813)
			(xy 342.899492 -379.794008) (xy 342.899492 -380.28626) (xy 342.899923 -380.295445) (xy 342.906422 -380.312629)
			(xy 342.912192 -380.319788) (xy 342.934076 -380.345437) (xy 342.972165 -380.401074) (xy 343.003315 -380.460872)
			(xy 343.027078 -380.523971) (xy 343.043113 -380.589462) (xy 343.051187 -380.656402) (xy 343.051187 -380.656463)
			(xy 346.329226 -380.656463) (xy 346.337269 -380.589641) (xy 346.353241 -380.524259) (xy 346.376913 -380.461255)
			(xy 346.407947 -380.401533) (xy 346.445896 -380.345948) (xy 346.467684 -380.320296) (xy 346.473463 -380.313138)
			(xy 346.479989 -380.295957) (xy 346.480384 -380.286768) (xy 346.480384 -379.7935) (xy 346.479977 -379.784312)
			(xy 346.473462 -379.767128) (xy 346.467684 -379.759972) (xy 346.445942 -379.734282) (xy 346.407989 -379.678702)
			(xy 346.376951 -379.618984) (xy 346.353274 -379.555984) (xy 346.337296 -379.490606) (xy 346.329247 -379.423787)
			(xy 346.329243 -379.356485) (xy 346.337283 -379.289665) (xy 346.353252 -379.224285) (xy 346.376922 -379.161282)
			(xy 346.407952 -379.10156) (xy 346.445898 -379.045976) (xy 346.467684 -379.020324) (xy 346.473493 -379.013188)
			(xy 346.480001 -378.99599) (xy 346.480384 -378.986796) (xy 346.480384 -378.828554) (xy 346.480797 -378.818388)
			(xy 346.488595 -378.799609) (xy 346.502986 -378.785243) (xy 346.521779 -378.777479) (xy 346.531946 -378.776992)
			(xy 347.248226 -378.776992) (xy 347.25838 -378.777511) (xy 347.277141 -378.785285) (xy 347.291504 -378.799642)
			(xy 347.299285 -378.8184) (xy 347.299788 -378.828554) (xy 347.299788 -378.986796) (xy 347.300203 -378.995983)
			(xy 347.306714 -379.013167) (xy 347.312488 -379.020324) (xy 347.334322 -379.045938) (xy 347.372268 -379.10153)
			(xy 347.403297 -379.161259) (xy 347.426966 -379.224269) (xy 347.442935 -379.289656) (xy 347.450975 -379.356482)
			(xy 347.450971 -379.42379) (xy 347.442922 -379.490616) (xy 347.426945 -379.556) (xy 347.403268 -379.619007)
			(xy 347.372231 -379.678732) (xy 347.334278 -379.734319) (xy 347.312488 -379.759972) (xy 347.306677 -379.767107)
			(xy 347.300171 -379.784305) (xy 347.299788 -379.7935) (xy 347.299788 -380.286768) (xy 347.300216 -380.295953)
			(xy 347.306718 -380.313138) (xy 347.312488 -380.320296) (xy 347.334295 -380.345932) (xy 347.372241 -380.401522)
			(xy 347.403272 -380.461248) (xy 347.426942 -380.524254) (xy 347.442913 -380.589638) (xy 347.450948 -380.656404)
			(xy 377.128751 -380.656404) (xy 377.136826 -380.589466) (xy 377.15286 -380.523978) (xy 377.176623 -380.460882)
			(xy 377.207772 -380.401087) (xy 377.24586 -380.345453) (xy 377.267724 -380.319788) (xy 377.273511 -380.312636)
			(xy 377.280031 -380.295451) (xy 377.280424 -380.28626) (xy 377.280424 -379.794008) (xy 377.280005 -379.784822)
			(xy 377.273497 -379.767638) (xy 377.267724 -379.76048) (xy 377.245906 -379.734776) (xy 377.207815 -379.679148)
			(xy 377.17666 -379.619357) (xy 377.152893 -379.556265) (xy 377.136853 -379.490781) (xy 377.128773 -379.423846)
			(xy 377.128769 -379.356426) (xy 377.13684 -379.28949) (xy 377.152871 -379.224004) (xy 377.176631 -379.160909)
			(xy 377.207777 -379.101114) (xy 377.245862 -379.045481) (xy 377.267724 -379.019816) (xy 377.273542 -379.012686)
			(xy 377.280043 -378.995484) (xy 377.280424 -378.986288) (xy 377.280424 -378.828554) (xy 377.280888 -378.818426)
			(xy 377.288628 -378.799707) (xy 377.302921 -378.785353) (xy 377.321607 -378.777533) (xy 377.331732 -378.776992)
			(xy 378.048012 -378.776992) (xy 378.058166 -378.777411) (xy 378.076917 -378.785209) (xy 378.09124 -378.799607)
			(xy 378.098941 -378.818398) (xy 378.09932 -378.828554) (xy 378.09932 -378.986288) (xy 378.099731 -378.995475)
			(xy 378.106244 -379.01266) (xy 378.11202 -379.019816) (xy 378.13393 -379.045443) (xy 378.172016 -379.101083)
			(xy 378.203164 -379.160885) (xy 378.226924 -379.223987) (xy 378.242956 -379.28948) (xy 378.251028 -379.356423)
			(xy 378.251023 -379.42385) (xy 378.242943 -379.490791) (xy 378.226903 -379.556282) (xy 378.203134 -379.619381)
			(xy 378.171979 -379.679179) (xy 378.133886 -379.734814) (xy 378.11202 -379.76048) (xy 378.106209 -379.767615)
			(xy 378.099702 -379.784813) (xy 378.09932 -379.794008) (xy 378.09932 -380.28626) (xy 378.099745 -380.295446)
			(xy 378.106248 -380.312631) (xy 378.11202 -380.319788) (xy 378.133903 -380.345437) (xy 378.17199 -380.401075)
			(xy 378.203138 -380.460873) (xy 378.226901 -380.523972) (xy 378.242934 -380.589463) (xy 378.251008 -380.656403)
			(xy 378.251008 -380.656464) (xy 381.529071 -380.656464) (xy 381.537113 -380.589643) (xy 381.553083 -380.524262)
			(xy 381.576752 -380.461258) (xy 381.607782 -380.401535) (xy 381.645726 -380.345948) (xy 381.667512 -380.320296)
			(xy 381.673294 -380.313141) (xy 381.679817 -380.295958) (xy 381.680212 -380.286768) (xy 381.680212 -379.7935)
			(xy 381.679799 -379.784313) (xy 381.673287 -379.767129) (xy 381.667512 -379.759972) (xy 381.645773 -379.73428)
			(xy 381.607824 -379.678699) (xy 381.57679 -379.618981) (xy 381.553116 -379.555981) (xy 381.537141 -379.490604)
			(xy 381.529093 -379.423786) (xy 381.529089 -379.356486) (xy 381.537128 -379.289667) (xy 381.553095 -379.224288)
			(xy 381.576761 -379.161285) (xy 381.607787 -379.101563) (xy 381.645728 -379.045977) (xy 381.667512 -379.020324)
			(xy 381.673325 -379.01319) (xy 381.679829 -378.995991) (xy 381.680212 -378.986796) (xy 381.680212 -378.828554)
			(xy 381.680695 -378.818397) (xy 381.68848 -378.799631) (xy 381.702848 -378.785269) (xy 381.721616 -378.777491)
			(xy 381.731774 -378.776992) (xy 382.448054 -378.776992) (xy 382.458203 -378.77757) (xy 382.476962 -378.785321)
			(xy 382.491328 -378.79966) (xy 382.499112 -378.818406) (xy 382.499616 -378.828554) (xy 382.499616 -378.986796)
			(xy 382.500025 -378.995983) (xy 382.506539 -379.013168) (xy 382.512316 -379.020324) (xy 382.534153 -379.045936)
			(xy 382.572103 -379.101528) (xy 382.603137 -379.161256) (xy 382.626809 -379.224266) (xy 382.64278 -379.289654)
			(xy 382.650821 -379.356481) (xy 382.650816 -379.423791) (xy 382.642767 -379.490618) (xy 382.626787 -379.556003)
			(xy 382.603107 -379.61901) (xy 382.572066 -379.678734) (xy 382.534108 -379.734321) (xy 382.512316 -379.759972)
			(xy 382.506508 -379.767109) (xy 382.5 -379.784306) (xy 382.499616 -379.7935) (xy 382.499616 -380.286768)
			(xy 382.500038 -380.295954) (xy 382.506543 -380.313139) (xy 382.512316 -380.320296) (xy 382.534125 -380.345931)
			(xy 382.572076 -380.401519) (xy 382.603111 -380.461245) (xy 382.626784 -380.524251) (xy 382.642757 -380.589636)
			(xy 382.650793 -380.656404) (xy 385.928839 -380.656404) (xy 385.936913 -380.589467) (xy 385.952947 -380.523979)
			(xy 385.976709 -380.460883) (xy 386.007858 -380.401087) (xy 386.045945 -380.345453) (xy 386.067808 -380.319788)
			(xy 386.073593 -380.312635) (xy 386.080114 -380.29545) (xy 386.080508 -380.28626) (xy 386.080508 -379.794008)
			(xy 386.080092 -379.784821) (xy 386.073582 -379.767637) (xy 386.067808 -379.76048) (xy 386.045991 -379.734776)
			(xy 386.0079 -379.679147) (xy 385.976747 -379.619356) (xy 385.95298 -379.556265) (xy 385.936941 -379.49078)
			(xy 385.928861 -379.423846) (xy 385.928857 -379.356426) (xy 385.936928 -379.289491) (xy 385.952958 -379.224004)
			(xy 385.976718 -379.160909) (xy 386.007863 -379.101115) (xy 386.045947 -379.045481) (xy 386.067808 -379.019816)
			(xy 386.073624 -379.012684) (xy 386.080127 -378.995483) (xy 386.080508 -378.986288) (xy 386.080508 -378.828554)
			(xy 386.080988 -378.818428) (xy 386.088725 -378.799712) (xy 386.103012 -378.785359) (xy 386.121693 -378.777535)
			(xy 386.131816 -378.776992) (xy 386.848096 -378.776992) (xy 386.858249 -378.777425) (xy 386.877 -378.785218)
			(xy 386.891323 -378.799611) (xy 386.899024 -378.818399) (xy 386.899404 -378.828554) (xy 386.899404 -378.986288)
			(xy 386.899819 -378.995475) (xy 386.906329 -379.012659) (xy 386.912104 -379.019816) (xy 386.934015 -379.045442)
			(xy 386.972102 -379.101083) (xy 387.00325 -379.160884) (xy 387.027012 -379.223986) (xy 387.043044 -379.28948)
			(xy 387.051116 -379.356422) (xy 387.051111 -379.42385) (xy 387.043031 -379.490791) (xy 387.02699 -379.556283)
			(xy 387.003221 -379.619382) (xy 386.972065 -379.679179) (xy 386.933971 -379.734815) (xy 386.912104 -379.76048)
			(xy 386.906291 -379.767614) (xy 386.899786 -379.784813) (xy 386.899404 -379.794008) (xy 386.899404 -380.28626)
			(xy 386.899832 -380.295445) (xy 386.906333 -380.31263) (xy 386.912104 -380.319788) (xy 386.933987 -380.345437)
			(xy 386.972075 -380.401074) (xy 387.003225 -380.460872) (xy 387.026988 -380.523971) (xy 387.043022 -380.589462)
			(xy 387.051096 -380.656402) (xy 387.051096 -380.656464) (xy 390.329159 -380.656464) (xy 390.3372 -380.589643)
			(xy 390.35317 -380.524263) (xy 390.376839 -380.461259) (xy 390.407867 -380.401536) (xy 390.445811 -380.345949)
			(xy 390.467596 -380.320296) (xy 390.473376 -380.313139) (xy 390.479901 -380.295958) (xy 390.480296 -380.286768)
			(xy 390.480296 -379.7935) (xy 390.479887 -379.784313) (xy 390.473372 -379.767128) (xy 390.467596 -379.759972)
			(xy 390.445857 -379.73428) (xy 390.407909 -379.678699) (xy 390.376876 -379.61898) (xy 390.353203 -379.555981)
			(xy 390.337228 -379.490604) (xy 390.32918 -379.423786) (xy 390.329176 -379.356486) (xy 390.337215 -379.289667)
			(xy 390.353181 -379.224288) (xy 390.376847 -379.161286) (xy 390.407872 -379.101563) (xy 390.445812 -379.045977)
			(xy 390.467596 -379.020324) (xy 390.473407 -379.013189) (xy 390.479913 -378.995991) (xy 390.480296 -378.986796)
			(xy 390.480296 -378.828554) (xy 390.480795 -378.818398) (xy 390.488576 -378.799636) (xy 390.50294 -378.785274)
			(xy 390.521702 -378.777494) (xy 390.531858 -378.776992) (xy 391.248138 -378.776992) (xy 391.258293 -378.777501)
			(xy 391.277054 -378.785279) (xy 391.291416 -378.79964) (xy 391.299197 -378.8184) (xy 391.2997 -378.828554)
			(xy 391.2997 -378.986796) (xy 391.300112 -378.995983) (xy 391.306625 -379.013167) (xy 391.3124 -379.020324)
			(xy 391.334234 -379.045938) (xy 391.372178 -379.101531) (xy 391.403207 -379.16126) (xy 391.426876 -379.224269)
			(xy 391.442844 -379.289656) (xy 391.450884 -379.356482) (xy 391.45088 -379.42379) (xy 391.442831 -379.490615)
			(xy 391.426855 -379.556) (xy 391.403178 -379.619006) (xy 391.372141 -379.678731) (xy 391.334189 -379.734319)
			(xy 391.3124 -379.759972) (xy 391.30659 -379.767108) (xy 391.300083 -379.784306) (xy 391.2997 -379.7935)
			(xy 391.2997 -380.286768) (xy 391.300126 -380.295954) (xy 391.306629 -380.313138) (xy 391.3124 -380.320296)
			(xy 391.334206 -380.345933) (xy 391.372152 -380.401522) (xy 391.403182 -380.461248) (xy 391.426852 -380.524255)
			(xy 391.442822 -380.589638) (xy 391.450857 -380.656404) (xy 421.12866 -380.656404) (xy 421.136735 -380.589466)
			(xy 421.152769 -380.523978) (xy 421.176533 -380.460881) (xy 421.207683 -380.401086) (xy 421.245772 -380.345453)
			(xy 421.267636 -380.319788) (xy 421.273425 -380.312637) (xy 421.279943 -380.295451) (xy 421.280336 -380.28626)
			(xy 421.280336 -379.794008) (xy 421.279914 -379.784822) (xy 421.273408 -379.767638) (xy 421.267636 -379.76048)
			(xy 421.245818 -379.734776) (xy 421.207725 -379.679148) (xy 421.176571 -379.619358) (xy 421.152802 -379.556266)
			(xy 421.136762 -379.490781) (xy 421.128682 -379.423846) (xy 421.128678 -379.356426) (xy 421.136749 -379.28949)
			(xy 421.152781 -379.224003) (xy 421.176541 -379.160908) (xy 421.207688 -379.101114) (xy 421.245774 -379.045481)
			(xy 421.267636 -379.019816) (xy 421.273455 -379.012687) (xy 421.279956 -378.995484) (xy 421.280336 -378.986288)
			(xy 421.280336 -378.828554) (xy 421.280789 -378.818425) (xy 421.288531 -378.799703) (xy 421.302827 -378.785349)
			(xy 421.321517 -378.777531) (xy 421.331644 -378.776992) (xy 422.047924 -378.776992) (xy 422.058079 -378.777402)
			(xy 422.07683 -378.785204) (xy 422.091152 -378.799604) (xy 422.098853 -378.818397) (xy 422.099232 -378.828554)
			(xy 422.099232 -378.986288) (xy 422.099663 -378.995473) (xy 422.106164 -379.012656) (xy 422.111932 -379.019816)
			(xy 422.133842 -379.045443) (xy 422.171927 -379.101084) (xy 422.203074 -379.160885) (xy 422.226834 -379.223987)
			(xy 422.242865 -379.289481) (xy 422.250937 -379.356423) (xy 422.250932 -379.423849) (xy 422.242852 -379.49079)
			(xy 422.226813 -379.556282) (xy 422.203045 -379.61938) (xy 422.17189 -379.679178) (xy 422.133798 -379.734814)
			(xy 422.111932 -379.76048) (xy 422.106111 -379.767607) (xy 422.099613 -379.784812) (xy 422.099232 -379.794008)
			(xy 422.099232 -380.28626) (xy 422.099677 -380.295443) (xy 422.106168 -380.312627) (xy 422.111932 -380.319788)
			(xy 422.133814 -380.345438) (xy 422.171901 -380.401075) (xy 422.203049 -380.460874) (xy 422.22681 -380.523973)
			(xy 422.242843 -380.589463) (xy 422.250917 -380.656403) (xy 422.250917 -380.656463) (xy 425.52898 -380.656463)
			(xy 425.537022 -380.589642) (xy 425.552992 -380.524262) (xy 425.576662 -380.461258) (xy 425.607692 -380.401535)
			(xy 425.645638 -380.345948) (xy 425.667424 -380.320296) (xy 425.673208 -380.313142) (xy 425.679729 -380.295958)
			(xy 425.680124 -380.286768) (xy 425.680124 -379.7935) (xy 425.679709 -379.784313) (xy 425.673198 -379.767129)
			(xy 425.667424 -379.759972) (xy 425.645684 -379.734281) (xy 425.607735 -379.678699) (xy 425.5767 -379.618981)
			(xy 425.553026 -379.555982) (xy 425.53705 -379.490605) (xy 425.529002 -379.423787) (xy 425.528998 -379.356486)
			(xy 425.537037 -379.289667) (xy 425.553004 -379.224287) (xy 425.576671 -379.161285) (xy 425.607698 -379.101563)
			(xy 425.64564 -379.045977) (xy 425.667424 -379.020324) (xy 425.673238 -379.013191) (xy 425.679742 -378.995991)
			(xy 425.680124 -378.986796) (xy 425.680124 -378.828554) (xy 425.680595 -378.818395) (xy 425.688382 -378.799628)
			(xy 425.702754 -378.785264) (xy 425.721527 -378.777489) (xy 425.731686 -378.776992) (xy 426.447966 -378.776992)
			(xy 426.458116 -378.77756) (xy 426.476875 -378.785315) (xy 426.49124 -378.799657) (xy 426.499024 -378.818405)
			(xy 426.499528 -378.828554) (xy 426.499528 -378.986796) (xy 426.499934 -378.995984) (xy 426.50645 -379.013168)
			(xy 426.512228 -379.020324) (xy 426.534064 -379.045937) (xy 426.572014 -379.101528) (xy 426.603047 -379.161257)
			(xy 426.626718 -379.224267) (xy 426.642689 -379.289654) (xy 426.65073 -379.356481) (xy 426.650725 -379.423791)
			(xy 426.642676 -379.490617) (xy 426.626697 -379.556003) (xy 426.603017 -379.619009) (xy 426.571977 -379.678734)
			(xy 426.53402 -379.73432) (xy 426.512228 -379.759972) (xy 426.50641 -379.767101) (xy 426.49991 -379.784304)
			(xy 426.499528 -379.7935) (xy 426.499528 -380.286768) (xy 426.499947 -380.295954) (xy 426.506454 -380.313139)
			(xy 426.512228 -380.320296) (xy 426.534036 -380.345932) (xy 426.571987 -380.40152) (xy 426.603021 -380.461245)
			(xy 426.626694 -380.524252) (xy 426.642667 -380.589636) (xy 426.650703 -380.656404) (xy 429.928748 -380.656404)
			(xy 429.936823 -380.589467) (xy 429.952857 -380.523978) (xy 429.976619 -380.460882) (xy 430.007769 -380.401087)
			(xy 430.045857 -380.345453) (xy 430.06772 -380.319788) (xy 430.073506 -380.312636) (xy 430.080027 -380.295451)
			(xy 430.08042 -380.28626) (xy 430.08042 -379.794008) (xy 430.080001 -379.784822) (xy 430.073493 -379.767638)
			(xy 430.06772 -379.76048) (xy 430.045902 -379.734776) (xy 430.007811 -379.679148) (xy 429.976657 -379.619357)
			(xy 429.952889 -379.556265) (xy 429.93685 -379.490781) (xy 429.92877 -379.423846) (xy 429.928766 -379.356426)
			(xy 429.936837 -379.289491) (xy 429.952868 -379.224004) (xy 429.976628 -379.160909) (xy 430.007774 -379.101114)
			(xy 430.045858 -379.045481) (xy 430.06772 -379.019816) (xy 430.073537 -379.012685) (xy 430.080039 -378.995484)
			(xy 430.08042 -378.986288) (xy 430.08042 -378.828554) (xy 430.080888 -378.818427) (xy 430.088628 -378.799708)
			(xy 430.102919 -378.785354) (xy 430.121603 -378.777533) (xy 430.131728 -378.776992) (xy 430.848008 -378.776992)
			(xy 430.858162 -378.777415) (xy 430.876913 -378.785212) (xy 430.891235 -378.799608) (xy 430.898936 -378.818398)
			(xy 430.899316 -378.828554) (xy 430.899316 -378.986288) (xy 430.899728 -378.995475) (xy 430.90624 -379.01266)
			(xy 430.912016 -379.019816) (xy 430.933927 -379.045443) (xy 430.972013 -379.101083) (xy 431.003161 -379.160885)
			(xy 431.026921 -379.223987) (xy 431.042953 -379.28948) (xy 431.051025 -379.356422) (xy 431.05102 -379.42385)
			(xy 431.04294 -379.490791) (xy 431.0269 -379.556282) (xy 431.003131 -379.619381) (xy 430.971976 -379.679179)
			(xy 430.933882 -379.734814) (xy 430.912016 -379.76048) (xy 430.906205 -379.767615) (xy 430.899698 -379.784813)
			(xy 430.899316 -379.794008) (xy 430.899316 -380.28626) (xy 430.899742 -380.295446) (xy 430.906244 -380.31263)
			(xy 430.912016 -380.319788) (xy 430.933899 -380.345437) (xy 430.971986 -380.401074) (xy 431.003135 -380.460873)
			(xy 431.026897 -380.523972) (xy 431.042931 -380.589463) (xy 431.051005 -380.656403) (xy 431.051005 -380.656464)
			(xy 434.329068 -380.656464) (xy 434.33711 -380.589643) (xy 434.35308 -380.524262) (xy 434.376749 -380.461259)
			(xy 434.407778 -380.401535) (xy 434.445722 -380.345949) (xy 434.467508 -380.320296) (xy 434.47329 -380.31314)
			(xy 434.479813 -380.295958) (xy 434.480208 -380.286768) (xy 434.480208 -379.7935) (xy 434.479796 -379.784313)
			(xy 434.473283 -379.767129) (xy 434.467508 -379.759972) (xy 434.445769 -379.73428) (xy 434.407821 -379.678699)
			(xy 434.376787 -379.61898) (xy 434.353113 -379.555981) (xy 434.337137 -379.490604) (xy 434.32909 -379.423786)
			(xy 434.329086 -379.356486) (xy 434.337125 -379.289667) (xy 434.353091 -379.224288) (xy 434.376757 -379.161286)
			(xy 434.407783 -379.101563) (xy 434.445724 -379.045977) (xy 434.467508 -379.020324) (xy 434.47332 -379.01319)
			(xy 434.479825 -378.995991) (xy 434.480208 -378.986796) (xy 434.480208 -378.828554) (xy 434.480695 -378.818397)
			(xy 434.488479 -378.799633) (xy 434.502846 -378.78527) (xy 434.521613 -378.777492) (xy 434.53177 -378.776992)
			(xy 435.24805 -378.776992) (xy 435.258213 -378.777504) (xy 435.276998 -378.785264) (xy 435.291383 -378.799622)
			(xy 435.299177 -378.818392) (xy 435.299612 -378.828554) (xy 435.299612 -378.986796) (xy 435.300021 -378.995983)
			(xy 435.306535 -379.013168) (xy 435.312312 -379.020324) (xy 435.334148 -379.045937) (xy 435.372099 -379.101528)
			(xy 435.403133 -379.161256) (xy 435.426805 -379.224266) (xy 435.442776 -379.289654) (xy 435.450817 -379.356481)
			(xy 435.450813 -379.423791) (xy 435.442763 -379.490618) (xy 435.426784 -379.556003) (xy 435.403103 -379.61901)
			(xy 435.372062 -379.678734) (xy 435.334104 -379.73432) (xy 435.312312 -379.759972) (xy 435.306504 -379.767109)
			(xy 435.299996 -379.784306) (xy 435.299612 -379.7935) (xy 435.299612 -380.286768) (xy 435.300035 -380.295954)
			(xy 435.306539 -380.313139) (xy 435.312312 -380.320296) (xy 435.334121 -380.345931) (xy 435.372072 -380.401519)
			(xy 435.403107 -380.461244) (xy 435.426781 -380.524251) (xy 435.442754 -380.589636) (xy 435.450797 -380.656461)
			(xy 435.450796 -380.723769) (xy 435.442749 -380.790594) (xy 435.426772 -380.855977) (xy 435.403095 -380.918983)
			(xy 435.372057 -380.978707) (xy 435.334102 -381.034292) (xy 435.312312 -381.059944) (xy 435.306516 -381.067089)
			(xy 435.3 -381.08428) (xy 435.299612 -381.093472) (xy 435.299612 -381.251206) (xy 435.29924 -381.261384)
			(xy 435.291444 -381.280189) (xy 435.277041 -381.294575) (xy 435.258229 -381.302351) (xy 435.24805 -381.302768)
			(xy 434.53177 -381.302768) (xy 434.521611 -381.302291) (xy 434.502842 -381.294508) (xy 434.488478 -381.280138)
			(xy 434.480704 -381.261365) (xy 434.480208 -381.251206) (xy 434.480208 -381.093472) (xy 434.47981 -381.084284)
			(xy 434.473288 -381.067099) (xy 434.467508 -381.059944) (xy 434.445741 -381.034275) (xy 434.407793 -380.97869)
			(xy 434.376761 -380.918969) (xy 434.353088 -380.855967) (xy 434.337115 -380.790587) (xy 434.32907 -380.723766)
			(xy 434.329068 -380.656464) (xy 431.051005 -380.656464) (xy 431.051003 -380.723827) (xy 431.042926 -380.790767)
			(xy 431.026889 -380.856257) (xy 431.003123 -380.919354) (xy 430.971971 -380.979151) (xy 430.933881 -381.034786)
			(xy 430.912016 -381.060452) (xy 430.906217 -381.067595) (xy 430.899703 -381.084787) (xy 430.899316 -381.09398)
			(xy 430.899316 -381.251206) (xy 430.898877 -381.261338) (xy 430.891139 -381.280068) (xy 430.876838 -381.294426)
			(xy 430.858138 -381.302237) (xy 430.848008 -381.302768) (xy 430.131728 -381.302768) (xy 430.121572 -381.302355)
			(xy 430.102814 -381.294563) (xy 430.088488 -381.280163) (xy 430.080793 -381.261364) (xy 430.08042 -381.251206)
			(xy 430.08042 -381.09398) (xy 430.080015 -381.084792) (xy 430.073497 -381.067608) (xy 430.06772 -381.060452)
			(xy 430.045875 -381.034771) (xy 430.007784 -380.979139) (xy 429.976632 -380.919345) (xy 429.952865 -380.85625)
			(xy 429.936828 -380.790763) (xy 429.92875 -380.723826) (xy 429.928748 -380.656404) (xy 426.650703 -380.656404)
			(xy 426.65071 -380.656461) (xy 426.650708 -380.723769) (xy 426.642661 -380.790593) (xy 426.626685 -380.855977)
			(xy 426.603009 -380.918982) (xy 426.571971 -380.978706) (xy 426.534018 -381.034292) (xy 426.512228 -381.059944)
			(xy 426.506422 -381.067082) (xy 426.499915 -381.084278) (xy 426.499528 -381.093472) (xy 426.499528 -381.251206)
			(xy 426.49914 -381.261382) (xy 426.491347 -381.280184) (xy 426.47695 -381.294569) (xy 426.458143 -381.302348)
			(xy 426.447966 -381.302768) (xy 425.731686 -381.302768) (xy 425.721528 -381.302278) (xy 425.70276 -381.2945)
			(xy 425.688395 -381.280133) (xy 425.68062 -381.261364) (xy 425.680124 -381.251206) (xy 425.680124 -381.093472)
			(xy 425.679722 -381.084284) (xy 425.673202 -381.0671) (xy 425.667424 -381.059944) (xy 425.645656 -381.034276)
			(xy 425.607708 -380.978691) (xy 425.576675 -380.91897) (xy 425.553001 -380.855967) (xy 425.537027 -380.790587)
			(xy 425.528982 -380.723767) (xy 425.52898 -380.656463) (xy 422.250917 -380.656463) (xy 422.250915 -380.723827)
			(xy 422.242838 -380.790766) (xy 422.226801 -380.856256) (xy 422.203036 -380.919354) (xy 422.171885 -380.979151)
			(xy 422.133796 -381.034786) (xy 422.111932 -381.060452) (xy 422.106123 -381.067588) (xy 422.099618 -381.084786)
			(xy 422.099232 -381.09398) (xy 422.099232 -381.251206) (xy 422.098777 -381.261337) (xy 422.091042 -381.280063)
			(xy 422.076746 -381.29442) (xy 422.058052 -381.302234) (xy 422.047924 -381.302768) (xy 421.331644 -381.302768)
			(xy 421.321489 -381.302342) (xy 421.302731 -381.294555) (xy 421.288405 -381.280159) (xy 421.28071 -381.261363)
			(xy 421.280336 -381.251206) (xy 421.280336 -381.09398) (xy 421.279927 -381.084793) (xy 421.273412 -381.067609)
			(xy 421.267636 -381.060452) (xy 421.24579 -381.034771) (xy 421.207699 -380.97914) (xy 421.176545 -380.919346)
			(xy 421.152778 -380.856251) (xy 421.13674 -380.790764) (xy 421.128662 -380.723826) (xy 421.12866 -380.656404)
			(xy 391.450857 -380.656404) (xy 391.450864 -380.656462) (xy 391.450863 -380.723768) (xy 391.442817 -380.790591)
			(xy 391.426843 -380.855974) (xy 391.40317 -380.918979) (xy 391.372136 -380.978704) (xy 391.334188 -381.034291)
			(xy 391.3124 -381.059944) (xy 391.306602 -381.067088) (xy 391.300088 -381.08428) (xy 391.2997 -381.093472)
			(xy 391.2997 -381.251206) (xy 391.299172 -381.261359) (xy 391.291403 -381.280121) (xy 391.277048 -381.294485)
			(xy 391.258291 -381.302266) (xy 391.248138 -381.302768) (xy 390.531858 -381.302768) (xy 390.521698 -381.302301)
			(xy 390.502929 -381.294514) (xy 390.488566 -381.28014) (xy 390.480792 -381.261366) (xy 390.480296 -381.251206)
			(xy 390.480296 -381.093472) (xy 390.4799 -381.084283) (xy 390.473377 -381.067099) (xy 390.467596 -381.059944)
			(xy 390.445829 -381.034275) (xy 390.407883 -380.97869) (xy 390.376851 -380.918968) (xy 390.353179 -380.855966)
			(xy 390.337206 -380.790586) (xy 390.329161 -380.723766) (xy 390.329159 -380.656464) (xy 387.051096 -380.656464)
			(xy 387.051094 -380.723828) (xy 387.043016 -380.790767) (xy 387.026979 -380.856257) (xy 387.003213 -380.919355)
			(xy 386.97206 -380.979152) (xy 386.933969 -381.034787) (xy 386.912104 -381.060452) (xy 386.906303 -381.067594)
			(xy 386.899791 -381.084787) (xy 386.899404 -381.09398) (xy 386.899404 -381.251206) (xy 386.89888 -381.261328)
			(xy 386.891158 -381.280041) (xy 386.876884 -381.294395) (xy 386.858215 -381.302222) (xy 386.848096 -381.302768)
			(xy 386.131816 -381.302768) (xy 386.121659 -381.302365) (xy 386.102901 -381.294568) (xy 386.088576 -381.280166)
			(xy 386.080881 -381.261365) (xy 386.080508 -381.251206) (xy 386.080508 -381.09398) (xy 386.080106 -381.084792)
			(xy 386.073587 -381.067608) (xy 386.067808 -381.060452) (xy 386.045963 -381.034771) (xy 386.007874 -380.979139)
			(xy 385.976722 -380.919345) (xy 385.952956 -380.85625) (xy 385.936919 -380.790763) (xy 385.928841 -380.723826)
			(xy 385.928839 -380.656404) (xy 382.650793 -380.656404) (xy 382.6508 -380.656461) (xy 382.650799 -380.723769)
			(xy 382.642752 -380.790593) (xy 382.626775 -380.855977) (xy 382.603098 -380.918983) (xy 382.57206 -380.978707)
			(xy 382.534106 -381.034292) (xy 382.512316 -381.059944) (xy 382.50652 -381.06709) (xy 382.500005 -381.08428)
			(xy 382.499616 -381.093472) (xy 382.499616 -381.251206) (xy 382.49924 -381.261384) (xy 382.491444 -381.280187)
			(xy 382.477044 -381.294574) (xy 382.458232 -381.30235) (xy 382.448054 -381.302768) (xy 381.731774 -381.302768)
			(xy 381.721615 -381.302288) (xy 381.702847 -381.294506) (xy 381.688482 -381.280137) (xy 381.680708 -381.261365)
			(xy 381.680212 -381.251206) (xy 381.680212 -381.093472) (xy 381.679813 -381.084284) (xy 381.673291 -381.0671)
			(xy 381.667512 -381.059944) (xy 381.645745 -381.034275) (xy 381.607797 -380.978691) (xy 381.576764 -380.918969)
			(xy 381.553092 -380.855967) (xy 381.537118 -380.790587) (xy 381.529073 -380.723767) (xy 381.529071 -380.656464)
			(xy 378.251008 -380.656464) (xy 378.251006 -380.723827) (xy 378.242929 -380.790767) (xy 378.226892 -380.856257)
			(xy 378.203126 -380.919354) (xy 378.171974 -380.979151) (xy 378.133884 -381.034786) (xy 378.11202 -381.060452)
			(xy 378.106221 -381.067596) (xy 378.099707 -381.084787) (xy 378.09932 -381.09398) (xy 378.09932 -381.251206)
			(xy 378.098877 -381.261338) (xy 378.09114 -381.280067) (xy 378.07684 -381.294424) (xy 378.058142 -381.302236)
			(xy 378.048012 -381.302768) (xy 377.331732 -381.302768) (xy 377.321576 -381.302352) (xy 377.302818 -381.294561)
			(xy 377.288492 -381.280162) (xy 377.280797 -381.261364) (xy 377.280424 -381.251206) (xy 377.280424 -381.09398)
			(xy 377.280018 -381.084792) (xy 377.273501 -381.067608) (xy 377.267724 -381.060452) (xy 377.245879 -381.034771)
			(xy 377.207788 -380.979139) (xy 377.176635 -380.919345) (xy 377.152869 -380.856251) (xy 377.136831 -380.790763)
			(xy 377.128753 -380.723826) (xy 377.128751 -380.656404) (xy 347.450948 -380.656404) (xy 347.450955 -380.656462)
			(xy 347.450954 -380.723768) (xy 347.442908 -380.790592) (xy 347.426934 -380.855975) (xy 347.40326 -380.91898)
			(xy 347.372226 -380.978704) (xy 347.334276 -381.034291) (xy 347.312488 -381.059944) (xy 347.306689 -381.067087)
			(xy 347.300176 -381.084279) (xy 347.299788 -381.093472) (xy 347.299788 -381.251206) (xy 347.299272 -381.261361)
			(xy 347.2915 -381.280125) (xy 347.277142 -381.294489) (xy 347.258381 -381.302268) (xy 347.248226 -381.302768)
			(xy 346.531946 -381.302768) (xy 346.521778 -381.302299) (xy 346.502986 -381.29453) (xy 346.488599 -381.280158)
			(xy 346.480812 -381.261373) (xy 346.480384 -381.251206) (xy 346.480384 -381.093472) (xy 346.479991 -381.084283)
			(xy 346.473466 -381.067099) (xy 346.467684 -381.059944) (xy 346.445915 -381.034276) (xy 346.407962 -380.978693)
			(xy 346.376926 -380.918972) (xy 346.35325 -380.85597) (xy 346.337274 -380.790589) (xy 346.329228 -380.723767)
			(xy 346.329226 -380.656463) (xy 343.051187 -380.656463) (xy 343.051185 -380.723828) (xy 343.043107 -380.790767)
			(xy 343.027069 -380.856258) (xy 343.003303 -380.919356) (xy 342.972149 -380.979152) (xy 342.934057 -381.034787)
			(xy 342.912192 -381.060452) (xy 342.90639 -381.067593) (xy 342.899879 -381.084787) (xy 342.899492 -381.09398)
			(xy 342.899492 -381.251206) (xy 342.898979 -381.261329) (xy 342.891255 -381.280044) (xy 342.876978 -381.294399)
			(xy 342.858304 -381.302224) (xy 342.848184 -381.302768) (xy 342.131904 -381.302768) (xy 342.121746 -381.302374)
			(xy 342.102988 -381.294574) (xy 342.088663 -381.280168) (xy 342.080969 -381.261366) (xy 342.080596 -381.251206)
			(xy 342.080596 -381.09398) (xy 342.080196 -381.084792) (xy 342.073675 -381.067608) (xy 342.067896 -381.060452)
			(xy 342.046052 -381.03477) (xy 342.007963 -380.979138) (xy 341.976811 -380.919344) (xy 341.953046 -380.856249)
			(xy 341.93701 -380.790762) (xy 341.928932 -380.723826) (xy 341.92893 -380.656404) (xy 338.65086 -380.656404)
			(xy 338.650867 -380.656462) (xy 338.650866 -380.723768) (xy 338.64282 -380.790591) (xy 338.626846 -380.855974)
			(xy 338.603173 -380.918979) (xy 338.57214 -380.978704) (xy 338.534192 -381.034291) (xy 338.512404 -381.059944)
			(xy 338.506607 -381.067089) (xy 338.500092 -381.08428) (xy 338.499704 -381.093472) (xy 338.499704 -381.251206)
			(xy 338.499172 -381.261359) (xy 338.491404 -381.28012) (xy 338.47705 -381.294484) (xy 338.458295 -381.302265)
			(xy 338.448142 -381.302768) (xy 337.731862 -381.302768) (xy 337.721703 -381.302298) (xy 337.702934 -381.294512)
			(xy 337.68857 -381.280139) (xy 337.680796 -381.261366) (xy 337.6803 -381.251206) (xy 337.6803 -381.093472)
			(xy 337.679904 -381.084283) (xy 337.67338 -381.067099) (xy 337.6676 -381.059944) (xy 337.645833 -381.034275)
			(xy 337.607886 -380.97869) (xy 337.576854 -380.918969) (xy 337.553182 -380.855966) (xy 337.537209 -380.790587)
			(xy 337.529164 -380.723766) (xy 337.529162 -380.656464) (xy 334.251099 -380.656464) (xy 334.251097 -380.723828)
			(xy 334.243019 -380.790767) (xy 334.226982 -380.856257) (xy 334.203216 -380.919355) (xy 334.172063 -380.979152)
			(xy 334.133973 -381.034787) (xy 334.112108 -381.060452) (xy 334.106308 -381.067595) (xy 334.099795 -381.084787)
			(xy 334.099408 -381.09398) (xy 334.099408 -381.251206) (xy 334.09888 -381.261327) (xy 334.091159 -381.280039)
			(xy 334.076886 -381.294394) (xy 334.058218 -381.302221) (xy 334.0481 -381.302768) (xy 333.33182 -381.302768)
			(xy 333.321663 -381.302362) (xy 333.302905 -381.294567) (xy 333.28858 -381.280165) (xy 333.280885 -381.261365)
			(xy 333.280512 -381.251206) (xy 333.280512 -381.09398) (xy 333.280109 -381.084792) (xy 333.27359 -381.067608)
			(xy 333.267812 -381.060452) (xy 333.245967 -381.034771) (xy 333.207877 -380.979139) (xy 333.176725 -380.919345)
			(xy 333.152959 -380.85625) (xy 333.136922 -380.790763) (xy 333.128844 -380.723826) (xy 333.128842 -380.656404)
			(xy 303.451069 -380.656404) (xy 303.451067 -380.723828) (xy 303.442989 -380.790768) (xy 303.42695 -380.856259)
			(xy 303.403182 -380.919357) (xy 303.372027 -380.979153) (xy 303.333934 -381.034787) (xy 303.312068 -381.060452)
			(xy 303.306263 -381.067591) (xy 303.299754 -381.084786) (xy 303.299368 -381.09398) (xy 303.299368 -381.251206)
			(xy 303.298878 -381.261332) (xy 303.29115 -381.280052) (xy 303.276865 -381.294408) (xy 303.258184 -381.302228)
			(xy 303.24806 -381.302768) (xy 302.53178 -381.302768) (xy 302.521621 -381.302394) (xy 302.502861 -381.294586)
			(xy 302.488538 -381.280174) (xy 302.480844 -381.261368) (xy 302.480472 -381.251206) (xy 302.480472 -381.09398)
			(xy 302.480078 -381.084791) (xy 302.473554 -381.067607) (xy 302.467772 -381.060452) (xy 302.445929 -381.03477)
			(xy 302.407841 -380.979137) (xy 302.376691 -380.919343) (xy 302.352927 -380.856248) (xy 302.336891 -380.790762)
			(xy 302.328814 -380.723826) (xy 302.328812 -380.656404) (xy 299.050742 -380.656404) (xy 299.050749 -380.656462)
			(xy 299.050747 -380.723768) (xy 299.042702 -380.790592) (xy 299.026727 -380.855975) (xy 299.003053 -380.91898)
			(xy 298.972018 -380.978704) (xy 298.934068 -381.034292) (xy 298.91228 -381.059944) (xy 298.90648 -381.067087)
			(xy 298.899968 -381.084279) (xy 298.89958 -381.093472) (xy 298.89958 -381.251206) (xy 298.899072 -381.261362)
			(xy 298.891299 -381.280128) (xy 298.876938 -381.294492) (xy 298.858174 -381.302269) (xy 298.848018 -381.302768)
			(xy 298.131738 -381.302768) (xy 298.12157 -381.302305) (xy 298.102777 -381.294534) (xy 298.088391 -381.28016)
			(xy 298.080604 -381.261374) (xy 298.080176 -381.251206) (xy 298.080176 -381.093472) (xy 298.079785 -381.084283)
			(xy 298.073258 -381.067098) (xy 298.067476 -381.059944) (xy 298.045707 -381.034276) (xy 298.007755 -380.978693)
			(xy 297.976719 -380.918972) (xy 297.953043 -380.855969) (xy 297.937068 -380.790589) (xy 297.929022 -380.723767)
			(xy 297.92902 -380.656463) (xy 294.650981 -380.656463) (xy 294.650979 -380.723828) (xy 294.642901 -380.790768)
			(xy 294.626863 -380.856258) (xy 294.603096 -380.919356) (xy 294.571942 -380.979153) (xy 294.53385 -381.034787)
			(xy 294.511984 -381.060452) (xy 294.506181 -381.067593) (xy 294.499671 -381.084787) (xy 294.499284 -381.09398)
			(xy 294.499284 -381.251206) (xy 294.498779 -381.26133) (xy 294.491054 -381.280047) (xy 294.476773 -381.294402)
			(xy 294.458097 -381.302225) (xy 294.447976 -381.302768) (xy 293.731696 -381.302768) (xy 293.721538 -381.302381)
			(xy 293.702779 -381.294578) (xy 293.688455 -381.28017) (xy 293.680761 -381.261367) (xy 293.680388 -381.251206)
			(xy 293.680388 -381.09398) (xy 293.67999 -381.084791) (xy 293.673468 -381.067607) (xy 293.667688 -381.060452)
			(xy 293.645844 -381.03477) (xy 293.607756 -380.979138) (xy 293.576605 -380.919344) (xy 293.55284 -380.856249)
			(xy 293.536803 -380.790762) (xy 293.528726 -380.723826) (xy 293.528724 -380.656404) (xy 290.250654 -380.656404)
			(xy 290.250661 -380.656462) (xy 290.25066 -380.723768) (xy 290.242614 -380.790591) (xy 290.22664 -380.855974)
			(xy 290.202966 -380.918979) (xy 290.171933 -380.978704) (xy 290.133984 -381.034291) (xy 290.112196 -381.059944)
			(xy 290.106398 -381.067088) (xy 290.099884 -381.084279) (xy 290.099496 -381.093472) (xy 290.099496 -381.251206)
			(xy 290.098972 -381.26136) (xy 290.091202 -381.280123) (xy 290.076846 -381.294486) (xy 290.058088 -381.302267)
			(xy 290.047934 -381.302768) (xy 289.331654 -381.302768) (xy 289.321494 -381.302304) (xy 289.302725 -381.294516)
			(xy 289.288362 -381.280141) (xy 289.280588 -381.261366) (xy 289.280092 -381.251206) (xy 289.280092 -381.093472)
			(xy 289.279697 -381.084283) (xy 289.273173 -381.067099) (xy 289.267392 -381.059944) (xy 289.245622 -381.034276)
			(xy 289.207669 -380.978693) (xy 289.176632 -380.918972) (xy 289.152956 -380.85597) (xy 289.13698 -380.790589)
			(xy 289.128934 -380.723767) (xy 289.128932 -380.656463) (xy 276.776531 -380.656463) (xy 276.720065 -380.793728)
			(xy 276.634707 -380.980199) (xy 276.542138 -381.163197) (xy 276.442501 -381.342444) (xy 276.335945 -381.517667)
			(xy 276.222634 -381.688599) (xy 276.102741 -381.85498) (xy 275.976447 -382.016556) (xy 275.843945 -382.173083)
			(xy 275.797584 -382.223705) (xy 286.928753 -382.223705) (xy 286.928754 -382.15628) (xy 286.936832 -382.08934)
			(xy 286.95287 -382.02385) (xy 286.976638 -381.960752) (xy 287.007792 -381.900956) (xy 287.045886 -381.845322)
			(xy 287.067752 -381.819658) (xy 287.073555 -381.812518) (xy 287.080065 -381.795323) (xy 287.080452 -381.78613)
			(xy 287.080452 -381.628904) (xy 287.080987 -381.618801) (xy 287.088715 -381.600133) (xy 287.102996 -381.585839)
			(xy 287.121658 -381.578096) (xy 287.13176 -381.577596) (xy 287.84804 -381.577596) (xy 287.858151 -381.578052)
			(xy 287.876829 -381.585802) (xy 287.891122 -381.600108) (xy 287.898856 -381.618793) (xy 287.899348 -381.628904)
			(xy 287.899348 -381.78613) (xy 287.899755 -381.795317) (xy 287.906272 -381.812501) (xy 287.912048 -381.819658)
			(xy 287.933904 -381.84533) (xy 287.971996 -381.900963) (xy 288.00315 -381.960757) (xy 288.026917 -382.023853)
			(xy 288.042955 -382.089342) (xy 288.051033 -382.156281) (xy 288.051034 -382.223645) (xy 291.329073 -382.223645)
			(xy 291.329074 -382.15634) (xy 291.337119 -382.089516) (xy 291.353093 -382.024133) (xy 291.376767 -381.961128)
			(xy 291.407801 -381.901405) (xy 291.445751 -381.845818) (xy 291.46754 -381.820166) (xy 291.473339 -381.813022)
			(xy 291.479851 -381.795831) (xy 291.48024 -381.786638) (xy 291.48024 -381.628904) (xy 291.480626 -381.618745)
			(xy 291.488427 -381.599985) (xy 291.502836 -381.58566) (xy 291.521641 -381.577968) (xy 291.531802 -381.577596)
			(xy 292.248082 -381.577596) (xy 292.258202 -381.57814) (xy 292.276915 -381.585854) (xy 292.29127 -381.600122)
			(xy 292.299098 -381.618787) (xy 292.299644 -381.628904) (xy 292.299644 -381.786638) (xy 292.300049 -381.795826)
			(xy 292.306568 -381.813009) (xy 292.312344 -381.820166) (xy 292.334122 -381.845826) (xy 292.372072 -381.901411)
			(xy 292.403107 -381.961133) (xy 292.426781 -382.024137) (xy 292.442755 -382.089518) (xy 292.450801 -382.15634)
			(xy 292.450801 -382.223645) (xy 292.450794 -382.223705) (xy 295.728841 -382.223705) (xy 295.728842 -382.15628)
			(xy 295.73692 -382.08934) (xy 295.752957 -382.02385) (xy 295.776724 -381.960753) (xy 295.807878 -381.900957)
			(xy 295.84597 -381.845323) (xy 295.867836 -381.819658) (xy 295.873637 -381.812516) (xy 295.880148 -381.795323)
			(xy 295.880536 -381.78613) (xy 295.880536 -381.628904) (xy 295.88092 -381.618777) (xy 295.888674 -381.600067)
			(xy 295.903001 -381.585751) (xy 295.921717 -381.578012) (xy 295.931844 -381.577596) (xy 296.648124 -381.577596)
			(xy 296.658234 -381.578065) (xy 296.676912 -381.58581) (xy 296.691206 -381.600112) (xy 296.69894 -381.618794)
			(xy 296.699432 -381.628904) (xy 296.699432 -381.78613) (xy 296.699843 -381.795317) (xy 296.706358 -381.8125)
			(xy 296.712132 -381.819658) (xy 296.733985 -381.845332) (xy 296.772072 -381.900966) (xy 296.803221 -381.960761)
			(xy 296.826985 -382.023857) (xy 296.84302 -382.089345) (xy 296.851096 -382.156281) (xy 296.851097 -382.223704)
			(xy 296.851097 -382.223705) (xy 300.128632 -382.223705) (xy 300.128633 -382.15628) (xy 300.13671 -382.089341)
			(xy 300.152748 -382.023851) (xy 300.176514 -381.960753) (xy 300.207667 -381.900957) (xy 300.245759 -381.845323)
			(xy 300.267624 -381.819658) (xy 300.273424 -381.812515) (xy 300.279936 -381.795323) (xy 300.280324 -381.78613)
			(xy 300.280324 -381.628904) (xy 300.28072 -381.618779) (xy 300.288471 -381.600071) (xy 300.302794 -381.585755)
			(xy 300.321507 -381.578014) (xy 300.331632 -381.577596) (xy 301.047912 -381.577596) (xy 301.058021 -381.578075)
			(xy 301.076699 -381.585816) (xy 301.090993 -381.600115) (xy 301.098728 -381.618795) (xy 301.09922 -381.628904)
			(xy 301.09922 -381.78613) (xy 301.099611 -381.795319) (xy 301.106138 -381.812504) (xy 301.11192 -381.819658)
			(xy 301.133773 -381.845332) (xy 301.171861 -381.900965) (xy 301.203011 -381.960761) (xy 301.226775 -382.023856)
			(xy 301.242811 -382.089344) (xy 301.250887 -382.156281) (xy 301.250888 -382.223646) (xy 330.929191 -382.223646)
			(xy 330.929192 -382.156339) (xy 330.937238 -382.089516) (xy 330.953213 -382.024133) (xy 330.976888 -381.961128)
			(xy 331.007923 -381.901404) (xy 331.045875 -381.845818) (xy 331.067664 -381.820166) (xy 331.073465 -381.813025)
			(xy 331.079975 -381.795831) (xy 331.080364 -381.786638) (xy 331.080364 -381.628904) (xy 331.080824 -381.618755)
			(xy 331.088612 -381.600009) (xy 331.102996 -381.585687) (xy 331.121775 -381.577981) (xy 331.131926 -381.577596)
			(xy 331.848206 -381.577596) (xy 331.858328 -381.57812) (xy 331.877041 -381.585842) (xy 331.891395 -381.600116)
			(xy 331.899222 -381.618785) (xy 331.899768 -381.628904) (xy 331.899768 -381.786638) (xy 331.900167 -381.795826)
			(xy 331.906689 -381.81301) (xy 331.912468 -381.820166) (xy 331.934246 -381.845826) (xy 331.972195 -381.901412)
			(xy 332.003228 -381.961134) (xy 332.026901 -382.024138) (xy 332.042874 -382.089519) (xy 332.050919 -382.15634)
			(xy 332.05092 -382.223645) (xy 332.050913 -382.223704) (xy 335.328984 -382.223704) (xy 335.328985 -382.156281)
			(xy 335.337061 -382.089342) (xy 335.353096 -382.023853) (xy 335.37686 -381.960756) (xy 335.40801 -381.900959)
			(xy 335.446097 -381.845324) (xy 335.46796 -381.819658) (xy 335.473764 -381.812519) (xy 335.480273 -381.795323)
			(xy 335.48066 -381.78613) (xy 335.48066 -381.628904) (xy 335.481187 -381.6188) (xy 335.488916 -381.60013)
			(xy 335.5032 -381.585837) (xy 335.521865 -381.578095) (xy 335.531968 -381.577596) (xy 336.248248 -381.577596)
			(xy 336.258359 -381.578046) (xy 336.277038 -381.585799) (xy 336.291331 -381.600106) (xy 336.299064 -381.618792)
			(xy 336.299556 -381.628904) (xy 336.299556 -381.78613) (xy 336.299962 -381.795317) (xy 336.30648 -381.812501)
			(xy 336.312256 -381.819658) (xy 336.334112 -381.845331) (xy 336.372204 -381.900963) (xy 336.403357 -381.960758)
			(xy 336.427124 -382.023854) (xy 336.443161 -382.089342) (xy 336.451239 -382.156281) (xy 336.45124 -382.223645)
			(xy 339.729279 -382.223645) (xy 339.72928 -382.156339) (xy 339.737325 -382.089516) (xy 339.753299 -382.024133)
			(xy 339.776974 -381.961128) (xy 339.808009 -381.901404) (xy 339.845959 -381.845818) (xy 339.867748 -381.820166)
			(xy 339.873547 -381.813023) (xy 339.880059 -381.795831) (xy 339.880448 -381.786638) (xy 339.880448 -381.628904)
			(xy 339.880924 -381.618757) (xy 339.888708 -381.600014) (xy 339.903088 -381.585693) (xy 339.921861 -381.577984)
			(xy 339.93201 -381.577596) (xy 340.64829 -381.577596) (xy 340.658411 -381.578133) (xy 340.677123 -381.58585)
			(xy 340.691478 -381.60012) (xy 340.699306 -381.618786) (xy 340.699852 -381.628904) (xy 340.699852 -381.786638)
			(xy 340.700255 -381.795826) (xy 340.706775 -381.813009) (xy 340.712552 -381.820166) (xy 340.73433 -381.845826)
			(xy 340.77228 -381.901411) (xy 340.803314 -381.961134) (xy 340.826988 -382.024137) (xy 340.842962 -382.089518)
			(xy 340.851007 -382.15634) (xy 340.851007 -382.223645) (xy 344.12907 -382.223645) (xy 344.129071 -382.15634)
			(xy 344.137116 -382.089516) (xy 344.15309 -382.024134) (xy 344.176764 -381.961129) (xy 344.207798 -381.901405)
			(xy 344.245748 -381.845818) (xy 344.267536 -381.820166) (xy 344.273334 -381.813022) (xy 344.279847 -381.79583)
			(xy 344.280236 -381.786638) (xy 344.280236 -381.628904) (xy 344.280626 -381.618746) (xy 344.288427 -381.599986)
			(xy 344.302834 -381.585662) (xy 344.321637 -381.577968) (xy 344.331798 -381.577596) (xy 345.048078 -381.577596)
			(xy 345.058198 -381.578143) (xy 345.07691 -381.585856) (xy 345.091266 -381.600123) (xy 345.099094 -381.618787)
			(xy 345.09964 -381.628904) (xy 345.09964 -381.786638) (xy 345.100045 -381.795825) (xy 345.106564 -381.813009)
			(xy 345.11234 -381.820166) (xy 345.134118 -381.845826) (xy 345.172069 -381.901411) (xy 345.203104 -381.961133)
			(xy 345.226778 -382.024137) (xy 345.242752 -382.089518) (xy 345.250798 -382.15634) (xy 345.250798 -382.223645)
			(xy 345.250798 -382.223646) (xy 374.9291 -382.223646) (xy 374.929101 -382.156339) (xy 374.937147 -382.089515)
			(xy 374.953122 -382.024132) (xy 374.976798 -381.961127) (xy 375.007834 -381.901404) (xy 375.045787 -381.845818)
			(xy 375.067576 -381.820166) (xy 375.073367 -381.813016) (xy 375.079886 -381.795829) (xy 375.080276 -381.786638)
			(xy 375.080276 -381.628904) (xy 375.080724 -381.618753) (xy 375.088514 -381.600005) (xy 375.102902 -381.585683)
			(xy 375.121685 -381.577979) (xy 375.131838 -381.577596) (xy 375.848118 -381.577596) (xy 375.85824 -381.57811)
			(xy 375.876954 -381.585836) (xy 375.891308 -381.600113) (xy 375.899134 -381.618784) (xy 375.89968 -381.628904)
			(xy 375.89968 -381.786638) (xy 375.900076 -381.795827) (xy 375.9066 -381.813011) (xy 375.91238 -381.820166)
			(xy 375.934157 -381.845826) (xy 375.972105 -381.901412) (xy 376.003138 -381.961135) (xy 376.02681 -382.024138)
			(xy 376.042784 -382.089519) (xy 376.050828 -382.156341) (xy 376.050829 -382.223644) (xy 376.050822 -382.223704)
			(xy 379.328893 -382.223704) (xy 379.328894 -382.156281) (xy 379.33697 -382.089342) (xy 379.353006 -382.023853)
			(xy 379.37677 -381.960756) (xy 379.40792 -381.900959) (xy 379.446008 -381.845324) (xy 379.467872 -381.819658)
			(xy 379.473678 -381.81252) (xy 379.480185 -381.795324) (xy 379.480572 -381.78613) (xy 379.480572 -381.628904)
			(xy 379.481088 -381.618799) (xy 379.488819 -381.600126) (xy 379.503106 -381.585832) (xy 379.521775 -381.578092)
			(xy 379.53188 -381.577596) (xy 380.24816 -381.577596) (xy 380.258279 -381.578049) (xy 380.276981 -381.585783)
			(xy 380.291297 -381.600088) (xy 380.299044 -381.618785) (xy 380.299468 -381.628904) (xy 380.299468 -381.78613)
			(xy 380.299871 -381.795318) (xy 380.30639 -381.812502) (xy 380.312168 -381.819658) (xy 380.334023 -381.845331)
			(xy 380.372114 -381.900963) (xy 380.403267 -381.960758) (xy 380.427033 -382.023854) (xy 380.443071 -382.089343)
			(xy 380.451148 -382.156281) (xy 380.451149 -382.223646) (xy 383.729188 -382.223646) (xy 383.729189 -382.156339)
			(xy 383.737235 -382.089516) (xy 383.753209 -382.024133) (xy 383.776884 -381.961128) (xy 383.80792 -381.901404)
			(xy 383.845871 -381.845818) (xy 383.86766 -381.820166) (xy 383.873461 -381.813024) (xy 383.879971 -381.795831)
			(xy 383.88036 -381.786638) (xy 383.88036 -381.628904) (xy 383.880824 -381.618755) (xy 383.888611 -381.600011)
			(xy 383.902994 -381.585689) (xy 383.921771 -381.577981) (xy 383.931922 -381.577596) (xy 384.648202 -381.577596)
			(xy 384.658323 -381.578124) (xy 384.677036 -381.585844) (xy 384.691391 -381.600117) (xy 384.699218 -381.618786)
			(xy 384.699764 -381.628904) (xy 384.699764 -381.786638) (xy 384.700164 -381.795826) (xy 384.706686 -381.81301)
			(xy 384.712464 -381.820166) (xy 384.734242 -381.845826) (xy 384.772191 -381.901412) (xy 384.803224 -381.961134)
			(xy 384.826898 -382.024137) (xy 384.842871 -382.089519) (xy 384.850916 -382.15634) (xy 384.850917 -382.223645)
			(xy 388.128979 -382.223645) (xy 388.12898 -382.156339) (xy 388.137025 -382.089516) (xy 388.152999 -382.024133)
			(xy 388.176674 -381.961128) (xy 388.207709 -381.901404) (xy 388.245659 -381.845818) (xy 388.267448 -381.820166)
			(xy 388.273247 -381.813023) (xy 388.279759 -381.795831) (xy 388.280148 -381.786638) (xy 388.280148 -381.628904)
			(xy 388.280624 -381.618757) (xy 388.288408 -381.600014) (xy 388.302788 -381.585693) (xy 388.321561 -381.577984)
			(xy 388.33171 -381.577596) (xy 389.04799 -381.577596) (xy 389.058111 -381.578133) (xy 389.076823 -381.58585)
			(xy 389.091178 -381.60012) (xy 389.099006 -381.618786) (xy 389.099552 -381.628904) (xy 389.099552 -381.786638)
			(xy 389.099955 -381.795826) (xy 389.106475 -381.813009) (xy 389.112252 -381.820166) (xy 389.13403 -381.845826)
			(xy 389.17198 -381.901411) (xy 389.203014 -381.961134) (xy 389.226688 -382.024137) (xy 389.242662 -382.089518)
			(xy 389.250707 -382.15634) (xy 389.250707 -382.223645) (xy 389.250707 -382.223646) (xy 418.92901 -382.223646)
			(xy 418.92901 -382.156339) (xy 418.937056 -382.089515) (xy 418.953032 -382.024132) (xy 418.976708 -381.961127)
			(xy 419.007745 -381.901403) (xy 419.045698 -381.845818) (xy 419.067488 -381.820166) (xy 419.07328 -381.813018)
			(xy 419.079798 -381.79583) (xy 419.080188 -381.786638) (xy 419.080188 -381.628904) (xy 419.080625 -381.618752)
			(xy 419.088417 -381.600002) (xy 419.102809 -381.585679) (xy 419.121596 -381.577977) (xy 419.13175 -381.577596)
			(xy 419.84803 -381.577596) (xy 419.858153 -381.578101) (xy 419.876867 -381.58583) (xy 419.89122 -381.60011)
			(xy 419.899046 -381.618783) (xy 419.899592 -381.628904) (xy 419.899592 -381.786638) (xy 419.899986 -381.795827)
			(xy 419.906511 -381.813011) (xy 419.912292 -381.820166) (xy 419.934069 -381.845827) (xy 419.972016 -381.901413)
			(xy 420.003048 -381.961135) (xy 420.02672 -382.024139) (xy 420.042693 -382.089519) (xy 420.050737 -382.156341)
			(xy 420.050738 -382.223644) (xy 420.050731 -382.223705) (xy 423.328802 -382.223705) (xy 423.328803 -382.15628)
			(xy 423.33688 -382.089342) (xy 423.352916 -382.023852) (xy 423.37668 -381.960755) (xy 423.407831 -381.900959)
			(xy 423.44592 -381.845324) (xy 423.467784 -381.819658) (xy 423.473579 -381.812512) (xy 423.480095 -381.795322)
			(xy 423.480484 -381.78613) (xy 423.480484 -381.628904) (xy 423.480988 -381.618798) (xy 423.488721 -381.600122)
			(xy 423.503012 -381.585828) (xy 423.521686 -381.57809) (xy 423.531792 -381.577596) (xy 424.248072 -381.577596)
			(xy 424.258192 -381.578039) (xy 424.276895 -381.585777) (xy 424.29121 -381.600085) (xy 424.298957 -381.618784)
			(xy 424.29938 -381.628904) (xy 424.29938 -381.78613) (xy 424.29978 -381.795318) (xy 424.306301 -381.812502)
			(xy 424.31208 -381.819658) (xy 424.333935 -381.845331) (xy 424.372025 -381.900964) (xy 424.403177 -381.960759)
			(xy 424.426943 -382.023855) (xy 424.44298 -382.089343) (xy 424.451057 -382.156281) (xy 424.451058 -382.223646)
			(xy 427.729097 -382.223646) (xy 427.729098 -382.156339) (xy 427.737144 -382.089515) (xy 427.753119 -382.024132)
			(xy 427.776794 -381.961127) (xy 427.807831 -381.901404) (xy 427.845783 -381.845818) (xy 427.867572 -381.820166)
			(xy 427.873374 -381.813025) (xy 427.879883 -381.795831) (xy 427.880272 -381.786638) (xy 427.880272 -381.628904)
			(xy 427.880724 -381.618754) (xy 427.888513 -381.600007) (xy 427.9029 -381.585684) (xy 427.921682 -381.577979)
			(xy 427.931834 -381.577596) (xy 428.648114 -381.577596) (xy 428.658236 -381.578114) (xy 428.676949 -381.585838)
			(xy 428.691303 -381.600114) (xy 428.69913 -381.618785) (xy 428.699676 -381.628904) (xy 428.699676 -381.786638)
			(xy 428.700073 -381.795826) (xy 428.706596 -381.81301) (xy 428.712376 -381.820166) (xy 428.734154 -381.845826)
			(xy 428.772102 -381.901412) (xy 428.803135 -381.961135) (xy 428.826807 -382.024138) (xy 428.84278 -382.089519)
			(xy 428.850825 -382.15634) (xy 428.850826 -382.223644) (xy 428.850826 -382.223646) (xy 432.128888 -382.223646)
			(xy 432.128889 -382.156339) (xy 432.136935 -382.089516) (xy 432.152909 -382.024133) (xy 432.176584 -381.961128)
			(xy 432.20762 -381.901404) (xy 432.245571 -381.845818) (xy 432.26736 -381.820166) (xy 432.273161 -381.813024)
			(xy 432.279671 -381.795831) (xy 432.28006 -381.786638) (xy 432.28006 -381.628904) (xy 432.280524 -381.618755)
			(xy 432.288311 -381.600011) (xy 432.302694 -381.585689) (xy 432.321471 -381.577981) (xy 432.331622 -381.577596)
			(xy 433.047902 -381.577596) (xy 433.058023 -381.578124) (xy 433.076736 -381.585844) (xy 433.091091 -381.600117)
			(xy 433.098918 -381.618786) (xy 433.099464 -381.628904) (xy 433.099464 -381.786638) (xy 433.099864 -381.795826)
			(xy 433.106386 -381.81301) (xy 433.112164 -381.820166) (xy 433.133942 -381.845826) (xy 433.171891 -381.901412)
			(xy 433.202924 -381.961134) (xy 433.226598 -382.024137) (xy 433.242571 -382.089519) (xy 433.250616 -382.15634)
			(xy 433.250617 -382.223645) (xy 433.242574 -382.290466) (xy 433.226602 -382.355848) (xy 433.202931 -382.418852)
			(xy 433.171899 -382.478576) (xy 433.133951 -382.534162) (xy 433.112164 -382.559814) (xy 433.106374 -382.566964)
			(xy 433.099856 -382.584151) (xy 433.099464 -382.593342) (xy 433.099464 -383.086864) (xy 433.0999 -383.096048)
			(xy 433.106397 -383.113232) (xy 433.112164 -383.120392) (xy 433.133967 -383.146031) (xy 433.171916 -383.20162)
			(xy 433.202948 -383.261345) (xy 433.226386 -383.323727) (xy 434.32903 -383.323727) (xy 434.329034 -383.256419)
			(xy 434.337081 -383.189595) (xy 434.353057 -383.124211) (xy 434.376732 -383.061205) (xy 434.407768 -383.00148)
			(xy 434.445719 -382.945893) (xy 434.467508 -382.92024) (xy 434.473313 -382.913101) (xy 434.479823 -382.895906)
			(xy 434.480208 -382.886712) (xy 434.480208 -382.728724) (xy 434.480641 -382.71857) (xy 434.48843 -382.699817)
			(xy 434.502824 -382.685492) (xy 434.521614 -382.677793) (xy 434.53177 -382.677416) (xy 435.24805 -382.677416)
			(xy 435.258171 -382.677967) (xy 435.276886 -382.685674) (xy 435.291243 -382.69994) (xy 435.299068 -382.718607)
			(xy 435.299612 -382.728724) (xy 435.299612 -382.886712) (xy 435.300014 -382.8959) (xy 435.306533 -382.913084)
			(xy 435.312312 -382.92024) (xy 435.334066 -382.945921) (xy 435.372019 -383.001502) (xy 435.403056 -383.061221)
			(xy 435.426733 -383.124222) (xy 435.44271 -383.189601) (xy 435.450758 -383.256421) (xy 435.450761 -383.323724)
			(xy 435.44272 -383.390546) (xy 435.426749 -383.455926) (xy 435.403079 -383.518929) (xy 435.372047 -383.578652)
			(xy 435.334099 -383.634237) (xy 435.312312 -383.659888) (xy 435.306497 -383.66702) (xy 435.299993 -383.684221)
			(xy 435.299612 -383.693416) (xy 435.299612 -384.186684) (xy 435.300027 -384.195871) (xy 435.306537 -384.213055)
			(xy 435.312312 -384.220212) (xy 435.334137 -384.245834) (xy 435.372087 -384.301424) (xy 435.403122 -384.361151)
			(xy 435.426795 -384.42416) (xy 435.442767 -384.489546) (xy 435.450809 -384.556373) (xy 435.450805 -384.623681)
			(xy 435.442757 -384.690507) (xy 435.426779 -384.755892) (xy 435.4031 -384.818898) (xy 435.37206 -384.878623)
			(xy 435.334103 -384.934208) (xy 435.312312 -384.95986) (xy 435.306509 -384.967001) (xy 435.299998 -384.984195)
			(xy 435.299612 -384.993388) (xy 435.299612 -385.151376) (xy 435.299159 -385.161527) (xy 435.291374 -385.180277)
			(xy 435.276987 -385.194601) (xy 435.258203 -385.202303) (xy 435.24805 -385.202684) (xy 434.53177 -385.202684)
			(xy 434.521644 -385.202199) (xy 434.502927 -385.194466) (xy 434.488573 -385.180179) (xy 434.48075 -385.161499)
			(xy 434.480208 -385.151376) (xy 434.480208 -384.993388) (xy 434.479802 -384.9842) (xy 434.473285 -384.967016)
			(xy 434.467508 -384.95986) (xy 434.445757 -384.934178) (xy 434.407809 -384.878595) (xy 434.376776 -384.818876)
			(xy 434.353102 -384.755875) (xy 434.337128 -384.690497) (xy 434.329081 -384.623678) (xy 434.329078 -384.556376)
			(xy 434.337118 -384.489557) (xy 434.353086 -384.424177) (xy 434.376753 -384.361174) (xy 434.407781 -384.301451)
			(xy 434.445723 -384.245864) (xy 434.467508 -384.220212) (xy 434.473325 -384.213082) (xy 434.479827 -384.19588)
			(xy 434.480208 -384.186684) (xy 434.480208 -383.693416) (xy 434.479788 -383.68423) (xy 434.473281 -383.667046)
			(xy 434.467508 -383.659888) (xy 434.445686 -383.634265) (xy 434.40774 -383.578673) (xy 434.37671 -383.518945)
			(xy 434.353041 -383.455937) (xy 434.337071 -383.390552) (xy 434.32903 -383.323727) (xy 433.226386 -383.323727)
			(xy 433.22662 -383.324351) (xy 433.242592 -383.389735) (xy 433.250634 -383.456559) (xy 433.250633 -383.523865)
			(xy 433.242587 -383.590689) (xy 433.226613 -383.656072) (xy 433.202938 -383.719077) (xy 433.171903 -383.778801)
			(xy 433.133953 -383.834388) (xy 433.112164 -383.86004) (xy 433.106363 -383.867182) (xy 433.099852 -383.884375)
			(xy 433.099464 -383.893568) (xy 433.099464 -384.051556) (xy 433.099042 -384.061712) (xy 433.091254 -384.08047)
			(xy 433.076856 -384.094796) (xy 433.05806 -384.102491) (xy 433.047902 -384.102864) (xy 432.331622 -384.102864)
			(xy 432.321497 -384.102356) (xy 432.302777 -384.094636) (xy 432.28842 -384.080356) (xy 432.2806 -384.061678)
			(xy 432.28006 -384.051556) (xy 432.28006 -383.893568) (xy 432.279652 -383.884381) (xy 432.273135 -383.867197)
			(xy 432.26736 -383.86004) (xy 432.245587 -383.834375) (xy 432.207637 -383.778791) (xy 432.176602 -383.719069)
			(xy 432.152927 -383.656066) (xy 432.136952 -383.590686) (xy 432.128907 -383.523864) (xy 432.128905 -383.45656)
			(xy 432.136948 -383.389738) (xy 432.15292 -383.324357) (xy 432.176592 -383.261353) (xy 432.207624 -383.20163)
			(xy 432.245573 -383.146044) (xy 432.26736 -383.120392) (xy 432.27315 -383.113242) (xy 432.279667 -383.096055)
			(xy 432.28006 -383.086864) (xy 432.28006 -382.593342) (xy 432.279616 -382.584159) (xy 432.273125 -382.566975)
			(xy 432.26736 -382.559814) (xy 432.245562 -382.53417) (xy 432.207612 -382.478583) (xy 432.176578 -382.418858)
			(xy 432.152905 -382.355853) (xy 432.136932 -382.290469) (xy 432.128888 -382.223646) (xy 428.850826 -382.223646)
			(xy 428.842783 -382.290466) (xy 428.826812 -382.355848) (xy 428.803141 -382.418852) (xy 428.772109 -382.478575)
			(xy 428.734163 -382.534162) (xy 428.712376 -382.559814) (xy 428.706588 -382.566965) (xy 428.700069 -382.584151)
			(xy 428.699676 -382.593342) (xy 428.699676 -383.086864) (xy 428.700109 -383.096049) (xy 428.706607 -383.113233)
			(xy 428.712376 -383.120392) (xy 428.734179 -383.146031) (xy 428.772126 -383.20162) (xy 428.803158 -383.261345)
			(xy 428.826616 -383.323786) (xy 429.928711 -383.323786) (xy 429.928714 -383.25636) (xy 429.936794 -383.189418)
			(xy 429.952834 -383.123927) (xy 429.976603 -383.060829) (xy 430.007759 -383.001032) (xy 430.045853 -382.945397)
			(xy 430.06772 -382.919732) (xy 430.07353 -382.912597) (xy 430.080036 -382.895398) (xy 430.08042 -382.886204)
			(xy 430.08042 -382.728724) (xy 430.080836 -382.718601) (xy 430.08858 -382.699894) (xy 430.102897 -382.685578)
			(xy 430.121605 -382.677835) (xy 430.131728 -382.677416) (xy 430.848008 -382.677416) (xy 430.858133 -382.67781)
			(xy 430.87684 -382.685564) (xy 430.891154 -382.699887) (xy 430.898896 -382.718599) (xy 430.899316 -382.728724)
			(xy 430.899316 -382.886204) (xy 430.899721 -382.895392) (xy 430.906238 -382.912576) (xy 430.912016 -382.919732)
			(xy 430.933844 -382.945427) (xy 430.971933 -383.001057) (xy 431.003084 -383.06085) (xy 431.02685 -383.123943)
			(xy 431.042887 -383.189428) (xy 431.050966 -383.256363) (xy 431.050969 -383.323783) (xy 431.042897 -383.390719)
			(xy 431.026866 -383.456206) (xy 431.003106 -383.519301) (xy 430.971961 -383.579096) (xy 430.933877 -383.634731)
			(xy 430.912016 -383.660396) (xy 430.90624 -383.667556) (xy 430.899713 -383.684735) (xy 430.899316 -383.693924)
			(xy 430.899316 -384.186176) (xy 430.899734 -384.195362) (xy 430.906242 -384.212547) (xy 430.912016 -384.219704)
			(xy 430.933915 -384.24534) (xy 430.972001 -384.300979) (xy 431.00315 -384.36078) (xy 431.026911 -384.42388)
			(xy 431.042944 -384.489373) (xy 431.051016 -384.556314) (xy 431.051013 -384.62374) (xy 431.042934 -384.690681)
			(xy 431.026895 -384.756171) (xy 431.003128 -384.81927) (xy 430.971974 -384.879067) (xy 430.933882 -384.934702)
			(xy 430.912016 -384.960368) (xy 430.90621 -384.967507) (xy 430.8997 -384.984702) (xy 430.899316 -384.993896)
			(xy 430.899316 -385.151376) (xy 430.898865 -385.161495) (xy 430.891128 -385.180195) (xy 430.876822 -385.19451)
			(xy 430.858127 -385.202259) (xy 430.848008 -385.202684) (xy 430.131728 -385.202684) (xy 430.121605 -385.202261)
			(xy 430.102899 -385.194519) (xy 430.088583 -385.180204) (xy 430.08084 -385.161499) (xy 430.08042 -385.151376)
			(xy 430.08042 -384.993896) (xy 430.080008 -384.984709) (xy 430.073495 -384.967525) (xy 430.06772 -384.960368)
			(xy 430.045891 -384.934674) (xy 430.0078 -384.879044) (xy 429.976646 -384.819252) (xy 429.952879 -384.756159)
			(xy 429.936841 -384.690673) (xy 429.928761 -384.623738) (xy 429.928758 -384.556316) (xy 429.936831 -384.48938)
			(xy 429.952863 -384.423893) (xy 429.976624 -384.360797) (xy 430.007772 -384.301002) (xy 430.045857 -384.245369)
			(xy 430.06772 -384.219704) (xy 430.0735 -384.212547) (xy 430.080024 -384.195365) (xy 430.08042 -384.186176)
			(xy 430.08042 -383.693924) (xy 430.079994 -383.684739) (xy 430.073491 -383.667554) (xy 430.06772 -383.660396)
			(xy 430.04582 -383.63476) (xy 430.007731 -383.579122) (xy 429.976581 -383.519322) (xy 429.952818 -383.456221)
			(xy 429.936784 -383.390728) (xy 429.928711 -383.323786) (xy 428.826616 -383.323786) (xy 428.826829 -383.324352)
			(xy 428.842801 -383.389735) (xy 428.850843 -383.456559) (xy 428.850842 -383.523865) (xy 428.842797 -383.590688)
			(xy 428.826822 -383.656071) (xy 428.803148 -383.719077) (xy 428.772114 -383.778801) (xy 428.734164 -383.834388)
			(xy 428.712376 -383.86004) (xy 428.706577 -383.867183) (xy 428.700065 -383.884375) (xy 428.699676 -383.893568)
			(xy 428.699676 -384.051556) (xy 428.699242 -384.06171) (xy 428.691456 -384.080466) (xy 428.677063 -384.094792)
			(xy 428.65827 -384.102489) (xy 428.648114 -384.102864) (xy 427.931834 -384.102864) (xy 427.92171 -384.102345)
			(xy 427.90299 -384.09463) (xy 427.888633 -384.080353) (xy 427.880812 -384.061677) (xy 427.880272 -384.051556)
			(xy 427.880272 -383.893568) (xy 427.879883 -383.884378) (xy 427.873355 -383.867194) (xy 427.867572 -383.86004)
			(xy 427.845799 -383.834375) (xy 427.807848 -383.778791) (xy 427.776812 -383.71907) (xy 427.753137 -383.656067)
			(xy 427.737162 -383.590686) (xy 427.729116 -383.523864) (xy 427.729114 -383.45656) (xy 427.737157 -383.389738)
			(xy 427.75313 -383.324356) (xy 427.776802 -383.261352) (xy 427.807835 -383.201629) (xy 427.845784 -383.146044)
			(xy 427.867572 -383.120392) (xy 427.873363 -383.113243) (xy 427.879879 -383.096055) (xy 427.880272 -383.086864)
			(xy 427.880272 -382.593342) (xy 427.879848 -382.584156) (xy 427.873344 -382.566971) (xy 427.867572 -382.559814)
			(xy 427.845774 -382.53417) (xy 427.807823 -382.478583) (xy 427.776788 -382.418859) (xy 427.753115 -382.355853)
			(xy 427.737141 -382.29047) (xy 427.729097 -382.223646) (xy 424.451058 -382.223646) (xy 424.451058 -382.223704)
			(xy 424.442983 -382.290642) (xy 424.426948 -382.356131) (xy 424.403184 -382.419227) (xy 424.372033 -382.479023)
			(xy 424.333944 -382.534657) (xy 424.31208 -382.560322) (xy 424.306289 -382.567471) (xy 424.299772 -382.584659)
			(xy 424.29938 -382.59385) (xy 424.29938 -383.086356) (xy 424.299816 -383.09554) (xy 424.306312 -383.112725)
			(xy 424.31208 -383.119884) (xy 424.33396 -383.145536) (xy 424.37205 -383.201172) (xy 424.403201 -383.26097)
			(xy 424.426837 -383.323727) (xy 425.528942 -383.323727) (xy 425.528946 -383.256419) (xy 425.536993 -383.189594)
			(xy 425.55297 -383.12421) (xy 425.576646 -383.061204) (xy 425.607682 -383.00148) (xy 425.645635 -382.945892)
			(xy 425.667424 -382.92024) (xy 425.673231 -382.913103) (xy 425.679739 -382.895906) (xy 425.680124 -382.886712)
			(xy 425.680124 -382.728724) (xy 425.680542 -382.718568) (xy 425.688334 -382.699812) (xy 425.702732 -382.685487)
			(xy 425.721528 -382.67779) (xy 425.731686 -382.677416) (xy 426.447966 -382.677416) (xy 426.458088 -382.677954)
			(xy 426.476803 -382.685666) (xy 426.49116 -382.699937) (xy 426.498984 -382.718606) (xy 426.499528 -382.728724)
			(xy 426.499528 -382.886712) (xy 426.499926 -382.895901) (xy 426.506447 -382.913085) (xy 426.512228 -382.92024)
			(xy 426.533981 -382.945921) (xy 426.571933 -383.001502) (xy 426.60297 -383.061222) (xy 426.626646 -383.124223)
			(xy 426.642623 -383.189602) (xy 426.65067 -383.256422) (xy 426.650673 -383.323724) (xy 426.642632 -383.390545)
			(xy 426.626662 -383.455926) (xy 426.602992 -383.518929) (xy 426.571961 -383.578651) (xy 426.534014 -383.634236)
			(xy 426.512228 -383.659888) (xy 426.506403 -383.667013) (xy 426.499907 -383.684219) (xy 426.499528 -383.693416)
			(xy 426.499528 -384.186684) (xy 426.499939 -384.195871) (xy 426.506451 -384.213056) (xy 426.512228 -384.220212)
			(xy 426.534052 -384.245834) (xy 426.572002 -384.301424) (xy 426.603036 -384.361152) (xy 426.626708 -384.42416)
			(xy 426.64268 -384.489546) (xy 426.650721 -384.556373) (xy 426.650718 -384.623681) (xy 426.64267 -384.690507)
			(xy 426.626692 -384.755892) (xy 426.603014 -384.818898) (xy 426.571974 -384.878622) (xy 426.534019 -384.934208)
			(xy 426.512228 -384.95986) (xy 426.506415 -384.966993) (xy 426.499912 -384.984193) (xy 426.499528 -384.993388)
			(xy 426.499528 -385.151376) (xy 426.499059 -385.161525) (xy 426.491277 -385.180272) (xy 426.476895 -385.194595)
			(xy 426.458117 -385.202301) (xy 426.447966 -385.202684) (xy 425.731686 -385.202684) (xy 425.721561 -385.202185)
			(xy 425.702845 -385.194457) (xy 425.68849 -385.180175) (xy 425.680667 -385.161498) (xy 425.680124 -385.151376)
			(xy 425.680124 -384.993388) (xy 425.679714 -384.984201) (xy 425.6732 -384.967017) (xy 425.667424 -384.95986)
			(xy 425.645672 -384.934178) (xy 425.607723 -384.878596) (xy 425.576689 -384.818876) (xy 425.553015 -384.755876)
			(xy 425.53704 -384.690497) (xy 425.528994 -384.623678) (xy 425.52899 -384.556376) (xy 425.537031 -384.489556)
			(xy 425.552999 -384.424176) (xy 425.576667 -384.361173) (xy 425.607696 -384.301451) (xy 425.645639 -384.245865)
			(xy 425.667424 -384.220212) (xy 425.673243 -384.213083) (xy 425.679744 -384.19588) (xy 425.680124 -384.186684)
			(xy 425.680124 -383.693416) (xy 425.679701 -383.68423) (xy 425.673195 -383.667046) (xy 425.667424 -383.659888)
			(xy 425.645601 -383.634265) (xy 425.607655 -383.578674) (xy 425.576624 -383.518946) (xy 425.552954 -383.455938)
			(xy 425.536984 -383.390552) (xy 425.528942 -383.323727) (xy 424.426837 -383.323727) (xy 424.426965 -383.324068)
			(xy 424.443 -383.389559) (xy 424.451075 -383.456499) (xy 424.451074 -383.523925) (xy 424.442996 -383.590864)
			(xy 424.426958 -383.656355) (xy 424.403191 -383.719452) (xy 424.372038 -383.779249) (xy 424.333946 -383.834883)
			(xy 424.31208 -383.860548) (xy 424.306278 -383.867689) (xy 424.299767 -383.884883) (xy 424.29938 -383.894076)
			(xy 424.29938 -384.051556) (xy 424.298947 -384.061678) (xy 424.29121 -384.080385) (xy 424.276898 -384.094701)
			(xy 424.258194 -384.102444) (xy 424.248072 -384.102864) (xy 423.531792 -384.102864) (xy 423.521665 -384.10249)
			(xy 423.502954 -384.094732) (xy 423.488639 -384.080402) (xy 423.4809 -384.061684) (xy 423.480484 -384.051556)
			(xy 423.480484 -383.894076) (xy 423.480089 -383.884887) (xy 423.473565 -383.867703) (xy 423.467784 -383.860548)
			(xy 423.445936 -383.83487) (xy 423.407848 -383.779237) (xy 423.376698 -383.719442) (xy 423.352933 -383.656347)
			(xy 423.336897 -383.59086) (xy 423.32882 -383.523923) (xy 423.328819 -383.456501) (xy 423.336893 -383.389564)
			(xy 423.352926 -383.324076) (xy 423.376688 -383.26098) (xy 423.407836 -383.201184) (xy 423.445922 -383.145549)
			(xy 423.467784 -383.119884) (xy 423.473568 -383.11273) (xy 423.480091 -383.095546) (xy 423.480484 -383.086356)
			(xy 423.480484 -382.59385) (xy 423.480054 -382.584665) (xy 423.473554 -382.56748) (xy 423.467784 -382.560322)
			(xy 423.445911 -382.534665) (xy 423.407823 -382.479029) (xy 423.376674 -382.419231) (xy 423.352911 -382.356133)
			(xy 423.336877 -382.290643) (xy 423.328802 -382.223705) (xy 420.050731 -382.223705) (xy 420.042695 -382.290466)
			(xy 420.026725 -382.355847) (xy 420.003054 -382.418851) (xy 419.972024 -382.478574) (xy 419.934078 -382.534161)
			(xy 419.912292 -382.559814) (xy 419.906506 -382.566967) (xy 419.899985 -382.584151) (xy 419.899592 -382.593342)
			(xy 419.899592 -383.086864) (xy 419.900021 -383.096049) (xy 419.906522 -383.113234) (xy 419.912292 -383.120392)
			(xy 419.934094 -383.146032) (xy 419.972041 -383.201621) (xy 420.003072 -383.261346) (xy 420.02653 -383.323787)
			(xy 421.128623 -383.323787) (xy 421.128626 -383.256359) (xy 421.136706 -383.189418) (xy 421.152747 -383.123926)
			(xy 421.176516 -383.060828) (xy 421.207673 -383.001031) (xy 421.245769 -382.945397) (xy 421.267636 -382.919732)
			(xy 421.273449 -382.912598) (xy 421.279953 -382.895399) (xy 421.280336 -382.886204) (xy 421.280336 -382.728724)
			(xy 421.280736 -382.718599) (xy 421.288483 -382.699889) (xy 421.302805 -382.685572) (xy 421.321518 -382.677832)
			(xy 421.331644 -382.677416) (xy 422.047924 -382.677416) (xy 422.058036 -382.677866) (xy 422.076718 -382.685614)
			(xy 422.091013 -382.699922) (xy 422.098744 -382.718611) (xy 422.099232 -382.728724) (xy 422.099232 -382.886204)
			(xy 422.099656 -382.895389) (xy 422.106162 -382.912573) (xy 422.111932 -382.919732) (xy 422.133759 -382.945427)
			(xy 422.171847 -383.001058) (xy 422.202998 -383.06085) (xy 422.226762 -383.123943) (xy 422.242799 -383.189428)
			(xy 422.250878 -383.256363) (xy 422.250881 -383.323783) (xy 422.242809 -383.390718) (xy 422.226778 -383.456205)
			(xy 422.20302 -383.5193) (xy 422.171875 -383.579096) (xy 422.133793 -383.63473) (xy 422.111932 -383.660396)
			(xy 422.106146 -383.667549) (xy 422.099627 -383.684734) (xy 422.099232 -383.693924) (xy 422.099232 -384.186176)
			(xy 422.099669 -384.19536) (xy 422.106166 -384.212544) (xy 422.111932 -384.219704) (xy 422.13383 -384.245341)
			(xy 422.171916 -384.30098) (xy 422.203063 -384.36078) (xy 422.226824 -384.423881) (xy 422.242856 -384.489373)
			(xy 422.250928 -384.556314) (xy 422.250925 -384.62374) (xy 422.242846 -384.69068) (xy 422.226808 -384.756171)
			(xy 422.203041 -384.819269) (xy 422.171888 -384.879066) (xy 422.133797 -384.934702) (xy 422.111932 -384.960368)
			(xy 422.106116 -384.967499) (xy 422.099615 -384.984701) (xy 422.099232 -384.993896) (xy 422.099232 -385.151376)
			(xy 422.098696 -385.161479) (xy 422.090972 -385.180151) (xy 422.076691 -385.194445) (xy 422.058027 -385.202187)
			(xy 422.047924 -385.202684) (xy 421.331644 -385.202684) (xy 421.321522 -385.202247) (xy 421.302817 -385.194511)
			(xy 421.2885 -385.1802) (xy 421.280756 -385.161497) (xy 421.280336 -385.151376) (xy 421.280336 -384.993896)
			(xy 421.27992 -384.98471) (xy 421.27341 -384.967526) (xy 421.267636 -384.960368) (xy 421.245806 -384.934674)
			(xy 421.207714 -384.879045) (xy 421.17656 -384.819253) (xy 421.152792 -384.756159) (xy 421.136753 -384.690673)
			(xy 421.128674 -384.623738) (xy 421.12867 -384.556316) (xy 421.136743 -384.48938) (xy 421.152776 -384.423892)
			(xy 421.176538 -384.360797) (xy 421.207686 -384.301002) (xy 421.245773 -384.245369) (xy 421.267636 -384.219704)
			(xy 421.273418 -384.212549) (xy 421.27994 -384.195366) (xy 421.280336 -384.186176) (xy 421.280336 -383.693924)
			(xy 421.279906 -383.684739) (xy 421.273405 -383.667555) (xy 421.267636 -383.660396) (xy 421.245735 -383.634761)
			(xy 421.207645 -383.579123) (xy 421.176494 -383.519323) (xy 421.152731 -383.456222) (xy 421.136696 -383.390729)
			(xy 421.128623 -383.323787) (xy 420.02653 -383.323787) (xy 420.026742 -383.324352) (xy 420.042713 -383.389736)
			(xy 420.050756 -383.456559) (xy 420.050754 -383.523865) (xy 420.042709 -383.590688) (xy 420.026735 -383.656071)
			(xy 420.003062 -383.719076) (xy 419.972028 -383.7788) (xy 419.93408 -383.834387) (xy 419.912292 -383.86004)
			(xy 419.906495 -383.867185) (xy 419.899981 -383.884376) (xy 419.899592 -383.893568) (xy 419.899592 -384.051556)
			(xy 419.899142 -384.061708) (xy 419.89136 -384.080461) (xy 419.876971 -384.094786) (xy 419.858184 -384.102486)
			(xy 419.84803 -384.102864) (xy 419.13175 -384.102864) (xy 419.121627 -384.102333) (xy 419.102908 -384.094622)
			(xy 419.08855 -384.080349) (xy 419.080728 -384.061676) (xy 419.080188 -384.051556) (xy 419.080188 -383.893568)
			(xy 419.079796 -383.884379) (xy 419.07327 -383.867194) (xy 419.067488 -383.86004) (xy 419.045715 -383.834376)
			(xy 419.007762 -383.778792) (xy 418.976725 -383.719071) (xy 418.95305 -383.656068) (xy 418.937074 -383.590686)
			(xy 418.929028 -383.523864) (xy 418.929026 -383.45656) (xy 418.93707 -383.389737) (xy 418.953042 -383.324355)
			(xy 418.976716 -383.261351) (xy 419.00775 -383.201629) (xy 419.0457 -383.146043) (xy 419.067488 -383.120392)
			(xy 419.073269 -383.113236) (xy 419.079793 -383.096054) (xy 419.080188 -383.086864) (xy 419.080188 -382.593342)
			(xy 419.07976 -382.584157) (xy 419.073259 -382.566972) (xy 419.067488 -382.559814) (xy 419.045689 -382.534171)
			(xy 419.007737 -382.478584) (xy 418.976702 -382.41886) (xy 418.953027 -382.355854) (xy 418.937054 -382.29047)
			(xy 418.92901 -382.223646) (xy 389.250707 -382.223646) (xy 389.242664 -382.290467) (xy 389.226692 -382.355848)
			(xy 389.20302 -382.418853) (xy 389.171987 -382.478576) (xy 389.134039 -382.534162) (xy 389.112252 -382.559814)
			(xy 389.106461 -382.566963) (xy 389.099944 -382.584151) (xy 389.099552 -382.593342) (xy 389.099552 -383.086864)
			(xy 389.09999 -383.096048) (xy 389.106485 -383.113232) (xy 389.112252 -383.120392) (xy 389.134056 -383.146031)
			(xy 389.172005 -383.201619) (xy 389.203038 -383.261344) (xy 389.226475 -383.323726) (xy 390.329121 -383.323726)
			(xy 390.329125 -383.256419) (xy 390.337172 -383.189595) (xy 390.353147 -383.124211) (xy 390.376822 -383.061206)
			(xy 390.407857 -383.001481) (xy 390.445807 -382.945893) (xy 390.467596 -382.92024) (xy 390.4734 -382.9131)
			(xy 390.47991 -382.895906) (xy 390.480296 -382.886712) (xy 390.480296 -382.728724) (xy 390.480741 -382.718572)
			(xy 390.488528 -382.699821) (xy 390.502918 -382.685497) (xy 390.521704 -382.677795) (xy 390.531858 -382.677416)
			(xy 391.248138 -382.677416) (xy 391.258264 -382.677895) (xy 391.276982 -382.685631) (xy 391.291336 -382.699919)
			(xy 391.299158 -382.7186) (xy 391.2997 -382.728724) (xy 391.2997 -382.886712) (xy 391.300105 -382.8959)
			(xy 391.306622 -382.913084) (xy 391.3124 -382.92024) (xy 391.334151 -382.945922) (xy 391.372099 -383.001505)
			(xy 391.403131 -383.061225) (xy 391.426804 -383.124225) (xy 391.442779 -383.189603) (xy 391.450825 -383.256422)
			(xy 391.450828 -383.323724) (xy 391.442788 -383.390543) (xy 391.42682 -383.455923) (xy 391.403153 -383.518926)
			(xy 391.372126 -383.578649) (xy 391.334184 -383.634235) (xy 391.3124 -383.659888) (xy 391.306584 -383.667019)
			(xy 391.300081 -383.68422) (xy 391.2997 -383.693416) (xy 391.2997 -384.186684) (xy 391.300118 -384.19587)
			(xy 391.306626 -384.213055) (xy 391.3124 -384.220212) (xy 391.334222 -384.245836) (xy 391.372167 -384.301427)
			(xy 391.403197 -384.361155) (xy 391.426866 -384.424163) (xy 391.442835 -384.489548) (xy 391.450876 -384.556374)
			(xy 391.450872 -384.623681) (xy 391.442825 -384.690505) (xy 391.42685 -384.755889) (xy 391.403175 -384.818895)
			(xy 391.372139 -384.878619) (xy 391.334189 -384.934207) (xy 391.3124 -384.95986) (xy 391.306595 -384.967)
			(xy 391.300086 -384.984194) (xy 391.2997 -384.993388) (xy 391.2997 -385.151376) (xy 391.299259 -385.161529)
			(xy 391.291471 -385.180281) (xy 391.27708 -385.194605) (xy 391.258292 -385.202305) (xy 391.248138 -385.202684)
			(xy 390.531858 -385.202684) (xy 390.521732 -385.202209) (xy 390.503014 -385.194471) (xy 390.48866 -385.180182)
			(xy 390.480838 -385.1615) (xy 390.480296 -385.151376) (xy 390.480296 -384.993388) (xy 390.479892 -384.9842)
			(xy 390.473374 -384.967016) (xy 390.467596 -384.95986) (xy 390.445845 -384.934178) (xy 390.407898 -384.878595)
			(xy 390.376865 -384.818875) (xy 390.353192 -384.755875) (xy 390.337218 -384.690496) (xy 390.329172 -384.623678)
			(xy 390.329169 -384.556376) (xy 390.337209 -384.489557) (xy 390.353176 -384.424177) (xy 390.376843 -384.361174)
			(xy 390.40787 -384.301452) (xy 390.445812 -384.245865) (xy 390.467596 -384.220212) (xy 390.473412 -384.21308)
			(xy 390.479915 -384.19588) (xy 390.480296 -384.186684) (xy 390.480296 -383.693416) (xy 390.479879 -383.68423)
			(xy 390.47337 -383.667045) (xy 390.467596 -383.659888) (xy 390.445774 -383.634264) (xy 390.407829 -383.578673)
			(xy 390.3768 -383.518945) (xy 390.353131 -383.455937) (xy 390.337162 -383.390552) (xy 390.329121 -383.323726)
			(xy 389.226475 -383.323726) (xy 389.22671 -383.324351) (xy 389.242682 -383.389735) (xy 389.250725 -383.456559)
			(xy 389.250724 -383.523865) (xy 389.242678 -383.590689) (xy 389.226703 -383.656072) (xy 389.203028 -383.719078)
			(xy 389.171992 -383.778802) (xy 389.134041 -383.834388) (xy 389.112252 -383.86004) (xy 389.10645 -383.867181)
			(xy 389.09994 -383.884375) (xy 389.099552 -383.893568) (xy 389.099552 -384.051556) (xy 389.099043 -384.061701)
			(xy 389.091272 -384.080442) (xy 389.076902 -384.094765) (xy 389.058136 -384.102476) (xy 389.04799 -384.102864)
			(xy 388.33171 -384.102864) (xy 388.321584 -384.102365) (xy 388.302864 -384.094642) (xy 388.288508 -384.080359)
			(xy 388.280687 -384.061679) (xy 388.280148 -384.051556) (xy 388.280148 -383.893568) (xy 388.279742 -383.884381)
			(xy 388.273224 -383.867197) (xy 388.267448 -383.86004) (xy 388.245676 -383.834375) (xy 388.207726 -383.778791)
			(xy 388.176692 -383.719069) (xy 388.153018 -383.656066) (xy 388.137043 -383.590685) (xy 388.128998 -383.523864)
			(xy 388.128996 -383.45656) (xy 388.137039 -383.389738) (xy 388.15301 -383.324357) (xy 388.176682 -383.261353)
			(xy 388.207714 -383.20163) (xy 388.245661 -383.146044) (xy 388.267448 -383.120392) (xy 388.273236 -383.113241)
			(xy 388.279755 -383.096055) (xy 388.280148 -383.086864) (xy 388.280148 -382.593342) (xy 388.279707 -382.584158)
			(xy 388.273213 -382.566974) (xy 388.267448 -382.559814) (xy 388.24565 -382.53417) (xy 388.207701 -382.478583)
			(xy 388.176668 -382.418858) (xy 388.152995 -382.355852) (xy 388.137022 -382.290469) (xy 388.128979 -382.223645)
			(xy 384.850917 -382.223645) (xy 384.842874 -382.290466) (xy 384.826902 -382.355848) (xy 384.803231 -382.418852)
			(xy 384.772199 -382.478576) (xy 384.734251 -382.534162) (xy 384.712464 -382.559814) (xy 384.706674 -382.566964)
			(xy 384.700156 -382.584151) (xy 384.699764 -382.593342) (xy 384.699764 -383.086864) (xy 384.7002 -383.096048)
			(xy 384.706697 -383.113232) (xy 384.712464 -383.120392) (xy 384.734267 -383.146031) (xy 384.772216 -383.20162)
			(xy 384.803248 -383.261345) (xy 384.826708 -383.323786) (xy 385.928802 -383.323786) (xy 385.928805 -383.25636)
			(xy 385.936885 -383.189419) (xy 385.952924 -383.123928) (xy 385.976693 -383.060829) (xy 386.007848 -383.001032)
			(xy 386.045942 -382.945397) (xy 386.067808 -382.919732) (xy 386.073617 -382.912596) (xy 386.080124 -382.895398)
			(xy 386.080508 -382.886204) (xy 386.080508 -382.728724) (xy 386.080936 -382.718602) (xy 386.088677 -382.699897)
			(xy 386.102991 -382.685582) (xy 386.121694 -382.677837) (xy 386.131816 -382.677416) (xy 386.848096 -382.677416)
			(xy 386.85822 -382.67782) (xy 386.876927 -382.685569) (xy 386.891242 -382.69989) (xy 386.898984 -382.7186)
			(xy 386.899404 -382.728724) (xy 386.899404 -382.886204) (xy 386.899811 -382.895391) (xy 386.906327 -382.912576)
			(xy 386.912104 -382.919732) (xy 386.933932 -382.945426) (xy 386.972022 -383.001057) (xy 387.003174 -383.060849)
			(xy 387.02694 -383.123942) (xy 387.042978 -383.189428) (xy 387.051057 -383.256363) (xy 387.05106 -383.323783)
			(xy 387.042988 -383.390719) (xy 387.026956 -383.456206) (xy 387.003196 -383.519301) (xy 386.97205 -383.579097)
			(xy 386.933966 -383.634731) (xy 386.912104 -383.660396) (xy 386.906327 -383.667555) (xy 386.899801 -383.684735)
			(xy 386.899404 -383.693924) (xy 386.899404 -384.186176) (xy 386.899825 -384.195362) (xy 386.906331 -384.212547)
			(xy 386.912104 -384.219704) (xy 386.934003 -384.24534) (xy 386.972091 -384.300979) (xy 387.003239 -384.360779)
			(xy 387.027001 -384.42388) (xy 387.043034 -384.489372) (xy 387.051107 -384.556314) (xy 387.051104 -384.62374)
			(xy 387.043025 -384.690681) (xy 387.026985 -384.756172) (xy 387.003217 -384.81927) (xy 386.972063 -384.879068)
			(xy 386.93397 -384.934703) (xy 386.912104 -384.960368) (xy 386.906297 -384.967506) (xy 386.899788 -384.984702)
			(xy 386.899404 -384.993896) (xy 386.899404 -385.151376) (xy 386.898965 -385.161496) (xy 386.891225 -385.180199)
			(xy 386.876916 -385.194514) (xy 386.858216 -385.202261) (xy 386.848096 -385.202684) (xy 386.131816 -385.202684)
			(xy 386.121693 -385.202271) (xy 386.102986 -385.194525) (xy 386.088671 -385.180207) (xy 386.080928 -385.1615)
			(xy 386.080508 -385.151376) (xy 386.080508 -384.993896) (xy 386.080098 -384.984709) (xy 386.073584 -384.967525)
			(xy 386.067808 -384.960368) (xy 386.045979 -384.934674) (xy 386.007889 -384.879044) (xy 385.976736 -384.819251)
			(xy 385.95297 -384.756158) (xy 385.936931 -384.690673) (xy 385.928852 -384.623738) (xy 385.928849 -384.556317)
			(xy 385.936922 -384.489381) (xy 385.952954 -384.423893) (xy 385.976714 -384.360798) (xy 386.007861 -384.301003)
			(xy 386.045946 -384.245369) (xy 386.067808 -384.219704) (xy 386.073586 -384.212546) (xy 386.080112 -384.195365)
			(xy 386.080508 -384.186176) (xy 386.080508 -383.693924) (xy 386.080084 -383.684738) (xy 386.07358 -383.667554)
			(xy 386.067808 -383.660396) (xy 386.045908 -383.63476) (xy 386.00782 -383.579122) (xy 385.976671 -383.519321)
			(xy 385.952908 -383.456221) (xy 385.936875 -383.390728) (xy 385.928802 -383.323786) (xy 384.826708 -383.323786)
			(xy 384.82692 -383.324351) (xy 384.842892 -383.389735) (xy 384.850934 -383.456559) (xy 384.850933 -383.523865)
			(xy 384.842887 -383.590689) (xy 384.826913 -383.656072) (xy 384.803238 -383.719077) (xy 384.772203 -383.778801)
			(xy 384.734253 -383.834388) (xy 384.712464 -383.86004) (xy 384.706663 -383.867182) (xy 384.700152 -383.884375)
			(xy 384.699764 -383.893568) (xy 384.699764 -384.051556) (xy 384.699342 -384.061712) (xy 384.691554 -384.08047)
			(xy 384.677156 -384.094796) (xy 384.65836 -384.102491) (xy 384.648202 -384.102864) (xy 383.931922 -384.102864)
			(xy 383.921797 -384.102356) (xy 383.903077 -384.094636) (xy 383.88872 -384.080356) (xy 383.8809 -384.061678)
			(xy 383.88036 -384.051556) (xy 383.88036 -383.893568) (xy 383.879952 -383.884381) (xy 383.873435 -383.867197)
			(xy 383.86766 -383.86004) (xy 383.845887 -383.834375) (xy 383.807937 -383.778791) (xy 383.776902 -383.719069)
			(xy 383.753227 -383.656066) (xy 383.737252 -383.590686) (xy 383.729207 -383.523864) (xy 383.729205 -383.45656)
			(xy 383.737248 -383.389738) (xy 383.75322 -383.324357) (xy 383.776892 -383.261353) (xy 383.807924 -383.20163)
			(xy 383.845873 -383.146044) (xy 383.86766 -383.120392) (xy 383.87345 -383.113242) (xy 383.879967 -383.096055)
			(xy 383.88036 -383.086864) (xy 383.88036 -382.593342) (xy 383.879916 -382.584159) (xy 383.873425 -382.566975)
			(xy 383.86766 -382.559814) (xy 383.845862 -382.53417) (xy 383.807912 -382.478583) (xy 383.776878 -382.418858)
			(xy 383.753205 -382.355853) (xy 383.737232 -382.290469) (xy 383.729188 -382.223646) (xy 380.451149 -382.223646)
			(xy 380.451149 -382.223704) (xy 380.443073 -382.290642) (xy 380.427038 -382.356131) (xy 380.403273 -382.419228)
			(xy 380.372122 -382.479024) (xy 380.334032 -382.534657) (xy 380.312168 -382.560322) (xy 380.306375 -382.56747)
			(xy 380.299859 -382.584658) (xy 380.299468 -382.59385) (xy 380.299468 -383.086356) (xy 380.299907 -383.09554)
			(xy 380.306401 -383.112724) (xy 380.312168 -383.119884) (xy 380.334049 -383.145536) (xy 380.372139 -383.201171)
			(xy 380.403291 -383.260969) (xy 380.426928 -383.323727) (xy 381.529033 -383.323727) (xy 381.529037 -383.256419)
			(xy 381.537084 -383.189595) (xy 381.55306 -383.124211) (xy 381.576736 -383.061205) (xy 381.607772 -383.00148)
			(xy 381.645723 -382.945893) (xy 381.667512 -382.92024) (xy 381.673318 -382.913101) (xy 381.679827 -382.895906)
			(xy 381.680212 -382.886712) (xy 381.680212 -382.728724) (xy 381.680641 -382.71857) (xy 381.688431 -382.699816)
			(xy 381.702826 -382.685491) (xy 381.721618 -382.677793) (xy 381.731774 -382.677416) (xy 382.448054 -382.677416)
			(xy 382.458175 -382.677964) (xy 382.47689 -382.685672) (xy 382.491247 -382.699939) (xy 382.499072 -382.718606)
			(xy 382.499616 -382.728724) (xy 382.499616 -382.886712) (xy 382.500017 -382.8959) (xy 382.506537 -382.913085)
			(xy 382.512316 -382.92024) (xy 382.53407 -382.945921) (xy 382.572023 -383.001502) (xy 382.60306 -383.061221)
			(xy 382.626737 -383.124222) (xy 382.642713 -383.189601) (xy 382.650761 -383.256421) (xy 382.650764 -383.323724)
			(xy 382.642723 -383.390545) (xy 382.626753 -383.455926) (xy 382.603082 -383.518929) (xy 382.57205 -383.578652)
			(xy 382.534103 -383.634236) (xy 382.512316 -383.659888) (xy 382.506501 -383.667021) (xy 382.499997 -383.684221)
			(xy 382.499616 -383.693416) (xy 382.499616 -384.186684) (xy 382.50003 -384.195871) (xy 382.506541 -384.213055)
			(xy 382.512316 -384.220212) (xy 382.53414 -384.245834) (xy 382.572091 -384.301424) (xy 382.603125 -384.361151)
			(xy 382.626798 -384.42416) (xy 382.64277 -384.489546) (xy 382.650812 -384.556373) (xy 382.650808 -384.623681)
			(xy 382.64276 -384.690507) (xy 382.626782 -384.755892) (xy 382.603103 -384.818898) (xy 382.572063 -384.878622)
			(xy 382.534107 -384.934208) (xy 382.512316 -384.95986) (xy 382.506513 -384.967001) (xy 382.500002 -384.984195)
			(xy 382.499616 -384.993388) (xy 382.499616 -385.151376) (xy 382.499159 -385.161527) (xy 382.491375 -385.180275)
			(xy 382.476989 -385.194599) (xy 382.458206 -385.202303) (xy 382.448054 -385.202684) (xy 381.731774 -385.202684)
			(xy 381.721649 -385.202196) (xy 381.702931 -385.194464) (xy 381.688577 -385.180179) (xy 381.680754 -385.161499)
			(xy 381.680212 -385.151376) (xy 381.680212 -384.993388) (xy 381.679805 -384.984201) (xy 381.673289 -384.967016)
			(xy 381.667512 -384.95986) (xy 381.64576 -384.934178) (xy 381.607812 -384.878596) (xy 381.576779 -384.818876)
			(xy 381.553105 -384.755875) (xy 381.537131 -384.690497) (xy 381.529084 -384.623678) (xy 381.529081 -384.556376)
			(xy 381.537121 -384.489557) (xy 381.553089 -384.424177) (xy 381.576757 -384.361174) (xy 381.607784 -384.301451)
			(xy 381.645727 -384.245864) (xy 381.667512 -384.220212) (xy 381.67333 -384.213082) (xy 381.679831 -384.19588)
			(xy 381.680212 -384.186684) (xy 381.680212 -383.693416) (xy 381.679791 -383.68423) (xy 381.673285 -383.667046)
			(xy 381.667512 -383.659888) (xy 381.64569 -383.634265) (xy 381.607744 -383.578673) (xy 381.576714 -383.518946)
			(xy 381.553044 -383.455937) (xy 381.537074 -383.390552) (xy 381.529033 -383.323727) (xy 380.426928 -383.323727)
			(xy 380.427056 -383.324068) (xy 380.443091 -383.389559) (xy 380.451166 -383.456499) (xy 380.451165 -383.523925)
			(xy 380.443087 -383.590865) (xy 380.427049 -383.656355) (xy 380.403281 -383.719453) (xy 380.372127 -383.779249)
			(xy 380.334034 -383.834883) (xy 380.312168 -383.860548) (xy 380.306364 -383.867688) (xy 380.299855 -383.884883)
			(xy 380.299468 -383.894076) (xy 380.299468 -384.051556) (xy 380.299047 -384.06168) (xy 380.291308 -384.080388)
			(xy 380.276992 -384.094705) (xy 380.258284 -384.102446) (xy 380.24816 -384.102864) (xy 379.53188 -384.102864)
			(xy 379.521752 -384.1025) (xy 379.503041 -384.094738) (xy 379.488726 -384.080405) (xy 379.480988 -384.061685)
			(xy 379.480572 -384.051556) (xy 379.480572 -383.894076) (xy 379.48018 -383.884887) (xy 379.473654 -383.867702)
			(xy 379.467872 -383.860548) (xy 379.446025 -383.834869) (xy 379.407937 -383.779236) (xy 379.376788 -383.719441)
			(xy 379.353024 -383.656346) (xy 379.336988 -383.590859) (xy 379.328911 -383.523923) (xy 379.32891 -383.456501)
			(xy 379.336984 -383.389564) (xy 379.353017 -383.324077) (xy 379.376778 -383.260981) (xy 379.407925 -383.201185)
			(xy 379.44601 -383.14555) (xy 379.467872 -383.119884) (xy 379.473667 -383.112738) (xy 379.48018 -383.095548)
			(xy 379.480572 -383.086356) (xy 379.480572 -382.59385) (xy 379.480144 -382.584665) (xy 379.473643 -382.56748)
			(xy 379.467872 -382.560322) (xy 379.445999 -382.534664) (xy 379.407913 -382.479028) (xy 379.376764 -382.419231)
			(xy 379.353002 -382.356133) (xy 379.336968 -382.290643) (xy 379.328893 -382.223704) (xy 376.050822 -382.223704)
			(xy 376.042786 -382.290466) (xy 376.026815 -382.355847) (xy 376.003144 -382.418851) (xy 375.972113 -382.478575)
			(xy 375.934167 -382.534162) (xy 375.91238 -382.559814) (xy 375.906593 -382.566966) (xy 375.900073 -382.584151)
			(xy 375.89968 -382.593342) (xy 375.89968 -383.086864) (xy 375.900112 -383.096049) (xy 375.906611 -383.113233)
			(xy 375.91238 -383.120392) (xy 375.934183 -383.146031) (xy 375.97213 -383.20162) (xy 376.003162 -383.261346)
			(xy 376.02662 -383.323786) (xy 377.128714 -383.323786) (xy 377.128717 -383.256359) (xy 377.136797 -383.189418)
			(xy 377.152837 -383.123927) (xy 377.176606 -383.060828) (xy 377.207762 -383.001031) (xy 377.245857 -382.945397)
			(xy 377.267724 -382.919732) (xy 377.273535 -382.912597) (xy 377.28004 -382.895399) (xy 377.280424 -382.886204)
			(xy 377.280424 -382.728724) (xy 377.280836 -382.7186) (xy 377.288581 -382.699892) (xy 377.302899 -382.685576)
			(xy 377.321608 -382.677834) (xy 377.331732 -382.677416) (xy 378.048012 -382.677416) (xy 378.058137 -382.677806)
			(xy 378.076844 -382.685561) (xy 378.091159 -382.699886) (xy 378.098901 -382.718598) (xy 378.09932 -382.728724)
			(xy 378.09932 -382.886204) (xy 378.099724 -382.895392) (xy 378.106241 -382.912576) (xy 378.11202 -382.919732)
			(xy 378.133848 -382.945427) (xy 378.171936 -383.001058) (xy 378.203088 -383.06085) (xy 378.226853 -383.123943)
			(xy 378.24289 -383.189428) (xy 378.250969 -383.256363) (xy 378.250972 -383.323783) (xy 378.2429 -383.390719)
			(xy 378.226869 -383.456205) (xy 378.20311 -383.519301) (xy 378.171964 -383.579096) (xy 378.133881 -383.63473)
			(xy 378.11202 -383.660396) (xy 378.106245 -383.667557) (xy 378.099717 -383.684735) (xy 378.09932 -383.693924)
			(xy 378.09932 -384.186176) (xy 378.099737 -384.195363) (xy 378.106245 -384.212547) (xy 378.11202 -384.219704)
			(xy 378.133919 -384.24534) (xy 378.172005 -384.30098) (xy 378.203153 -384.36078) (xy 378.226914 -384.423881)
			(xy 378.242947 -384.489373) (xy 378.251019 -384.556314) (xy 378.251016 -384.62374) (xy 378.242937 -384.69068)
			(xy 378.226898 -384.756171) (xy 378.203131 -384.81927) (xy 378.171977 -384.879067) (xy 378.133885 -384.934702)
			(xy 378.11202 -384.960368) (xy 378.106214 -384.967507) (xy 378.099704 -384.984702) (xy 378.09932 -384.993896)
			(xy 378.09932 -385.151376) (xy 378.098865 -385.161494) (xy 378.091128 -385.180194) (xy 378.076824 -385.194508)
			(xy 378.05813 -385.202258) (xy 378.048012 -385.202684) (xy 377.331732 -385.202684) (xy 377.32161 -385.202258)
			(xy 377.302903 -385.194517) (xy 377.288587 -385.180203) (xy 377.280844 -385.161498) (xy 377.280424 -385.151376)
			(xy 377.280424 -384.993896) (xy 377.280011 -384.984709) (xy 377.273499 -384.967525) (xy 377.267724 -384.960368)
			(xy 377.245895 -384.934674) (xy 377.207803 -384.879044) (xy 377.17665 -384.819252) (xy 377.152882 -384.756159)
			(xy 377.136844 -384.690673) (xy 377.128765 -384.623738) (xy 377.128761 -384.556316) (xy 377.136834 -384.48938)
			(xy 377.152866 -384.423893) (xy 377.176627 -384.360797) (xy 377.207775 -384.301002) (xy 377.245861 -384.245369)
			(xy 377.267724 -384.219704) (xy 377.273504 -384.212547) (xy 377.280028 -384.195365) (xy 377.280424 -384.186176)
			(xy 377.280424 -383.693924) (xy 377.279997 -383.684739) (xy 377.273494 -383.667555) (xy 377.267724 -383.660396)
			(xy 377.245824 -383.63476) (xy 377.207735 -383.579122) (xy 377.176584 -383.519322) (xy 377.152821 -383.456221)
			(xy 377.136787 -383.390728) (xy 377.128714 -383.323786) (xy 376.02662 -383.323786) (xy 376.026833 -383.324352)
			(xy 376.042804 -383.389735) (xy 376.050846 -383.456559) (xy 376.050845 -383.523865) (xy 376.0428 -383.590688)
			(xy 376.026826 -383.656071) (xy 376.003152 -383.719076) (xy 375.972118 -383.778801) (xy 375.934168 -383.834388)
			(xy 375.91238 -383.86004) (xy 375.906582 -383.867184) (xy 375.900069 -383.884375) (xy 375.89968 -383.893568)
			(xy 375.89968 -384.051556) (xy 375.899242 -384.06171) (xy 375.891457 -384.080465) (xy 375.877065 -384.094791)
			(xy 375.858274 -384.102488) (xy 375.848118 -384.102864) (xy 375.131838 -384.102864) (xy 375.121714 -384.102342)
			(xy 375.102995 -384.094628) (xy 375.088637 -384.080352) (xy 375.080816 -384.061677) (xy 375.080276 -384.051556)
			(xy 375.080276 -383.893568) (xy 375.079886 -383.884379) (xy 375.073359 -383.867194) (xy 375.067576 -383.86004)
			(xy 375.045803 -383.834375) (xy 375.007851 -383.778792) (xy 374.976815 -383.71907) (xy 374.95314 -383.656067)
			(xy 374.937165 -383.590686) (xy 374.929119 -383.523864) (xy 374.929117 -383.45656) (xy 374.93716 -383.389738)
			(xy 374.953133 -383.324356) (xy 374.976805 -383.261352) (xy 375.007839 -383.201629) (xy 375.045788 -383.146044)
			(xy 375.067576 -383.120392) (xy 375.073356 -383.113235) (xy 375.079881 -383.096054) (xy 375.080276 -383.086864)
			(xy 375.080276 -382.593342) (xy 375.079851 -382.584156) (xy 375.073348 -382.566971) (xy 375.067576 -382.559814)
			(xy 375.045777 -382.53417) (xy 375.007826 -382.478584) (xy 374.976792 -382.418859) (xy 374.953118 -382.355853)
			(xy 374.937144 -382.29047) (xy 374.9291 -382.223646) (xy 345.250798 -382.223646) (xy 345.242755 -382.290467)
			(xy 345.226782 -382.355849) (xy 345.20311 -382.418853) (xy 345.172077 -382.478576) (xy 345.134128 -382.534162)
			(xy 345.11234 -382.559814) (xy 345.106548 -382.566962) (xy 345.100032 -382.584151) (xy 345.09964 -382.593342)
			(xy 345.09964 -383.086864) (xy 345.100081 -383.096048) (xy 345.106575 -383.113232) (xy 345.11234 -383.120392)
			(xy 345.134144 -383.146031) (xy 345.172094 -383.201619) (xy 345.203127 -383.261344) (xy 345.226566 -383.323727)
			(xy 346.329188 -383.323727) (xy 346.329192 -383.256419) (xy 346.33724 -383.189593) (xy 346.353218 -383.124208)
			(xy 346.376897 -383.061202) (xy 346.407937 -383.001478) (xy 346.445893 -382.945892) (xy 346.467684 -382.92024)
			(xy 346.473487 -382.913099) (xy 346.479998 -382.895905) (xy 346.480384 -382.886712) (xy 346.480384 -382.728724)
			(xy 346.480841 -382.718573) (xy 346.488625 -382.699825) (xy 346.503011 -382.685501) (xy 346.521794 -382.677797)
			(xy 346.531946 -382.677416) (xy 347.248226 -382.677416) (xy 347.258351 -382.677904) (xy 347.277069 -382.685636)
			(xy 347.291423 -382.699921) (xy 347.299246 -382.718601) (xy 347.299788 -382.728724) (xy 347.299788 -382.886712)
			(xy 347.300195 -382.895899) (xy 347.306711 -382.913084) (xy 347.312488 -382.92024) (xy 347.33424 -382.945922)
			(xy 347.372188 -383.001504) (xy 347.403221 -383.061224) (xy 347.426895 -383.124225) (xy 347.442869 -383.189603)
			(xy 347.450916 -383.256422) (xy 347.450919 -383.323724) (xy 347.442879 -383.390543) (xy 347.426911 -383.455923)
			(xy 347.403243 -383.518926) (xy 347.372216 -383.578649) (xy 347.334273 -383.634236) (xy 347.312488 -383.659888)
			(xy 347.30667 -383.667018) (xy 347.300169 -383.68422) (xy 347.299788 -383.693416) (xy 347.299788 -384.186684)
			(xy 347.300209 -384.19587) (xy 347.306715 -384.213054) (xy 347.312488 -384.220212) (xy 347.33431 -384.245835)
			(xy 347.372256 -384.301427) (xy 347.403286 -384.361154) (xy 347.426956 -384.424163) (xy 347.442926 -384.489548)
			(xy 347.450967 -384.556373) (xy 347.450963 -384.623681) (xy 347.442916 -384.690505) (xy 347.42694 -384.755889)
			(xy 347.403264 -384.818895) (xy 347.372228 -384.87862) (xy 347.334277 -384.934207) (xy 347.312488 -384.95986)
			(xy 347.306682 -384.966999) (xy 347.300173 -384.984194) (xy 347.299788 -384.993388) (xy 347.299788 -385.151376)
			(xy 347.299359 -385.16153) (xy 347.291569 -385.180284) (xy 347.277174 -385.194609) (xy 347.258382 -385.202307)
			(xy 347.248226 -385.202684) (xy 346.531946 -385.202684) (xy 346.521825 -385.202136) (xy 346.50311 -385.194428)
			(xy 346.488753 -385.180161) (xy 346.480928 -385.161494) (xy 346.480384 -385.151376) (xy 346.480384 -384.993388)
			(xy 346.479983 -384.9842) (xy 346.473463 -384.967015) (xy 346.467684 -384.95986) (xy 346.44593 -384.934179)
			(xy 346.407977 -384.878598) (xy 346.37694 -384.818879) (xy 346.353263 -384.755878) (xy 346.337287 -384.690499)
			(xy 346.329239 -384.623679) (xy 346.329236 -384.556376) (xy 346.337277 -384.489555) (xy 346.353247 -384.424174)
			(xy 346.376918 -384.361171) (xy 346.40795 -384.301448) (xy 346.445897 -384.245864) (xy 346.467684 -384.220212)
			(xy 346.473499 -384.213079) (xy 346.480003 -384.195879) (xy 346.480384 -384.186684) (xy 346.480384 -383.693416)
			(xy 346.47997 -383.684229) (xy 346.473459 -383.667045) (xy 346.467684 -383.659888) (xy 346.44586 -383.634266)
			(xy 346.407909 -383.578676) (xy 346.376875 -383.518949) (xy 346.353202 -383.45594) (xy 346.33723 -383.390554)
			(xy 346.329188 -383.323727) (xy 345.226566 -383.323727) (xy 345.2268 -383.32435) (xy 345.242773 -383.389734)
			(xy 345.250816 -383.456559) (xy 345.250814 -383.523865) (xy 345.242768 -383.590689) (xy 345.226793 -383.656073)
			(xy 345.203118 -383.719078) (xy 345.172081 -383.778802) (xy 345.134129 -383.834388) (xy 345.11234 -383.86004)
			(xy 345.106537 -383.86718) (xy 345.100028 -383.884375) (xy 345.09964 -383.893568) (xy 345.09964 -384.051556)
			(xy 345.099143 -384.061702) (xy 345.09137 -384.080446) (xy 345.076996 -384.094769) (xy 345.058226 -384.102478)
			(xy 345.048078 -384.102864) (xy 344.331798 -384.102864) (xy 344.321672 -384.102375) (xy 344.302951 -384.094647)
			(xy 344.288595 -384.080362) (xy 344.280775 -384.06168) (xy 344.280236 -384.051556) (xy 344.280236 -383.893568)
			(xy 344.279833 -383.88438) (xy 344.273313 -383.867196) (xy 344.267536 -383.86004) (xy 344.245764 -383.834375)
			(xy 344.207815 -383.77879) (xy 344.176781 -383.719068) (xy 344.153108 -383.656066) (xy 344.137134 -383.590685)
			(xy 344.129089 -383.523864) (xy 344.129087 -383.45656) (xy 344.13713 -383.389739) (xy 344.153101 -383.324358)
			(xy 344.176772 -383.261354) (xy 344.207803 -383.201631) (xy 344.24575 -383.146044) (xy 344.267536 -383.120392)
			(xy 344.273323 -383.11324) (xy 344.279843 -383.096055) (xy 344.280236 -383.086864) (xy 344.280236 -382.593342)
			(xy 344.279797 -382.584158) (xy 344.273303 -382.566974) (xy 344.267536 -382.559814) (xy 344.245738 -382.53417)
			(xy 344.20779 -382.478582) (xy 344.176757 -382.418858) (xy 344.153085 -382.355852) (xy 344.137113 -382.290469)
			(xy 344.12907 -382.223645) (xy 340.851007 -382.223645) (xy 340.842964 -382.290467) (xy 340.826992 -382.355848)
			(xy 340.80332 -382.418853) (xy 340.772287 -382.478576) (xy 340.734339 -382.534162) (xy 340.712552 -382.559814)
			(xy 340.706761 -382.566963) (xy 340.700244 -382.584151) (xy 340.699852 -382.593342) (xy 340.699852 -383.086864)
			(xy 340.70029 -383.096048) (xy 340.706785 -383.113232) (xy 340.712552 -383.120392) (xy 340.734356 -383.146031)
			(xy 340.772305 -383.201619) (xy 340.803338 -383.261344) (xy 340.826798 -383.323786) (xy 341.928893 -383.323786)
			(xy 341.928896 -383.25636) (xy 341.936975 -383.189419) (xy 341.953015 -383.123928) (xy 341.976783 -383.06083)
			(xy 342.007937 -383.001032) (xy 342.04603 -382.945397) (xy 342.067896 -382.919732) (xy 342.073703 -382.912594)
			(xy 342.080212 -382.895398) (xy 342.080596 -382.886204) (xy 342.080596 -382.728724) (xy 342.081035 -382.718604)
			(xy 342.088775 -382.699901) (xy 342.103084 -382.685586) (xy 342.121784 -382.677839) (xy 342.131904 -382.677416)
			(xy 342.848184 -382.677416) (xy 342.858307 -382.677829) (xy 342.877014 -382.685575) (xy 342.891329 -382.699893)
			(xy 342.899072 -382.7186) (xy 342.899492 -382.728724) (xy 342.899492 -382.886204) (xy 342.899902 -382.895391)
			(xy 342.906416 -382.912575) (xy 342.912192 -382.919732) (xy 342.934021 -382.945426) (xy 342.972111 -383.001056)
			(xy 343.003264 -383.060849) (xy 343.02703 -383.123942) (xy 343.043069 -383.189427) (xy 343.051148 -383.256362)
			(xy 343.051151 -383.323783) (xy 343.043078 -383.390719) (xy 343.027046 -383.456207) (xy 343.003286 -383.519302)
			(xy 342.972139 -383.579097) (xy 342.934054 -383.634731) (xy 342.912192 -383.660396) (xy 342.906414 -383.667554)
			(xy 342.899888 -383.684735) (xy 342.899492 -383.693924) (xy 342.899492 -384.186176) (xy 342.899916 -384.195362)
			(xy 342.90642 -384.212546) (xy 342.912192 -384.219704) (xy 342.934092 -384.24534) (xy 342.97218 -384.300978)
			(xy 343.003329 -384.360779) (xy 343.027092 -384.423879) (xy 343.043125 -384.489372) (xy 343.051198 -384.556314)
			(xy 343.051195 -384.62374) (xy 343.043115 -384.690681) (xy 343.027076 -384.756172) (xy 343.003307 -384.819271)
			(xy 342.972152 -384.879068) (xy 342.934058 -384.934703) (xy 342.912192 -384.960368) (xy 342.906383 -384.967504)
			(xy 342.899876 -384.984702) (xy 342.899492 -384.993896) (xy 342.899492 -385.151376) (xy 342.899064 -385.161498)
			(xy 342.891323 -385.180203) (xy 342.877009 -385.194518) (xy 342.858306 -385.202263) (xy 342.848184 -385.202684)
			(xy 342.131904 -385.202684) (xy 342.12178 -385.20228) (xy 342.103073 -385.194531) (xy 342.088758 -385.18021)
			(xy 342.081016 -385.1615) (xy 342.080596 -385.151376) (xy 342.080596 -384.993896) (xy 342.080189 -384.984709)
			(xy 342.073673 -384.967524) (xy 342.067896 -384.960368) (xy 342.046068 -384.934674) (xy 342.007978 -384.879043)
			(xy 341.976826 -384.819251) (xy 341.95306 -384.756158) (xy 341.937022 -384.690672) (xy 341.928943 -384.623737)
			(xy 341.92894 -384.556317) (xy 341.937012 -384.489381) (xy 341.953044 -384.423894) (xy 341.976804 -384.360799)
			(xy 342.00795 -384.301003) (xy 342.046034 -384.245369) (xy 342.067896 -384.219704) (xy 342.073673 -384.212545)
			(xy 342.080199 -384.195365) (xy 342.080596 -384.186176) (xy 342.080596 -383.693924) (xy 342.080175 -383.684738)
			(xy 342.073669 -383.667553) (xy 342.067896 -383.660396) (xy 342.045997 -383.63476) (xy 342.007909 -383.579121)
			(xy 341.976761 -383.519321) (xy 341.952999 -383.45622) (xy 341.936966 -383.390728) (xy 341.928893 -383.323786)
			(xy 340.826798 -383.323786) (xy 340.82701 -383.324351) (xy 340.842982 -383.389735) (xy 340.851025 -383.456559)
			(xy 340.851024 -383.523865) (xy 340.842978 -383.590689) (xy 340.827003 -383.656072) (xy 340.803328 -383.719078)
			(xy 340.772292 -383.778802) (xy 340.734341 -383.834388) (xy 340.712552 -383.86004) (xy 340.70675 -383.867181)
			(xy 340.70024 -383.884375) (xy 340.699852 -383.893568) (xy 340.699852 -384.051556) (xy 340.699343 -384.061701)
			(xy 340.691572 -384.080442) (xy 340.677202 -384.094765) (xy 340.658436 -384.102476) (xy 340.64829 -384.102864)
			(xy 339.93201 -384.102864) (xy 339.921884 -384.102365) (xy 339.903164 -384.094642) (xy 339.888808 -384.080359)
			(xy 339.880987 -384.061679) (xy 339.880448 -384.051556) (xy 339.880448 -383.893568) (xy 339.880042 -383.884381)
			(xy 339.873524 -383.867197) (xy 339.867748 -383.86004) (xy 339.845976 -383.834375) (xy 339.808026 -383.778791)
			(xy 339.776992 -383.719069) (xy 339.753318 -383.656066) (xy 339.737343 -383.590685) (xy 339.729298 -383.523864)
			(xy 339.729296 -383.45656) (xy 339.737339 -383.389738) (xy 339.75331 -383.324357) (xy 339.776982 -383.261353)
			(xy 339.808014 -383.20163) (xy 339.845961 -383.146044) (xy 339.867748 -383.120392) (xy 339.873536 -383.113241)
			(xy 339.880055 -383.096055) (xy 339.880448 -383.086864) (xy 339.880448 -382.593342) (xy 339.880007 -382.584158)
			(xy 339.873513 -382.566974) (xy 339.867748 -382.559814) (xy 339.84595 -382.53417) (xy 339.808001 -382.478583)
			(xy 339.776968 -382.418858) (xy 339.753295 -382.355852) (xy 339.737322 -382.290469) (xy 339.729279 -382.223645)
			(xy 336.45124 -382.223645) (xy 336.45124 -382.223704) (xy 336.443164 -382.290643) (xy 336.427128 -382.356132)
			(xy 336.403363 -382.419228) (xy 336.372211 -382.479024) (xy 336.334121 -382.534658) (xy 336.312256 -382.560322)
			(xy 336.306462 -382.567469) (xy 336.299947 -382.584658) (xy 336.299556 -382.59385) (xy 336.299556 -383.086356)
			(xy 336.299997 -383.09554) (xy 336.306491 -383.112724) (xy 336.312256 -383.119884) (xy 336.334137 -383.145536)
			(xy 336.372228 -383.201171) (xy 336.403381 -383.260969) (xy 336.427018 -383.323726) (xy 337.529124 -383.323726)
			(xy 337.529128 -383.256419) (xy 337.537175 -383.189595) (xy 337.55315 -383.124211) (xy 337.576825 -383.061205)
			(xy 337.607861 -383.001481) (xy 337.645811 -382.945893) (xy 337.6676 -382.92024) (xy 337.673405 -382.9131)
			(xy 337.679914 -382.895906) (xy 337.6803 -382.886712) (xy 337.6803 -382.728724) (xy 337.680741 -382.718571)
			(xy 337.688529 -382.699819) (xy 337.70292 -382.685495) (xy 337.721708 -382.677795) (xy 337.731862 -382.677416)
			(xy 338.448142 -382.677416) (xy 338.458268 -382.677891) (xy 338.476986 -382.685629) (xy 338.49134 -382.699918)
			(xy 338.499162 -382.7186) (xy 338.499704 -382.728724) (xy 338.499704 -382.886712) (xy 338.500108 -382.8959)
			(xy 338.506626 -382.913084) (xy 338.512404 -382.92024) (xy 338.534155 -382.945922) (xy 338.572102 -383.001505)
			(xy 338.603135 -383.061225) (xy 338.626808 -383.124225) (xy 338.642782 -383.189604) (xy 338.650828 -383.256422)
			(xy 338.650831 -383.323724) (xy 338.642791 -383.390543) (xy 338.626824 -383.455923) (xy 338.603157 -383.518926)
			(xy 338.57213 -383.578648) (xy 338.534188 -383.634235) (xy 338.512404 -383.659888) (xy 338.506588 -383.66702)
			(xy 338.500085 -383.68422) (xy 338.499704 -383.693416) (xy 338.499704 -384.186684) (xy 338.500121 -384.19587)
			(xy 338.50663 -384.213055) (xy 338.512404 -384.220212) (xy 338.534226 -384.245836) (xy 338.572171 -384.301427)
			(xy 338.6032 -384.361155) (xy 338.626869 -384.424163) (xy 338.642838 -384.489548) (xy 338.650879 -384.556374)
			(xy 338.650875 -384.623681) (xy 338.642828 -384.690505) (xy 338.626853 -384.755889) (xy 338.603178 -384.818894)
			(xy 338.572143 -384.878619) (xy 338.534193 -384.934207) (xy 338.512404 -384.95986) (xy 338.5066 -384.967)
			(xy 338.50009 -384.984194) (xy 338.499704 -384.993388) (xy 338.499704 -385.151376) (xy 338.499259 -385.161528)
			(xy 338.491472 -385.180279) (xy 338.477082 -385.194603) (xy 338.458296 -385.202305) (xy 338.448142 -385.202684)
			(xy 337.731862 -385.202684) (xy 337.721736 -385.202205) (xy 337.703018 -385.194469) (xy 337.688664 -385.180181)
			(xy 337.680842 -385.1615) (xy 337.6803 -385.151376) (xy 337.6803 -384.993388) (xy 337.679895 -384.9842)
			(xy 337.673378 -384.967016) (xy 337.6676 -384.95986) (xy 337.645849 -384.934178) (xy 337.607901 -384.878595)
			(xy 337.576869 -384.818875) (xy 337.553196 -384.755875) (xy 337.537221 -384.690497) (xy 337.529175 -384.623678)
			(xy 337.529172 -384.556376) (xy 337.537212 -384.489557) (xy 337.55318 -384.424177) (xy 337.576847 -384.361174)
			(xy 337.607874 -384.301451) (xy 337.645816 -384.245865) (xy 337.6676 -384.220212) (xy 337.673416 -384.213081)
			(xy 337.679919 -384.19588) (xy 337.6803 -384.186684) (xy 337.6803 -383.693416) (xy 337.679882 -383.68423)
			(xy 337.673374 -383.667045) (xy 337.6676 -383.659888) (xy 337.645778 -383.634264) (xy 337.607833 -383.578673)
			(xy 337.576803 -383.518945) (xy 337.553134 -383.455937) (xy 337.537165 -383.390552) (xy 337.529124 -383.323726)
			(xy 336.427018 -383.323726) (xy 336.427146 -383.324067) (xy 336.443182 -383.389559) (xy 336.451257 -383.456499)
			(xy 336.451256 -383.523925) (xy 336.443177 -383.590865) (xy 336.427139 -383.656356) (xy 336.403371 -383.719453)
			(xy 336.372216 -383.77925) (xy 336.334122 -383.834883) (xy 336.312256 -383.860548) (xy 336.306451 -383.867687)
			(xy 336.299943 -383.884882) (xy 336.299556 -383.894076) (xy 336.299556 -384.051556) (xy 336.29898 -384.061655)
			(xy 336.291267 -384.080321) (xy 336.276999 -384.094616) (xy 336.258346 -384.102362) (xy 336.248248 -384.102864)
			(xy 335.531968 -384.102864) (xy 335.521839 -384.102509) (xy 335.503128 -384.094744) (xy 335.488813 -384.080408)
			(xy 335.481076 -384.061686) (xy 335.48066 -384.051556) (xy 335.48066 -383.894076) (xy 335.480248 -383.884889)
			(xy 335.473734 -383.867706) (xy 335.46796 -383.860548) (xy 335.446113 -383.834869) (xy 335.408027 -383.779236)
			(xy 335.376877 -383.719441) (xy 335.353114 -383.656346) (xy 335.337079 -383.590859) (xy 335.329002 -383.523923)
			(xy 335.329001 -383.456501) (xy 335.337074 -383.389565) (xy 335.353107 -383.324077) (xy 335.376868 -383.260981)
			(xy 335.408014 -383.201185) (xy 335.446098 -383.14555) (xy 335.46796 -383.119884) (xy 335.473753 -383.112737)
			(xy 335.480268 -383.095548) (xy 335.48066 -383.086356) (xy 335.48066 -382.59385) (xy 335.480213 -382.584667)
			(xy 335.473723 -382.567483) (xy 335.46796 -382.560322) (xy 335.446088 -382.534664) (xy 335.408002 -382.479028)
			(xy 335.376854 -382.41923) (xy 335.353092 -382.356132) (xy 335.337058 -382.290643) (xy 335.328984 -382.223704)
			(xy 332.050913 -382.223704) (xy 332.042877 -382.290466) (xy 332.026905 -382.355848) (xy 332.003234 -382.418852)
			(xy 331.972202 -382.478575) (xy 331.934255 -382.534162) (xy 331.912468 -382.559814) (xy 331.906679 -382.566964)
			(xy 331.90016 -382.584151) (xy 331.899768 -382.593342) (xy 331.899768 -383.086864) (xy 331.900203 -383.096048)
			(xy 331.9067 -383.113233) (xy 331.912468 -383.120392) (xy 331.934271 -383.146031) (xy 331.972219 -383.20162)
			(xy 332.003251 -383.261345) (xy 332.026711 -383.323786) (xy 333.128805 -383.323786) (xy 333.128808 -383.25636)
			(xy 333.136888 -383.189419) (xy 333.152927 -383.123927) (xy 333.176696 -383.060829) (xy 333.207852 -383.001032)
			(xy 333.245945 -382.945397) (xy 333.267812 -382.919732) (xy 333.273621 -382.912596) (xy 333.280128 -382.895398)
			(xy 333.280512 -382.886204) (xy 333.280512 -382.728724) (xy 333.280936 -382.718602) (xy 333.288678 -382.699896)
			(xy 333.302993 -382.685581) (xy 333.321698 -382.677837) (xy 333.33182 -382.677416) (xy 334.0481 -382.677416)
			(xy 334.058224 -382.677816) (xy 334.076931 -382.685568) (xy 334.091246 -382.699889) (xy 334.098988 -382.718599)
			(xy 334.099408 -382.728724) (xy 334.099408 -382.886204) (xy 334.099815 -382.895392) (xy 334.106331 -382.912576)
			(xy 334.112108 -382.919732) (xy 334.133936 -382.945427) (xy 334.172026 -383.001057) (xy 334.203177 -383.060849)
			(xy 334.226943 -383.123942) (xy 334.242981 -383.189428) (xy 334.25106 -383.256363) (xy 334.251063 -383.323783)
			(xy 334.242991 -383.390719) (xy 334.226959 -383.456206) (xy 334.2032 -383.519301) (xy 334.172053 -383.579096)
			(xy 334.13397 -383.634731) (xy 334.112108 -383.660396) (xy 334.106332 -383.667556) (xy 334.099805 -383.684735)
			(xy 334.099408 -383.693924) (xy 334.099408 -384.186176) (xy 334.099828 -384.195362) (xy 334.106335 -384.212547)
			(xy 334.112108 -384.219704) (xy 334.134007 -384.24534) (xy 334.172094 -384.300979) (xy 334.203243 -384.360779)
			(xy 334.227005 -384.42388) (xy 334.243037 -384.489373) (xy 334.25111 -384.556314) (xy 334.251107 -384.62374)
			(xy 334.243028 -384.690681) (xy 334.226989 -384.756172) (xy 334.203221 -384.81927) (xy 334.172066 -384.879067)
			(xy 334.133974 -384.934703) (xy 334.112108 -384.960368) (xy 334.106301 -384.967506) (xy 334.099792 -384.984702)
			(xy 334.099408 -384.993896) (xy 334.099408 -385.151376) (xy 334.098965 -385.161496) (xy 334.091226 -385.180198)
			(xy 334.076918 -385.194512) (xy 334.05822 -385.20226) (xy 334.0481 -385.202684) (xy 333.33182 -385.202684)
			(xy 333.321697 -385.202267) (xy 333.302991 -385.194523) (xy 333.288675 -385.180206) (xy 333.280932 -385.161499)
			(xy 333.280512 -385.151376) (xy 333.280512 -384.993896) (xy 333.280101 -384.984709) (xy 333.273587 -384.967525)
			(xy 333.267812 -384.960368) (xy 333.245983 -384.934674) (xy 333.207892 -384.879044) (xy 333.176739 -384.819252)
			(xy 333.152973 -384.756158) (xy 333.136934 -384.690673) (xy 333.128855 -384.623738) (xy 333.128852 -384.556316)
			(xy 333.136925 -384.48938) (xy 333.152957 -384.423893) (xy 333.176717 -384.360798) (xy 333.207865 -384.301003)
			(xy 333.24595 -384.245369) (xy 333.267812 -384.219704) (xy 333.273591 -384.212546) (xy 333.280116 -384.195365)
			(xy 333.280512 -384.186176) (xy 333.280512 -383.693924) (xy 333.280088 -383.684738) (xy 333.273583 -383.667554)
			(xy 333.267812 -383.660396) (xy 333.245912 -383.63476) (xy 333.207824 -383.579122) (xy 333.176674 -383.519322)
			(xy 333.152911 -383.456221) (xy 333.136878 -383.390728) (xy 333.128805 -383.323786) (xy 332.026711 -383.323786)
			(xy 332.026923 -383.324351) (xy 332.042895 -383.389735) (xy 332.050937 -383.456559) (xy 332.050936 -383.523865)
			(xy 332.04289 -383.590689) (xy 332.026916 -383.656072) (xy 332.003242 -383.719077) (xy 331.972207 -383.778801)
			(xy 331.934257 -383.834388) (xy 331.912468 -383.86004) (xy 331.906668 -383.867183) (xy 331.900156 -383.884375)
			(xy 331.899768 -383.893568) (xy 331.899768 -384.051556) (xy 331.899342 -384.061711) (xy 331.891555 -384.080469)
			(xy 331.877159 -384.094795) (xy 331.858363 -384.10249) (xy 331.848206 -384.102864) (xy 331.131926 -384.102864)
			(xy 331.121801 -384.102352) (xy 331.103082 -384.094634) (xy 331.088724 -384.080355) (xy 331.080904 -384.061678)
			(xy 331.080364 -384.051556) (xy 331.080364 -383.893568) (xy 331.079955 -383.884381) (xy 331.073439 -383.867198)
			(xy 331.067664 -383.86004) (xy 331.045891 -383.834375) (xy 331.00794 -383.778791) (xy 330.976905 -383.71907)
			(xy 330.95323 -383.656067) (xy 330.937256 -383.590686) (xy 330.92921 -383.523864) (xy 330.929208 -383.45656)
			(xy 330.937251 -383.389738) (xy 330.953223 -383.324356) (xy 330.976895 -383.261352) (xy 331.007928 -383.20163)
			(xy 331.045877 -383.146044) (xy 331.067664 -383.120392) (xy 331.073454 -383.113243) (xy 331.079971 -383.096055)
			(xy 331.080364 -383.086864) (xy 331.080364 -382.593342) (xy 331.079919 -382.584159) (xy 331.073428 -382.566975)
			(xy 331.067664 -382.559814) (xy 331.045866 -382.53417) (xy 331.007916 -382.478583) (xy 330.976881 -382.418859)
			(xy 330.953208 -382.355853) (xy 330.937235 -382.29047) (xy 330.929191 -382.223646) (xy 301.250888 -382.223646)
			(xy 301.250888 -382.223704) (xy 301.242813 -382.290641) (xy 301.226779 -382.356129) (xy 301.203017 -382.419226)
			(xy 301.171869 -382.479022) (xy 301.133783 -382.534656) (xy 301.11192 -382.560322) (xy 301.106134 -382.567475)
			(xy 301.099612 -382.584659) (xy 301.09922 -382.59385) (xy 301.09922 -383.086356) (xy 301.099647 -383.095542)
			(xy 301.106148 -383.112726) (xy 301.11192 -383.119884) (xy 301.133799 -383.145537) (xy 301.171886 -383.201173)
			(xy 301.203035 -383.260972) (xy 301.22669 -383.323786) (xy 302.328775 -383.323786) (xy 302.328778 -383.25636)
			(xy 302.336857 -383.18942) (xy 302.352895 -383.123929) (xy 302.376662 -383.060831) (xy 302.407816 -383.001033)
			(xy 302.445907 -382.945398) (xy 302.467772 -382.919732) (xy 302.473589 -382.912601) (xy 302.480089 -382.895399)
			(xy 302.480472 -382.886204) (xy 302.480472 -382.728724) (xy 302.480935 -382.718606) (xy 302.48867 -382.699909)
			(xy 302.502972 -382.685595) (xy 302.521663 -382.677843) (xy 302.53178 -382.677416) (xy 303.24806 -382.677416)
			(xy 303.258182 -382.677849) (xy 303.276888 -382.685587) (xy 303.291204 -382.699899) (xy 303.298948 -382.718602)
			(xy 303.299368 -382.728724) (xy 303.299368 -382.886204) (xy 303.299783 -382.89539) (xy 303.306294 -382.912575)
			(xy 303.312068 -382.919732) (xy 303.333898 -382.945426) (xy 303.37199 -383.001056) (xy 303.403144 -383.060847)
			(xy 303.426911 -383.123941) (xy 303.44295 -383.189427) (xy 303.451029 -383.256362) (xy 303.451033 -383.323784)
			(xy 303.44296 -383.39072) (xy 303.426927 -383.456208) (xy 303.403166 -383.519303) (xy 303.372017 -383.579098)
			(xy 303.333931 -383.634731) (xy 303.312068 -383.660396) (xy 303.306286 -383.667552) (xy 303.299764 -383.684734)
			(xy 303.299368 -383.693924) (xy 303.299368 -384.186176) (xy 303.299797 -384.195361) (xy 303.306299 -384.212545)
			(xy 303.312068 -384.219704) (xy 303.333968 -384.24534) (xy 303.372058 -384.300978) (xy 303.403209 -384.360778)
			(xy 303.426973 -384.423878) (xy 303.443007 -384.489371) (xy 303.45108 -384.556313) (xy 303.451077 -384.623741)
			(xy 303.442997 -384.690682) (xy 303.426957 -384.756173) (xy 303.403187 -384.819272) (xy 303.37203 -384.879069)
			(xy 303.333935 -384.934703) (xy 303.312068 -384.960368) (xy 303.306256 -384.967502) (xy 303.299751 -384.984701)
			(xy 303.299368 -384.993896) (xy 303.299368 -385.151376) (xy 303.298964 -385.161501) (xy 303.291218 -385.18021)
			(xy 303.276897 -385.194527) (xy 303.258185 -385.202267) (xy 303.24806 -385.202684) (xy 302.53178 -385.202684)
			(xy 302.521654 -385.2023) (xy 302.502947 -385.194542) (xy 302.488633 -385.180216) (xy 302.480891 -385.161502)
			(xy 302.480472 -385.151376) (xy 302.480472 -384.993896) (xy 302.48007 -384.984708) (xy 302.473551 -384.967523)
			(xy 302.467772 -384.960368) (xy 302.445944 -384.934673) (xy 302.407856 -384.879042) (xy 302.376706 -384.81925)
			(xy 302.352941 -384.756157) (xy 302.336904 -384.690672) (xy 302.328825 -384.623737) (xy 302.328822 -384.556317)
			(xy 302.336894 -384.489382) (xy 302.352925 -384.423895) (xy 302.376684 -384.3608) (xy 302.407829 -384.301004)
			(xy 302.445911 -384.24537) (xy 302.467772 -384.219704) (xy 302.473558 -384.212552) (xy 302.480077 -384.195366)
			(xy 302.480472 -384.186176) (xy 302.480472 -383.693924) (xy 302.480057 -383.684737) (xy 302.473547 -383.667552)
			(xy 302.467772 -383.660396) (xy 302.445874 -383.634759) (xy 302.407788 -383.57912) (xy 302.37664 -383.51932)
			(xy 302.352879 -383.456219) (xy 302.336847 -383.390727) (xy 302.328775 -383.323786) (xy 301.22669 -383.323786)
			(xy 301.226797 -383.32407) (xy 301.242831 -383.38956) (xy 301.250905 -383.4565) (xy 301.250904 -383.523924)
			(xy 301.242827 -383.590863) (xy 301.22679 -383.656353) (xy 301.203025 -383.71945) (xy 301.171874 -383.779247)
			(xy 301.133784 -383.834882) (xy 301.11192 -383.860548) (xy 301.106123 -383.867693) (xy 301.099608 -383.884884)
			(xy 301.09922 -383.894076) (xy 301.09922 -384.051556) (xy 301.098748 -384.061673) (xy 301.091018 -384.080372)
			(xy 301.076719 -384.094687) (xy 301.058029 -384.102437) (xy 301.047912 -384.102864) (xy 300.331632 -384.102864)
			(xy 300.321507 -384.102457) (xy 300.302797 -384.094713) (xy 300.28848 -384.080393) (xy 300.28074 -384.061681)
			(xy 300.280324 -384.051556) (xy 300.280324 -383.894076) (xy 300.27992 -383.884888) (xy 300.273402 -383.867704)
			(xy 300.267624 -383.860548) (xy 300.245775 -383.83487) (xy 300.207684 -383.779238) (xy 300.176531 -383.719444)
			(xy 300.152765 -383.656349) (xy 300.136728 -383.590861) (xy 300.12865 -383.523923) (xy 300.128649 -383.456501)
			(xy 300.136724 -383.389563) (xy 300.152758 -383.324074) (xy 300.176522 -383.260978) (xy 300.207672 -383.201183)
			(xy 300.24576 -383.145549) (xy 300.267624 -383.119884) (xy 300.273413 -383.112733) (xy 300.279931 -383.095547)
			(xy 300.280324 -383.086356) (xy 300.280324 -382.59385) (xy 300.279884 -382.584666) (xy 300.273391 -382.567482)
			(xy 300.267624 -382.560322) (xy 300.245749 -382.534665) (xy 300.207659 -382.47903) (xy 300.176508 -382.419233)
			(xy 300.152743 -382.356135) (xy 300.136708 -382.290645) (xy 300.128632 -382.223705) (xy 296.851097 -382.223705)
			(xy 296.843022 -382.290641) (xy 296.826989 -382.356129) (xy 296.803227 -382.419225) (xy 296.77208 -382.479021)
			(xy 296.733994 -382.534656) (xy 296.712132 -382.560322) (xy 296.706335 -382.567467) (xy 296.699823 -382.584658)
			(xy 296.699432 -382.59385) (xy 296.699432 -383.086356) (xy 296.699878 -383.095539) (xy 296.706368 -383.112723)
			(xy 296.712132 -383.119884) (xy 296.734011 -383.145537) (xy 296.772097 -383.201174) (xy 296.803245 -383.260972)
			(xy 296.826877 -383.323727) (xy 297.928982 -383.323727) (xy 297.928985 -383.256419) (xy 297.937033 -383.189593)
			(xy 297.953011 -383.124208) (xy 297.97669 -383.061202) (xy 298.007729 -383.001478) (xy 298.045685 -382.945891)
			(xy 298.067476 -382.92024) (xy 298.073278 -382.913098) (xy 298.07979 -382.895905) (xy 298.080176 -382.886712)
			(xy 298.080176 -382.728724) (xy 298.080641 -382.718574) (xy 298.088424 -382.699827) (xy 298.102807 -382.685504)
			(xy 298.121587 -382.677799) (xy 298.131738 -382.677416) (xy 298.848018 -382.677416) (xy 298.858143 -382.677911)
			(xy 298.87686 -382.68564) (xy 298.891215 -382.699923) (xy 298.899038 -382.718602) (xy 298.89958 -382.728724)
			(xy 298.89958 -382.886712) (xy 298.899989 -382.895899) (xy 298.906504 -382.913083) (xy 298.91228 -382.92024)
			(xy 298.934031 -382.945922) (xy 298.97198 -383.001504) (xy 299.003014 -383.061224) (xy 299.026688 -383.124225)
			(xy 299.042663 -383.189603) (xy 299.050709 -383.256422) (xy 299.050713 -383.323724) (xy 299.042672 -383.390544)
			(xy 299.026704 -383.455924) (xy 299.003036 -383.518926) (xy 298.972008 -383.578649) (xy 298.934065 -383.634235)
			(xy 298.91228 -383.659888) (xy 298.906461 -383.667017) (xy 298.89996 -383.68422) (xy 298.89958 -383.693416)
			(xy 298.89958 -384.186684) (xy 298.900003 -384.19587) (xy 298.906508 -384.213054) (xy 298.91228 -384.220212)
			(xy 298.934103 -384.245835) (xy 298.972049 -384.301426) (xy 299.00308 -384.361154) (xy 299.02675 -384.424162)
			(xy 299.04272 -384.489548) (xy 299.050761 -384.556373) (xy 299.050757 -384.623681) (xy 299.04271 -384.690506)
			(xy 299.026734 -384.75589) (xy 299.003058 -384.818895) (xy 298.972021 -384.87862) (xy 298.934069 -384.934208)
			(xy 298.91228 -384.95986) (xy 298.906473 -384.966998) (xy 298.899965 -384.984194) (xy 298.89958 -384.993388)
			(xy 298.89958 -385.151376) (xy 298.899159 -385.161531) (xy 298.891367 -385.180287) (xy 298.87697 -385.194612)
			(xy 298.858175 -385.202309) (xy 298.848018 -385.202684) (xy 298.131738 -385.202684) (xy 298.121617 -385.202143)
			(xy 298.102901 -385.194432) (xy 298.088544 -385.180162) (xy 298.08072 -385.161494) (xy 298.080176 -385.151376)
			(xy 298.080176 -384.993388) (xy 298.079777 -384.9842) (xy 298.073256 -384.967015) (xy 298.067476 -384.95986)
			(xy 298.045723 -384.934179) (xy 298.00777 -384.878598) (xy 297.976733 -384.818878) (xy 297.953057 -384.755878)
			(xy 297.93708 -384.690499) (xy 297.929033 -384.623679) (xy 297.92903 -384.556376) (xy 297.937071 -384.489555)
			(xy 297.953041 -384.424174) (xy 297.976711 -384.361171) (xy 298.007742 -384.301449) (xy 298.045689 -384.245864)
			(xy 298.067476 -384.220212) (xy 298.07329 -384.213079) (xy 298.079795 -384.195879) (xy 298.080176 -384.186684)
			(xy 298.080176 -383.693416) (xy 298.079764 -383.684229) (xy 298.073252 -383.667044) (xy 298.067476 -383.659888)
			(xy 298.045651 -383.634266) (xy 298.007701 -383.578676) (xy 297.976668 -383.518948) (xy 297.952995 -383.45594)
			(xy 297.937024 -383.390554) (xy 297.928982 -383.323727) (xy 296.826877 -383.323727) (xy 296.827007 -383.324071)
			(xy 296.84304 -383.389561) (xy 296.851114 -383.4565) (xy 296.851113 -383.523924) (xy 296.843036 -383.590863)
			(xy 296.827 -383.656352) (xy 296.803235 -383.71945) (xy 296.772084 -383.779247) (xy 296.733996 -383.834882)
			(xy 296.712132 -383.860548) (xy 296.706324 -383.867685) (xy 296.699818 -383.884882) (xy 296.699432 -383.894076)
			(xy 296.699432 -384.051556) (xy 296.698949 -384.061672) (xy 296.691221 -384.080368) (xy 296.676925 -384.094683)
			(xy 296.658239 -384.102435) (xy 296.648124 -384.102864) (xy 295.931844 -384.102864) (xy 295.92172 -384.102447)
			(xy 295.90301 -384.094707) (xy 295.888693 -384.08039) (xy 295.880953 -384.06168) (xy 295.880536 -384.051556)
			(xy 295.880536 -383.894076) (xy 295.880129 -383.884889) (xy 295.873612 -383.867705) (xy 295.867836 -383.860548)
			(xy 295.845986 -383.83487) (xy 295.807895 -383.779238) (xy 295.776742 -383.719444) (xy 295.752975 -383.656349)
			(xy 295.736937 -383.590861) (xy 295.728859 -383.523924) (xy 295.728858 -383.4565) (xy 295.736933 -383.389563)
			(xy 295.752968 -383.324074) (xy 295.776732 -383.260978) (xy 295.807883 -383.201182) (xy 295.845972 -383.145549)
			(xy 295.867836 -383.119884) (xy 295.873626 -383.112735) (xy 295.880144 -383.095547) (xy 295.880536 -383.086356)
			(xy 295.880536 -382.59385) (xy 295.880094 -382.584666) (xy 295.873601 -382.567482) (xy 295.867836 -382.560322)
			(xy 295.845961 -382.534665) (xy 295.80787 -382.479031) (xy 295.776718 -382.419233) (xy 295.752953 -382.356135)
			(xy 295.736917 -382.290645) (xy 295.728841 -382.223705) (xy 292.450794 -382.223705) (xy 292.442758 -382.290467)
			(xy 292.426786 -382.355849) (xy 292.403113 -382.418853) (xy 292.37208 -382.478576) (xy 292.334131 -382.534162)
			(xy 292.312344 -382.559814) (xy 292.306552 -382.566962) (xy 292.300036 -382.584151) (xy 292.299644 -382.593342)
			(xy 292.299644 -383.086864) (xy 292.300084 -383.096048) (xy 292.306578 -383.113232) (xy 292.312344 -383.120392)
			(xy 292.334148 -383.146031) (xy 292.372098 -383.201619) (xy 292.403131 -383.261344) (xy 292.426592 -383.323786)
			(xy 293.528687 -383.323786) (xy 293.52869 -383.25636) (xy 293.536769 -383.189419) (xy 293.552808 -383.123928)
			(xy 293.576576 -383.06083) (xy 293.60773 -383.001033) (xy 293.645822 -382.945397) (xy 293.667688 -382.919732)
			(xy 293.673495 -382.912594) (xy 293.680004 -382.895398) (xy 293.680388 -382.886204) (xy 293.680388 -382.728724)
			(xy 293.680835 -382.718605) (xy 293.688573 -382.699904) (xy 293.70288 -382.685589) (xy 293.721577 -382.677841)
			(xy 293.731696 -382.677416) (xy 294.447976 -382.677416) (xy 294.458099 -382.677836) (xy 294.476805 -382.685579)
			(xy 294.491121 -382.699895) (xy 294.498864 -382.718601) (xy 294.499284 -382.728724) (xy 294.499284 -382.886204)
			(xy 294.499696 -382.895391) (xy 294.506209 -382.912575) (xy 294.511984 -382.919732) (xy 294.533813 -382.945426)
			(xy 294.571904 -383.001056) (xy 294.603057 -383.060848) (xy 294.626824 -383.123941) (xy 294.642863 -383.189427)
			(xy 294.650942 -383.256362) (xy 294.650945 -383.323784) (xy 294.642872 -383.39072) (xy 294.62684 -383.456207)
			(xy 294.603079 -383.519302) (xy 294.571932 -383.579097) (xy 294.533846 -383.634731) (xy 294.511984 -383.660396)
			(xy 294.506205 -383.667553) (xy 294.49968 -383.684735) (xy 294.499284 -383.693924) (xy 294.499284 -384.186176)
			(xy 294.499709 -384.195361) (xy 294.506213 -384.212546) (xy 294.511984 -384.219704) (xy 294.533884 -384.24534)
			(xy 294.571973 -384.300978) (xy 294.603123 -384.360778) (xy 294.626885 -384.423879) (xy 294.642919 -384.489372)
			(xy 294.650992 -384.556314) (xy 294.650989 -384.62374) (xy 294.642909 -384.690681) (xy 294.626869 -384.756173)
			(xy 294.603101 -384.819271) (xy 294.571945 -384.879068) (xy 294.533851 -384.934703) (xy 294.511984 -384.960368)
			(xy 294.506174 -384.967504) (xy 294.499668 -384.984702) (xy 294.499284 -384.993896) (xy 294.499284 -385.151376)
			(xy 294.498864 -385.161499) (xy 294.491121 -385.180205) (xy 294.476805 -385.194521) (xy 294.458099 -385.202264)
			(xy 294.447976 -385.202684) (xy 293.731696 -385.202684) (xy 293.721571 -385.202287) (xy 293.702865 -385.194534)
			(xy 293.68855 -385.180212) (xy 293.680808 -385.161501) (xy 293.680388 -385.151376) (xy 293.680388 -384.993896)
			(xy 293.679982 -384.984708) (xy 293.673466 -384.967524) (xy 293.667688 -384.960368) (xy 293.64586 -384.934673)
			(xy 293.607771 -384.879043) (xy 293.576619 -384.819251) (xy 293.552854 -384.756158) (xy 293.536816 -384.690672)
			(xy 293.528737 -384.623737) (xy 293.528734 -384.556317) (xy 293.536806 -384.489381) (xy 293.552838 -384.423894)
			(xy 293.576597 -384.360799) (xy 293.607743 -384.301004) (xy 293.645827 -384.245369) (xy 293.667688 -384.219704)
			(xy 293.673464 -384.212544) (xy 293.679991 -384.195365) (xy 293.680388 -384.186176) (xy 293.680388 -383.693924)
			(xy 293.679969 -383.684738) (xy 293.673462 -383.667553) (xy 293.667688 -383.660396) (xy 293.645789 -383.63476)
			(xy 293.607702 -383.579121) (xy 293.576554 -383.51932) (xy 293.552792 -383.45622) (xy 293.53676 -383.390727)
			(xy 293.528687 -383.323786) (xy 292.426592 -383.323786) (xy 292.426804 -383.32435) (xy 292.442776 -383.389734)
			(xy 292.450819 -383.456559) (xy 292.450818 -383.523865) (xy 292.442772 -383.590689) (xy 292.426797 -383.656073)
			(xy 292.403121 -383.719078) (xy 292.372085 -383.778802) (xy 292.334133 -383.834388) (xy 292.312344 -383.86004)
			(xy 292.306541 -383.86718) (xy 292.300032 -383.884375) (xy 292.299644 -383.893568) (xy 292.299644 -384.051556)
			(xy 292.299143 -384.061702) (xy 292.29137 -384.080445) (xy 292.276998 -384.094768) (xy 292.258229 -384.102477)
			(xy 292.248082 -384.102864) (xy 291.531802 -384.102864) (xy 291.521676 -384.102372) (xy 291.502956 -384.094645)
			(xy 291.488599 -384.080361) (xy 291.480779 -384.06168) (xy 291.48024 -384.051556) (xy 291.48024 -383.893568)
			(xy 291.479836 -383.88438) (xy 291.473317 -383.867197) (xy 291.46754 -383.86004) (xy 291.445768 -383.834375)
			(xy 291.407819 -383.77879) (xy 291.376785 -383.719068) (xy 291.353111 -383.656066) (xy 291.337137 -383.590685)
			(xy 291.329092 -383.523864) (xy 291.32909 -383.45656) (xy 291.337133 -383.389739) (xy 291.353104 -383.324357)
			(xy 291.376775 -383.261354) (xy 291.407806 -383.20163) (xy 291.445753 -383.146044) (xy 291.46754 -383.120392)
			(xy 291.473328 -383.113241) (xy 291.479847 -383.096055) (xy 291.48024 -383.086864) (xy 291.48024 -382.593342)
			(xy 291.4798 -382.584158) (xy 291.473306 -382.566974) (xy 291.46754 -382.559814) (xy 291.445742 -382.53417)
			(xy 291.407794 -382.478582) (xy 291.376761 -382.418858) (xy 291.353088 -382.355852) (xy 291.337116 -382.290469)
			(xy 291.329073 -382.223645) (xy 288.051034 -382.223645) (xy 288.051034 -382.223704) (xy 288.042958 -382.290643)
			(xy 288.026922 -382.356132) (xy 288.003157 -382.419229) (xy 287.972004 -382.479024) (xy 287.933913 -382.534658)
			(xy 287.912048 -382.560322) (xy 287.906253 -382.567468) (xy 287.899739 -382.584658) (xy 287.899348 -382.59385)
			(xy 287.899348 -383.086356) (xy 287.899791 -383.095539) (xy 287.906283 -383.112723) (xy 287.912048 -383.119884)
			(xy 287.93393 -383.145535) (xy 287.972021 -383.201171) (xy 288.003174 -383.260968) (xy 288.026812 -383.323727)
			(xy 289.128894 -383.323727) (xy 289.128898 -383.256418) (xy 289.136946 -383.189593) (xy 289.152924 -383.124208)
			(xy 289.176604 -383.061202) (xy 289.207644 -383.001477) (xy 289.245601 -382.945891) (xy 289.267392 -382.92024)
			(xy 289.273196 -382.9131) (xy 289.279706 -382.895905) (xy 289.280092 -382.886712) (xy 289.280092 -382.728724)
			(xy 289.280541 -382.718572) (xy 289.288327 -382.699822) (xy 289.302715 -382.685498) (xy 289.321501 -382.677796)
			(xy 289.331654 -382.677416) (xy 290.047934 -382.677416) (xy 290.05806 -382.677898) (xy 290.076777 -382.685632)
			(xy 290.091132 -382.69992) (xy 290.098954 -382.7186) (xy 290.099496 -382.728724) (xy 290.099496 -382.886712)
			(xy 290.099901 -382.8959) (xy 290.106419 -382.913084) (xy 290.112196 -382.92024) (xy 290.133947 -382.945922)
			(xy 290.171895 -383.001505) (xy 290.202928 -383.061225) (xy 290.226601 -383.124225) (xy 290.242576 -383.189603)
			(xy 290.250622 -383.256422) (xy 290.250625 -383.323724) (xy 290.242585 -383.390543) (xy 290.226617 -383.455923)
			(xy 290.20295 -383.518926) (xy 290.171923 -383.578649) (xy 290.133981 -383.634235) (xy 290.112196 -383.659888)
			(xy 290.106379 -383.667019) (xy 290.099877 -383.68422) (xy 290.099496 -383.693416) (xy 290.099496 -384.186684)
			(xy 290.099915 -384.19587) (xy 290.106423 -384.213055) (xy 290.112196 -384.220212) (xy 290.134018 -384.245836)
			(xy 290.171963 -384.301427) (xy 290.202993 -384.361155) (xy 290.226662 -384.424163) (xy 290.242632 -384.489548)
			(xy 290.250673 -384.556373) (xy 290.250669 -384.623681) (xy 290.242622 -384.690505) (xy 290.226646 -384.755889)
			(xy 290.202971 -384.818895) (xy 290.171936 -384.87862) (xy 290.133985 -384.934207) (xy 290.112196 -384.95986)
			(xy 290.106391 -384.966999) (xy 290.099881 -384.984194) (xy 290.099496 -384.993388) (xy 290.099496 -385.151376)
			(xy 290.099059 -385.161529) (xy 290.09127 -385.180282) (xy 290.076878 -385.194606) (xy 290.058089 -385.202306)
			(xy 290.047934 -385.202684) (xy 289.331654 -385.202684) (xy 289.321527 -385.202212) (xy 289.30281 -385.194473)
			(xy 289.288456 -385.180183) (xy 289.280634 -385.1615) (xy 289.280092 -385.151376) (xy 289.280092 -384.993388)
			(xy 289.279689 -384.9842) (xy 289.273171 -384.967016) (xy 289.267392 -384.95986) (xy 289.245638 -384.934179)
			(xy 289.207685 -384.878598) (xy 289.176647 -384.818879) (xy 289.15297 -384.755878) (xy 289.136993 -384.690499)
			(xy 289.128945 -384.623679) (xy 289.128942 -384.556375) (xy 289.136983 -384.489554) (xy 289.152954 -384.424174)
			(xy 289.176625 -384.36117) (xy 289.207657 -384.301448) (xy 289.245605 -384.245863) (xy 289.267392 -384.220212)
			(xy 289.273208 -384.21308) (xy 289.279711 -384.195879) (xy 289.280092 -384.186684) (xy 289.280092 -383.693416)
			(xy 289.279676 -383.684229) (xy 289.273167 -383.667045) (xy 289.267392 -383.659888) (xy 289.245567 -383.634266)
			(xy 289.207616 -383.578676) (xy 289.176581 -383.518949) (xy 289.152908 -383.45594) (xy 289.136936 -383.390554)
			(xy 289.128894 -383.323727) (xy 288.026812 -383.323727) (xy 288.02694 -383.324067) (xy 288.042976 -383.389558)
			(xy 288.051051 -383.456499) (xy 288.05105 -383.523925) (xy 288.042971 -383.590865) (xy 288.026933 -383.656356)
			(xy 288.003164 -383.719454) (xy 287.972009 -383.77925) (xy 287.933915 -383.834884) (xy 287.912048 -383.860548)
			(xy 287.906242 -383.867686) (xy 287.899734 -383.884882) (xy 287.899348 -383.894076) (xy 287.899348 -384.051556)
			(xy 287.898849 -384.06167) (xy 287.891124 -384.080363) (xy 287.876834 -384.094677) (xy 287.858153 -384.102432)
			(xy 287.84804 -384.102864) (xy 287.13176 -384.102864) (xy 287.12163 -384.102516) (xy 287.102919 -384.094748)
			(xy 287.088605 -384.08041) (xy 287.080868 -384.061686) (xy 287.080452 -384.051556) (xy 287.080452 -383.894076)
			(xy 287.080042 -383.884889) (xy 287.073527 -383.867705) (xy 287.067752 -383.860548) (xy 287.045902 -383.834871)
			(xy 287.007809 -383.779239) (xy 286.976655 -383.719445) (xy 286.952888 -383.65635) (xy 286.936849 -383.590862)
			(xy 286.928772 -383.523924) (xy 286.92877 -383.4565) (xy 286.936845 -383.389562) (xy 286.952881 -383.324073)
			(xy 286.976645 -383.260977) (xy 287.007797 -383.201182) (xy 287.045887 -383.145548) (xy 287.067752 -383.119884)
			(xy 287.073544 -383.112736) (xy 287.08006 -383.095547) (xy 287.080452 -383.086356) (xy 287.080452 -382.59385)
			(xy 287.080006 -382.584667) (xy 287.073516 -382.567483) (xy 287.067752 -382.560322) (xy 287.045876 -382.534666)
			(xy 287.007785 -382.479031) (xy 286.976631 -382.419234) (xy 286.952865 -382.356136) (xy 286.936829 -382.290645)
			(xy 286.928753 -382.223705) (xy 275.797584 -382.223705) (xy 275.705437 -382.32432) (xy 275.561134 -382.470038)
			(xy 275.411255 -382.610015) (xy 275.256029 -382.744038) (xy 275.095692 -382.871902) (xy 274.930489 -382.993413)
			(xy 274.76067 -383.108386) (xy 274.586495 -383.216646) (xy 274.408229 -383.318028) (xy 274.226143 -383.412377)
			(xy 274.040514 -383.499551) (xy 273.851626 -383.579415) (xy 273.659765 -383.651849) (xy 273.465224 -383.716742)
			(xy 273.2683 -383.773996) (xy 273.069292 -383.823522) (xy 272.868503 -383.865247) (xy 272.666239 -383.899105)
			(xy 272.462807 -383.925047) (xy 272.258519 -383.943031) (xy 272.053685 -383.953032) (xy 271.848616 -383.955032)
			(xy 271.643625 -383.949031) (xy 271.439025 -383.935036) (xy 271.235126 -383.913069) (xy 271.03224 -383.883163)
			(xy 270.830675 -383.845364) (xy 270.630739 -383.79973) (xy 270.432735 -383.74633) (xy 270.236965 -383.685245)
			(xy 270.043727 -383.616568) (xy 269.853317 -383.540404) (xy 269.666022 -383.45687) (xy 269.48213 -383.366091)
			(xy 269.30192 -383.268207) (xy 269.125665 -383.163366) (xy 268.953636 -383.051728) (xy 268.786093 -382.933463)
			(xy 268.623292 -382.808752) (xy 268.46548 -382.677783) (xy 268.312899 -382.540758) (xy 268.16578 -382.397883)
			(xy 268.024347 -382.249377) (xy 267.888817 -382.095466) (xy 267.759394 -381.936384) (xy 267.636277 -381.772374)
			(xy 267.519652 -381.603685) (xy 267.409698 -381.430575) (xy 267.306582 -381.253306) (xy 267.210461 -381.072149)
			(xy 267.12148 -380.88738) (xy 267.039777 -380.69928) (xy 266.965475 -380.508135) (xy 266.898687 -380.314237)
			(xy 266.839515 -380.11788) (xy 266.788049 -379.919365) (xy 266.744367 -379.718992) (xy 266.708537 -379.517068)
			(xy 266.680612 -379.3139) (xy 266.660635 -379.109797) (xy 266.648637 -378.905069) (xy 266.644636 -378.70003)
			(xy 262.441436 -378.70003) (xy 262.561832 -378.820426) (xy 262.579119 -378.838423) (xy 262.608435 -378.878804)
			(xy 262.631082 -378.92327) (xy 262.646503 -378.970728) (xy 262.654321 -379.020012) (xy 262.654796 -379.044962)
			(xy 262.654796 -385.608376) (xy 454.303373 -385.608376) (xy 454.303373 -385.479236) (xy 454.311323 -385.350341)
			(xy 454.327193 -385.222181) (xy 454.350922 -385.09524) (xy 454.382421 -384.970001) (xy 454.42157 -384.846938)
			(xy 454.468221 -384.726519) (xy 454.522196 -384.6092) (xy 454.583291 -384.495426) (xy 454.651274 -384.385629)
			(xy 454.725888 -384.280226) (xy 454.806849 -384.179616) (xy 454.893849 -384.084181) (xy 454.98656 -383.994282)
			(xy 455.08463 -383.910261) (xy 455.187685 -383.832437) (xy 455.295336 -383.761105) (xy 455.407175 -383.696535)
			(xy 455.522776 -383.638973) (xy 455.641701 -383.588636) (xy 455.7635 -383.545716) (xy 455.88771 -383.510375)
			(xy 456.013859 -383.482748) (xy 456.141471 -383.462939) (xy 456.27006 -383.451023) (xy 456.399138 -383.447047)
			(xy 456.528216 -383.451023) (xy 456.656805 -383.462939) (xy 456.784417 -383.482748) (xy 456.910566 -383.510375)
			(xy 457.034776 -383.545716) (xy 457.156575 -383.588636) (xy 457.2755 -383.638973) (xy 457.391101 -383.696535)
			(xy 457.50294 -383.761105) (xy 457.610591 -383.832437) (xy 457.713646 -383.910261) (xy 457.811716 -383.994282)
			(xy 457.904427 -384.084181) (xy 457.991427 -384.179616) (xy 458.072388 -384.280226) (xy 458.147002 -384.385629)
			(xy 458.214985 -384.495426) (xy 458.27608 -384.6092) (xy 458.330055 -384.726519) (xy 458.376706 -384.846938)
			(xy 458.415855 -384.970001) (xy 458.447354 -385.09524) (xy 458.471083 -385.222181) (xy 458.486953 -385.350341)
			(xy 458.494903 -385.479236) (xy 458.4954 -385.543806) (xy 458.494903 -385.608376) (xy 458.486953 -385.737271)
			(xy 458.471083 -385.865431) (xy 458.447354 -385.992372) (xy 458.415855 -386.117611) (xy 458.376706 -386.240674)
			(xy 458.330055 -386.361093) (xy 458.27608 -386.478412) (xy 458.214985 -386.592186) (xy 458.147002 -386.701983)
			(xy 458.072388 -386.807386) (xy 457.991427 -386.907996) (xy 457.904427 -387.003431) (xy 457.811716 -387.09333)
			(xy 457.713646 -387.177351) (xy 457.610591 -387.255175) (xy 457.50294 -387.326507) (xy 457.391101 -387.391077)
			(xy 457.2755 -387.448639) (xy 457.156575 -387.498976) (xy 457.034776 -387.541896) (xy 456.910566 -387.577237)
			(xy 456.784417 -387.604864) (xy 456.656805 -387.624673) (xy 456.528216 -387.636589) (xy 456.399138 -387.640566)
			(xy 456.27006 -387.636589) (xy 456.141471 -387.624673) (xy 456.013859 -387.604864) (xy 455.88771 -387.577237)
			(xy 455.7635 -387.541896) (xy 455.641701 -387.498976) (xy 455.522776 -387.448639) (xy 455.407175 -387.391077)
			(xy 455.295336 -387.326507) (xy 455.187685 -387.255175) (xy 455.08463 -387.177351) (xy 454.98656 -387.09333)
			(xy 454.893849 -387.003431) (xy 454.806849 -386.907996) (xy 454.725888 -386.807386) (xy 454.651274 -386.701983)
			(xy 454.583291 -386.592186) (xy 454.522196 -386.478412) (xy 454.468221 -386.361093) (xy 454.42157 -386.240674)
			(xy 454.382421 -386.117611) (xy 454.350922 -385.992372) (xy 454.327193 -385.865431) (xy 454.311323 -385.737271)
			(xy 454.303373 -385.608376) (xy 262.654796 -385.608376) (xy 262.654796 -387.940042) (xy 262.654337 -387.964995)
			(xy 262.646538 -388.014288) (xy 262.631124 -388.061754) (xy 262.608473 -388.106223) (xy 262.579145 -388.146602)
			(xy 262.561832 -388.164578) (xy 259.433314 -391.293096) (xy 259.415314 -391.310377) (xy 259.374929 -391.339679)
			(xy 259.330463 -391.362313) (xy 259.283006 -391.377722) (xy 259.233726 -391.385529) (xy 259.208778 -391.38606)
			(xy 245.30812 -391.38606) (xy 245.298058 -391.386499) (xy 245.27948 -391.394241) (xy 245.272052 -391.401046)
			(xy 244.461792 -392.211306) (xy 244.454947 -392.218705) (xy 244.447216 -392.237303) (xy 244.446806 -392.247374)
			(xy 244.446806 -393.099798) (xy 262.940808 -393.099798) (xy 262.944812 -392.89461) (xy 262.956819 -392.689734)
			(xy 262.97681 -392.485483) (xy 263.004755 -392.282168) (xy 263.040611 -392.080097) (xy 263.084325 -391.879579)
			(xy 263.135828 -391.68092) (xy 263.195043 -391.484421) (xy 263.261879 -391.290382) (xy 263.336235 -391.099099)
			(xy 263.417998 -390.910862) (xy 263.507043 -390.725959) (xy 263.603234 -390.544671) (xy 263.706425 -390.367274)
			(xy 263.816459 -390.194037) (xy 263.933168 -390.025226) (xy 264.056374 -389.861097) (xy 264.185891 -389.7019)
			(xy 264.32152 -389.547878) (xy 264.463055 -389.399264) (xy 264.61028 -389.256286) (xy 264.762972 -389.119161)
			(xy 264.920898 -388.988097) (xy 265.083817 -388.863295) (xy 265.251482 -388.744945) (xy 265.423636 -388.633226)
			(xy 265.600018 -388.528309) (xy 265.780359 -388.430354) (xy 265.964385 -388.33951) (xy 266.151815 -388.255914)
			(xy 266.342364 -388.179695) (xy 266.535741 -388.110969) (xy 266.731653 -388.04984) (xy 266.9298 -387.996401)
			(xy 267.129882 -387.950734) (xy 267.331593 -387.912907) (xy 267.534626 -387.88298) (xy 267.738673 -387.860997)
			(xy 267.943422 -387.846992) (xy 268.148561 -387.840986) (xy 268.353778 -387.842988) (xy 268.558761 -387.852996)
			(xy 268.763198 -387.870993) (xy 268.966776 -387.896953) (xy 269.169187 -387.930836) (xy 269.370121 -387.972591)
			(xy 269.569274 -388.022154) (xy 269.766341 -388.079449) (xy 269.961023 -388.144389) (xy 270.153023 -388.216875)
			(xy 270.342048 -388.296798) (xy 270.527811 -388.384034) (xy 270.710029 -388.478452) (xy 270.888425 -388.579907)
			(xy 271.062726 -388.688246) (xy 271.232668 -388.803302) (xy 271.397991 -388.924902) (xy 271.558444 -389.052859)
			(xy 271.713783 -389.186978) (xy 271.86377 -389.327057) (xy 272.008178 -389.472881) (xy 272.146786 -389.624227)
			(xy 272.279384 -389.780867) (xy 272.40577 -389.942561) (xy 272.52575 -390.109063) (xy 272.639143 -390.280119)
			(xy 272.745776 -390.455469) (xy 272.845486 -390.634846) (xy 272.938122 -390.817976) (xy 273.023542 -391.004582)
			(xy 273.101616 -391.194378) (xy 273.172226 -391.387076) (xy 273.235263 -391.582382) (xy 273.290633 -391.779998)
			(xy 273.33825 -391.979625) (xy 273.378042 -392.180957) (xy 273.409949 -392.383689) (xy 273.433922 -392.587511)
			(xy 273.449924 -392.792114) (xy 273.457931 -392.997184) (xy 273.458432 -393.099798) (xy 273.457931 -393.202412)
			(xy 273.449924 -393.407482) (xy 273.433922 -393.612085) (xy 273.409949 -393.815907) (xy 273.378042 -394.018639)
			(xy 273.33825 -394.219971) (xy 273.290633 -394.419598) (xy 273.235263 -394.617214) (xy 273.172226 -394.81252)
			(xy 273.101616 -395.005218) (xy 273.023542 -395.195014) (xy 272.938122 -395.38162) (xy 272.845486 -395.56475)
			(xy 272.745776 -395.744127) (xy 272.639143 -395.919477) (xy 272.52575 -396.090533) (xy 272.40577 -396.257035)
			(xy 272.279384 -396.418729) (xy 272.146786 -396.575369) (xy 272.008178 -396.726715) (xy 271.86377 -396.872539)
			(xy 271.713783 -397.012618) (xy 271.558444 -397.146737) (xy 271.397991 -397.274694) (xy 271.232668 -397.396294)
			(xy 271.062726 -397.51135) (xy 270.888425 -397.619689) (xy 270.710029 -397.721144) (xy 270.527811 -397.815562)
			(xy 270.510088 -397.823885) (xy 286.928734 -397.823885) (xy 286.928737 -397.756458) (xy 286.936817 -397.689516)
			(xy 286.952859 -397.624024) (xy 286.976629 -397.560925) (xy 287.007787 -397.501128) (xy 287.045884 -397.445494)
			(xy 287.067752 -397.41983) (xy 287.073567 -397.412698) (xy 287.080069 -397.395497) (xy 287.080452 -397.386302)
			(xy 287.080452 -396.89405) (xy 287.080006 -396.884867) (xy 287.073516 -396.867683) (xy 287.067752 -396.860522)
			(xy 287.045876 -396.834866) (xy 287.007785 -396.779231) (xy 286.976631 -396.719434) (xy 286.952865 -396.656336)
			(xy 286.936829 -396.590845) (xy 286.928753 -396.523905) (xy 286.928754 -396.45648) (xy 286.936832 -396.38954)
			(xy 286.95287 -396.32405) (xy 286.976638 -396.260952) (xy 287.007792 -396.201156) (xy 287.045886 -396.145522)
			(xy 287.067752 -396.119858) (xy 287.073555 -396.112718) (xy 287.080065 -396.095523) (xy 287.080452 -396.08633)
			(xy 287.080452 -395.92885) (xy 287.080968 -395.918725) (xy 287.088682 -395.900003) (xy 287.102959 -395.885644)
			(xy 287.121638 -395.877825) (xy 287.13176 -395.877288) (xy 287.84804 -395.877288) (xy 287.858195 -395.877689)
			(xy 287.876946 -395.885495) (xy 287.891268 -395.899898) (xy 287.898968 -395.918693) (xy 287.899348 -395.92885)
			(xy 287.899348 -396.08633) (xy 287.899755 -396.095517) (xy 287.906272 -396.112701) (xy 287.912048 -396.119858)
			(xy 287.933904 -396.14553) (xy 287.971996 -396.201163) (xy 288.00315 -396.260957) (xy 288.026917 -396.324053)
			(xy 288.042955 -396.389542) (xy 288.051033 -396.456481) (xy 288.051034 -396.523904) (xy 288.042958 -396.590843)
			(xy 288.026922 -396.656332) (xy 288.003157 -396.719429) (xy 287.972004 -396.779224) (xy 287.933913 -396.834858)
			(xy 287.912048 -396.860522) (xy 287.906253 -396.867668) (xy 287.899739 -396.884858) (xy 287.899348 -396.89405)
			(xy 287.899348 -397.386302) (xy 287.899769 -397.395488) (xy 287.906276 -397.412672) (xy 287.912048 -397.41983)
			(xy 287.933876 -397.445525) (xy 287.97197 -397.501154) (xy 288.000733 -397.556355) (xy 289.128926 -397.556355)
			(xy 289.13697 -397.489532) (xy 289.152943 -397.42415) (xy 289.176617 -397.361145) (xy 289.207652 -397.301423)
			(xy 289.245603 -397.245837) (xy 289.267392 -397.220186) (xy 289.273176 -397.213032) (xy 289.279698 -397.195848)
			(xy 289.280092 -397.186658) (xy 289.280092 -397.028924) (xy 289.280541 -397.018772) (xy 289.288327 -397.000022)
			(xy 289.302715 -396.985698) (xy 289.321501 -396.977996) (xy 289.331654 -396.977616) (xy 290.047934 -396.977616)
			(xy 290.05806 -396.978098) (xy 290.076777 -396.985832) (xy 290.091132 -397.00012) (xy 290.098954 -397.0188)
			(xy 290.099496 -397.028924) (xy 290.099496 -397.186658) (xy 290.099927 -397.195843) (xy 290.106426 -397.213027)
			(xy 290.112196 -397.220186) (xy 290.133992 -397.245831) (xy 290.171939 -397.301419) (xy 290.20297 -397.361144)
			(xy 290.22664 -397.424149) (xy 290.242612 -397.489532) (xy 290.250654 -397.556355) (xy 290.250653 -397.62366)
			(xy 290.242609 -397.690483) (xy 290.226636 -397.755865) (xy 290.202963 -397.81887) (xy 290.200388 -397.823825)
			(xy 291.329053 -397.823825) (xy 291.329057 -397.756517) (xy 291.337105 -397.689692) (xy 291.353082 -397.624308)
			(xy 291.376759 -397.561302) (xy 291.407796 -397.501577) (xy 291.44575 -397.44599) (xy 291.46754 -397.420338)
			(xy 291.47335 -397.413203) (xy 291.479856 -397.396004) (xy 291.48024 -397.38681) (xy 291.48024 -396.893542)
			(xy 291.4798 -396.884358) (xy 291.473306 -396.867174) (xy 291.46754 -396.860014) (xy 291.445742 -396.83437)
			(xy 291.407794 -396.778782) (xy 291.376761 -396.719058) (xy 291.353088 -396.656052) (xy 291.337116 -396.590669)
			(xy 291.329073 -396.523845) (xy 291.329074 -396.45654) (xy 291.337119 -396.389716) (xy 291.353093 -396.324333)
			(xy 291.376767 -396.261328) (xy 291.407801 -396.201605) (xy 291.445751 -396.146018) (xy 291.46754 -396.120366)
			(xy 291.473339 -396.113222) (xy 291.479851 -396.096031) (xy 291.48024 -396.086838) (xy 291.48024 -395.92885)
			(xy 291.480705 -395.918681) (xy 291.488474 -395.899887) (xy 291.502847 -395.885501) (xy 291.521634 -395.877714)
			(xy 291.531802 -395.877288) (xy 292.248082 -395.877288) (xy 292.258259 -395.87768) (xy 292.277063 -395.885468)
			(xy 292.29145 -395.899864) (xy 292.299227 -395.918673) (xy 292.299644 -395.92885) (xy 292.299644 -396.086838)
			(xy 292.300049 -396.096026) (xy 292.306568 -396.113209) (xy 292.312344 -396.120366) (xy 292.334122 -396.146026)
			(xy 292.372072 -396.201611) (xy 292.403107 -396.261333) (xy 292.426781 -396.324337) (xy 292.442755 -396.389718)
			(xy 292.450801 -396.45654) (xy 292.450801 -396.523845) (xy 292.442758 -396.590667) (xy 292.426786 -396.656049)
			(xy 292.403113 -396.719053) (xy 292.37208 -396.778776) (xy 292.334131 -396.834362) (xy 292.312344 -396.860014)
			(xy 292.306552 -396.867162) (xy 292.300036 -396.884351) (xy 292.299644 -396.893542) (xy 292.299644 -397.38681)
			(xy 292.300062 -397.395996) (xy 292.306572 -397.41318) (xy 292.312344 -397.420338) (xy 292.334095 -397.446021)
			(xy 292.372046 -397.501602) (xy 292.40047 -397.556296) (xy 293.528718 -397.556296) (xy 293.536793 -397.489359)
			(xy 293.552827 -397.42387) (xy 293.576589 -397.360774) (xy 293.607738 -397.300978) (xy 293.645825 -397.245343)
			(xy 293.667688 -397.219678) (xy 293.673475 -397.212526) (xy 293.679996 -397.195341) (xy 293.680388 -397.18615)
			(xy 293.680388 -397.028924) (xy 293.680835 -397.018805) (xy 293.688573 -397.000104) (xy 293.70288 -396.985789)
			(xy 293.721577 -396.978041) (xy 293.731696 -396.977616) (xy 294.447976 -396.977616) (xy 294.458099 -396.978036)
			(xy 294.476805 -396.985779) (xy 294.491121 -397.000095) (xy 294.498864 -397.018801) (xy 294.499284 -397.028924)
			(xy 294.499284 -397.18615) (xy 294.499722 -397.195334) (xy 294.506217 -397.212519) (xy 294.511984 -397.219678)
			(xy 294.533858 -397.245335) (xy 294.571948 -397.30097) (xy 294.603099 -397.360767) (xy 294.626863 -397.423865)
			(xy 294.642899 -397.489356) (xy 294.650974 -397.556295) (xy 294.650973 -397.62372) (xy 294.642896 -397.690659)
			(xy 294.626859 -397.756149) (xy 294.603093 -397.819246) (xy 294.600676 -397.823885) (xy 295.728821 -397.823885)
			(xy 295.728825 -397.756458) (xy 295.736905 -397.689516) (xy 295.752946 -397.624025) (xy 295.776716 -397.560926)
			(xy 295.807873 -397.501129) (xy 295.845969 -397.445495) (xy 295.867836 -397.41983) (xy 295.873649 -397.412697)
			(xy 295.880153 -397.395497) (xy 295.880536 -397.386302) (xy 295.880536 -396.89405) (xy 295.880094 -396.884866)
			(xy 295.873601 -396.867682) (xy 295.867836 -396.860522) (xy 295.845961 -396.834865) (xy 295.80787 -396.779231)
			(xy 295.776718 -396.719433) (xy 295.752953 -396.656335) (xy 295.736917 -396.590845) (xy 295.728841 -396.523905)
			(xy 295.728842 -396.45648) (xy 295.73692 -396.38954) (xy 295.752957 -396.32405) (xy 295.776724 -396.260953)
			(xy 295.807878 -396.201157) (xy 295.84597 -396.145523) (xy 295.867836 -396.119858) (xy 295.873637 -396.112716)
			(xy 295.880148 -396.095523) (xy 295.880536 -396.08633) (xy 295.880536 -395.92885) (xy 295.881067 -395.918727)
			(xy 295.888778 -395.900008) (xy 295.903051 -395.88565) (xy 295.921724 -395.877828) (xy 295.931844 -395.877288)
			(xy 296.648124 -395.877288) (xy 296.658278 -395.877702) (xy 296.677029 -395.885503) (xy 296.691351 -395.899902)
			(xy 296.699052 -395.918694) (xy 296.699432 -395.92885) (xy 296.699432 -396.08633) (xy 296.699843 -396.095517)
			(xy 296.706358 -396.1127) (xy 296.712132 -396.119858) (xy 296.733985 -396.145532) (xy 296.772072 -396.201166)
			(xy 296.803221 -396.260961) (xy 296.826985 -396.324057) (xy 296.84302 -396.389545) (xy 296.851096 -396.456481)
			(xy 296.851097 -396.523904) (xy 296.843022 -396.590841) (xy 296.826989 -396.656329) (xy 296.803227 -396.719425)
			(xy 296.77208 -396.779221) (xy 296.733994 -396.834856) (xy 296.712132 -396.860522) (xy 296.706335 -396.867667)
			(xy 296.699823 -396.884858) (xy 296.699432 -396.89405) (xy 296.699432 -397.386302) (xy 296.699856 -397.395487)
			(xy 296.706362 -397.412671) (xy 296.712132 -397.41983) (xy 296.733958 -397.445527) (xy 296.772045 -397.501157)
			(xy 296.800802 -397.556355) (xy 297.929014 -397.556355) (xy 297.937057 -397.489532) (xy 297.95303 -397.42415)
			(xy 297.976704 -397.361146) (xy 298.007738 -397.301423) (xy 298.045688 -397.245838) (xy 298.067476 -397.220186)
			(xy 298.073258 -397.21303) (xy 298.079782 -397.195848) (xy 298.080176 -397.186658) (xy 298.080176 -397.028924)
			(xy 298.080641 -397.018774) (xy 298.088424 -397.000027) (xy 298.102807 -396.985704) (xy 298.121587 -396.977999)
			(xy 298.131738 -396.977616) (xy 298.848018 -396.977616) (xy 298.858143 -396.978111) (xy 298.87686 -396.98584)
			(xy 298.891215 -397.000123) (xy 298.899038 -397.018802) (xy 298.89958 -397.028924) (xy 298.89958 -397.186658)
			(xy 298.900015 -397.195842) (xy 298.906512 -397.213027) (xy 298.91228 -397.220186) (xy 298.934077 -397.24583)
			(xy 298.972024 -397.301418) (xy 299.003056 -397.361143) (xy 299.026728 -397.424149) (xy 299.042699 -397.489532)
			(xy 299.050742 -397.556355) (xy 299.050741 -397.62366) (xy 299.042697 -397.690483) (xy 299.026723 -397.755866)
			(xy 299.00305 -397.818871) (xy 299.000445 -397.823885) (xy 300.128612 -397.823885) (xy 300.128616 -397.756458)
			(xy 300.136696 -397.689517) (xy 300.152736 -397.624025) (xy 300.176506 -397.560927) (xy 300.207662 -397.501129)
			(xy 300.245757 -397.445495) (xy 300.267624 -397.41983) (xy 300.273436 -397.412696) (xy 300.27994 -397.395497)
			(xy 300.280324 -397.386302) (xy 300.280324 -396.89405) (xy 300.279884 -396.884866) (xy 300.273391 -396.867682)
			(xy 300.267624 -396.860522) (xy 300.245749 -396.834865) (xy 300.207659 -396.77923) (xy 300.176508 -396.719433)
			(xy 300.152743 -396.656335) (xy 300.136708 -396.590845) (xy 300.128632 -396.523905) (xy 300.128633 -396.45648)
			(xy 300.13671 -396.389541) (xy 300.152748 -396.324051) (xy 300.176514 -396.260953) (xy 300.207667 -396.201157)
			(xy 300.245759 -396.145523) (xy 300.267624 -396.119858) (xy 300.273424 -396.112715) (xy 300.279936 -396.095523)
			(xy 300.280324 -396.08633) (xy 300.280324 -395.92885) (xy 300.280867 -395.918728) (xy 300.288576 -395.900011)
			(xy 300.302845 -395.885654) (xy 300.321514 -395.87783) (xy 300.331632 -395.877288) (xy 301.047912 -395.877288)
			(xy 301.058065 -395.877711) (xy 301.076816 -395.885509) (xy 301.091138 -395.899904) (xy 301.09884 -395.918694)
			(xy 301.09922 -395.92885) (xy 301.09922 -396.08633) (xy 301.099611 -396.095519) (xy 301.106138 -396.112704)
			(xy 301.11192 -396.119858) (xy 301.133773 -396.145532) (xy 301.171861 -396.201165) (xy 301.203011 -396.260961)
			(xy 301.226775 -396.324056) (xy 301.242811 -396.389544) (xy 301.250887 -396.456481) (xy 301.250888 -396.523904)
			(xy 301.242813 -396.590841) (xy 301.226779 -396.656329) (xy 301.203017 -396.719426) (xy 301.171869 -396.779222)
			(xy 301.133783 -396.834856) (xy 301.11192 -396.860522) (xy 301.106134 -396.867675) (xy 301.099612 -396.884859)
			(xy 301.09922 -396.89405) (xy 301.09922 -397.386302) (xy 301.099625 -397.39549) (xy 301.106142 -397.412674)
			(xy 301.11192 -397.41983) (xy 301.133746 -397.445526) (xy 301.171834 -397.501157) (xy 301.200562 -397.556296)
			(xy 302.328806 -397.556296) (xy 302.336881 -397.489359) (xy 302.352914 -397.423871) (xy 302.376676 -397.360775)
			(xy 302.407824 -397.300979) (xy 302.44591 -397.245344) (xy 302.467772 -397.219678) (xy 302.473569 -397.212534)
			(xy 302.480081 -397.195342) (xy 302.480472 -397.18615) (xy 302.480472 -397.028924) (xy 302.480935 -397.018806)
			(xy 302.48867 -397.000109) (xy 302.502972 -396.985795) (xy 302.521663 -396.978043) (xy 302.53178 -396.977616)
			(xy 303.24806 -396.977616) (xy 303.258182 -396.978049) (xy 303.276888 -396.985787) (xy 303.291204 -397.000099)
			(xy 303.298948 -397.018802) (xy 303.299368 -397.028924) (xy 303.299368 -397.18615) (xy 303.299809 -397.195334)
			(xy 303.306302 -397.212518) (xy 303.312068 -397.219678) (xy 303.333943 -397.245335) (xy 303.372033 -397.30097)
			(xy 303.403185 -397.360767) (xy 303.426951 -397.423865) (xy 303.442986 -397.489355) (xy 303.451062 -397.556295)
			(xy 303.451061 -397.62372) (xy 303.442984 -397.69066) (xy 303.426946 -397.75615) (xy 303.403179 -397.819247)
			(xy 303.372026 -397.879043) (xy 303.333934 -397.934677) (xy 303.312068 -397.960342) (xy 303.306267 -397.967484)
			(xy 303.299756 -397.984677) (xy 303.299368 -397.99387) (xy 303.299368 -398.486376) (xy 303.299797 -398.495561)
			(xy 303.306299 -398.512745) (xy 303.312068 -398.519904) (xy 303.333968 -398.54554) (xy 303.372058 -398.601178)
			(xy 303.403209 -398.660978) (xy 303.426973 -398.724078) (xy 303.443007 -398.789571) (xy 303.45108 -398.856513)
			(xy 303.451077 -398.923941) (xy 303.442997 -398.990882) (xy 303.426957 -399.056373) (xy 303.403187 -399.119472)
			(xy 303.37203 -399.179269) (xy 303.333935 -399.234903) (xy 303.312068 -399.260568) (xy 303.306256 -399.267702)
			(xy 303.299751 -399.284901) (xy 303.299368 -399.294096) (xy 303.299368 -399.451576) (xy 303.298964 -399.461701)
			(xy 303.291218 -399.48041) (xy 303.276897 -399.494727) (xy 303.258185 -399.502467) (xy 303.24806 -399.502884)
			(xy 302.53178 -399.502884) (xy 302.521654 -399.5025) (xy 302.502947 -399.494742) (xy 302.488633 -399.480416)
			(xy 302.480891 -399.461702) (xy 302.480472 -399.451576) (xy 302.480472 -399.294096) (xy 302.48007 -399.284908)
			(xy 302.473551 -399.267723) (xy 302.467772 -399.260568) (xy 302.445944 -399.234873) (xy 302.407856 -399.179242)
			(xy 302.376706 -399.11945) (xy 302.352941 -399.056357) (xy 302.336904 -398.990872) (xy 302.328825 -398.923937)
			(xy 302.328822 -398.856517) (xy 302.336894 -398.789582) (xy 302.352925 -398.724095) (xy 302.376684 -398.661)
			(xy 302.407829 -398.601204) (xy 302.445911 -398.54557) (xy 302.467772 -398.519904) (xy 302.473558 -398.512752)
			(xy 302.480077 -398.495566) (xy 302.480472 -398.486376) (xy 302.480472 -397.99387) (xy 302.480082 -397.98468)
			(xy 302.473555 -397.967496) (xy 302.467772 -397.960342) (xy 302.445919 -397.934668) (xy 302.407832 -397.879034)
			(xy 302.376682 -397.819239) (xy 302.352919 -397.756143) (xy 302.336883 -397.690656) (xy 302.328807 -397.623719)
			(xy 302.328806 -397.556296) (xy 301.200562 -397.556296) (xy 301.202986 -397.560949) (xy 301.226751 -397.624042)
			(xy 301.242789 -397.689527) (xy 301.250867 -397.756461) (xy 301.250871 -397.823882) (xy 301.242799 -397.890817)
			(xy 301.226768 -397.956304) (xy 301.203009 -398.019399) (xy 301.171864 -398.079194) (xy 301.133781 -398.134828)
			(xy 301.11192 -398.160494) (xy 301.106146 -398.167655) (xy 301.099617 -398.184833) (xy 301.09922 -398.194022)
			(xy 301.09922 -398.351502) (xy 301.098774 -398.361634) (xy 301.091038 -398.380362) (xy 301.076739 -398.39472)
			(xy 301.058042 -398.402532) (xy 301.047912 -398.403064) (xy 300.331632 -398.403064) (xy 300.321475 -398.402652)
			(xy 300.302717 -398.39486) (xy 300.288391 -398.38046) (xy 300.280696 -398.361661) (xy 300.280324 -398.351502)
			(xy 300.280324 -398.194022) (xy 300.279898 -398.184837) (xy 300.273395 -398.167652) (xy 300.267624 -398.160494)
			(xy 300.245722 -398.13486) (xy 300.207633 -398.079222) (xy 300.176482 -398.019421) (xy 300.152719 -397.95632)
			(xy 300.136686 -397.890827) (xy 300.128612 -397.823885) (xy 299.000445 -397.823885) (xy 298.972017 -397.878595)
			(xy 298.934068 -397.934182) (xy 298.91228 -397.959834) (xy 298.906484 -397.96698) (xy 298.89997 -397.98417)
			(xy 298.89958 -397.993362) (xy 298.89958 -398.486884) (xy 298.900003 -398.49607) (xy 298.906508 -398.513254)
			(xy 298.91228 -398.520412) (xy 298.934103 -398.546035) (xy 298.972049 -398.601626) (xy 299.00308 -398.661354)
			(xy 299.02675 -398.724362) (xy 299.04272 -398.789748) (xy 299.050761 -398.856573) (xy 299.050757 -398.923881)
			(xy 299.04271 -398.990706) (xy 299.026734 -399.05609) (xy 299.003058 -399.119095) (xy 298.972021 -399.17882)
			(xy 298.934069 -399.234408) (xy 298.91228 -399.26006) (xy 298.906473 -399.267198) (xy 298.899965 -399.284394)
			(xy 298.89958 -399.293588) (xy 298.89958 -399.451576) (xy 298.899159 -399.461731) (xy 298.891367 -399.480487)
			(xy 298.87697 -399.494812) (xy 298.858175 -399.502509) (xy 298.848018 -399.502884) (xy 298.131738 -399.502884)
			(xy 298.121617 -399.502343) (xy 298.102901 -399.494632) (xy 298.088544 -399.480362) (xy 298.08072 -399.461694)
			(xy 298.080176 -399.451576) (xy 298.080176 -399.293588) (xy 298.079777 -399.2844) (xy 298.073256 -399.267215)
			(xy 298.067476 -399.26006) (xy 298.045723 -399.234379) (xy 298.00777 -399.178798) (xy 297.976733 -399.119078)
			(xy 297.953057 -399.056078) (xy 297.93708 -398.990699) (xy 297.929033 -398.923879) (xy 297.92903 -398.856576)
			(xy 297.937071 -398.789755) (xy 297.953041 -398.724374) (xy 297.976711 -398.661371) (xy 298.007742 -398.601649)
			(xy 298.045689 -398.546064) (xy 298.067476 -398.520412) (xy 298.07329 -398.513279) (xy 298.079795 -398.496079)
			(xy 298.080176 -398.486884) (xy 298.080176 -397.993362) (xy 298.079789 -397.984172) (xy 298.07326 -397.966988)
			(xy 298.067476 -397.959834) (xy 298.045697 -397.934174) (xy 298.007746 -397.87859) (xy 297.97671 -397.818868)
			(xy 297.953035 -397.755864) (xy 297.93706 -397.690482) (xy 297.929015 -397.62366) (xy 297.929014 -397.556355)
			(xy 296.800802 -397.556355) (xy 296.803196 -397.56095) (xy 296.826961 -397.624042) (xy 296.842998 -397.689527)
			(xy 296.851076 -397.756461) (xy 296.85108 -397.823881) (xy 296.843008 -397.890817) (xy 296.826978 -397.956303)
			(xy 296.803219 -398.019398) (xy 296.772075 -398.079194) (xy 296.733993 -398.134828) (xy 296.712132 -398.160494)
			(xy 296.706347 -398.167647) (xy 296.699827 -398.184832) (xy 296.699432 -398.194022) (xy 296.699432 -398.351502)
			(xy 296.698974 -398.361632) (xy 296.691241 -398.380359) (xy 296.676945 -398.394716) (xy 296.658252 -398.40253)
			(xy 296.648124 -398.403064) (xy 295.931844 -398.403064) (xy 295.921688 -398.402642) (xy 295.90293 -398.394854)
			(xy 295.888604 -398.380456) (xy 295.880909 -398.36166) (xy 295.880536 -398.351502) (xy 295.880536 -398.194022)
			(xy 295.880107 -398.184837) (xy 295.873606 -398.167653) (xy 295.867836 -398.160494) (xy 295.845933 -398.13486)
			(xy 295.807843 -398.079222) (xy 295.776692 -398.019422) (xy 295.752929 -397.956321) (xy 295.736895 -397.890827)
			(xy 295.728821 -397.823885) (xy 294.600676 -397.823885) (xy 294.57194 -397.879043) (xy 294.533849 -397.934677)
			(xy 294.511984 -397.960342) (xy 294.506185 -397.967486) (xy 294.499672 -397.984677) (xy 294.499284 -397.99387)
			(xy 294.499284 -398.486376) (xy 294.499709 -398.495561) (xy 294.506213 -398.512746) (xy 294.511984 -398.519904)
			(xy 294.533884 -398.54554) (xy 294.571973 -398.601178) (xy 294.603123 -398.660978) (xy 294.626885 -398.724079)
			(xy 294.642919 -398.789572) (xy 294.650992 -398.856514) (xy 294.650989 -398.92394) (xy 294.642909 -398.990881)
			(xy 294.626869 -399.056373) (xy 294.603101 -399.119471) (xy 294.571945 -399.179268) (xy 294.533851 -399.234903)
			(xy 294.511984 -399.260568) (xy 294.506174 -399.267704) (xy 294.499668 -399.284902) (xy 294.499284 -399.294096)
			(xy 294.499284 -399.451576) (xy 294.498864 -399.461699) (xy 294.491121 -399.480405) (xy 294.476805 -399.494721)
			(xy 294.458099 -399.502464) (xy 294.447976 -399.502884) (xy 293.731696 -399.502884) (xy 293.721571 -399.502487)
			(xy 293.702865 -399.494734) (xy 293.68855 -399.480412) (xy 293.680808 -399.461701) (xy 293.680388 -399.451576)
			(xy 293.680388 -399.294096) (xy 293.679982 -399.284908) (xy 293.673466 -399.267724) (xy 293.667688 -399.260568)
			(xy 293.64586 -399.234873) (xy 293.607771 -399.179243) (xy 293.576619 -399.119451) (xy 293.552854 -399.056358)
			(xy 293.536816 -398.990872) (xy 293.528737 -398.923937) (xy 293.528734 -398.856517) (xy 293.536806 -398.789581)
			(xy 293.552838 -398.724094) (xy 293.576597 -398.660999) (xy 293.607743 -398.601204) (xy 293.645827 -398.545569)
			(xy 293.667688 -398.519904) (xy 293.673464 -398.512744) (xy 293.679991 -398.495565) (xy 293.680388 -398.486376)
			(xy 293.680388 -397.99387) (xy 293.679995 -397.984681) (xy 293.673469 -397.967497) (xy 293.667688 -397.960342)
			(xy 293.645834 -397.934668) (xy 293.607746 -397.879035) (xy 293.576596 -397.81924) (xy 293.552831 -397.756144)
			(xy 293.536796 -397.690656) (xy 293.528719 -397.623719) (xy 293.528718 -397.556296) (xy 292.40047 -397.556296)
			(xy 292.403082 -397.561322) (xy 292.426757 -397.624322) (xy 292.442733 -397.689701) (xy 292.450781 -397.75652)
			(xy 292.450784 -397.823823) (xy 292.442744 -397.890643) (xy 292.426774 -397.956023) (xy 292.403105 -398.019026)
			(xy 292.372075 -398.078748) (xy 292.33413 -398.134334) (xy 292.312344 -398.159986) (xy 292.306522 -398.167113)
			(xy 292.300024 -398.184318) (xy 292.299644 -398.193514) (xy 292.299644 -398.351502) (xy 292.299237 -398.361676)
			(xy 292.291448 -398.380474) (xy 292.277057 -398.39486) (xy 292.258256 -398.402641) (xy 292.248082 -398.403064)
			(xy 291.531802 -398.403064) (xy 291.521645 -398.402565) (xy 291.502876 -398.394792) (xy 291.488511 -398.380427)
			(xy 291.480736 -398.361659) (xy 291.48024 -398.351502) (xy 291.48024 -398.193514) (xy 291.479814 -398.184329)
			(xy 291.473311 -398.167145) (xy 291.46754 -398.159986) (xy 291.445715 -398.134365) (xy 291.407767 -398.078774)
			(xy 291.376735 -398.019046) (xy 291.353065 -397.956037) (xy 291.337094 -397.890651) (xy 291.329053 -397.823825)
			(xy 290.200388 -397.823825) (xy 290.171931 -397.878594) (xy 290.133983 -397.934181) (xy 290.112196 -397.959834)
			(xy 290.106402 -397.966981) (xy 290.099886 -397.98417) (xy 290.099496 -397.993362) (xy 290.099496 -398.486884)
			(xy 290.099915 -398.49607) (xy 290.106423 -398.513255) (xy 290.112196 -398.520412) (xy 290.134018 -398.546036)
			(xy 290.171963 -398.601627) (xy 290.202993 -398.661355) (xy 290.226662 -398.724363) (xy 290.242632 -398.789748)
			(xy 290.250673 -398.856573) (xy 290.250669 -398.923881) (xy 290.242622 -398.990705) (xy 290.226646 -399.056089)
			(xy 290.202971 -399.119095) (xy 290.171936 -399.17882) (xy 290.133985 -399.234407) (xy 290.112196 -399.26006)
			(xy 290.106391 -399.267199) (xy 290.099881 -399.284394) (xy 290.099496 -399.293588) (xy 290.099496 -399.451576)
			(xy 290.099059 -399.461729) (xy 290.09127 -399.480482) (xy 290.076878 -399.494806) (xy 290.058089 -399.502506)
			(xy 290.047934 -399.502884) (xy 289.331654 -399.502884) (xy 289.321527 -399.502412) (xy 289.30281 -399.494673)
			(xy 289.288456 -399.480383) (xy 289.280634 -399.4617) (xy 289.280092 -399.451576) (xy 289.280092 -399.293588)
			(xy 289.279689 -399.2844) (xy 289.273171 -399.267216) (xy 289.267392 -399.26006) (xy 289.245638 -399.234379)
			(xy 289.207685 -399.178798) (xy 289.176647 -399.119079) (xy 289.15297 -399.056078) (xy 289.136993 -398.990699)
			(xy 289.128945 -398.923879) (xy 289.128942 -398.856575) (xy 289.136983 -398.789754) (xy 289.152954 -398.724374)
			(xy 289.176625 -398.66137) (xy 289.207657 -398.601648) (xy 289.245605 -398.546063) (xy 289.267392 -398.520412)
			(xy 289.273208 -398.51328) (xy 289.279711 -398.496079) (xy 289.280092 -398.486884) (xy 289.280092 -397.993362)
			(xy 289.279702 -397.984173) (xy 289.273175 -397.966988) (xy 289.267392 -397.959834) (xy 289.245612 -397.934174)
			(xy 289.20766 -397.87859) (xy 289.176623 -397.818868) (xy 289.152948 -397.755865) (xy 289.136972 -397.690483)
			(xy 289.128927 -397.62366) (xy 289.128926 -397.556355) (xy 288.000733 -397.556355) (xy 288.003125 -397.560946)
			(xy 288.026894 -397.624039) (xy 288.042933 -397.689525) (xy 288.051013 -397.756461) (xy 288.051016 -397.823882)
			(xy 288.042944 -397.890819) (xy 288.026911 -397.956307) (xy 288.003148 -398.019402) (xy 287.971999 -398.079197)
			(xy 287.933912 -398.13483) (xy 287.912048 -398.160494) (xy 287.906265 -398.167649) (xy 287.899744 -398.184832)
			(xy 287.899348 -398.194022) (xy 287.899348 -398.351502) (xy 287.898875 -398.36163) (xy 287.891144 -398.380354)
			(xy 287.876853 -398.39471) (xy 287.858166 -398.402527) (xy 287.84804 -398.403064) (xy 287.13176 -398.403064)
			(xy 287.121599 -398.40271) (xy 287.102839 -398.394895) (xy 287.088515 -398.380477) (xy 287.080824 -398.361666)
			(xy 287.080452 -398.351502) (xy 287.080452 -398.194022) (xy 287.08002 -398.184837) (xy 287.07352 -398.167653)
			(xy 287.067752 -398.160494) (xy 287.045849 -398.13486) (xy 287.007758 -398.079223) (xy 286.976606 -398.019423)
			(xy 286.952842 -397.956321) (xy 286.936807 -397.890828) (xy 286.928734 -397.823885) (xy 270.510088 -397.823885)
			(xy 270.342048 -397.902798) (xy 270.153023 -397.982721) (xy 269.961023 -398.055207) (xy 269.766341 -398.120147)
			(xy 269.569274 -398.177442) (xy 269.370121 -398.227005) (xy 269.169187 -398.26876) (xy 268.966776 -398.302643)
			(xy 268.763198 -398.328603) (xy 268.558761 -398.3466) (xy 268.353778 -398.356608) (xy 268.148561 -398.35861)
			(xy 267.943422 -398.352604) (xy 267.738673 -398.338599) (xy 267.534626 -398.316616) (xy 267.331593 -398.286689)
			(xy 267.129882 -398.248862) (xy 266.9298 -398.203195) (xy 266.731653 -398.149756) (xy 266.535741 -398.088627)
			(xy 266.342364 -398.019901) (xy 266.151815 -397.943682) (xy 265.964385 -397.860086) (xy 265.780359 -397.769242)
			(xy 265.600018 -397.671287) (xy 265.423636 -397.56637) (xy 265.251482 -397.454651) (xy 265.083817 -397.336301)
			(xy 264.920898 -397.211499) (xy 264.762972 -397.080435) (xy 264.61028 -396.94331) (xy 264.463055 -396.800332)
			(xy 264.32152 -396.651718) (xy 264.185891 -396.497696) (xy 264.056374 -396.338499) (xy 263.933168 -396.17437)
			(xy 263.816459 -396.005559) (xy 263.706425 -395.832322) (xy 263.603234 -395.654925) (xy 263.507043 -395.473637)
			(xy 263.417998 -395.288734) (xy 263.336235 -395.100497) (xy 263.261879 -394.909214) (xy 263.195043 -394.715175)
			(xy 263.135828 -394.518676) (xy 263.084325 -394.320017) (xy 263.040611 -394.119499) (xy 263.004755 -393.917428)
			(xy 262.97681 -393.714113) (xy 262.956819 -393.509862) (xy 262.944812 -393.304986) (xy 262.940808 -393.099798)
			(xy 244.446806 -393.099798) (xy 244.446806 -399.877788) (xy 244.446318 -399.902738) (xy 244.438514 -399.952023)
			(xy 244.423096 -399.999481) (xy 244.400444 -400.043942) (xy 244.371115 -400.084313) (xy 244.353842 -400.102324)
			(xy 243.288058 -401.168108) (xy 243.270059 -401.185391) (xy 243.229675 -401.214698) (xy 243.185209 -401.237337)
			(xy 243.137752 -401.252752) (xy 243.08847 -401.260565) (xy 243.063522 -401.261072) (xy 239.143794 -401.261072)
			(xy 239.133724 -401.261495) (xy 239.115118 -401.269208) (xy 239.107726 -401.276058) (xy 238.659987 -401.723797)
			(xy 286.928745 -401.723797) (xy 286.928747 -401.65637) (xy 286.936826 -401.58943) (xy 286.952865 -401.523939)
			(xy 286.976634 -401.460841) (xy 287.00779 -401.401044) (xy 287.045885 -401.34541) (xy 287.067752 -401.319746)
			(xy 287.07356 -401.312609) (xy 287.080067 -401.295412) (xy 287.080452 -401.286218) (xy 287.080452 -400.793966)
			(xy 287.080046 -400.784779) (xy 287.073528 -400.767595) (xy 287.067752 -400.760438) (xy 287.045892 -400.734769)
			(xy 287.0078 -400.679136) (xy 286.976646 -400.619341) (xy 286.952879 -400.556244) (xy 286.936842 -400.490755)
			(xy 286.928764 -400.423817) (xy 286.928764 -400.356392) (xy 286.93684 -400.289454) (xy 286.952876 -400.223964)
			(xy 286.976642 -400.160867) (xy 287.007795 -400.101072) (xy 287.045887 -400.045438) (xy 287.067752 -400.019774)
			(xy 287.073549 -400.012629) (xy 287.080062 -399.995438) (xy 287.080452 -399.986246) (xy 287.080452 -399.828766)
			(xy 287.080899 -399.818636) (xy 287.08864 -399.799911) (xy 287.102939 -399.785556) (xy 287.121632 -399.77774)
			(xy 287.13176 -399.777204) (xy 287.84804 -399.777204) (xy 287.858197 -399.777589) (xy 287.876951 -399.785399)
			(xy 287.891273 -399.799806) (xy 287.898971 -399.818606) (xy 287.899348 -399.828766) (xy 287.899348 -399.986246)
			(xy 287.899796 -399.995429) (xy 287.906285 -400.012613) (xy 287.912048 -400.019774) (xy 287.93392 -400.045433)
			(xy 287.972012 -400.101068) (xy 288.003165 -400.160864) (xy 288.026931 -400.223962) (xy 288.042968 -400.289452)
			(xy 288.051044 -400.356392) (xy 288.051043 -400.423817) (xy 288.042966 -400.490757) (xy 288.026928 -400.556247)
			(xy 288.003161 -400.619344) (xy 287.972007 -400.67914) (xy 287.933914 -400.734774) (xy 287.912048 -400.760438)
			(xy 287.906246 -400.767579) (xy 287.899736 -400.784773) (xy 287.899348 -400.793966) (xy 287.899348 -401.286218)
			(xy 287.899761 -401.295405) (xy 287.906274 -401.312588) (xy 287.912048 -401.319746) (xy 287.933892 -401.345428)
			(xy 287.971985 -401.401059) (xy 288.00314 -401.460852) (xy 288.026907 -401.523947) (xy 288.042946 -401.589435)
			(xy 288.051024 -401.656372) (xy 288.051026 -401.723795) (xy 288.042952 -401.790733) (xy 288.026917 -401.856221)
			(xy 288.003153 -401.919317) (xy 287.972002 -401.979113) (xy 287.933912 -402.034746) (xy 287.912048 -402.06041)
			(xy 287.906258 -402.06756) (xy 287.899741 -402.084747) (xy 287.899348 -402.093938) (xy 287.899348 -402.251418)
			(xy 287.898888 -402.261547) (xy 287.891152 -402.280271) (xy 287.876858 -402.294627) (xy 287.858167 -402.302444)
			(xy 287.84804 -402.30298) (xy 287.13176 -402.30298) (xy 287.121601 -402.302611) (xy 287.102844 -402.294798)
			(xy 287.088521 -402.280385) (xy 287.080826 -402.26158) (xy 287.080452 -402.251418) (xy 287.080452 -402.093938)
			(xy 287.080012 -402.084754) (xy 287.073518 -402.06757) (xy 287.067752 -402.06041) (xy 287.045865 -402.034763)
			(xy 287.007773 -401.979127) (xy 286.97662 -401.919329) (xy 286.952855 -401.85623) (xy 286.93682 -401.790738)
			(xy 286.928745 -401.723797) (xy 238.659987 -401.723797) (xy 237.559965 -402.823819) (xy 289.128886 -402.823819)
			(xy 289.12889 -402.756509) (xy 289.13694 -402.689682) (xy 289.15292 -402.624297) (xy 289.1766 -402.56129)
			(xy 289.207642 -402.501565) (xy 289.2456 -402.445979) (xy 289.267392 -402.420328) (xy 289.273201 -402.413191)
			(xy 289.279708 -402.395994) (xy 289.280092 -402.3868) (xy 289.280092 -401.893532) (xy 289.279668 -401.884346)
			(xy 289.273164 -401.867162) (xy 289.267392 -401.860004) (xy 289.245583 -401.834369) (xy 289.207631 -401.778781)
			(xy 289.176596 -401.719056) (xy 289.152922 -401.656049) (xy 289.136949 -401.590664) (xy 289.128906 -401.523839)
			(xy 289.128907 -401.456531) (xy 289.136954 -401.389706) (xy 289.152931 -401.324322) (xy 289.176608 -401.261317)
			(xy 289.207647 -401.201593) (xy 289.245601 -401.146007) (xy 289.267392 -401.120356) (xy 289.273189 -401.113211)
			(xy 289.279704 -401.09602) (xy 289.280092 -401.086828) (xy 289.280092 -400.92884) (xy 289.280554 -400.918689)
			(xy 289.288335 -400.89994) (xy 289.30272 -400.885615) (xy 289.321502 -400.877913) (xy 289.331654 -400.877532)
			(xy 290.047934 -400.877532) (xy 290.058062 -400.877998) (xy 290.076782 -400.885736) (xy 290.091137 -400.900028)
			(xy 290.098957 -400.918714) (xy 290.099496 -400.92884) (xy 290.099496 -401.086828) (xy 290.099893 -401.096017)
			(xy 290.106416 -401.113201) (xy 290.112196 -401.120356) (xy 290.133963 -401.146025) (xy 290.17191 -401.20161)
			(xy 290.202942 -401.261331) (xy 290.226615 -401.324334) (xy 290.242588 -401.389713) (xy 290.250633 -401.456534)
			(xy 290.250635 -401.523836) (xy 290.242593 -401.590657) (xy 290.226624 -401.656038) (xy 290.202955 -401.719041)
			(xy 290.200515 -401.723737) (xy 291.329064 -401.723737) (xy 291.329066 -401.65643) (xy 291.337113 -401.589606)
			(xy 291.353088 -401.524222) (xy 291.376763 -401.461217) (xy 291.407799 -401.401493) (xy 291.445751 -401.345906)
			(xy 291.46754 -401.320254) (xy 291.473344 -401.313114) (xy 291.479853 -401.295919) (xy 291.48024 -401.286726)
			(xy 291.48024 -400.793458) (xy 291.479841 -400.78427) (xy 291.473319 -400.767086) (xy 291.46754 -400.75993)
			(xy 291.445758 -400.734273) (xy 291.407809 -400.678687) (xy 291.376776 -400.618964) (xy 291.353103 -400.55596)
			(xy 291.337129 -400.490579) (xy 291.329085 -400.423757) (xy 291.329084 -400.356452) (xy 291.337128 -400.28963)
			(xy 291.3531 -400.224248) (xy 291.376772 -400.161244) (xy 291.407805 -400.101521) (xy 291.445753 -400.045934)
			(xy 291.46754 -400.020282) (xy 291.473332 -400.013134) (xy 291.479848 -399.995945) (xy 291.48024 -399.986754)
			(xy 291.48024 -399.828766) (xy 291.480706 -399.818606) (xy 291.488492 -399.799835) (xy 291.502866 -399.785471)
			(xy 291.521641 -399.777698) (xy 291.531802 -399.777204) (xy 292.248082 -399.777204) (xy 292.258234 -399.777747)
			(xy 292.276997 -399.785509) (xy 292.291361 -399.79986) (xy 292.299143 -399.818614) (xy 292.299644 -399.828766)
			(xy 292.299644 -399.986754) (xy 292.300089 -399.995937) (xy 292.30658 -400.013121) (xy 292.312344 -400.020282)
			(xy 292.334138 -400.045929) (xy 292.372088 -400.101516) (xy 292.403122 -400.16124) (xy 292.426795 -400.224245)
			(xy 292.442768 -400.289628) (xy 292.450812 -400.356452) (xy 292.450811 -400.423757) (xy 292.442766 -400.490581)
			(xy 292.426792 -400.555963) (xy 292.403118 -400.618968) (xy 292.372083 -400.678692) (xy 292.334132 -400.734278)
			(xy 292.312344 -400.75993) (xy 292.306545 -400.767073) (xy 292.300033 -400.784266) (xy 292.299644 -400.793458)
			(xy 292.299644 -401.286726) (xy 292.300054 -401.295913) (xy 292.306569 -401.313097) (xy 292.312344 -401.320254)
			(xy 292.33411 -401.345924) (xy 292.372061 -401.401507) (xy 292.403096 -401.461228) (xy 292.426771 -401.524231)
			(xy 292.442746 -401.589611) (xy 292.450792 -401.656432) (xy 292.450794 -401.723735) (xy 292.442752 -401.790557)
			(xy 292.426781 -401.855938) (xy 292.40311 -401.918941) (xy 292.372078 -401.978664) (xy 292.334131 -402.03425)
			(xy 292.312344 -402.059902) (xy 292.306557 -402.067054) (xy 292.300038 -402.084239) (xy 292.299644 -402.09343)
			(xy 292.299644 -402.251418) (xy 292.299181 -402.261579) (xy 292.291397 -402.280352) (xy 292.277022 -402.294718)
			(xy 292.258244 -402.302488) (xy 292.248082 -402.30298) (xy 291.531802 -402.30298) (xy 291.521647 -402.302465)
			(xy 291.502881 -402.294695) (xy 291.488516 -402.280336) (xy 291.480739 -402.261573) (xy 291.48024 -402.251418)
			(xy 291.48024 -402.09343) (xy 291.479806 -402.084246) (xy 291.473308 -402.067061) (xy 291.46754 -402.059902)
			(xy 291.44573 -402.034268) (xy 291.407782 -401.978679) (xy 291.37675 -401.918953) (xy 291.353078 -401.855946)
			(xy 291.337107 -401.790561) (xy 291.329064 -401.723737) (xy 290.200515 -401.723737) (xy 290.171926 -401.778764)
			(xy 290.133981 -401.834351) (xy 290.112196 -401.860004) (xy 290.106415 -401.86716) (xy 290.099891 -401.884342)
			(xy 290.099496 -401.893532) (xy 290.099496 -402.3868) (xy 290.099907 -402.395987) (xy 290.10642 -402.413171)
			(xy 290.112196 -402.420328) (xy 290.133935 -402.44602) (xy 290.171883 -402.501601) (xy 290.202916 -402.56132)
			(xy 290.22659 -402.624319) (xy 290.242566 -402.689696) (xy 290.250613 -402.756514) (xy 290.250617 -402.823814)
			(xy 290.250609 -402.823878) (xy 293.528678 -402.823878) (xy 293.528683 -402.75645) (xy 293.536763 -402.689509)
			(xy 293.552803 -402.624017) (xy 293.576572 -402.560919) (xy 293.607728 -402.501121) (xy 293.645822 -402.445485)
			(xy 293.667688 -402.41982) (xy 293.6735 -402.412685) (xy 293.680006 -402.395487) (xy 293.680388 -402.386292)
			(xy 293.680388 -401.89404) (xy 293.679961 -401.884854) (xy 293.67346 -401.86767) (xy 293.667688 -401.860512)
			(xy 293.645805 -401.834863) (xy 293.607717 -401.779226) (xy 293.576568 -401.719427) (xy 293.552806 -401.656328)
			(xy 293.536772 -401.590837) (xy 293.528698 -401.523897) (xy 293.5287 -401.456472) (xy 293.536777 -401.389533)
			(xy 293.552815 -401.324043) (xy 293.576581 -401.260945) (xy 293.607733 -401.201149) (xy 293.645823 -401.145513)
			(xy 293.667688 -401.119848) (xy 293.673488 -401.112705) (xy 293.680001 -401.095513) (xy 293.680388 -401.08632)
			(xy 293.680388 -400.92884) (xy 293.680849 -400.918722) (xy 293.688581 -400.900021) (xy 293.702884 -400.885706)
			(xy 293.721578 -400.877957) (xy 293.731696 -400.877532) (xy 294.447976 -400.877532) (xy 294.458101 -400.877936)
			(xy 294.47681 -400.885682) (xy 294.491127 -400.900003) (xy 294.498867 -400.918715) (xy 294.499284 -400.92884)
			(xy 294.499284 -401.08632) (xy 294.499688 -401.095508) (xy 294.506206 -401.112692) (xy 294.511984 -401.119848)
			(xy 294.533829 -401.145529) (xy 294.571919 -401.201161) (xy 294.603072 -401.260955) (xy 294.626838 -401.32405)
			(xy 294.642875 -401.389537) (xy 294.650953 -401.456474) (xy 294.650955 -401.523896) (xy 294.64288 -401.590833)
			(xy 294.626847 -401.656322) (xy 294.603084 -401.719418) (xy 294.600803 -401.723797) (xy 295.728833 -401.723797)
			(xy 295.728835 -401.65637) (xy 295.736913 -401.58943) (xy 295.752952 -401.523939) (xy 295.77672 -401.460841)
			(xy 295.807876 -401.401045) (xy 295.845969 -401.345411) (xy 295.867836 -401.319746) (xy 295.873643 -401.312608)
			(xy 295.88015 -401.295412) (xy 295.880536 -401.286218) (xy 295.880536 -400.793966) (xy 295.880134 -400.784778)
			(xy 295.873614 -400.767594) (xy 295.867836 -400.760438) (xy 295.845977 -400.734769) (xy 295.807885 -400.679135)
			(xy 295.776732 -400.61934) (xy 295.752966 -400.556244) (xy 295.736929 -400.490755) (xy 295.728852 -400.423816)
			(xy 295.728852 -400.356393) (xy 295.736928 -400.289454) (xy 295.752964 -400.223965) (xy 295.776729 -400.160868)
			(xy 295.807881 -400.101072) (xy 295.845971 -400.045439) (xy 295.867836 -400.019774) (xy 295.873631 -400.012628)
			(xy 295.880146 -399.995438) (xy 295.880536 -399.986246) (xy 295.880536 -399.828766) (xy 295.880999 -399.818638)
			(xy 295.888737 -399.799916) (xy 295.90303 -399.785561) (xy 295.921718 -399.777743) (xy 295.931844 -399.777204)
			(xy 296.648124 -399.777204) (xy 296.65828 -399.777602) (xy 296.677034 -399.785406) (xy 296.691357 -399.79981)
			(xy 296.699055 -399.818608) (xy 296.699432 -399.828766) (xy 296.699432 -399.986246) (xy 296.699883 -399.995429)
			(xy 296.70637 -400.012613) (xy 296.712132 -400.019774) (xy 296.734001 -400.045435) (xy 296.772087 -400.101071)
			(xy 296.803236 -400.160868) (xy 296.826998 -400.223965) (xy 296.843032 -400.289455) (xy 296.851107 -400.356393)
			(xy 296.851107 -400.423816) (xy 296.843031 -400.490754) (xy 296.826996 -400.556243) (xy 296.803232 -400.61934)
			(xy 296.772083 -400.679137) (xy 296.733995 -400.734772) (xy 296.712132 -400.760438) (xy 296.706329 -400.767578)
			(xy 296.69982 -400.784773) (xy 296.699432 -400.793966) (xy 296.699432 -401.286218) (xy 296.699849 -401.295404)
			(xy 296.70636 -401.312588) (xy 296.712132 -401.319746) (xy 296.733973 -401.34543) (xy 296.77206 -401.401062)
			(xy 296.80321 -401.460856) (xy 296.826974 -401.523951) (xy 296.84301 -401.589437) (xy 296.851088 -401.656373)
			(xy 296.85109 -401.723794) (xy 296.843016 -401.79073) (xy 296.826984 -401.856218) (xy 296.803224 -401.919314)
			(xy 296.772078 -401.979109) (xy 296.733994 -402.034744) (xy 296.712132 -402.06041) (xy 296.70634 -402.067558)
			(xy 296.699825 -402.084747) (xy 296.699432 -402.093938) (xy 296.699432 -402.251418) (xy 296.698988 -402.261549)
			(xy 296.691249 -402.280276) (xy 296.676949 -402.294633) (xy 296.658253 -402.302447) (xy 296.648124 -402.30298)
			(xy 295.931844 -402.30298) (xy 295.92169 -402.302542) (xy 295.902935 -402.294757) (xy 295.888609 -402.280365)
			(xy 295.880912 -402.261574) (xy 295.880536 -402.251418) (xy 295.880536 -402.093938) (xy 295.880099 -402.084754)
			(xy 295.873603 -402.06757) (xy 295.867836 -402.06041) (xy 295.845949 -402.034763) (xy 295.807859 -401.979127)
			(xy 295.776707 -401.919328) (xy 295.752942 -401.856229) (xy 295.736907 -401.790737) (xy 295.728833 -401.723797)
			(xy 294.600803 -401.723797) (xy 294.571935 -401.779213) (xy 294.533847 -401.834847) (xy 294.511984 -401.860512)
			(xy 294.506198 -401.867665) (xy 294.499678 -401.88485) (xy 294.499284 -401.89404) (xy 294.499284 -402.386292)
			(xy 294.499702 -402.395478) (xy 294.506211 -402.412662) (xy 294.511984 -402.41982) (xy 294.533801 -402.445524)
			(xy 294.571893 -402.501152) (xy 294.603046 -402.560943) (xy 294.626814 -402.624035) (xy 294.642853 -402.68952)
			(xy 294.650933 -402.756454) (xy 294.650937 -402.823819) (xy 297.928973 -402.823819) (xy 297.928978 -402.756509)
			(xy 297.937027 -402.689683) (xy 297.953006 -402.624297) (xy 297.976686 -402.561291) (xy 298.007727 -402.501566)
			(xy 298.045684 -402.445979) (xy 298.067476 -402.420328) (xy 298.073283 -402.41319) (xy 298.079792 -402.395994)
			(xy 298.080176 -402.3868) (xy 298.080176 -401.893532) (xy 298.079756 -401.884346) (xy 298.07325 -401.867161)
			(xy 298.067476 -401.860004) (xy 298.045668 -401.834368) (xy 298.007717 -401.77878) (xy 297.976683 -401.719055)
			(xy 297.953009 -401.656048) (xy 297.937037 -401.590664) (xy 297.928993 -401.523839) (xy 297.928995 -401.456531)
			(xy 297.937042 -401.389707) (xy 297.953018 -401.324323) (xy 297.976695 -401.261318) (xy 298.007732 -401.201594)
			(xy 298.045686 -401.146008) (xy 298.067476 -401.120356) (xy 298.073271 -401.113209) (xy 298.079787 -401.09602)
			(xy 298.080176 -401.086828) (xy 298.080176 -400.92884) (xy 298.080654 -400.918691) (xy 298.088432 -400.899945)
			(xy 298.102811 -400.885621) (xy 298.121588 -400.877915) (xy 298.131738 -400.877532) (xy 298.848018 -400.877532)
			(xy 298.858145 -400.878011) (xy 298.876865 -400.885744) (xy 298.89122 -400.900032) (xy 298.89904 -400.918716)
			(xy 298.89958 -400.92884) (xy 298.89958 -401.086828) (xy 298.899981 -401.096016) (xy 298.906502 -401.1132)
			(xy 298.91228 -401.120356) (xy 298.934048 -401.146024) (xy 298.971996 -401.201609) (xy 299.003029 -401.261331)
			(xy 299.026702 -401.324333) (xy 299.042676 -401.389713) (xy 299.050721 -401.456533) (xy 299.050723 -401.523837)
			(xy 299.042681 -401.590657) (xy 299.026711 -401.656038) (xy 299.003041 -401.719042) (xy 299.000571 -401.723796)
			(xy 300.128624 -401.723796) (xy 300.128626 -401.656371) (xy 300.136704 -401.58943) (xy 300.152743 -401.52394)
			(xy 300.17651 -401.460842) (xy 300.207665 -401.401045) (xy 300.245758 -401.345411) (xy 300.267624 -401.319746)
			(xy 300.273429 -401.312607) (xy 300.279938 -401.295412) (xy 300.280324 -401.286218) (xy 300.280324 -400.793966)
			(xy 300.279925 -400.784778) (xy 300.273403 -400.767594) (xy 300.267624 -400.760438) (xy 300.245765 -400.734768)
			(xy 300.207675 -400.679135) (xy 300.176522 -400.61934) (xy 300.152757 -400.556243) (xy 300.13672 -400.490755)
			(xy 300.128643 -400.423816) (xy 300.128643 -400.356393) (xy 300.136719 -400.289454) (xy 300.152754 -400.223965)
			(xy 300.176519 -400.160869) (xy 300.20767 -400.101073) (xy 300.24576 -400.045439) (xy 300.267624 -400.019774)
			(xy 300.273417 -400.012626) (xy 300.279933 -399.995438) (xy 300.280324 -399.986246) (xy 300.280324 -399.828766)
			(xy 300.280798 -399.818639) (xy 300.288534 -399.79992) (xy 300.302824 -399.785566) (xy 300.321507 -399.777745)
			(xy 300.331632 -399.777204) (xy 301.047912 -399.777204) (xy 301.058067 -399.777612) (xy 301.076821 -399.785412)
			(xy 301.091144 -399.799813) (xy 301.098843 -399.818608) (xy 301.09922 -399.828766) (xy 301.09922 -399.986246)
			(xy 301.099652 -399.995431) (xy 301.10615 -400.012616) (xy 301.11192 -400.019774) (xy 301.133789 -400.045435)
			(xy 301.171876 -400.10107) (xy 301.203026 -400.160867) (xy 301.226789 -400.223965) (xy 301.242823 -400.289454)
			(xy 301.250898 -400.356393) (xy 301.250898 -400.423816) (xy 301.242821 -400.490755) (xy 301.226786 -400.556244)
			(xy 301.203022 -400.619341) (xy 301.171872 -400.679137) (xy 301.133784 -400.734772) (xy 301.11192 -400.760438)
			(xy 301.106127 -400.767586) (xy 301.09961 -400.784774) (xy 301.09922 -400.793966) (xy 301.09922 -401.286218)
			(xy 301.099617 -401.295407) (xy 301.106139 -401.312591) (xy 301.11192 -401.319746) (xy 301.133762 -401.345429)
			(xy 301.17185 -401.401062) (xy 301.203 -401.460856) (xy 301.226765 -401.52395) (xy 301.242801 -401.589437)
			(xy 301.250878 -401.656373) (xy 301.25088 -401.723794) (xy 301.242807 -401.790731) (xy 301.226775 -401.856218)
			(xy 301.203014 -401.919314) (xy 301.171867 -401.97911) (xy 301.133782 -402.034744) (xy 301.11192 -402.06041)
			(xy 301.106139 -402.067566) (xy 301.099614 -402.084748) (xy 301.09922 -402.093938) (xy 301.09922 -402.251418)
			(xy 301.098787 -402.261551) (xy 301.091046 -402.28028) (xy 301.076743 -402.294637) (xy 301.058043 -402.302449)
			(xy 301.047912 -402.30298) (xy 300.331632 -402.30298) (xy 300.321477 -402.302552) (xy 300.302722 -402.294763)
			(xy 300.288396 -402.280368) (xy 300.280699 -402.261575) (xy 300.280324 -402.251418) (xy 300.280324 -402.093938)
			(xy 300.27989 -402.084753) (xy 300.273392 -402.067569) (xy 300.267624 -402.06041) (xy 300.245738 -402.034763)
			(xy 300.207648 -401.979126) (xy 300.176497 -401.919328) (xy 300.152733 -401.856229) (xy 300.136698 -401.790737)
			(xy 300.128624 -401.723796) (xy 299.000571 -401.723796) (xy 298.972011 -401.778765) (xy 298.934066 -401.834352)
			(xy 298.91228 -401.860004) (xy 298.906497 -401.867159) (xy 298.899975 -401.884342) (xy 298.89958 -401.893532)
			(xy 298.89958 -402.3868) (xy 298.899994 -402.395987) (xy 298.906505 -402.413171) (xy 298.91228 -402.420328)
			(xy 298.93402 -402.446019) (xy 298.971969 -402.501601) (xy 299.003003 -402.561319) (xy 299.026678 -402.624318)
			(xy 299.042653 -402.689696) (xy 299.050701 -402.756513) (xy 299.050705 -402.823814) (xy 299.050697 -402.823877)
			(xy 302.328766 -402.823877) (xy 302.328771 -402.75645) (xy 302.336851 -402.689509) (xy 302.35289 -402.624018)
			(xy 302.376659 -402.560919) (xy 302.407814 -402.501122) (xy 302.445906 -402.445486) (xy 302.467772 -402.41982)
			(xy 302.473594 -402.412693) (xy 302.480091 -402.395488) (xy 302.480472 -402.386292) (xy 302.480472 -401.89404)
			(xy 302.480049 -401.884854) (xy 302.473545 -401.867669) (xy 302.467772 -401.860512) (xy 302.445889 -401.834863)
			(xy 302.407803 -401.779225) (xy 302.376655 -401.719426) (xy 302.352893 -401.656328) (xy 302.33686 -401.590837)
			(xy 302.328786 -401.523897) (xy 302.328788 -401.456473) (xy 302.336865 -401.389534) (xy 302.352902 -401.324044)
			(xy 302.376667 -401.260946) (xy 302.407819 -401.201149) (xy 302.445908 -401.145514) (xy 302.467772 -401.119848)
			(xy 302.473582 -401.112713) (xy 302.480087 -401.095514) (xy 302.480472 -401.08632) (xy 302.480472 -400.92884)
			(xy 302.480948 -400.918724) (xy 302.488678 -400.900026) (xy 302.502976 -400.885712) (xy 302.521664 -400.87796)
			(xy 302.53178 -400.877532) (xy 303.24806 -400.877532) (xy 303.258184 -400.87795) (xy 303.276893 -400.885691)
			(xy 303.291209 -400.900007) (xy 303.29895 -400.918716) (xy 303.299368 -400.92884) (xy 303.299368 -401.08632)
			(xy 303.299776 -401.095507) (xy 303.306292 -401.112691) (xy 303.312068 -401.119848) (xy 303.333913 -401.145529)
			(xy 303.372005 -401.20116) (xy 303.403158 -401.260954) (xy 303.426925 -401.324049) (xy 303.442963 -401.389537)
			(xy 303.451041 -401.456474) (xy 303.451043 -401.523896) (xy 303.442968 -401.590834) (xy 303.426934 -401.656322)
			(xy 303.40317 -401.719418) (xy 303.37202 -401.779214) (xy 303.333932 -401.834847) (xy 303.312068 -401.860512)
			(xy 303.30628 -401.867663) (xy 303.299761 -401.884849) (xy 303.299368 -401.89404) (xy 303.299368 -402.386292)
			(xy 303.299789 -402.395478) (xy 303.306296 -402.412662) (xy 303.312068 -402.41982) (xy 303.333886 -402.445524)
			(xy 303.371978 -402.501152) (xy 303.403133 -402.560942) (xy 303.426901 -402.624034) (xy 303.442941 -402.689519)
			(xy 303.451021 -402.756454) (xy 303.451025 -402.823874) (xy 303.442954 -402.89081) (xy 303.426922 -402.956297)
			(xy 303.403162 -403.019392) (xy 303.372015 -403.079186) (xy 303.33393 -403.134819) (xy 303.312068 -403.160484)
			(xy 303.306249 -403.167613) (xy 303.299749 -403.184816) (xy 303.299368 -403.194012) (xy 303.299368 -403.351492)
			(xy 303.298977 -403.361618) (xy 303.291225 -403.380328) (xy 303.276901 -403.394643) (xy 303.258186 -403.402383)
			(xy 303.24806 -403.4028) (xy 302.53178 -403.4028) (xy 302.52167 -403.402331) (xy 302.502991 -403.394587)
			(xy 302.488697 -403.380285) (xy 302.480963 -403.361602) (xy 302.480472 -403.351492) (xy 302.480472 -403.194012)
			(xy 302.480062 -403.184825) (xy 302.473549 -403.16764) (xy 302.467772 -403.160484) (xy 302.445862 -403.134857)
			(xy 302.407776 -403.079216) (xy 302.376629 -403.019415) (xy 302.352869 -402.956313) (xy 302.336838 -402.890819)
			(xy 302.328766 -402.823877) (xy 299.050697 -402.823877) (xy 299.042666 -402.890633) (xy 299.026699 -402.956013)
			(xy 299.003032 -403.019015) (xy 298.972006 -403.078737) (xy 298.934064 -403.134323) (xy 298.91228 -403.159976)
			(xy 298.906466 -403.167109) (xy 298.899963 -403.184309) (xy 298.89958 -403.193504) (xy 298.89958 -403.351492)
			(xy 298.899171 -403.361648) (xy 298.891375 -403.380404) (xy 298.876974 -403.394729) (xy 298.858176 -403.402425)
			(xy 298.848018 -403.4028) (xy 298.131738 -403.4028) (xy 298.121619 -403.402243) (xy 298.102906 -403.394535)
			(xy 298.08855 -403.380271) (xy 298.080722 -403.361608) (xy 298.080176 -403.351492) (xy 298.080176 -403.193504)
			(xy 298.079769 -403.184316) (xy 298.073254 -403.167132) (xy 298.067476 -403.159976) (xy 298.04564 -403.134363)
			(xy 298.00769 -403.078772) (xy 297.976657 -403.019043) (xy 297.952985 -402.956034) (xy 297.937014 -402.890646)
			(xy 297.928973 -402.823819) (xy 294.650937 -402.823819) (xy 294.650937 -402.823874) (xy 294.642866 -402.890809)
			(xy 294.626835 -402.956296) (xy 294.603076 -403.019391) (xy 294.57193 -403.079186) (xy 294.533846 -403.134819)
			(xy 294.511984 -403.160484) (xy 294.506167 -403.167615) (xy 294.499665 -403.184816) (xy 294.499284 -403.194012)
			(xy 294.499284 -403.351492) (xy 294.498877 -403.361616) (xy 294.491129 -403.380322) (xy 294.476809 -403.394638)
			(xy 294.4581 -403.40238) (xy 294.447976 -403.4028) (xy 293.731696 -403.4028) (xy 293.721573 -403.402387)
			(xy 293.70287 -403.394638) (xy 293.688556 -403.38032) (xy 293.68081 -403.361615) (xy 293.680388 -403.351492)
			(xy 293.680388 -403.194012) (xy 293.679975 -403.184825) (xy 293.673464 -403.167641) (xy 293.667688 -403.160484)
			(xy 293.645777 -403.134857) (xy 293.607691 -403.079217) (xy 293.576543 -403.019415) (xy 293.552782 -402.956314)
			(xy 293.53675 -402.89082) (xy 293.528678 -402.823878) (xy 290.250609 -402.823878) (xy 290.242579 -402.890633)
			(xy 290.226612 -402.956012) (xy 290.202946 -403.019014) (xy 290.17192 -403.078737) (xy 290.133979 -403.134323)
			(xy 290.112196 -403.159976) (xy 290.106384 -403.16711) (xy 290.099879 -403.184309) (xy 290.099496 -403.193504)
			(xy 290.099496 -403.351492) (xy 290.099072 -403.361646) (xy 290.091278 -403.380399) (xy 290.076882 -403.394723)
			(xy 290.05809 -403.402422) (xy 290.047934 -403.4028) (xy 289.331654 -403.4028) (xy 289.321529 -403.402312)
			(xy 289.302815 -403.394577) (xy 289.288461 -403.380292) (xy 289.280637 -403.361614) (xy 289.280092 -403.351492)
			(xy 289.280092 -403.193504) (xy 289.279682 -403.184317) (xy 289.273168 -403.167132) (xy 289.267392 -403.159976)
			(xy 289.245556 -403.134363) (xy 289.207605 -403.078772) (xy 289.176571 -403.019044) (xy 289.152898 -402.956034)
			(xy 289.136927 -402.890647) (xy 289.128886 -402.823819) (xy 237.559965 -402.823819) (xy 237.421928 -402.961856)
			(xy 237.415087 -402.969256) (xy 237.407369 -402.987855) (xy 237.406942 -402.997924) (xy 237.406942 -405.623708)
			(xy 286.928756 -405.623708) (xy 286.928757 -405.556283) (xy 286.936834 -405.489343) (xy 286.952872 -405.423853)
			(xy 286.976639 -405.360756) (xy 287.007793 -405.30096) (xy 287.045886 -405.245326) (xy 287.067752 -405.219662)
			(xy 287.073554 -405.212521) (xy 287.080064 -405.195327) (xy 287.080452 -405.186134) (xy 287.080452 -404.693882)
			(xy 287.080039 -404.684695) (xy 287.073526 -404.667512) (xy 287.067752 -404.660354) (xy 287.045908 -404.634672)
			(xy 287.007815 -404.579041) (xy 286.97666 -404.519248) (xy 286.952893 -404.456153) (xy 286.936854 -404.390665)
			(xy 286.928776 -404.323728) (xy 286.928774 -404.256305) (xy 286.936848 -404.189367) (xy 286.952883 -404.123879)
			(xy 286.976647 -404.060783) (xy 287.007798 -404.000987) (xy 287.045888 -403.945354) (xy 287.067752 -403.91969)
			(xy 287.073542 -403.91254) (xy 287.080059 -403.895353) (xy 287.080452 -403.886162) (xy 287.080452 -403.728682)
			(xy 287.080912 -403.718553) (xy 287.088648 -403.699829) (xy 287.102942 -403.685473) (xy 287.121633 -403.677656)
			(xy 287.13176 -403.67712) (xy 287.84804 -403.67712) (xy 287.858199 -403.677489) (xy 287.876956 -403.685302)
			(xy 287.891279 -403.699715) (xy 287.898974 -403.71852) (xy 287.899348 -403.728682) (xy 287.899348 -403.886162)
			(xy 287.899788 -403.895346) (xy 287.906282 -403.91253) (xy 287.912048 -403.91969) (xy 287.933935 -403.945337)
			(xy 287.972027 -404.000973) (xy 288.00318 -404.060771) (xy 288.026945 -404.12387) (xy 288.04298 -404.189362)
			(xy 288.051055 -404.256303) (xy 288.051053 -404.32373) (xy 288.042974 -404.39067) (xy 288.026935 -404.456161)
			(xy 288.003166 -404.519259) (xy 287.97201 -404.579056) (xy 287.933915 -404.63469) (xy 287.912048 -404.660354)
			(xy 287.90624 -404.667491) (xy 287.899733 -404.684688) (xy 287.899348 -404.693882) (xy 287.899348 -405.186134)
			(xy 287.899754 -405.195321) (xy 287.906272 -405.212505) (xy 287.912048 -405.219662) (xy 287.933908 -405.245331)
			(xy 287.972 -405.300964) (xy 288.003154 -405.360759) (xy 288.026921 -405.423856) (xy 288.042958 -405.489345)
			(xy 288.051036 -405.556283) (xy 288.051036 -405.623708) (xy 288.04296 -405.690646) (xy 288.026924 -405.756136)
			(xy 288.003158 -405.819233) (xy 287.972005 -405.879028) (xy 287.933913 -405.934662) (xy 287.912048 -405.960326)
			(xy 287.906251 -405.967471) (xy 287.899738 -405.984662) (xy 287.899348 -405.993854) (xy 287.899348 -406.151334)
			(xy 287.898901 -406.161464) (xy 287.89116 -406.180189) (xy 287.876861 -406.194544) (xy 287.858168 -406.20236)
			(xy 287.84804 -406.202896) (xy 287.13176 -406.202896) (xy 287.121603 -406.202511) (xy 287.102849 -406.194701)
			(xy 287.088527 -406.180294) (xy 287.080829 -406.161494) (xy 287.080452 -406.151334) (xy 287.080452 -405.993854)
			(xy 287.080004 -405.984671) (xy 287.073515 -405.967487) (xy 287.067752 -405.960326) (xy 287.04588 -405.934667)
			(xy 287.007788 -405.879032) (xy 286.976635 -405.819236) (xy 286.952869 -405.756138) (xy 286.936832 -405.690648)
			(xy 286.928756 -405.623708) (xy 237.406942 -405.623708) (xy 237.406942 -406.72373) (xy 289.128897 -406.72373)
			(xy 289.1289 -406.656422) (xy 289.136948 -406.589596) (xy 289.152926 -406.524211) (xy 289.176605 -406.461205)
			(xy 289.207645 -406.401481) (xy 289.245601 -406.345895) (xy 289.267392 -406.320244) (xy 289.273194 -406.313103)
			(xy 289.279706 -406.295909) (xy 289.280092 -406.286716) (xy 289.280092 -405.793448) (xy 289.279661 -405.784263)
			(xy 289.273162 -405.767078) (xy 289.267392 -405.75992) (xy 289.245599 -405.734272) (xy 289.207647 -405.678686)
			(xy 289.176611 -405.618962) (xy 289.152936 -405.555957) (xy 289.136961 -405.490574) (xy 289.128917 -405.42375)
			(xy 289.128917 -405.356444) (xy 289.136962 -405.28962) (xy 289.152937 -405.224237) (xy 289.176613 -405.161232)
			(xy 289.20765 -405.101509) (xy 289.245602 -405.045923) (xy 289.267392 -405.020272) (xy 289.273182 -405.013122)
			(xy 289.279701 -404.995935) (xy 289.280092 -404.986744) (xy 289.280092 -404.828756) (xy 289.280486 -404.8186)
			(xy 289.288294 -404.799848) (xy 289.302699 -404.785527) (xy 289.321496 -404.777827) (xy 289.331654 -404.777448)
			(xy 290.047934 -404.777448) (xy 290.058064 -404.777899) (xy 290.076787 -404.785639) (xy 290.091143 -404.799936)
			(xy 290.098959 -404.818628) (xy 290.099496 -404.828756) (xy 290.099496 -404.986744) (xy 290.099886 -404.995933)
			(xy 290.106414 -405.013117) (xy 290.112196 -405.020272) (xy 290.133979 -405.045928) (xy 290.171925 -405.101515)
			(xy 290.202957 -405.161238) (xy 290.226628 -405.224242) (xy 290.242601 -405.289623) (xy 290.250644 -405.356445)
			(xy 290.250645 -405.423749) (xy 290.242602 -405.490571) (xy 290.22663 -405.555952) (xy 290.202959 -405.618957)
			(xy 290.200522 -405.623648) (xy 291.329076 -405.623648) (xy 291.329076 -405.556343) (xy 291.337121 -405.48952)
			(xy 291.353095 -405.424137) (xy 291.376768 -405.361132) (xy 291.407802 -405.301409) (xy 291.445752 -405.245822)
			(xy 291.46754 -405.22017) (xy 291.473337 -405.213025) (xy 291.47985 -405.195834) (xy 291.48024 -405.186642)
			(xy 291.48024 -404.693374) (xy 291.479833 -404.684187) (xy 291.473316 -404.667003) (xy 291.46754 -404.659846)
			(xy 291.445774 -404.634176) (xy 291.407825 -404.578592) (xy 291.37679 -404.518871) (xy 291.353116 -404.455869)
			(xy 291.337142 -404.390489) (xy 291.329096 -404.323668) (xy 291.329094 -404.256365) (xy 291.337136 -404.189544)
			(xy 291.353106 -404.124163) (xy 291.376777 -404.061159) (xy 291.407808 -404.001436) (xy 291.445754 -403.94585)
			(xy 291.46754 -403.920198) (xy 291.473325 -403.913045) (xy 291.479846 -403.89586) (xy 291.48024 -403.88667)
			(xy 291.48024 -403.728682) (xy 291.480718 -403.718523) (xy 291.488499 -403.699753) (xy 291.50287 -403.685388)
			(xy 291.521643 -403.677615) (xy 291.531802 -403.67712) (xy 292.248082 -403.67712) (xy 292.258236 -403.677648)
			(xy 292.277002 -403.685413) (xy 292.291367 -403.699768) (xy 292.299145 -403.718528) (xy 292.299644 -403.728682)
			(xy 292.299644 -403.88667) (xy 292.300081 -403.895854) (xy 292.306577 -403.913038) (xy 292.312344 -403.920198)
			(xy 292.334154 -403.945832) (xy 292.372103 -404.001421) (xy 292.403137 -404.061147) (xy 292.426809 -404.124153)
			(xy 292.442781 -404.189538) (xy 292.450824 -404.256363) (xy 292.450822 -404.32367) (xy 292.442775 -404.390495)
			(xy 292.426799 -404.455878) (xy 292.403123 -404.518884) (xy 292.372086 -404.578608) (xy 292.334134 -404.634194)
			(xy 292.312344 -404.659846) (xy 292.306539 -404.666985) (xy 292.300031 -404.68418) (xy 292.299644 -404.693374)
			(xy 292.299644 -405.186642) (xy 292.300047 -405.19583) (xy 292.306567 -405.213013) (xy 292.312344 -405.22017)
			(xy 292.334126 -405.245827) (xy 292.372076 -405.301412) (xy 292.403111 -405.361135) (xy 292.426785 -405.424139)
			(xy 292.442758 -405.489521) (xy 292.450803 -405.556343) (xy 292.450804 -405.623648) (xy 292.44276 -405.69047)
			(xy 292.426787 -405.755852) (xy 292.403114 -405.818857) (xy 292.372081 -405.87858) (xy 292.334132 -405.934166)
			(xy 292.312344 -405.959818) (xy 292.30655 -405.966965) (xy 292.300035 -405.984154) (xy 292.299644 -405.993346)
			(xy 292.299644 -406.151334) (xy 292.299194 -406.161496) (xy 292.291405 -406.18027) (xy 292.277026 -406.194634)
			(xy 292.258245 -406.202404) (xy 292.248082 -406.202896) (xy 291.531802 -406.202896) (xy 291.521649 -406.202366)
			(xy 291.502886 -406.194598) (xy 291.488522 -406.180244) (xy 291.480741 -406.161487) (xy 291.48024 -406.151334)
			(xy 291.48024 -405.993346) (xy 291.479799 -405.984162) (xy 291.473306 -405.966978) (xy 291.46754 -405.959818)
			(xy 291.445746 -405.934171) (xy 291.407797 -405.878584) (xy 291.376764 -405.818859) (xy 291.353092 -405.755854)
			(xy 291.337119 -405.690471) (xy 291.329076 -405.623648) (xy 290.200522 -405.623648) (xy 290.171928 -405.67868)
			(xy 290.133982 -405.734267) (xy 290.112196 -405.75992) (xy 290.106408 -405.767071) (xy 290.099888 -405.784257)
			(xy 290.099496 -405.793448) (xy 290.099496 -406.286716) (xy 290.099899 -406.295904) (xy 290.106418 -406.313088)
			(xy 290.112196 -406.320244) (xy 290.133951 -406.345922) (xy 290.171899 -406.401506) (xy 290.202931 -406.461226)
			(xy 290.226605 -406.524227) (xy 290.242579 -406.589606) (xy 290.250625 -406.656425) (xy 290.250628 -406.723727)
			(xy 290.250621 -406.723789) (xy 293.52869 -406.723789) (xy 293.528692 -406.656363) (xy 293.536771 -406.589423)
			(xy 293.55281 -406.523932) (xy 293.576577 -406.460834) (xy 293.607731 -406.401037) (xy 293.645823 -406.345401)
			(xy 293.667688 -406.319736) (xy 293.673493 -406.312597) (xy 293.680003 -406.295402) (xy 293.680388 -406.286208)
			(xy 293.680388 -405.793956) (xy 293.680002 -405.784766) (xy 293.673472 -405.767582) (xy 293.667688 -405.760428)
			(xy 293.645821 -405.734766) (xy 293.607733 -405.679131) (xy 293.576583 -405.619334) (xy 293.552819 -405.556237)
			(xy 293.536785 -405.490747) (xy 293.528709 -405.423809) (xy 293.52871 -405.356385) (xy 293.536786 -405.289447)
			(xy 293.552821 -405.223958) (xy 293.576585 -405.160861) (xy 293.607736 -405.101064) (xy 293.645824 -405.045429)
			(xy 293.667688 -405.019764) (xy 293.673481 -405.012616) (xy 293.679998 -404.995428) (xy 293.680388 -404.986236)
			(xy 293.680388 -404.828756) (xy 293.680849 -404.818646) (xy 293.688599 -404.799969) (xy 293.702903 -404.785676)
			(xy 293.721586 -404.777941) (xy 293.731696 -404.777448) (xy 294.447976 -404.777448) (xy 294.458077 -404.778003)
			(xy 294.476745 -404.785723) (xy 294.491038 -404.799998) (xy 294.498783 -404.818656) (xy 294.499284 -404.828756)
			(xy 294.499284 -404.986236) (xy 294.49968 -404.995425) (xy 294.506204 -405.012609) (xy 294.511984 -405.019764)
			(xy 294.533845 -405.045432) (xy 294.571934 -405.101066) (xy 294.603086 -405.160862) (xy 294.626851 -405.223958)
			(xy 294.642888 -405.289447) (xy 294.650964 -405.356385) (xy 294.650964 -405.423809) (xy 294.642889 -405.490747)
			(xy 294.626853 -405.556236) (xy 294.603089 -405.619333) (xy 294.60081 -405.623708) (xy 295.728844 -405.623708)
			(xy 295.728845 -405.556283) (xy 295.736922 -405.489344) (xy 295.752959 -405.423854) (xy 295.776725 -405.360757)
			(xy 295.807879 -405.30096) (xy 295.84597 -405.245327) (xy 295.867836 -405.219662) (xy 295.873636 -405.212519)
			(xy 295.880148 -405.195327) (xy 295.880536 -405.186134) (xy 295.880536 -404.693882) (xy 295.880126 -404.684695)
			(xy 295.873611 -404.667511) (xy 295.867836 -404.660354) (xy 295.845992 -404.634672) (xy 295.807901 -404.57904)
			(xy 295.776747 -404.519247) (xy 295.75298 -404.456152) (xy 295.736942 -404.390665) (xy 295.728864 -404.323728)
			(xy 295.728862 -404.256305) (xy 295.736936 -404.189368) (xy 295.75297 -404.123879) (xy 295.776733 -404.060783)
			(xy 295.807884 -404.000988) (xy 295.845972 -403.945355) (xy 295.867836 -403.91969) (xy 295.873624 -403.912539)
			(xy 295.880143 -403.895353) (xy 295.880536 -403.886162) (xy 295.880536 -403.728682) (xy 295.881011 -403.718555)
			(xy 295.888744 -403.699834) (xy 295.903034 -403.685478) (xy 295.921719 -403.677659) (xy 295.931844 -403.67712)
			(xy 296.648124 -403.67712) (xy 296.658282 -403.677502) (xy 296.677039 -403.685309) (xy 296.691362 -403.699718)
			(xy 296.699058 -403.718521) (xy 296.699432 -403.728682) (xy 296.699432 -403.886162) (xy 296.699876 -403.895345)
			(xy 296.706368 -403.912529) (xy 296.712132 -403.91969) (xy 296.734016 -403.945338) (xy 296.772102 -404.000976)
			(xy 296.80325 -404.060775) (xy 296.827012 -404.123874) (xy 296.843045 -404.189364) (xy 296.851118 -404.256304)
			(xy 296.851117 -404.323729) (xy 296.843039 -404.390668) (xy 296.827002 -404.456158) (xy 296.803237 -404.519256)
			(xy 296.772085 -404.579053) (xy 296.733996 -404.634688) (xy 296.712132 -404.660354) (xy 296.706322 -404.667489)
			(xy 296.699817 -404.684688) (xy 296.699432 -404.693882) (xy 296.699432 -405.186134) (xy 296.699841 -405.195321)
			(xy 296.706357 -405.212505) (xy 296.712132 -405.219662) (xy 296.733989 -405.245333) (xy 296.772076 -405.300967)
			(xy 296.803225 -405.360763) (xy 296.826988 -405.423859) (xy 296.843023 -405.489347) (xy 296.851099 -405.556284)
			(xy 296.851099 -405.623707) (xy 296.843025 -405.690644) (xy 296.826991 -405.756132) (xy 296.803229 -405.819229)
			(xy 296.77208 -405.879025) (xy 296.733994 -405.93466) (xy 296.712132 -405.960326) (xy 296.706334 -405.96747)
			(xy 296.699822 -405.984662) (xy 296.699432 -405.993854) (xy 296.699432 -406.151334) (xy 296.699001 -406.161466)
			(xy 296.691256 -406.180194) (xy 296.676953 -406.19455) (xy 296.658254 -406.202363) (xy 296.648124 -406.202896)
			(xy 295.931844 -406.202896) (xy 295.921692 -406.202442) (xy 295.90294 -406.19466) (xy 295.888615 -406.180273)
			(xy 295.880915 -406.161487) (xy 295.880536 -406.151334) (xy 295.880536 -405.993854) (xy 295.880092 -405.984671)
			(xy 295.873601 -405.967486) (xy 295.867836 -405.960326) (xy 295.845965 -405.934666) (xy 295.807874 -405.879032)
			(xy 295.776722 -405.819235) (xy 295.752956 -405.756137) (xy 295.73692 -405.690647) (xy 295.728844 -405.623708)
			(xy 294.60081 -405.623708) (xy 294.571938 -405.679129) (xy 294.533848 -405.734763) (xy 294.511984 -405.760428)
			(xy 294.506191 -405.767576) (xy 294.499675 -405.784764) (xy 294.499284 -405.793956) (xy 294.499284 -406.286208)
			(xy 294.499694 -406.295395) (xy 294.506208 -406.312579) (xy 294.511984 -406.319736) (xy 294.533817 -406.345427)
			(xy 294.571908 -406.401057) (xy 294.603061 -406.46085) (xy 294.626827 -406.523943) (xy 294.642866 -406.58943)
			(xy 294.650944 -406.656365) (xy 294.650947 -406.72373) (xy 297.928985 -406.72373) (xy 297.928988 -406.656422)
			(xy 297.937036 -406.589596) (xy 297.953013 -406.524212) (xy 297.976691 -406.461206) (xy 298.00773 -406.401482)
			(xy 298.045685 -406.345896) (xy 298.067476 -406.320244) (xy 298.073276 -406.313101) (xy 298.079789 -406.295909)
			(xy 298.080176 -406.286716) (xy 298.080176 -405.793448) (xy 298.079748 -405.784263) (xy 298.073247 -405.767078)
			(xy 298.067476 -405.75992) (xy 298.045683 -405.734272) (xy 298.007732 -405.678685) (xy 297.976697 -405.618962)
			(xy 297.953023 -405.555957) (xy 297.937049 -405.490574) (xy 297.929005 -405.42375) (xy 297.929005 -405.356444)
			(xy 297.93705 -405.28962) (xy 297.953025 -405.224238) (xy 297.9767 -405.161233) (xy 298.007735 -405.101509)
			(xy 298.045687 -405.045924) (xy 298.067476 -405.020272) (xy 298.073264 -405.013121) (xy 298.079785 -404.995935)
			(xy 298.080176 -404.986744) (xy 298.080176 -404.828756) (xy 298.080585 -404.818602) (xy 298.088391 -404.799853)
			(xy 298.102791 -404.785532) (xy 298.121582 -404.77783) (xy 298.131738 -404.777448) (xy 298.848018 -404.777448)
			(xy 298.858147 -404.777912) (xy 298.87687 -404.785647) (xy 298.891226 -404.79994) (xy 298.899043 -404.818629)
			(xy 298.89958 -404.828756) (xy 298.89958 -404.986744) (xy 298.899973 -404.995933) (xy 298.906499 -405.013117)
			(xy 298.91228 -405.020272) (xy 298.934063 -405.045928) (xy 298.972011 -405.101514) (xy 299.003043 -405.161237)
			(xy 299.026716 -405.224241) (xy 299.042688 -405.289623) (xy 299.050732 -405.356445) (xy 299.050733 -405.423749)
			(xy 299.042689 -405.490571) (xy 299.026717 -405.555953) (xy 299.003046 -405.618957) (xy 299.000577 -405.623708)
			(xy 300.128635 -405.623708) (xy 300.128635 -405.556283) (xy 300.136712 -405.489344) (xy 300.152749 -405.423854)
			(xy 300.176515 -405.360757) (xy 300.207668 -405.300961) (xy 300.245759 -405.245327) (xy 300.267624 -405.219662)
			(xy 300.273422 -405.212518) (xy 300.279935 -405.195326) (xy 300.280324 -405.186134) (xy 300.280324 -404.693882)
			(xy 300.279917 -404.684695) (xy 300.273401 -404.66751) (xy 300.267624 -404.660354) (xy 300.245781 -404.634671)
			(xy 300.20769 -404.57904) (xy 300.176537 -404.519246) (xy 300.15277 -404.456152) (xy 300.136733 -404.390664)
			(xy 300.128655 -404.323728) (xy 300.128653 -404.256305) (xy 300.136727 -404.189368) (xy 300.152761 -404.12388)
			(xy 300.176523 -404.060784) (xy 300.207673 -404.000989) (xy 300.245761 -403.945355) (xy 300.267624 -403.91969)
			(xy 300.27341 -403.912538) (xy 300.27993 -403.895352) (xy 300.280324 -403.886162) (xy 300.280324 -403.728682)
			(xy 300.280811 -403.718556) (xy 300.288542 -403.699837) (xy 300.302828 -403.685482) (xy 300.321509 -403.677661)
			(xy 300.331632 -403.67712) (xy 301.047912 -403.67712) (xy 301.058069 -403.677512) (xy 301.076826 -403.685315)
			(xy 301.09115 -403.699721) (xy 301.098846 -403.718522) (xy 301.09922 -403.728682) (xy 301.09922 -403.886162)
			(xy 301.099644 -403.895348) (xy 301.106147 -403.912533) (xy 301.11192 -403.91969) (xy 301.133805 -403.945338)
			(xy 301.171892 -404.000975) (xy 301.20304 -404.060774) (xy 301.226802 -404.123873) (xy 301.242836 -404.189364)
			(xy 301.250909 -404.256304) (xy 301.250907 -404.323729) (xy 301.24283 -404.390668) (xy 301.226793 -404.456158)
			(xy 301.203027 -404.519256) (xy 301.171875 -404.579053) (xy 301.133785 -404.634688) (xy 301.11192 -404.660354)
			(xy 301.10612 -404.667497) (xy 301.099607 -404.684689) (xy 301.09922 -404.693882) (xy 301.09922 -405.186134)
			(xy 301.099609 -405.195323) (xy 301.106137 -405.212508) (xy 301.11192 -405.219662) (xy 301.133777 -405.245332)
			(xy 301.171865 -405.300967) (xy 301.203015 -405.360762) (xy 301.226778 -405.423859) (xy 301.242814 -405.489347)
			(xy 301.25089 -405.556284) (xy 301.25089 -405.623707) (xy 301.242815 -405.690644) (xy 301.226781 -405.756133)
			(xy 301.203018 -405.819229) (xy 301.17187 -405.879026) (xy 301.133783 -405.93466) (xy 301.11192 -405.960326)
			(xy 301.106132 -405.967478) (xy 301.099612 -405.984663) (xy 301.09922 -405.993854) (xy 301.09922 -406.151334)
			(xy 301.0988 -406.161468) (xy 301.091054 -406.180197) (xy 301.076747 -406.194554) (xy 301.058044 -406.202365)
			(xy 301.047912 -406.202896) (xy 300.331632 -406.202896) (xy 300.321479 -406.202452) (xy 300.302727 -406.194667)
			(xy 300.288402 -406.180276) (xy 300.280702 -406.161488) (xy 300.280324 -406.151334) (xy 300.280324 -405.993854)
			(xy 300.279882 -405.98467) (xy 300.27339 -405.967486) (xy 300.267624 -405.960326) (xy 300.245753 -405.934666)
			(xy 300.207663 -405.879031) (xy 300.176511 -405.819235) (xy 300.152747 -405.756137) (xy 300.136711 -405.690647)
			(xy 300.128635 -405.623708) (xy 299.000577 -405.623708) (xy 298.972014 -405.678681) (xy 298.934067 -405.734268)
			(xy 298.91228 -405.75992) (xy 298.90649 -405.76707) (xy 298.899972 -405.784257) (xy 298.89958 -405.793448)
			(xy 298.89958 -406.286716) (xy 298.899987 -406.295903) (xy 298.906503 -406.313088) (xy 298.91228 -406.320244)
			(xy 298.934035 -406.345922) (xy 298.971984 -406.401506) (xy 299.003018 -406.461226) (xy 299.026691 -406.524227)
			(xy 299.042666 -406.589606) (xy 299.050712 -406.656425) (xy 299.050715 -406.723727) (xy 299.050708 -406.723789)
			(xy 302.328777 -406.723789) (xy 302.32878 -406.656363) (xy 302.336859 -406.589423) (xy 302.352897 -406.523933)
			(xy 302.376664 -406.460835) (xy 302.407816 -406.401037) (xy 302.445907 -406.345402) (xy 302.467772 -406.319736)
			(xy 302.473587 -406.312604) (xy 302.480089 -406.295403) (xy 302.480472 -406.286208) (xy 302.480472 -405.793956)
			(xy 302.480089 -405.784766) (xy 302.473557 -405.767581) (xy 302.467772 -405.760428) (xy 302.445905 -405.734766)
			(xy 302.407818 -405.67913) (xy 302.376669 -405.619333) (xy 302.352907 -405.556236) (xy 302.336872 -405.490747)
			(xy 302.328797 -405.423809) (xy 302.328798 -405.356385) (xy 302.336873 -405.289447) (xy 302.352908 -405.223958)
			(xy 302.376672 -405.160861) (xy 302.407821 -405.101065) (xy 302.445909 -405.04543) (xy 302.467772 -405.019764)
			(xy 302.473575 -405.012624) (xy 302.480084 -404.995429) (xy 302.480472 -404.986236) (xy 302.480472 -404.828756)
			(xy 302.480948 -404.818648) (xy 302.488695 -404.799974) (xy 302.502994 -404.785682) (xy 302.521672 -404.777944)
			(xy 302.53178 -404.777448) (xy 303.24806 -404.777448) (xy 303.25816 -404.778017) (xy 303.276827 -404.785732)
			(xy 303.291121 -404.800002) (xy 303.298867 -404.818657) (xy 303.299368 -404.828756) (xy 303.299368 -404.986236)
			(xy 303.299768 -404.995424) (xy 303.30629 -405.012608) (xy 303.312068 -405.019764) (xy 303.333929 -405.045432)
			(xy 303.37202 -405.101065) (xy 303.403173 -405.160861) (xy 303.426939 -405.223957) (xy 303.442975 -405.289447)
			(xy 303.451052 -405.356385) (xy 303.451052 -405.423809) (xy 303.442976 -405.490748) (xy 303.42694 -405.556237)
			(xy 303.403175 -405.619334) (xy 303.372023 -405.67913) (xy 303.333933 -405.734763) (xy 303.312068 -405.760428)
			(xy 303.306273 -405.767574) (xy 303.299758 -405.784764) (xy 303.299368 -405.793956) (xy 303.299368 -406.286208)
			(xy 303.299781 -406.295395) (xy 303.306294 -406.312579) (xy 303.312068 -406.319736) (xy 303.333902 -406.345427)
			(xy 303.371993 -406.401057) (xy 303.403147 -406.460849) (xy 303.426915 -406.523943) (xy 303.442953 -406.589429)
			(xy 303.451032 -406.656365) (xy 303.451035 -406.723787) (xy 303.442962 -406.790724) (xy 303.426929 -406.856211)
			(xy 303.403167 -406.919307) (xy 303.372018 -406.979102) (xy 303.333931 -407.034735) (xy 303.312068 -407.0604)
			(xy 303.306285 -407.067555) (xy 303.299763 -407.084738) (xy 303.299368 -407.093928) (xy 303.299368 -407.251408)
			(xy 303.29899 -407.261535) (xy 303.291233 -407.280245) (xy 303.276904 -407.29456) (xy 303.258187 -407.302299)
			(xy 303.24806 -407.302716) (xy 302.53178 -407.302716) (xy 302.521672 -407.302232) (xy 302.502996 -407.294491)
			(xy 302.488703 -407.280194) (xy 302.480966 -407.261516) (xy 302.480472 -407.251408) (xy 302.480472 -407.093928)
			(xy 302.480055 -407.084741) (xy 302.473547 -407.067557) (xy 302.467772 -407.0604) (xy 302.445878 -407.03476)
			(xy 302.407792 -406.979121) (xy 302.376644 -406.919321) (xy 302.352883 -406.856221) (xy 302.33685 -406.790729)
			(xy 302.328777 -406.723789) (xy 299.050708 -406.723789) (xy 299.042674 -406.790547) (xy 299.026705 -406.855927)
			(xy 299.003037 -406.91893) (xy 298.972009 -406.978653) (xy 298.934065 -407.034239) (xy 298.91228 -407.059892)
			(xy 298.906502 -407.06705) (xy 298.899977 -407.084231) (xy 298.89958 -407.09342) (xy 298.89958 -407.251408)
			(xy 298.899184 -407.261565) (xy 298.891382 -407.280321) (xy 298.876978 -407.294645) (xy 298.858177 -407.302341)
			(xy 298.848018 -407.302716) (xy 298.131738 -407.302716) (xy 298.121608 -407.302241) (xy 298.10288 -407.294517)
			(xy 298.088521 -407.280227) (xy 298.080708 -407.261535) (xy 298.080176 -407.251408) (xy 298.080176 -407.09342)
			(xy 298.079762 -407.084233) (xy 298.073252 -407.067048) (xy 298.067476 -407.059892) (xy 298.045656 -407.034266)
			(xy 298.007706 -406.978677) (xy 297.976672 -406.91895) (xy 297.952999 -406.855942) (xy 297.937027 -406.790556)
			(xy 297.928985 -406.72373) (xy 294.650947 -406.72373) (xy 294.650947 -406.723787) (xy 294.642874 -406.790723)
			(xy 294.626842 -406.856211) (xy 294.60308 -406.919306) (xy 294.571933 -406.979101) (xy 294.533847 -407.034735)
			(xy 294.511984 -407.0604) (xy 294.506203 -407.067556) (xy 294.49968 -407.084738) (xy 294.499284 -407.093928)
			(xy 294.499284 -407.251408) (xy 294.49889 -407.261533) (xy 294.491136 -407.28024) (xy 294.476813 -407.294554)
			(xy 294.458101 -407.302296) (xy 294.447976 -407.302716) (xy 293.731696 -407.302716) (xy 293.721589 -407.302218)
			(xy 293.702914 -407.294482) (xy 293.68862 -407.28019) (xy 293.680882 -407.261515) (xy 293.680388 -407.251408)
			(xy 293.680388 -407.093928) (xy 293.679967 -407.084742) (xy 293.673461 -407.067557) (xy 293.667688 -407.0604)
			(xy 293.645793 -407.03476) (xy 293.607706 -406.979122) (xy 293.576557 -406.919322) (xy 293.552796 -406.856222)
			(xy 293.536763 -406.79073) (xy 293.52869 -406.723789) (xy 290.250621 -406.723789) (xy 290.242587 -406.790547)
			(xy 290.226619 -406.855927) (xy 290.202951 -406.91893) (xy 290.171924 -406.978653) (xy 290.133981 -407.034239)
			(xy 290.112196 -407.059892) (xy 290.10642 -407.067052) (xy 290.099893 -407.084231) (xy 290.099496 -407.09342)
			(xy 290.099496 -407.251408) (xy 290.099085 -407.261563) (xy 290.091286 -407.280316) (xy 290.076886 -407.29464)
			(xy 290.058091 -407.302338) (xy 290.047934 -407.302716) (xy 289.331654 -407.302716) (xy 289.321519 -407.30231)
			(xy 289.302788 -407.294559) (xy 289.288432 -407.280248) (xy 289.280622 -407.261541) (xy 289.280092 -407.251408)
			(xy 289.280092 -407.09342) (xy 289.279674 -407.084234) (xy 289.273166 -407.067049) (xy 289.267392 -407.059892)
			(xy 289.245571 -407.034266) (xy 289.20762 -406.978677) (xy 289.176585 -406.918951) (xy 289.152912 -406.855943)
			(xy 289.136939 -406.790557) (xy 289.128897 -406.72373) (xy 237.406942 -406.72373) (xy 237.406942 -409.523887)
			(xy 286.928735 -409.523887) (xy 286.928738 -409.456459) (xy 286.936818 -409.389518) (xy 286.952859 -409.324026)
			(xy 286.97663 -409.260927) (xy 287.007788 -409.20113) (xy 287.045884 -409.145496) (xy 287.067752 -409.119832)
			(xy 287.073566 -409.1127) (xy 287.080069 -409.095499) (xy 287.080452 -409.086304) (xy 287.080452 -408.594052)
			(xy 287.080005 -408.584869) (xy 287.073516 -408.567685) (xy 287.067752 -408.560524) (xy 287.045878 -408.534866)
			(xy 287.007786 -408.479232) (xy 286.976633 -408.419435) (xy 286.952867 -408.356337) (xy 286.936831 -408.290847)
			(xy 286.928755 -408.223907) (xy 286.928755 -408.156481) (xy 286.936833 -408.089542) (xy 286.952871 -408.024051)
			(xy 286.976638 -407.960954) (xy 287.007793 -407.901158) (xy 287.045886 -407.845524) (xy 287.067752 -407.81986)
			(xy 287.073554 -407.812719) (xy 287.080064 -407.795525) (xy 287.080452 -407.786332) (xy 287.080452 -407.628852)
			(xy 287.080945 -407.618746) (xy 287.088689 -407.600076) (xy 287.102983 -407.585785) (xy 287.121654 -407.578043)
			(xy 287.13176 -407.577544) (xy 287.84804 -407.577544) (xy 287.858144 -407.578051) (xy 287.876813 -407.585791)
			(xy 287.891104 -407.600081) (xy 287.898847 -407.618748) (xy 287.899348 -407.628852) (xy 287.899348 -407.786332)
			(xy 287.899755 -407.795519) (xy 287.906272 -407.812703) (xy 287.912048 -407.81986) (xy 287.933906 -407.845531)
			(xy 287.971998 -407.901163) (xy 288.003152 -407.960958) (xy 288.026919 -408.024055) (xy 288.042957 -408.089543)
			(xy 288.051034 -408.156482) (xy 288.051035 -408.223906) (xy 288.042959 -408.290845) (xy 288.026923 -408.356334)
			(xy 288.003157 -408.419431) (xy 287.972004 -408.479226) (xy 287.933913 -408.53486) (xy 287.912048 -408.560524)
			(xy 287.906252 -408.56767) (xy 287.899739 -408.58486) (xy 287.899348 -408.594052) (xy 287.899348 -409.086304)
			(xy 287.899768 -409.09549) (xy 287.906276 -409.112674) (xy 287.912048 -409.119832) (xy 287.933878 -409.145526)
			(xy 287.971972 -409.201155) (xy 288.003127 -409.260947) (xy 288.026895 -409.32404) (xy 288.042935 -409.389526)
			(xy 288.051014 -409.456462) (xy 288.051018 -409.523884) (xy 288.042945 -409.590821) (xy 288.026911 -409.656308)
			(xy 288.003149 -409.719404) (xy 287.971999 -409.779199) (xy 287.933912 -409.834832) (xy 287.912048 -409.860496)
			(xy 287.906264 -409.86765) (xy 287.899743 -409.884834) (xy 287.899348 -409.894024) (xy 287.899348 -410.051504)
			(xy 287.898819 -410.061607) (xy 287.891089 -410.080276) (xy 287.876806 -410.094569) (xy 287.858143 -410.102312)
			(xy 287.84804 -410.102812) (xy 287.13176 -410.102812) (xy 287.12165 -410.102348) (xy 287.102973 -410.094599)
			(xy 287.08868 -410.080296) (xy 287.080945 -410.061614) (xy 287.080452 -410.051504) (xy 287.080452 -409.894024)
			(xy 287.080019 -409.884839) (xy 287.07352 -409.867655) (xy 287.067752 -409.860496) (xy 287.045851 -409.834861)
			(xy 287.00776 -409.779223) (xy 286.976608 -409.719423) (xy 286.952843 -409.656322) (xy 286.936809 -409.590829)
			(xy 286.928735 -409.523887) (xy 237.406942 -409.523887) (xy 237.406942 -410.623642) (xy 289.128908 -410.623642)
			(xy 289.12891 -410.556334) (xy 289.136956 -410.48951) (xy 289.152933 -410.424126) (xy 289.176609 -410.361121)
			(xy 289.207648 -410.301397) (xy 289.245602 -410.245811) (xy 289.267392 -410.22016) (xy 289.273187 -410.213014)
			(xy 289.279703 -410.195824) (xy 289.280092 -410.186632) (xy 289.280092 -409.693364) (xy 289.279701 -409.684175)
			(xy 289.273174 -409.66699) (xy 289.267392 -409.659836) (xy 289.245614 -409.634175) (xy 289.207662 -409.578591)
			(xy 289.176625 -409.518869) (xy 289.152949 -409.455866) (xy 289.136974 -409.390484) (xy 289.128928 -409.323662)
			(xy 289.128927 -409.256356) (xy 289.136971 -409.189534) (xy 289.152944 -409.124152) (xy 289.176618 -409.061147)
			(xy 289.207653 -409.001425) (xy 289.245603 -408.945839) (xy 289.267392 -408.920188) (xy 289.273175 -408.913033)
			(xy 289.279698 -408.89585) (xy 289.280092 -408.88666) (xy 289.280092 -408.728672) (xy 289.280498 -408.718517)
			(xy 289.288302 -408.699766) (xy 289.302703 -408.685443) (xy 289.321497 -408.677743) (xy 289.331654 -408.677364)
			(xy 290.047934 -408.677364) (xy 290.058066 -408.677799) (xy 290.076792 -408.685543) (xy 290.091148 -408.699845)
			(xy 290.098962 -408.718542) (xy 290.099496 -408.728672) (xy 290.099496 -408.88666) (xy 290.099926 -408.895845)
			(xy 290.106426 -408.91303) (xy 290.112196 -408.920188) (xy 290.133994 -408.945831) (xy 290.171941 -409.00142)
			(xy 290.202971 -409.061145) (xy 290.226642 -409.12415) (xy 290.242613 -409.189533) (xy 290.250656 -409.256356)
			(xy 290.250655 -409.323662) (xy 290.24261 -409.390484) (xy 290.226637 -409.455867) (xy 290.202964 -409.518872)
			(xy 290.200389 -409.523827) (xy 291.329055 -409.523827) (xy 291.329058 -409.456519) (xy 291.337106 -409.389694)
			(xy 291.353082 -409.32431) (xy 291.376759 -409.261304) (xy 291.407797 -409.201579) (xy 291.44575 -409.145992)
			(xy 291.46754 -409.12034) (xy 291.47335 -409.113204) (xy 291.479855 -409.096006) (xy 291.48024 -409.086812)
			(xy 291.48024 -408.593544) (xy 291.4798 -408.58436) (xy 291.473306 -408.567176) (xy 291.46754 -408.560016)
			(xy 291.445744 -408.53437) (xy 291.407796 -408.478783) (xy 291.376763 -408.419059) (xy 291.35309 -408.356053)
			(xy 291.337118 -408.29067) (xy 291.329074 -408.223847) (xy 291.329075 -408.156541) (xy 291.33712 -408.089718)
			(xy 291.353094 -408.024335) (xy 291.376767 -407.96133) (xy 291.407802 -407.901607) (xy 291.445752 -407.84602)
			(xy 291.46754 -407.820368) (xy 291.473338 -407.813224) (xy 291.479851 -407.796032) (xy 291.48024 -407.78684)
			(xy 291.48024 -407.628852) (xy 291.480583 -407.61869) (xy 291.488402 -407.599929) (xy 291.502823 -407.585606)
			(xy 291.521637 -407.577915) (xy 291.531802 -407.577544) (xy 292.248082 -407.577544) (xy 292.258208 -407.578041)
			(xy 292.27693 -407.585764) (xy 292.291287 -407.600047) (xy 292.299106 -407.618729) (xy 292.299644 -407.628852)
			(xy 292.299644 -407.78684) (xy 292.300048 -407.796028) (xy 292.306567 -407.813211) (xy 292.312344 -407.820368)
			(xy 292.334124 -407.846026) (xy 292.372074 -407.901612) (xy 292.403109 -407.961334) (xy 292.426783 -408.024338)
			(xy 292.442757 -408.089719) (xy 292.450802 -408.156542) (xy 292.450803 -408.223846) (xy 292.442759 -408.290669)
			(xy 292.426786 -408.356051) (xy 292.403114 -408.419055) (xy 292.372081 -408.478778) (xy 292.334132 -408.534364)
			(xy 292.312344 -408.560016) (xy 292.306551 -408.567164) (xy 292.300036 -408.584353) (xy 292.299644 -408.593544)
			(xy 292.299644 -409.086812) (xy 292.300061 -409.095998) (xy 292.306571 -409.113182) (xy 292.312344 -409.12034)
			(xy 292.334097 -409.146021) (xy 292.372048 -409.201603) (xy 292.403083 -409.261322) (xy 292.426759 -409.324323)
			(xy 292.442735 -409.389702) (xy 292.450782 -409.456522) (xy 292.450786 -409.523824) (xy 292.442745 -409.590645)
			(xy 292.426775 -409.656025) (xy 292.403106 -409.719028) (xy 292.372076 -409.77875) (xy 292.33413 -409.834336)
			(xy 292.312344 -409.859988) (xy 292.306521 -409.867114) (xy 292.300024 -409.884319) (xy 292.299644 -409.893516)
			(xy 292.299644 -410.051504) (xy 292.299182 -410.061653) (xy 292.291394 -410.080397) (xy 292.27701 -410.094718)
			(xy 292.258233 -410.102426) (xy 292.248082 -410.102812) (xy 291.531802 -410.102812) (xy 291.521682 -410.102273)
			(xy 291.502971 -410.094556) (xy 291.488616 -410.080286) (xy 291.480788 -410.061621) (xy 291.48024 -410.051504)
			(xy 291.48024 -409.893516) (xy 291.479813 -409.884331) (xy 291.47331 -409.867147) (xy 291.46754 -409.859988)
			(xy 291.445717 -409.834365) (xy 291.407769 -409.778774) (xy 291.376737 -409.719047) (xy 291.353066 -409.656039)
			(xy 291.337096 -409.590653) (xy 291.329055 -409.523827) (xy 290.200389 -409.523827) (xy 290.171931 -409.578596)
			(xy 290.133983 -409.634183) (xy 290.112196 -409.659836) (xy 290.106401 -409.666982) (xy 290.099886 -409.684172)
			(xy 290.099496 -409.693364) (xy 290.099496 -410.186632) (xy 290.099891 -410.195821) (xy 290.106415 -410.213005)
			(xy 290.112196 -410.22016) (xy 290.133967 -410.245826) (xy 290.171914 -410.301411) (xy 290.202946 -410.361133)
			(xy 290.226618 -410.424136) (xy 290.242591 -410.489516) (xy 290.250636 -410.556336) (xy 290.250638 -410.62364)
			(xy 290.250631 -410.6237) (xy 293.528701 -410.6237) (xy 293.528702 -410.556276) (xy 293.53678 -410.489336)
			(xy 293.552816 -410.423847) (xy 293.576582 -410.360749) (xy 293.607734 -410.300952) (xy 293.645824 -410.245317)
			(xy 293.667688 -410.219652) (xy 293.673486 -410.212508) (xy 293.68 -410.195317) (xy 293.680388 -410.186124)
			(xy 293.680388 -409.693872) (xy 293.679994 -409.684683) (xy 293.673469 -409.667499) (xy 293.667688 -409.660344)
			(xy 293.645836 -409.634669) (xy 293.607748 -409.579035) (xy 293.576597 -409.519241) (xy 293.552833 -409.456145)
			(xy 293.536797 -409.390657) (xy 293.52872 -409.32372) (xy 293.528719 -409.256298) (xy 293.536794 -409.189361)
			(xy 293.552828 -409.123872) (xy 293.57659 -409.060776) (xy 293.607739 -409.00098) (xy 293.645825 -408.945345)
			(xy 293.667688 -408.91968) (xy 293.673474 -408.912527) (xy 293.679995 -408.895343) (xy 293.680388 -408.886152)
			(xy 293.680388 -408.728672) (xy 293.680862 -408.718563) (xy 293.688606 -408.699886) (xy 293.702907 -408.685593)
			(xy 293.721587 -408.677857) (xy 293.731696 -408.677364) (xy 294.447976 -408.677364) (xy 294.458079 -408.677904)
			(xy 294.47675 -408.685627) (xy 294.491044 -408.699907) (xy 294.498786 -408.71857) (xy 294.499284 -408.728672)
			(xy 294.499284 -408.886152) (xy 294.499721 -408.895336) (xy 294.506216 -408.912521) (xy 294.511984 -408.91968)
			(xy 294.53386 -408.945335) (xy 294.57195 -409.000971) (xy 294.603101 -409.060768) (xy 294.626865 -409.123866)
			(xy 294.6429 -409.189357) (xy 294.650975 -409.256297) (xy 294.650974 -409.323721) (xy 294.642897 -409.390661)
			(xy 294.62686 -409.456151) (xy 294.603093 -409.519248) (xy 294.600676 -409.523887) (xy 295.728823 -409.523887)
			(xy 295.728826 -409.456459) (xy 295.736906 -409.389518) (xy 295.752947 -409.324026) (xy 295.776716 -409.260928)
			(xy 295.807873 -409.201131) (xy 295.845969 -409.145497) (xy 295.867836 -409.119832) (xy 295.873649 -409.112698)
			(xy 295.880153 -409.095499) (xy 295.880536 -409.086304) (xy 295.880536 -408.594052) (xy 295.880093 -408.584869)
			(xy 295.873601 -408.567684) (xy 295.867836 -408.560524) (xy 295.845963 -408.534866) (xy 295.807872 -408.479231)
			(xy 295.77672 -408.419434) (xy 295.752954 -408.356336) (xy 295.736918 -408.290846) (xy 295.728843 -408.223907)
			(xy 295.728843 -408.156481) (xy 295.736921 -408.089542) (xy 295.752958 -408.024052) (xy 295.776725 -407.960955)
			(xy 295.807878 -407.901159) (xy 295.84597 -407.845525) (xy 295.867836 -407.81986) (xy 295.873637 -407.812718)
			(xy 295.880148 -407.795525) (xy 295.880536 -407.786332) (xy 295.880536 -407.628852) (xy 295.880947 -407.618736)
			(xy 295.888707 -407.60005) (xy 295.903027 -407.585755) (xy 295.921727 -407.578029) (xy 295.931844 -407.577544)
			(xy 296.648124 -407.577544) (xy 296.658227 -407.578064) (xy 296.676895 -407.585799) (xy 296.691187 -407.600084)
			(xy 296.698931 -407.618749) (xy 296.699432 -407.628852) (xy 296.699432 -407.786332) (xy 296.699842 -407.795519)
			(xy 296.706357 -407.812703) (xy 296.712132 -407.81986) (xy 296.733987 -407.845532) (xy 296.772074 -407.901167)
			(xy 296.803223 -407.960962) (xy 296.826986 -408.024058) (xy 296.843021 -408.089546) (xy 296.851097 -408.156483)
			(xy 296.851098 -408.223905) (xy 296.843024 -408.290842) (xy 296.82699 -408.356331) (xy 296.803228 -408.419427)
			(xy 296.77208 -408.479223) (xy 296.733994 -408.534858) (xy 296.712132 -408.560524) (xy 296.706334 -408.567668)
			(xy 296.699822 -408.58486) (xy 296.699432 -408.594052) (xy 296.699432 -409.086304) (xy 296.699856 -409.095489)
			(xy 296.706362 -409.112673) (xy 296.712132 -409.119832) (xy 296.733959 -409.145527) (xy 296.772047 -409.201158)
			(xy 296.803198 -409.26095) (xy 296.826962 -409.324043) (xy 296.842999 -409.389528) (xy 296.851078 -409.456463)
			(xy 296.851081 -409.523883) (xy 296.843009 -409.590818) (xy 296.826978 -409.656305) (xy 296.80322 -409.7194)
			(xy 296.772075 -409.779196) (xy 296.733993 -409.83483) (xy 296.712132 -409.860496) (xy 296.706346 -409.867649)
			(xy 296.699827 -409.884834) (xy 296.699432 -409.894024) (xy 296.699432 -410.051504) (xy 296.698919 -410.061609)
			(xy 296.691186 -410.080281) (xy 296.676898 -410.094575) (xy 296.658229 -410.102315) (xy 296.648124 -410.102812)
			(xy 295.931844 -410.102812) (xy 295.921726 -410.102348) (xy 295.903026 -410.094617) (xy 295.88871 -410.080315)
			(xy 295.880961 -410.061622) (xy 295.880536 -410.051504) (xy 295.880536 -409.894024) (xy 295.880106 -409.884839)
			(xy 295.873605 -409.867655) (xy 295.867836 -409.860496) (xy 295.845935 -409.834861) (xy 295.807845 -409.779223)
			(xy 295.776694 -409.719423) (xy 295.752931 -409.656322) (xy 295.736896 -409.590829) (xy 295.728823 -409.523887)
			(xy 294.600676 -409.523887) (xy 294.57194 -409.579045) (xy 294.533849 -409.634679) (xy 294.511984 -409.660344)
			(xy 294.506184 -409.667487) (xy 294.499672 -409.684679) (xy 294.499284 -409.693872) (xy 294.499284 -410.186124)
			(xy 294.499686 -410.195312) (xy 294.506206 -410.212496) (xy 294.511984 -410.219652) (xy 294.533833 -410.24533)
			(xy 294.571923 -410.300962) (xy 294.603075 -410.360757) (xy 294.626841 -410.423852) (xy 294.642878 -410.489339)
			(xy 294.650956 -410.556277) (xy 294.650957 -410.623641) (xy 297.928996 -410.623641) (xy 297.928998 -410.556334)
			(xy 297.937044 -410.48951) (xy 297.95302 -410.424127) (xy 297.976696 -410.361121) (xy 298.007733 -410.301398)
			(xy 298.045686 -410.245812) (xy 298.067476 -410.22016) (xy 298.073269 -410.213012) (xy 298.079787 -410.195824)
			(xy 298.080176 -410.186632) (xy 298.080176 -409.693364) (xy 298.079788 -409.684174) (xy 298.07326 -409.66699)
			(xy 298.067476 -409.659836) (xy 298.045699 -409.634175) (xy 298.007747 -409.57859) (xy 297.976712 -409.518868)
			(xy 297.953037 -409.455865) (xy 297.937062 -409.390484) (xy 297.929016 -409.323661) (xy 297.929015 -409.256357)
			(xy 297.937058 -409.189534) (xy 297.953031 -409.124152) (xy 297.976704 -409.061148) (xy 298.007738 -409.001425)
			(xy 298.045688 -408.94584) (xy 298.067476 -408.920188) (xy 298.073257 -408.913032) (xy 298.079782 -408.89585)
			(xy 298.080176 -408.88666) (xy 298.080176 -408.728672) (xy 298.080598 -408.718519) (xy 298.088398 -408.699771)
			(xy 298.102794 -408.685449) (xy 298.121583 -408.677746) (xy 298.131738 -408.677364) (xy 298.848018 -408.677364)
			(xy 298.858149 -408.677812) (xy 298.876875 -408.68555) (xy 298.891232 -408.699849) (xy 298.899046 -408.718543)
			(xy 298.89958 -408.728672) (xy 298.89958 -408.88666) (xy 298.900014 -408.895845) (xy 298.906512 -408.913029)
			(xy 298.91228 -408.920188) (xy 298.934079 -408.945831) (xy 298.972026 -409.001419) (xy 299.003058 -409.061144)
			(xy 299.026729 -409.12415) (xy 299.042701 -409.189533) (xy 299.050744 -409.256356) (xy 299.050743 -409.323662)
			(xy 299.042698 -409.390485) (xy 299.026724 -409.455868) (xy 299.003051 -409.518873) (xy 299.000446 -409.523886)
			(xy 300.128614 -409.523886) (xy 300.128617 -409.456459) (xy 300.136697 -409.389518) (xy 300.152737 -409.324027)
			(xy 300.176506 -409.260928) (xy 300.207662 -409.201131) (xy 300.245757 -409.145497) (xy 300.267624 -409.119832)
			(xy 300.273435 -409.112697) (xy 300.27994 -409.095499) (xy 300.280324 -409.086304) (xy 300.280324 -408.594052)
			(xy 300.279883 -408.584868) (xy 300.27339 -408.567684) (xy 300.267624 -408.560524) (xy 300.245751 -408.534866)
			(xy 300.207661 -408.479231) (xy 300.17651 -408.419434) (xy 300.152745 -408.356336) (xy 300.136709 -408.290846)
			(xy 300.128634 -408.223906) (xy 300.128634 -408.156482) (xy 300.136711 -408.089542) (xy 300.152748 -408.024053)
			(xy 300.176514 -407.960955) (xy 300.207667 -407.901159) (xy 300.245759 -407.845525) (xy 300.267624 -407.81986)
			(xy 300.273423 -407.812717) (xy 300.279935 -407.795525) (xy 300.280324 -407.786332) (xy 300.280324 -407.628852)
			(xy 300.280747 -407.618737) (xy 300.288504 -407.600053) (xy 300.302821 -407.585759) (xy 300.321516 -407.578031)
			(xy 300.331632 -407.577544) (xy 301.047912 -407.577544) (xy 301.058015 -407.578074) (xy 301.076682 -407.585805)
			(xy 301.090975 -407.600088) (xy 301.098719 -407.61875) (xy 301.09922 -407.628852) (xy 301.09922 -407.786332)
			(xy 301.09961 -407.795521) (xy 301.106137 -407.812706) (xy 301.11192 -407.81986) (xy 301.133775 -407.845532)
			(xy 301.171863 -407.901166) (xy 301.203013 -407.960962) (xy 301.226777 -408.024057) (xy 301.242812 -408.089545)
			(xy 301.250888 -408.156483) (xy 301.250889 -408.223905) (xy 301.242814 -408.290843) (xy 301.22678 -408.356331)
			(xy 301.203018 -408.419427) (xy 301.171869 -408.479224) (xy 301.133783 -408.534858) (xy 301.11192 -408.560524)
			(xy 301.106133 -408.567676) (xy 301.099612 -408.584861) (xy 301.09922 -408.594052) (xy 301.09922 -409.086304)
			(xy 301.099624 -409.095492) (xy 301.106141 -409.112676) (xy 301.11192 -409.119832) (xy 301.133748 -409.145527)
			(xy 301.171836 -409.201158) (xy 301.202988 -409.26095) (xy 301.226753 -409.324043) (xy 301.24279 -409.389528)
			(xy 301.250869 -409.456463) (xy 301.250872 -409.523883) (xy 301.2428 -409.590819) (xy 301.226769 -409.656305)
			(xy 301.20301 -409.719401) (xy 301.171864 -409.779196) (xy 301.133781 -409.83483) (xy 301.11192 -409.860496)
			(xy 301.106145 -409.867657) (xy 301.099617 -409.884835) (xy 301.09922 -409.894024) (xy 301.09922 -410.051504)
			(xy 301.098719 -410.06161) (xy 301.090983 -410.080285) (xy 301.076692 -410.094579) (xy 301.058018 -410.102317)
			(xy 301.047912 -410.102812) (xy 300.331632 -410.102812) (xy 300.321513 -410.102358) (xy 300.302812 -410.094623)
			(xy 300.288497 -410.080318) (xy 300.280749 -410.061623) (xy 300.280324 -410.051504) (xy 300.280324 -409.894024)
			(xy 300.279897 -409.884839) (xy 300.273394 -409.867655) (xy 300.267624 -409.860496) (xy 300.245724 -409.83486)
			(xy 300.207635 -409.779222) (xy 300.176484 -409.719422) (xy 300.152721 -409.656321) (xy 300.136687 -409.590828)
			(xy 300.128614 -409.523886) (xy 299.000446 -409.523886) (xy 298.972017 -409.578597) (xy 298.934068 -409.634184)
			(xy 298.91228 -409.659836) (xy 298.906483 -409.666981) (xy 298.899969 -409.684172) (xy 298.89958 -409.693364)
			(xy 298.89958 -410.186632) (xy 298.899979 -410.19582) (xy 298.906501 -410.213004) (xy 298.91228 -410.22016)
			(xy 298.934052 -410.245825) (xy 298.972 -410.30141) (xy 299.003032 -410.361132) (xy 299.026705 -410.424135)
			(xy 299.042679 -410.489515) (xy 299.050724 -410.556336) (xy 299.050725 -410.62364) (xy 299.050718 -410.6237)
			(xy 302.328789 -410.6237) (xy 302.32879 -410.556276) (xy 302.336867 -410.489337) (xy 302.352904 -410.423847)
			(xy 302.376668 -410.36075) (xy 302.407819 -410.300953) (xy 302.445908 -410.245318) (xy 302.467772 -410.219652)
			(xy 302.47358 -410.212515) (xy 302.480086 -410.195318) (xy 302.480472 -410.186124) (xy 302.480472 -409.693872)
			(xy 302.480082 -409.684683) (xy 302.473555 -409.667498) (xy 302.467772 -409.660344) (xy 302.445921 -409.634669)
			(xy 302.407834 -409.579035) (xy 302.376684 -409.51924) (xy 302.35292 -409.456144) (xy 302.336885 -409.390657)
			(xy 302.328808 -409.32372) (xy 302.328807 -409.256298) (xy 302.336882 -409.189361) (xy 302.352915 -409.123873)
			(xy 302.376677 -409.060777) (xy 302.407824 -409.000981) (xy 302.44591 -408.945346) (xy 302.467772 -408.91968)
			(xy 302.473568 -408.912535) (xy 302.480081 -408.895344) (xy 302.480472 -408.886152) (xy 302.480472 -408.728672)
			(xy 302.480961 -408.718565) (xy 302.488703 -408.699891) (xy 302.502998 -408.685599) (xy 302.521673 -408.67786)
			(xy 302.53178 -408.677364) (xy 303.24806 -408.677364) (xy 303.258175 -408.677848) (xy 303.276871 -408.685576)
			(xy 303.291186 -408.699872) (xy 303.298939 -408.718557) (xy 303.299368 -408.728672) (xy 303.299368 -408.886152)
			(xy 303.299809 -408.895336) (xy 303.306302 -408.91252) (xy 303.312068 -408.91968) (xy 303.333945 -408.945335)
			(xy 303.372035 -409.00097) (xy 303.403187 -409.060768) (xy 303.426952 -409.123866) (xy 303.442988 -409.189356)
			(xy 303.451063 -409.256296) (xy 303.451062 -409.323722) (xy 303.442985 -409.390661) (xy 303.426947 -409.456151)
			(xy 303.40318 -409.519249) (xy 303.372026 -409.579045) (xy 303.333934 -409.634679) (xy 303.312068 -409.660344)
			(xy 303.306266 -409.667485) (xy 303.299755 -409.684679) (xy 303.299368 -409.693872) (xy 303.299368 -410.186124)
			(xy 303.299774 -410.195312) (xy 303.306291 -410.212495) (xy 303.312068 -410.219652) (xy 303.333917 -410.24533)
			(xy 303.372009 -410.300962) (xy 303.403162 -410.360756) (xy 303.426928 -410.423851) (xy 303.442966 -410.489339)
			(xy 303.451044 -410.556276) (xy 303.451045 -410.6237) (xy 303.44297 -410.690637) (xy 303.426935 -410.756126)
			(xy 303.403172 -410.819222) (xy 303.372021 -410.879018) (xy 303.333932 -410.934651) (xy 303.312068 -410.960316)
			(xy 303.306278 -410.967466) (xy 303.29976 -410.984653) (xy 303.299368 -410.993844) (xy 303.299368 -411.151324)
			(xy 303.299003 -411.161452) (xy 303.291241 -411.180162) (xy 303.276909 -411.194477) (xy 303.258189 -411.202216)
			(xy 303.24806 -411.202632) (xy 302.53178 -411.202632) (xy 302.521674 -411.202132) (xy 302.503001 -411.194394)
			(xy 302.488708 -411.180102) (xy 302.480969 -411.16143) (xy 302.480472 -411.151324) (xy 302.480472 -410.993844)
			(xy 302.480047 -410.984658) (xy 302.473544 -410.967474) (xy 302.467772 -410.960316) (xy 302.445893 -410.934663)
			(xy 302.407807 -410.879026) (xy 302.376658 -410.819228) (xy 302.352896 -410.75613) (xy 302.336863 -410.690639)
			(xy 302.328789 -410.6237) (xy 299.050718 -410.6237) (xy 299.042683 -410.690461) (xy 299.026712 -410.755842)
			(xy 299.003042 -410.818846) (xy 298.972012 -410.878569) (xy 298.934066 -410.934156) (xy 298.91228 -410.959808)
			(xy 298.906495 -410.966961) (xy 298.899974 -410.984146) (xy 298.89958 -410.993336) (xy 298.89958 -411.151324)
			(xy 298.899198 -411.161482) (xy 298.891391 -411.180239) (xy 298.876982 -411.194562) (xy 298.858179 -411.202258)
			(xy 298.848018 -411.202632) (xy 298.131738 -411.202632) (xy 298.12161 -411.202141) (xy 298.102885 -411.194421)
			(xy 298.088526 -411.180135) (xy 298.080711 -411.161449) (xy 298.080176 -411.151324) (xy 298.080176 -410.993336)
			(xy 298.079754 -410.98415) (xy 298.073249 -410.966965) (xy 298.067476 -410.959808) (xy 298.045672 -410.934169)
			(xy 298.007721 -410.878582) (xy 297.976686 -410.818857) (xy 297.953013 -410.75585) (xy 297.93704 -410.690466)
			(xy 297.928996 -410.623641) (xy 294.650957 -410.623641) (xy 294.650957 -410.623699) (xy 294.642883 -410.690637)
			(xy 294.626848 -410.756125) (xy 294.603085 -410.819221) (xy 294.571935 -410.879017) (xy 294.533848 -410.934651)
			(xy 294.511984 -410.960316) (xy 294.506196 -410.967467) (xy 294.499677 -410.984653) (xy 294.499284 -410.993844)
			(xy 294.499284 -411.151324) (xy 294.498834 -411.161436) (xy 294.491086 -411.180118) (xy 294.476778 -411.194413)
			(xy 294.458089 -411.202144) (xy 294.447976 -411.202632) (xy 293.731696 -411.202632) (xy 293.721591 -411.202119)
			(xy 293.702919 -411.194386) (xy 293.688625 -411.180098) (xy 293.680885 -411.161429) (xy 293.680388 -411.151324)
			(xy 293.680388 -410.993844) (xy 293.679959 -410.984659) (xy 293.673459 -410.967474) (xy 293.667688 -410.960316)
			(xy 293.645809 -410.934664) (xy 293.607721 -410.879027) (xy 293.576572 -410.819229) (xy 293.552809 -410.75613)
			(xy 293.536775 -410.69064) (xy 293.528701 -410.6237) (xy 290.250631 -410.6237) (xy 290.242595 -410.69046)
			(xy 290.226625 -410.755841) (xy 290.202956 -410.818845) (xy 290.171926 -410.878568) (xy 290.133982 -410.934155)
			(xy 290.112196 -410.959808) (xy 290.106413 -410.966963) (xy 290.09989 -410.984146) (xy 290.099496 -410.993336)
			(xy 290.099496 -411.151324) (xy 290.099098 -411.16148) (xy 290.091294 -411.180234) (xy 290.07689 -411.194557)
			(xy 290.058092 -411.202255) (xy 290.047934 -411.202632) (xy 289.331654 -411.202632) (xy 289.321521 -411.20221)
			(xy 289.302793 -411.194462) (xy 289.288438 -411.180156) (xy 289.280625 -411.161455) (xy 289.280092 -411.151324)
			(xy 289.280092 -410.993336) (xy 289.279666 -410.98415) (xy 289.273164 -410.966966) (xy 289.267392 -410.959808)
			(xy 289.245587 -410.934169) (xy 289.207635 -410.878582) (xy 289.1766 -410.818857) (xy 289.152925 -410.755851)
			(xy 289.136952 -410.690467) (xy 289.128908 -410.623642) (xy 237.406942 -410.623642) (xy 237.406942 -412.06928)
			(xy 237.406454 -412.09423) (xy 237.398652 -412.143517) (xy 237.383236 -412.190976) (xy 237.360587 -412.23544)
			(xy 237.331261 -412.275814) (xy 237.313978 -412.293816) (xy 235.9787 -413.629094) (xy 235.960702 -413.64638)
			(xy 235.92032 -413.675693) (xy 235.875854 -413.698339) (xy 235.828397 -413.713762) (xy 235.779114 -413.721582)
			(xy 235.754164 -413.722058) (xy 208.805526 -413.722058) (xy 208.780575 -413.721571) (xy 208.731288 -413.71377)
			(xy 208.683827 -413.698355) (xy 208.639362 -413.675707) (xy 208.598986 -413.646383) (xy 208.58099 -413.629094)
			(xy 207.025748 -412.073852) (xy 207.008463 -412.055854) (xy 206.979152 -412.015471) (xy 206.956509 -411.971006)
			(xy 206.941092 -411.923548) (xy 206.933278 -411.874265) (xy 206.932784 -411.849316) (xy 206.932784 -389.931402)
			(xy 206.932361 -389.921332) (xy 206.924645 -389.902729) (xy 206.917798 -389.895334) (xy 204.423264 -387.4008)
			(xy 204.405975 -387.382803) (xy 204.376657 -387.342423) (xy 204.354006 -387.297957) (xy 204.338581 -387.2505)
			(xy 204.33076 -387.201215) (xy 204.3303 -387.176264) (xy 204.3303 -378.650754) (xy 204.31379 -378.625608)
			(xy 204.299566 -378.619512) (xy 204.274164 -378.608112) (xy 204.226684 -378.579033) (xy 204.183937 -378.54336)
			(xy 204.146829 -378.501851) (xy 204.11615 -378.45539) (xy 204.092551 -378.404961) (xy 204.076533 -378.351638)
			(xy 204.068437 -378.296553) (xy 204.068435 -378.240876) (xy 204.076526 -378.185791) (xy 204.09254 -378.132466)
			(xy 204.116135 -378.082037) (xy 204.146811 -378.035572) (xy 204.183915 -377.994061) (xy 204.22666 -377.958385)
			(xy 204.274137 -377.929301) (xy 204.299566 -377.917964) (xy 204.31379 -377.911868) (xy 204.3303 -377.886722)
			(xy 204.3303 -374.857518) (xy 204.324458 -374.851676) (xy 204.307171 -374.833679) (xy 204.277856 -374.793297)
			(xy 204.25521 -374.748832) (xy 204.239788 -374.701374) (xy 204.231971 -374.65209) (xy 204.231494 -374.62714)
			(xy 204.231494 -371.243098) (xy 204.23107 -371.233028) (xy 204.223355 -371.214425) (xy 204.216508 -371.20703)
			(xy 204.18298 -371.173502) (xy 204.16569 -371.155506) (xy 204.13637 -371.115126) (xy 204.113718 -371.07066)
			(xy 204.098292 -371.023202) (xy 204.09047 -370.973917) (xy 204.090016 -370.948966) (xy 204.090016 -368.840258)
			(xy 204.07503 -368.80419) (xy 204.074014 -368.803174) (xy 203.870306 -368.599466) (xy 203.862911 -368.592611)
			(xy 203.844312 -368.584864) (xy 203.834238 -368.58448) (xy 201.915268 -368.58448) (xy 201.903938 -368.585085)
			(xy 201.883488 -368.594842) (xy 201.869256 -368.612473) (xy 201.865992 -368.623342) (xy 201.858803 -368.650669)
			(xy 201.837471 -368.702992) (xy 201.808659 -368.751598) (xy 201.772996 -368.795426) (xy 201.731261 -368.833517)
			(xy 201.684368 -368.86504) (xy 201.633339 -368.889305) (xy 201.579291 -368.905783) (xy 201.523404 -368.914113)
			(xy 201.4669 -368.914113) (xy 201.411013 -368.905783) (xy 201.356965 -368.889305) (xy 201.305936 -368.86504)
			(xy 201.259043 -368.833517) (xy 201.217308 -368.795426) (xy 201.181645 -368.751598) (xy 201.152833 -368.702992)
			(xy 201.131501 -368.650669) (xy 201.124312 -368.623342) (xy 201.121047 -368.612481) (xy 201.106782 -368.594888)
			(xy 201.086358 -368.585096) (xy 201.075036 -368.58448) (xy 197.866254 -368.58448) (xy 197.828154 -368.601752)
			(xy 197.809958 -368.621643) (xy 197.768932 -368.656614) (xy 197.723394 -368.685464) (xy 197.674249 -368.70762)
			(xy 197.622476 -368.72264) (xy 197.569104 -368.730226) (xy 197.515196 -368.730226) (xy 197.461824 -368.72264)
			(xy 197.410051 -368.70762) (xy 197.360906 -368.685464) (xy 197.315368 -368.656614) (xy 197.274342 -368.621643)
			(xy 197.256146 -368.601752) (xy 197.218046 -368.58448) (xy 104.800146 -368.58448) (xy 104.772206 -368.607594)
			(xy 104.76865 -368.625628) (xy 104.762947 -368.652795) (xy 104.74473 -368.705231) (xy 104.719106 -368.754472)
			(xy 104.686614 -368.799478) (xy 104.647942 -368.8393) (xy 104.603906 -368.873096) (xy 104.555436 -368.900152)
			(xy 104.503556 -368.919896) (xy 104.449363 -368.931912) (xy 104.394 -368.935946) (xy 104.338637 -368.931912)
			(xy 104.284444 -368.919896) (xy 104.232564 -368.900152) (xy 104.184094 -368.873096) (xy 104.140058 -368.8393)
			(xy 104.101386 -368.799478) (xy 104.068894 -368.754472) (xy 104.04327 -368.705231) (xy 104.025053 -368.652795)
			(xy 104.01935 -368.625628) (xy 104.015794 -368.607594) (xy 103.987854 -368.58448) (xy 103.781606 -368.58448)
			(xy 103.772208 -368.588544) (xy 103.748711 -368.597952) (xy 103.699859 -368.611188) (xy 103.649687 -368.617857)
			(xy 103.62438 -368.618262) (xy 103.599072 -368.617867) (xy 103.548898 -368.611203) (xy 103.500048 -368.597956)
			(xy 103.476552 -368.588544) (xy 103.467154 -368.58448) (xy 100.835206 -368.58448) (xy 100.82629 -368.584882)
			(xy 100.809539 -368.591006) (xy 100.80244 -368.596418) (xy 100.781664 -368.613454) (xy 100.736231 -368.642133)
			(xy 100.687224 -368.664155) (xy 100.635612 -368.679083) (xy 100.582416 -368.686621) (xy 100.528688 -368.686621)
			(xy 100.475492 -368.679083) (xy 100.42388 -368.664155) (xy 100.374873 -368.642133) (xy 100.32944 -368.613454)
			(xy 100.308664 -368.596418) (xy 100.301618 -368.590913) (xy 100.284833 -368.584781) (xy 100.275898 -368.58448)
			(xy 58.120026 -368.58448) (xy 58.092848 -368.605054) (xy 58.088276 -368.62131) (xy 58.080312 -368.647571)
			(xy 58.057892 -368.697659) (xy 58.028529 -368.744019) (xy 57.992828 -368.785695) (xy 57.951525 -368.821827)
			(xy 57.905472 -368.851669) (xy 57.855619 -368.874607) (xy 57.802995 -368.890167) (xy 57.748684 -368.898028)
			(xy 57.693808 -368.898028) (xy 57.639497 -368.890167) (xy 57.586873 -368.874607) (xy 57.53702 -368.851669)
			(xy 57.490967 -368.821827) (xy 57.449664 -368.785695) (xy 57.413963 -368.744019) (xy 57.3846 -368.697659)
			(xy 57.36218 -368.647571) (xy 57.354216 -368.62131) (xy 57.349644 -368.605054) (xy 57.322466 -368.58448)
			(xy 54.746906 -368.58448) (xy 54.719728 -368.605054) (xy 54.715156 -368.62131) (xy 54.707192 -368.647571)
			(xy 54.684772 -368.697659) (xy 54.655409 -368.744019) (xy 54.619708 -368.785695) (xy 54.578405 -368.821827)
			(xy 54.532352 -368.851669) (xy 54.482499 -368.874607) (xy 54.429875 -368.890167) (xy 54.375564 -368.898028)
			(xy 54.320688 -368.898028) (xy 54.266377 -368.890167) (xy 54.213753 -368.874607) (xy 54.1639 -368.851669)
			(xy 54.117847 -368.821827) (xy 54.076544 -368.785695) (xy 54.040843 -368.744019) (xy 54.01148 -368.697659)
			(xy 53.98906 -368.647571) (xy 53.981096 -368.62131) (xy 53.976524 -368.605054) (xy 53.949346 -368.58448)
			(xy 6.14299 -368.58448) (xy 6.1341 -368.588036) (xy 6.111889 -368.596339) (xy 6.065927 -368.608)
			(xy 6.018872 -368.613861) (xy 5.995162 -368.614198) (xy 5.971455 -368.613833) (xy 5.924406 -368.607955)
			(xy 5.878444 -368.596308) (xy 5.856224 -368.588036) (xy 5.847334 -368.58448) (xy 1.5748 -368.58448)
			(xy 1.564791 -368.584968) (xy 1.546296 -368.592626) (xy 1.532138 -368.606779) (xy 1.524472 -368.625271)
			(xy 1.524 -368.63528) (xy 1.524 -370.523703) (xy 27.348898 -370.523703) (xy 27.348899 -370.456279)
			(xy 27.356975 -370.38934) (xy 27.373012 -370.323851) (xy 27.396776 -370.260753) (xy 27.427927 -370.200957)
			(xy 27.466016 -370.145322) (xy 27.48788 -370.119656) (xy 27.493675 -370.11251) (xy 27.500191 -370.09532)
			(xy 27.50058 -370.086128) (xy 27.50058 -369.928902) (xy 27.501029 -369.918771) (xy 27.508764 -369.900042)
			(xy 27.523062 -369.885684) (xy 27.541759 -369.877872) (xy 27.551888 -369.87734) (xy 28.268168 -369.87734)
			(xy 28.278325 -369.877748) (xy 28.297085 -369.885541) (xy 28.311411 -369.899943) (xy 28.319104 -369.918743)
			(xy 28.319476 -369.928902) (xy 28.319476 -370.086128) (xy 28.319878 -370.095316) (xy 28.326398 -370.1125)
			(xy 28.332176 -370.119656) (xy 28.354029 -370.145331) (xy 28.39212 -370.200963) (xy 28.423272 -370.260758)
			(xy 28.447038 -370.323854) (xy 28.463075 -370.389342) (xy 28.471152 -370.456279) (xy 28.471153 -370.523644)
			(xy 31.749193 -370.523644) (xy 31.749194 -370.456338) (xy 31.75724 -370.389514) (xy 31.773215 -370.324131)
			(xy 31.79689 -370.261126) (xy 31.827927 -370.201402) (xy 31.865879 -370.145816) (xy 31.887668 -370.120164)
			(xy 31.893471 -370.113023) (xy 31.89998 -370.095829) (xy 31.900368 -370.086636) (xy 31.900368 -369.928902)
			(xy 31.900766 -369.918727) (xy 31.908556 -369.899926) (xy 31.92295 -369.88554) (xy 31.941755 -369.877761)
			(xy 31.95193 -369.87734) (xy 32.66821 -369.87734) (xy 32.678369 -369.877825) (xy 32.697138 -369.885603)
			(xy 32.711503 -369.899972) (xy 32.719277 -369.918743) (xy 32.719772 -369.928902) (xy 32.719772 -370.086636)
			(xy 32.720171 -370.095824) (xy 32.726693 -370.113008) (xy 32.732472 -370.120164) (xy 32.754248 -370.145826)
			(xy 32.792196 -370.201411) (xy 32.823229 -370.261134) (xy 32.846902 -370.324137) (xy 32.862876 -370.389518)
			(xy 32.870921 -370.456339) (xy 32.870922 -370.523643) (xy 32.870915 -370.523703) (xy 36.148986 -370.523703)
			(xy 36.148987 -370.456279) (xy 36.157063 -370.389341) (xy 36.173099 -370.323851) (xy 36.196863 -370.260754)
			(xy 36.228013 -370.200957) (xy 36.266101 -370.145322) (xy 36.287964 -370.119656) (xy 36.29377 -370.112518)
			(xy 36.300277 -370.095322) (xy 36.300664 -370.086128) (xy 36.300664 -369.928902) (xy 36.301129 -369.918772)
			(xy 36.308861 -369.900047) (xy 36.323154 -369.88569) (xy 36.341845 -369.877875) (xy 36.351972 -369.87734)
			(xy 37.068252 -369.87734) (xy 37.078408 -369.877762) (xy 37.097167 -369.885549) (xy 37.111494 -369.899947)
			(xy 37.119188 -369.918744) (xy 37.11956 -369.928902) (xy 37.11956 -370.086128) (xy 37.119966 -370.095315)
			(xy 37.126483 -370.112499) (xy 37.13226 -370.119656) (xy 37.154114 -370.14533) (xy 37.192205 -370.200963)
			(xy 37.223359 -370.260757) (xy 37.247125 -370.323853) (xy 37.263163 -370.389341) (xy 37.27124 -370.456279)
			(xy 37.271241 -370.523703) (xy 37.271241 -370.523704) (xy 40.548752 -370.523704) (xy 40.548753 -370.456278)
			(xy 40.556831 -370.389338) (xy 40.572869 -370.323848) (xy 40.596637 -370.26075) (xy 40.627792 -370.200954)
			(xy 40.665885 -370.14532) (xy 40.687752 -370.119656) (xy 40.693556 -370.112516) (xy 40.700065 -370.095321)
			(xy 40.700452 -370.086128) (xy 40.700452 -369.928902) (xy 40.700929 -369.918774) (xy 40.708658 -369.900051)
			(xy 40.722947 -369.885694) (xy 40.741634 -369.877877) (xy 40.75176 -369.87734) (xy 41.46804 -369.87734)
			(xy 41.478202 -369.87769) (xy 41.496963 -369.885506) (xy 41.511286 -369.899925) (xy 41.518977 -369.918738)
			(xy 41.519348 -369.928902) (xy 41.519348 -370.086128) (xy 41.519756 -370.095315) (xy 41.526273 -370.112499)
			(xy 41.532048 -370.119656) (xy 41.553902 -370.14533) (xy 41.591994 -370.200962) (xy 41.623149 -370.260757)
			(xy 41.646916 -370.323852) (xy 41.662954 -370.389341) (xy 41.671031 -370.456279) (xy 41.671032 -370.523644)
			(xy 44.949071 -370.523644) (xy 44.949073 -370.456338) (xy 44.957118 -370.389515) (xy 44.973092 -370.324132)
			(xy 44.996766 -370.261127) (xy 45.027801 -370.201403) (xy 45.065751 -370.145816) (xy 45.08754 -370.120164)
			(xy 45.093339 -370.113021) (xy 45.099851 -370.095829) (xy 45.10024 -370.086636) (xy 45.10024 -369.928902)
			(xy 45.100665 -369.91873) (xy 45.10845 -369.899935) (xy 45.122835 -369.88555) (xy 45.14163 -369.877765)
			(xy 45.151802 -369.87734) (xy 45.868082 -369.87734) (xy 45.878253 -369.877778) (xy 45.897047 -369.885558)
			(xy 45.911433 -369.899939) (xy 45.919218 -369.918731) (xy 45.919644 -369.928902) (xy 45.919644 -370.086636)
			(xy 45.92005 -370.095823) (xy 45.926568 -370.113007) (xy 45.932344 -370.120164) (xy 45.95412 -370.145826)
			(xy 45.992071 -370.20141) (xy 46.023105 -370.261132) (xy 46.046779 -370.324136) (xy 46.062754 -370.389517)
			(xy 46.070799 -370.456339) (xy 46.0708 -370.523643) (xy 46.062757 -370.590465) (xy 46.046785 -370.655847)
			(xy 46.023113 -370.718851) (xy 45.99208 -370.778574) (xy 45.954131 -370.83416) (xy 45.932344 -370.859812)
			(xy 45.926553 -370.866961) (xy 45.920036 -370.884149) (xy 45.919644 -370.89334) (xy 45.919644 -371.386862)
			(xy 45.920085 -371.396046) (xy 45.926578 -371.41323) (xy 45.932344 -371.42039) (xy 45.954146 -371.44603)
			(xy 45.992096 -371.501618) (xy 46.023129 -371.561343) (xy 46.046568 -371.623726) (xy 47.14919 -371.623726)
			(xy 47.149193 -371.556417) (xy 47.157242 -371.489591) (xy 47.17322 -371.424206) (xy 47.1969 -371.3612)
			(xy 47.22794 -371.301475) (xy 47.265897 -371.24589) (xy 47.287688 -371.220238) (xy 47.293492 -371.213098)
			(xy 47.300003 -371.195904) (xy 47.300388 -371.18671) (xy 47.300388 -371.028722) (xy 47.300783 -371.018546)
			(xy 47.30857 -370.999742) (xy 47.322966 -370.985355) (xy 47.341773 -370.977578) (xy 47.35195 -370.97716)
			(xy 48.06823 -370.97716) (xy 48.078392 -370.977609) (xy 48.097167 -370.985398) (xy 48.111532 -370.999777)
			(xy 48.119301 -371.018559) (xy 48.119792 -371.028722) (xy 48.119792 -371.18671) (xy 48.120199 -371.195898)
			(xy 48.126715 -371.213082) (xy 48.132492 -371.220238) (xy 48.154241 -371.245921) (xy 48.192189 -371.301504)
			(xy 48.196948 -371.310662) (xy 53.966364 -371.310662) (xy 53.966364 -370.447062) (xy 53.96685 -370.419793)
			(xy 53.974612 -370.365809) (xy 53.989977 -370.313479) (xy 54.012634 -370.263869) (xy 54.04212 -370.217988)
			(xy 54.077835 -370.176771) (xy 54.119052 -370.141056) (xy 54.164933 -370.11157) (xy 54.214543 -370.088913)
			(xy 54.266873 -370.073548) (xy 54.320857 -370.065786) (xy 54.375395 -370.065786) (xy 54.429379 -370.073548)
			(xy 54.481709 -370.088913) (xy 54.531319 -370.11157) (xy 54.5772 -370.141056) (xy 54.618417 -370.176771)
			(xy 54.654132 -370.217988) (xy 54.683618 -370.263869) (xy 54.706275 -370.313479) (xy 54.72164 -370.365809)
			(xy 54.729402 -370.419793) (xy 54.729888 -370.447062) (xy 54.729888 -371.310662) (xy 57.339484 -371.310662)
			(xy 57.339484 -370.447062) (xy 57.33997 -370.419793) (xy 57.347732 -370.365809) (xy 57.363097 -370.313479)
			(xy 57.385754 -370.263869) (xy 57.41524 -370.217988) (xy 57.450955 -370.176771) (xy 57.492172 -370.141056)
			(xy 57.538053 -370.11157) (xy 57.587663 -370.088913) (xy 57.639993 -370.073548) (xy 57.693977 -370.065786)
			(xy 57.748515 -370.065786) (xy 57.802499 -370.073548) (xy 57.854829 -370.088913) (xy 57.904439 -370.11157)
			(xy 57.95032 -370.141056) (xy 57.991537 -370.176771) (xy 58.027252 -370.217988) (xy 58.056738 -370.263869)
			(xy 58.079395 -370.313479) (xy 58.09476 -370.365809) (xy 58.102522 -370.419793) (xy 58.103008 -370.447062)
			(xy 58.103008 -370.523703) (xy 71.348807 -370.523703) (xy 71.348808 -370.456279) (xy 71.356885 -370.38934)
			(xy 71.372921 -370.32385) (xy 71.396686 -370.260753) (xy 71.427838 -370.200956) (xy 71.465928 -370.145321)
			(xy 71.487792 -370.119656) (xy 71.493589 -370.112511) (xy 71.500104 -370.09532) (xy 71.500492 -370.086128)
			(xy 71.500492 -369.928902) (xy 71.501027 -369.918781) (xy 71.508745 -369.900069) (xy 71.523016 -369.885715)
			(xy 71.541682 -369.877887) (xy 71.5518 -369.87734) (xy 72.26808 -369.87734) (xy 72.278238 -369.877739)
			(xy 72.296998 -369.885535) (xy 72.311323 -369.89994) (xy 72.319016 -369.918742) (xy 72.319388 -369.928902)
			(xy 72.319388 -370.086128) (xy 72.319787 -370.095316) (xy 72.326309 -370.1125) (xy 72.332088 -370.119656)
			(xy 72.353941 -370.145331) (xy 72.39203 -370.200964) (xy 72.423182 -370.260758) (xy 72.446948 -370.323854)
			(xy 72.462984 -370.389342) (xy 72.471061 -370.45628) (xy 72.471063 -370.523644) (xy 75.749102 -370.523644)
			(xy 75.749103 -370.456338) (xy 75.757149 -370.389513) (xy 75.773125 -370.32413) (xy 75.796801 -370.261125)
			(xy 75.827837 -370.201401) (xy 75.86579 -370.145816) (xy 75.88758 -370.120164) (xy 75.893372 -370.113015)
			(xy 75.89989 -370.095828) (xy 75.90028 -370.086636) (xy 75.90028 -369.928902) (xy 75.900666 -369.918725)
			(xy 75.908459 -369.899923) (xy 75.922856 -369.885536) (xy 75.941665 -369.877759) (xy 75.951842 -369.87734)
			(xy 76.668122 -369.87734) (xy 76.678281 -369.877815) (xy 76.697052 -369.885597) (xy 76.711416 -369.899969)
			(xy 76.71919 -369.918742) (xy 76.719684 -369.928902) (xy 76.719684 -370.086636) (xy 76.72008 -370.095825)
			(xy 76.726604 -370.113009) (xy 76.732384 -370.120164) (xy 76.754159 -370.145826) (xy 76.792107 -370.201412)
			(xy 76.82314 -370.261134) (xy 76.846812 -370.324137) (xy 76.862785 -370.389518) (xy 76.87083 -370.456339)
			(xy 76.870831 -370.523643) (xy 76.870824 -370.523703) (xy 80.148895 -370.523703) (xy 80.148896 -370.456279)
			(xy 80.156972 -370.38934) (xy 80.173008 -370.323851) (xy 80.196773 -370.260754) (xy 80.227924 -370.200957)
			(xy 80.266012 -370.145322) (xy 80.287876 -370.119656) (xy 80.293671 -370.112509) (xy 80.300187 -370.09532)
			(xy 80.300576 -370.086128) (xy 80.300576 -369.928902) (xy 80.301029 -369.918771) (xy 80.308763 -369.900043)
			(xy 80.32306 -369.885685) (xy 80.341755 -369.877873) (xy 80.351884 -369.87734) (xy 81.068164 -369.87734)
			(xy 81.078321 -369.877752) (xy 81.09708 -369.885543) (xy 81.111406 -369.899944) (xy 81.1191 -369.918743)
			(xy 81.119472 -369.928902) (xy 81.119472 -370.086128) (xy 81.119875 -370.095316) (xy 81.126394 -370.1125)
			(xy 81.132172 -370.119656) (xy 81.154025 -370.14533) (xy 81.192116 -370.200963) (xy 81.223269 -370.260758)
			(xy 81.247035 -370.323853) (xy 81.263072 -370.389342) (xy 81.271149 -370.456279) (xy 81.27115 -370.523703)
			(xy 84.548686 -370.523703) (xy 84.548687 -370.456279) (xy 84.556763 -370.389341) (xy 84.572799 -370.323851)
			(xy 84.596563 -370.260754) (xy 84.627713 -370.200957) (xy 84.665801 -370.145322) (xy 84.687664 -370.119656)
			(xy 84.69347 -370.112518) (xy 84.699977 -370.095322) (xy 84.700364 -370.086128) (xy 84.700364 -369.928902)
			(xy 84.700829 -369.918772) (xy 84.708561 -369.900047) (xy 84.722854 -369.88569) (xy 84.741545 -369.877875)
			(xy 84.751672 -369.87734) (xy 85.467952 -369.87734) (xy 85.478108 -369.877762) (xy 85.496867 -369.885549)
			(xy 85.511194 -369.899947) (xy 85.518888 -369.918744) (xy 85.51926 -369.928902) (xy 85.51926 -370.086128)
			(xy 85.519666 -370.095315) (xy 85.526183 -370.112499) (xy 85.53196 -370.119656) (xy 85.553814 -370.14533)
			(xy 85.591905 -370.200963) (xy 85.623059 -370.260757) (xy 85.646825 -370.323853) (xy 85.662863 -370.389341)
			(xy 85.67094 -370.456279) (xy 85.670941 -370.523644) (xy 115.349244 -370.523644) (xy 115.349245 -370.456338)
			(xy 115.35729 -370.389516) (xy 115.373263 -370.324133) (xy 115.396936 -370.261128) (xy 115.427969 -370.201404)
			(xy 115.465917 -370.145817) (xy 115.487704 -370.120164) (xy 115.493499 -370.113018) (xy 115.500014 -370.095828)
			(xy 115.500404 -370.086636) (xy 115.500404 -369.928902) (xy 115.500934 -369.918749) (xy 115.508702 -369.899986)
			(xy 115.523056 -369.885622) (xy 115.541813 -369.877841) (xy 115.551966 -369.87734) (xy 116.268246 -369.87734)
			(xy 116.278407 -369.877796) (xy 116.297177 -369.885586) (xy 116.311541 -369.899963) (xy 116.319314 -369.918741)
			(xy 116.319808 -369.928902) (xy 116.319808 -370.086636) (xy 116.320199 -370.095825) (xy 116.326726 -370.11301)
			(xy 116.332508 -370.120164) (xy 116.354286 -370.145825) (xy 116.392238 -370.201409) (xy 116.423275 -370.261131)
			(xy 116.446951 -370.324134) (xy 116.462926 -370.389516) (xy 116.470972 -370.456338) (xy 116.470973 -370.523644)
			(xy 116.470966 -370.523703) (xy 119.749013 -370.523703) (xy 119.749014 -370.456279) (xy 119.757091 -370.38934)
			(xy 119.773128 -370.32385) (xy 119.796893 -370.260752) (xy 119.828045 -370.200956) (xy 119.866135 -370.145321)
			(xy 119.888 -370.119656) (xy 119.893798 -370.112512) (xy 119.900312 -370.09532) (xy 119.9007 -370.086128)
			(xy 119.9007 -369.928902) (xy 119.901227 -369.91878) (xy 119.908947 -369.900067) (xy 119.92322 -369.885712)
			(xy 119.941889 -369.877886) (xy 119.952008 -369.87734) (xy 120.668288 -369.87734) (xy 120.678446 -369.877732)
			(xy 120.697206 -369.885531) (xy 120.711531 -369.899938) (xy 120.719224 -369.918741) (xy 120.719596 -369.928902)
			(xy 120.719596 -370.086128) (xy 120.719993 -370.095317) (xy 120.726516 -370.112501) (xy 120.732296 -370.119656)
			(xy 120.754148 -370.145331) (xy 120.792238 -370.200964) (xy 120.823389 -370.260759) (xy 120.847154 -370.323854)
			(xy 120.863191 -370.389342) (xy 120.871267 -370.45628) (xy 120.871269 -370.523644) (xy 124.149308 -370.523644)
			(xy 124.149309 -370.456338) (xy 124.157355 -370.389513) (xy 124.173331 -370.32413) (xy 124.197007 -370.261125)
			(xy 124.228045 -370.201401) (xy 124.265998 -370.145816) (xy 124.287788 -370.120164) (xy 124.293581 -370.113016)
			(xy 124.300098 -370.095828) (xy 124.300488 -370.086636) (xy 124.300488 -369.928902) (xy 124.300867 -369.918724)
			(xy 124.30866 -369.89992) (xy 124.32306 -369.885533) (xy 124.341872 -369.877757) (xy 124.35205 -369.87734)
			(xy 125.06833 -369.87734) (xy 125.07849 -369.877809) (xy 125.09726 -369.885593) (xy 125.111625 -369.899967)
			(xy 125.119398 -369.918742) (xy 125.119892 -369.928902) (xy 125.119892 -370.086636) (xy 125.120286 -370.095825)
			(xy 125.126811 -370.113009) (xy 125.132592 -370.120164) (xy 125.154367 -370.145826) (xy 125.192314 -370.201412)
			(xy 125.223346 -370.261134) (xy 125.247018 -370.324138) (xy 125.262991 -370.389518) (xy 125.271036 -370.456339)
			(xy 125.271037 -370.523643) (xy 125.271037 -370.523644) (xy 128.549099 -370.523644) (xy 128.5491 -370.456338)
			(xy 128.557146 -370.389514) (xy 128.573121 -370.32413) (xy 128.596797 -370.261125) (xy 128.627834 -370.201402)
			(xy 128.665787 -370.145816) (xy 128.687576 -370.120164) (xy 128.693368 -370.113015) (xy 128.699886 -370.095828)
			(xy 128.700276 -370.086636) (xy 128.700276 -369.928902) (xy 128.700666 -369.918726) (xy 128.708458 -369.899924)
			(xy 128.722854 -369.885538) (xy 128.741661 -369.877759) (xy 128.751838 -369.87734) (xy 129.468118 -369.87734)
			(xy 129.478277 -369.877818) (xy 129.497047 -369.885599) (xy 129.511412 -369.89997) (xy 129.519185 -369.918743)
			(xy 129.51968 -369.928902) (xy 129.51968 -370.086636) (xy 129.520077 -370.095824) (xy 129.5266 -370.113008)
			(xy 129.53238 -370.120164) (xy 129.554155 -370.145826) (xy 129.592103 -370.201412) (xy 129.623136 -370.261134)
			(xy 129.646809 -370.324137) (xy 129.662782 -370.389518) (xy 129.670827 -370.456339) (xy 129.670828 -370.523643)
			(xy 129.670828 -370.523644) (xy 159.349153 -370.523644) (xy 159.349154 -370.456338) (xy 159.357199 -370.389515)
			(xy 159.373173 -370.324133) (xy 159.396846 -370.261128) (xy 159.427879 -370.201404) (xy 159.465828 -370.145816)
			(xy 159.487616 -370.120164) (xy 159.493412 -370.113019) (xy 159.499927 -370.095828) (xy 159.500316 -370.086636)
			(xy 159.500316 -369.928902) (xy 159.500835 -369.918747) (xy 159.508604 -369.899982) (xy 159.522962 -369.885618)
			(xy 159.541723 -369.877839) (xy 159.551878 -369.87734) (xy 160.268158 -369.87734) (xy 160.278327 -369.877798)
			(xy 160.297121 -369.88557) (xy 160.311508 -369.899945) (xy 160.319294 -369.918733) (xy 160.31972 -369.928902)
			(xy 160.31972 -370.086636) (xy 160.320109 -370.095826) (xy 160.326637 -370.11301) (xy 160.33242 -370.120164)
			(xy 160.354197 -370.145825) (xy 160.392149 -370.20141) (xy 160.423185 -370.261131) (xy 160.44686 -370.324135)
			(xy 160.462835 -370.389516) (xy 160.470881 -370.456339) (xy 160.470882 -370.523643) (xy 160.470875 -370.523703)
			(xy 163.748922 -370.523703) (xy 163.748923 -370.456279) (xy 163.757 -370.389339) (xy 163.773037 -370.323849)
			(xy 163.796803 -370.260752) (xy 163.827956 -370.200955) (xy 163.866047 -370.145321) (xy 163.887912 -370.119656)
			(xy 163.893711 -370.112513) (xy 163.900224 -370.095321) (xy 163.900612 -370.086128) (xy 163.900612 -369.928902)
			(xy 163.901127 -369.918779) (xy 163.908849 -369.900063) (xy 163.923126 -369.885708) (xy 163.9418 -369.877884)
			(xy 163.95192 -369.87734) (xy 164.6682 -369.87734) (xy 164.678359 -369.877722) (xy 164.697119 -369.885526)
			(xy 164.711444 -369.899935) (xy 164.719136 -369.918741) (xy 164.719508 -369.928902) (xy 164.719508 -370.086128)
			(xy 164.719903 -370.095317) (xy 164.726427 -370.112501) (xy 164.732208 -370.119656) (xy 164.75406 -370.145331)
			(xy 164.792148 -370.200964) (xy 164.823299 -370.260759) (xy 164.847064 -370.323855) (xy 164.8631 -370.389343)
			(xy 164.871176 -370.45628) (xy 164.871178 -370.523644) (xy 168.149241 -370.523644) (xy 168.149242 -370.456338)
			(xy 168.157287 -370.389516) (xy 168.17326 -370.324133) (xy 168.196933 -370.261128) (xy 168.227965 -370.201404)
			(xy 168.265913 -370.145817) (xy 168.2877 -370.120164) (xy 168.293494 -370.113017) (xy 168.30001 -370.095828)
			(xy 168.3004 -370.086636) (xy 168.3004 -369.928902) (xy 168.300934 -369.918749) (xy 168.308701 -369.899987)
			(xy 168.323054 -369.885623) (xy 168.341809 -369.877842) (xy 168.351962 -369.87734) (xy 169.068242 -369.87734)
			(xy 169.078403 -369.877799) (xy 169.097173 -369.885588) (xy 169.111537 -369.899964) (xy 169.11931 -369.918741)
			(xy 169.119804 -369.928902) (xy 169.119804 -370.086636) (xy 169.120196 -370.095825) (xy 169.126722 -370.113009)
			(xy 169.132504 -370.120164) (xy 169.154279 -370.145826) (xy 169.192225 -370.201412) (xy 169.223256 -370.261135)
			(xy 169.246928 -370.324138) (xy 169.2629 -370.389519) (xy 169.270945 -370.456339) (xy 169.270946 -370.523643)
			(xy 169.270946 -370.523644) (xy 172.549008 -370.523644) (xy 172.549009 -370.456338) (xy 172.557055 -370.389513)
			(xy 172.573031 -370.32413) (xy 172.596707 -370.261125) (xy 172.627745 -370.201401) (xy 172.665698 -370.145816)
			(xy 172.687488 -370.120164) (xy 172.693281 -370.113016) (xy 172.699798 -370.095828) (xy 172.700188 -370.086636)
			(xy 172.700188 -369.928902) (xy 172.700567 -369.918724) (xy 172.70836 -369.89992) (xy 172.72276 -369.885533)
			(xy 172.741572 -369.877757) (xy 172.75175 -369.87734) (xy 173.46803 -369.87734) (xy 173.47819 -369.877809)
			(xy 173.49696 -369.885593) (xy 173.511325 -369.899967) (xy 173.519098 -369.918742) (xy 173.519592 -369.928902)
			(xy 173.519592 -370.086636) (xy 173.519986 -370.095825) (xy 173.526511 -370.113009) (xy 173.532292 -370.120164)
			(xy 173.554067 -370.145826) (xy 173.592014 -370.201412) (xy 173.623046 -370.261134) (xy 173.646718 -370.324138)
			(xy 173.662691 -370.389518) (xy 173.670736 -370.456339) (xy 173.670737 -370.523643) (xy 173.662694 -370.590464)
			(xy 173.646724 -370.655845) (xy 173.623054 -370.718849) (xy 173.592023 -370.778573) (xy 173.554078 -370.834159)
			(xy 173.532292 -370.859812) (xy 173.526507 -370.866965) (xy 173.519986 -370.88415) (xy 173.519592 -370.89334)
			(xy 173.519592 -371.386862) (xy 173.520022 -371.396047) (xy 173.526522 -371.413231) (xy 173.532292 -371.42039)
			(xy 173.554093 -371.446031) (xy 173.592039 -371.50162) (xy 173.62307 -371.561345) (xy 173.646506 -371.623725)
			(xy 174.74915 -371.623725) (xy 174.749154 -371.556417) (xy 174.757201 -371.489592) (xy 174.773178 -371.424208)
			(xy 174.796855 -371.361202) (xy 174.827893 -371.301477) (xy 174.865846 -371.24589) (xy 174.887636 -371.220238)
			(xy 174.893446 -371.213102) (xy 174.899952 -371.195904) (xy 174.900336 -371.18671) (xy 174.900336 -371.028722)
			(xy 174.900782 -371.018552) (xy 174.908559 -370.999758) (xy 174.922938 -370.985373) (xy 174.941728 -370.977587)
			(xy 174.951898 -370.97716) (xy 175.668178 -370.97716) (xy 175.678351 -370.977583) (xy 175.697149 -370.985364)
			(xy 175.711536 -370.999751) (xy 175.719317 -371.018549) (xy 175.71974 -371.028722) (xy 175.71974 -371.18671)
			(xy 175.720159 -371.195896) (xy 175.726668 -371.21308) (xy 175.73244 -371.220238) (xy 175.754191 -371.245921)
			(xy 175.792142 -371.301502) (xy 175.823178 -371.361221) (xy 175.846854 -371.424222) (xy 175.86283 -371.489601)
			(xy 175.870878 -371.55642) (xy 175.870881 -371.623723) (xy 175.862841 -371.690543) (xy 175.846871 -371.755923)
			(xy 175.823202 -371.818926) (xy 175.792172 -371.878649) (xy 175.754226 -371.934234) (xy 175.73244 -371.959886)
			(xy 175.726617 -371.967012) (xy 175.72012 -371.984218) (xy 175.71974 -371.993414) (xy 175.71974 -372.486682)
			(xy 175.720172 -372.495867) (xy 175.726672 -372.51305) (xy 175.73244 -372.52021) (xy 175.754262 -372.545834)
			(xy 175.792211 -372.601424) (xy 175.823244 -372.661151) (xy 175.846916 -372.72416) (xy 175.862887 -372.789545)
			(xy 175.870929 -372.856371) (xy 175.870926 -372.92368) (xy 175.862878 -372.990505) (xy 175.846901 -373.055889)
			(xy 175.823223 -373.118895) (xy 175.792185 -373.17862) (xy 175.754231 -373.234206) (xy 175.73244 -373.259858)
			(xy 175.726629 -373.266993) (xy 175.720125 -373.284191) (xy 175.71974 -373.293386) (xy 175.71974 -373.451374)
			(xy 175.719314 -373.461547) (xy 175.711534 -373.480345) (xy 175.697148 -373.494731) (xy 175.678351 -373.502513)
			(xy 175.668178 -373.502936) (xy 174.951898 -373.502936) (xy 174.941723 -373.502537) (xy 174.922923 -373.494747)
			(xy 174.908538 -373.480353) (xy 174.900757 -373.461549) (xy 174.900336 -373.451374) (xy 174.900336 -373.293386)
			(xy 174.899925 -373.284199) (xy 174.893411 -373.267015) (xy 174.887636 -373.259858) (xy 174.865882 -373.234178)
			(xy 174.827932 -373.178596) (xy 174.796898 -373.118876) (xy 174.773223 -373.055875) (xy 174.757248 -372.990496)
			(xy 174.749201 -372.923677) (xy 174.749198 -372.856374) (xy 174.757239 -372.789554) (xy 174.773208 -372.724174)
			(xy 174.796877 -372.661171) (xy 174.827906 -372.601448) (xy 174.865851 -372.545862) (xy 174.887636 -372.52021)
			(xy 174.893458 -372.513083) (xy 174.899957 -372.495878) (xy 174.900336 -372.486682) (xy 174.900336 -371.993414)
			(xy 174.899911 -371.984229) (xy 174.893407 -371.967044) (xy 174.887636 -371.959886) (xy 174.865811 -371.934265)
			(xy 174.827863 -371.878674) (xy 174.796832 -371.818946) (xy 174.773161 -371.755937) (xy 174.757191 -371.690551)
			(xy 174.74915 -371.623725) (xy 173.646506 -371.623725) (xy 173.646741 -371.624351) (xy 173.662712 -371.689734)
			(xy 173.670754 -371.756558) (xy 173.670753 -371.823863) (xy 173.662708 -371.890686) (xy 173.646734 -371.956069)
			(xy 173.623061 -372.019074) (xy 173.592028 -372.078798) (xy 173.55408 -372.134385) (xy 173.532292 -372.160038)
			(xy 173.526496 -372.167183) (xy 173.519981 -372.184374) (xy 173.519592 -372.193566) (xy 173.519592 -372.351554)
			(xy 173.519099 -372.361719) (xy 173.511335 -372.380507) (xy 173.496971 -372.394892) (xy 173.478194 -372.402684)
			(xy 173.46803 -372.403116) (xy 172.75175 -372.403116) (xy 172.741576 -372.402694) (xy 172.722773 -372.394917)
			(xy 172.708385 -372.38053) (xy 172.700607 -372.361728) (xy 172.700188 -372.351554) (xy 172.700188 -372.193566)
			(xy 172.699797 -372.184377) (xy 172.69327 -372.167192) (xy 172.687488 -372.160038) (xy 172.665713 -372.134375)
			(xy 172.62776 -372.078791) (xy 172.596724 -372.01907) (xy 172.573048 -371.956067) (xy 172.557072 -371.890685)
			(xy 172.549026 -371.823863) (xy 172.549025 -371.756558) (xy 172.557069 -371.689736) (xy 172.573042 -371.624354)
			(xy 172.596715 -371.561349) (xy 172.627749 -371.501627) (xy 172.6657 -371.446041) (xy 172.687488 -371.42039)
			(xy 172.69327 -371.413234) (xy 172.699794 -371.396052) (xy 172.700188 -371.386862) (xy 172.700188 -370.89334)
			(xy 172.699761 -370.884154) (xy 172.69326 -370.86697) (xy 172.687488 -370.859812) (xy 172.665687 -370.83417)
			(xy 172.627735 -370.778583) (xy 172.5967 -370.718859) (xy 172.573026 -370.655853) (xy 172.557052 -370.590469)
			(xy 172.549008 -370.523644) (xy 169.270946 -370.523644) (xy 169.262904 -370.590464) (xy 169.246933 -370.655845)
			(xy 169.223264 -370.718849) (xy 169.192234 -370.778572) (xy 169.15429 -370.834159) (xy 169.132504 -370.859812)
			(xy 169.12672 -370.866966) (xy 169.120198 -370.88415) (xy 169.119804 -370.89334) (xy 169.119804 -371.386862)
			(xy 169.120231 -371.396047) (xy 169.126733 -371.413232) (xy 169.132504 -371.42039) (xy 169.154304 -371.446031)
			(xy 169.19225 -371.50162) (xy 169.22328 -371.561346) (xy 169.246737 -371.623785) (xy 170.348831 -371.623785)
			(xy 170.348834 -371.556358) (xy 170.356914 -371.489416) (xy 170.372955 -371.423924) (xy 170.396726 -371.360825)
			(xy 170.427884 -371.301029) (xy 170.46598 -371.245394) (xy 170.487848 -371.21973) (xy 170.493663 -371.212598)
			(xy 170.500165 -371.195397) (xy 170.500548 -371.186202) (xy 170.500548 -371.028722) (xy 170.501045 -371.018596)
			(xy 170.508767 -370.999873) (xy 170.52305 -370.985516) (xy 170.541732 -370.977698) (xy 170.551856 -370.97716)
			(xy 171.268136 -370.97716) (xy 171.278287 -370.977591) (xy 171.297033 -370.985391) (xy 171.311354 -370.999784)
			(xy 171.319059 -371.018568) (xy 171.319444 -371.028722) (xy 171.319444 -371.186202) (xy 171.319866 -371.195388)
			(xy 171.326373 -371.212571) (xy 171.332144 -371.21973) (xy 171.353973 -371.245425) (xy 171.392066 -371.301054)
			(xy 171.423222 -371.360846) (xy 171.44699 -371.423939) (xy 171.46303 -371.489425) (xy 171.47111 -371.556361)
			(xy 171.471113 -371.623782) (xy 171.46304 -371.690719) (xy 171.447007 -371.756207) (xy 171.423245 -371.819302)
			(xy 171.392096 -371.879097) (xy 171.354008 -371.93473) (xy 171.332144 -371.960394) (xy 171.326361 -371.967548)
			(xy 171.31984 -371.984732) (xy 171.319444 -371.993922) (xy 171.319444 -372.486174) (xy 171.319879 -372.495358)
			(xy 171.326377 -372.512542) (xy 171.332144 -372.519702) (xy 171.354043 -372.545339) (xy 171.392135 -372.600976)
			(xy 171.423287 -372.660776) (xy 171.447052 -372.723876) (xy 171.463087 -372.789369) (xy 171.471161 -372.856312)
			(xy 171.471158 -372.923739) (xy 171.463077 -372.990681) (xy 171.447037 -373.056172) (xy 171.423266 -373.119271)
			(xy 171.392108 -373.179068) (xy 171.354012 -373.234702) (xy 171.332144 -373.260366) (xy 171.32633 -373.267499)
			(xy 171.319827 -373.284699) (xy 171.319444 -373.293894) (xy 171.319444 -373.451374) (xy 171.318952 -373.461501)
			(xy 171.31123 -373.480225) (xy 171.296945 -373.494583) (xy 171.27826 -373.5024) (xy 171.268136 -373.502936)
			(xy 170.551856 -373.502936) (xy 170.541704 -373.502515) (xy 170.522957 -373.494712) (xy 170.508637 -373.480316)
			(xy 170.500932 -373.461529) (xy 170.500548 -373.451374) (xy 170.500548 -373.293894) (xy 170.50013 -373.284708)
			(xy 170.493621 -373.267524) (xy 170.487848 -373.260366) (xy 170.466016 -373.234674) (xy 170.427923 -373.179044)
			(xy 170.396768 -373.119252) (xy 170.373 -373.056159) (xy 170.356961 -372.990673) (xy 170.348881 -372.923736)
			(xy 170.348878 -372.856315) (xy 170.356951 -372.789378) (xy 170.372985 -372.72389) (xy 170.396747 -372.660794)
			(xy 170.427897 -372.600999) (xy 170.465984 -372.545366) (xy 170.487848 -372.519702) (xy 170.493632 -372.512548)
			(xy 170.500153 -372.495364) (xy 170.500548 -372.486174) (xy 170.500548 -371.993922) (xy 170.500117 -371.984737)
			(xy 170.493617 -371.967553) (xy 170.487848 -371.960394) (xy 170.465945 -371.93476) (xy 170.427854 -371.879122)
			(xy 170.396703 -371.819322) (xy 170.372938 -371.756221) (xy 170.356904 -371.690728) (xy 170.348831 -371.623785)
			(xy 169.246737 -371.623785) (xy 169.24695 -371.624352) (xy 169.262921 -371.689735) (xy 169.270963 -371.756558)
			(xy 169.270962 -371.823863) (xy 169.262917 -371.890686) (xy 169.246944 -371.956068) (xy 169.223271 -372.019073)
			(xy 169.192239 -372.078798) (xy 169.154291 -372.134385) (xy 169.132504 -372.160038) (xy 169.126709 -372.167185)
			(xy 169.120193 -372.184374) (xy 169.119804 -372.193566) (xy 169.119804 -372.351554) (xy 169.1193 -372.361717)
			(xy 169.111537 -372.380503) (xy 169.097177 -372.394888) (xy 169.078405 -372.402682) (xy 169.068242 -372.403116)
			(xy 168.351962 -372.403116) (xy 168.341782 -372.402766) (xy 168.322978 -372.39496) (xy 168.308593 -372.380552)
			(xy 168.300817 -372.361734) (xy 168.3004 -372.351554) (xy 168.3004 -372.193566) (xy 168.300006 -372.184377)
			(xy 168.293481 -372.167193) (xy 168.2877 -372.160038) (xy 168.265927 -372.134374) (xy 168.227981 -372.078788)
			(xy 168.196949 -372.019066) (xy 168.173277 -371.956063) (xy 168.157304 -371.890683) (xy 168.14926 -371.823862)
			(xy 168.149258 -371.756559) (xy 168.1573 -371.689738) (xy 168.173271 -371.624357) (xy 168.19694 -371.561353)
			(xy 168.22797 -371.50163) (xy 168.265914 -371.446043) (xy 168.2877 -371.42039) (xy 168.293483 -371.413235)
			(xy 168.300006 -371.396052) (xy 168.3004 -371.386862) (xy 168.3004 -370.89334) (xy 168.299971 -370.884155)
			(xy 168.29347 -370.86697) (xy 168.2877 -370.859812) (xy 168.265902 -370.834169) (xy 168.227956 -370.77858)
			(xy 168.196925 -370.718855) (xy 168.173255 -370.65585) (xy 168.157284 -370.590467) (xy 168.149241 -370.523644)
			(xy 164.871178 -370.523644) (xy 164.871178 -370.523702) (xy 164.863103 -370.59064) (xy 164.847069 -370.656128)
			(xy 164.823307 -370.719224) (xy 164.792158 -370.77902) (xy 164.754071 -370.834655) (xy 164.732208 -370.86032)
			(xy 164.726421 -370.867472) (xy 164.7199 -370.884657) (xy 164.719508 -370.893848) (xy 164.719508 -371.386354)
			(xy 164.719938 -371.395539) (xy 164.726438 -371.412724) (xy 164.732208 -371.419882) (xy 164.754085 -371.445536)
			(xy 164.792173 -371.501172) (xy 164.823323 -371.56097) (xy 164.846957 -371.623726) (xy 165.949062 -371.623726)
			(xy 165.949066 -371.556417) (xy 165.957114 -371.489592) (xy 165.973091 -371.424207) (xy 165.996769 -371.361201)
			(xy 166.027807 -371.301477) (xy 166.065761 -371.24589) (xy 166.087552 -371.220238) (xy 166.093364 -371.213104)
			(xy 166.099868 -371.195905) (xy 166.100252 -371.18671) (xy 166.100252 -371.028722) (xy 166.100682 -371.01855)
			(xy 166.108463 -370.999753) (xy 166.122847 -370.985367) (xy 166.141642 -370.977584) (xy 166.151814 -370.97716)
			(xy 166.868094 -370.97716) (xy 166.878268 -370.977569) (xy 166.897067 -370.985356) (xy 166.911453 -370.999747)
			(xy 166.919234 -371.018548) (xy 166.919656 -371.028722) (xy 166.919656 -371.18671) (xy 166.920071 -371.195896)
			(xy 166.926582 -371.21308) (xy 166.932356 -371.220238) (xy 166.954106 -371.245921) (xy 166.992057 -371.301503)
			(xy 167.023092 -371.361222) (xy 167.046767 -371.424223) (xy 167.062743 -371.489601) (xy 167.07079 -371.55642)
			(xy 167.070793 -371.623722) (xy 167.062753 -371.690543) (xy 167.046784 -371.755923) (xy 167.023115 -371.818926)
			(xy 166.992086 -371.878648) (xy 166.954141 -371.934234) (xy 166.932356 -371.959886) (xy 166.926535 -371.967014)
			(xy 166.920036 -371.984218) (xy 166.919656 -371.993414) (xy 166.919656 -372.486682) (xy 166.920085 -372.495867)
			(xy 166.926586 -372.513051) (xy 166.932356 -372.52021) (xy 166.954177 -372.545834) (xy 166.992126 -372.601425)
			(xy 167.023158 -372.661152) (xy 167.046829 -372.72416) (xy 167.0628 -372.789546) (xy 167.070841 -372.856372)
			(xy 167.070838 -372.923679) (xy 167.06279 -372.990504) (xy 167.046814 -373.055889) (xy 167.023137 -373.118895)
			(xy 166.992099 -373.178619) (xy 166.954146 -373.234206) (xy 166.932356 -373.259858) (xy 166.926547 -373.266994)
			(xy 166.920041 -373.284192) (xy 166.919656 -373.293386) (xy 166.919656 -373.451374) (xy 166.919215 -373.461545)
			(xy 166.911437 -373.48034) (xy 166.897057 -373.494726) (xy 166.878264 -373.502511) (xy 166.868094 -373.502936)
			(xy 166.151814 -373.502936) (xy 166.14164 -373.502524) (xy 166.122841 -373.494739) (xy 166.108454 -373.480349)
			(xy 166.100673 -373.461548) (xy 166.100252 -373.451374) (xy 166.100252 -373.293386) (xy 166.099837 -373.2842)
			(xy 166.093325 -373.267016) (xy 166.087552 -373.259858) (xy 166.065797 -373.234178) (xy 166.027847 -373.178596)
			(xy 165.996811 -373.118877) (xy 165.973136 -373.055876) (xy 165.95716 -372.990497) (xy 165.949113 -372.923677)
			(xy 165.94911 -372.856374) (xy 165.957151 -372.789554) (xy 165.973121 -372.724173) (xy 165.99679 -372.66117)
			(xy 166.02782 -372.601448) (xy 166.065766 -372.545862) (xy 166.087552 -372.52021) (xy 166.093376 -372.513084)
			(xy 166.099873 -372.495879) (xy 166.100252 -372.486682) (xy 166.100252 -371.993414) (xy 166.099824 -371.984229)
			(xy 166.093321 -371.967045) (xy 166.087552 -371.959886) (xy 166.065726 -371.934265) (xy 166.027778 -371.878674)
			(xy 165.996745 -371.818947) (xy 165.973074 -371.755938) (xy 165.957104 -371.690552) (xy 165.949062 -371.623726)
			(xy 164.846957 -371.623726) (xy 164.847086 -371.624068) (xy 164.86312 -371.689559) (xy 164.871195 -371.756498)
			(xy 164.871194 -371.823923) (xy 164.863116 -371.890862) (xy 164.84708 -371.956352) (xy 164.823314 -372.019449)
			(xy 164.792162 -372.079246) (xy 164.754073 -372.134881) (xy 164.732208 -372.160546) (xy 164.72641 -372.16769)
			(xy 164.719896 -372.184881) (xy 164.719508 -372.194074) (xy 164.719508 -372.351554) (xy 164.718937 -372.361672)
			(xy 164.711233 -372.380383) (xy 164.696973 -372.394739) (xy 164.678314 -372.402568) (xy 164.6682 -372.403116)
			(xy 163.95192 -372.403116) (xy 163.941769 -372.402662) (xy 163.92302 -372.394876) (xy 163.908697 -372.38049)
			(xy 163.900993 -372.361707) (xy 163.900612 -372.351554) (xy 163.900612 -372.194074) (xy 163.900212 -372.184886)
			(xy 163.893691 -372.167702) (xy 163.887912 -372.160546) (xy 163.866061 -372.13487) (xy 163.827971 -372.079237)
			(xy 163.796819 -372.019442) (xy 163.773054 -371.956347) (xy 163.757017 -371.890859) (xy 163.74894 -371.823922)
			(xy 163.748939 -371.756499) (xy 163.757013 -371.689562) (xy 163.773048 -371.624073) (xy 163.796811 -371.560977)
			(xy 163.827961 -371.501181) (xy 163.866048 -371.445547) (xy 163.887912 -371.419882) (xy 163.8937 -371.412731)
			(xy 163.900219 -371.395545) (xy 163.900612 -371.386354) (xy 163.900612 -370.893848) (xy 163.900176 -370.884664)
			(xy 163.89368 -370.867479) (xy 163.887912 -370.86032) (xy 163.866036 -370.834665) (xy 163.827947 -370.779029)
			(xy 163.796796 -370.719232) (xy 163.773032 -370.656133) (xy 163.756997 -370.590643) (xy 163.748922 -370.523703)
			(xy 160.470875 -370.523703) (xy 160.462839 -370.590466) (xy 160.446866 -370.655848) (xy 160.423192 -370.718852)
			(xy 160.392158 -370.778575) (xy 160.354208 -370.83416) (xy 160.33242 -370.859812) (xy 160.326638 -370.866968)
			(xy 160.320114 -370.88415) (xy 160.31972 -370.89334) (xy 160.31972 -371.386862) (xy 160.320144 -371.396048)
			(xy 160.326647 -371.413233) (xy 160.33242 -371.42039) (xy 160.354223 -371.44603) (xy 160.392174 -371.501618)
			(xy 160.423209 -371.561342) (xy 160.44667 -371.623784) (xy 161.548767 -371.623784) (xy 161.548771 -371.556358)
			(xy 161.55685 -371.489418) (xy 161.572888 -371.423928) (xy 161.596655 -371.360829) (xy 161.627808 -371.301032)
			(xy 161.665899 -371.245396) (xy 161.687764 -371.21973) (xy 161.693581 -371.212599) (xy 161.700082 -371.195397)
			(xy 161.700464 -371.186202) (xy 161.700464 -371.028722) (xy 161.700945 -371.018594) (xy 161.70867 -370.999868)
			(xy 161.722959 -370.985511) (xy 161.741646 -370.977695) (xy 161.751772 -370.97716) (xy 162.468052 -370.97716)
			(xy 162.478198 -370.97766) (xy 162.496942 -370.985432) (xy 162.511265 -370.999805) (xy 162.518974 -371.018575)
			(xy 162.51936 -371.028722) (xy 162.51936 -371.186202) (xy 162.519778 -371.195388) (xy 162.526287 -371.212572)
			(xy 162.53206 -371.21973) (xy 162.553888 -371.245425) (xy 162.591981 -371.301055) (xy 162.623135 -371.360846)
			(xy 162.646903 -371.423939) (xy 162.662942 -371.489425) (xy 162.671022 -371.556361) (xy 162.671025 -371.623782)
			(xy 162.662953 -371.690719) (xy 162.64692 -371.756206) (xy 162.623158 -371.819302) (xy 162.59201 -371.879096)
			(xy 162.553923 -371.934729) (xy 162.53206 -371.960394) (xy 162.526278 -371.96755) (xy 162.519756 -371.984732)
			(xy 162.51936 -371.993922) (xy 162.51936 -372.486174) (xy 162.519791 -372.495359) (xy 162.526291 -372.512543)
			(xy 162.53206 -372.519702) (xy 162.553959 -372.545339) (xy 162.592049 -372.600977) (xy 162.623201 -372.660776)
			(xy 162.646965 -372.723877) (xy 162.662999 -372.78937) (xy 162.671073 -372.856312) (xy 162.67107 -372.923739)
			(xy 162.66299 -372.99068) (xy 162.646949 -373.056172) (xy 162.62318 -373.11927) (xy 162.592023 -373.179067)
			(xy 162.553927 -373.234701) (xy 162.53206 -373.260366) (xy 162.526248 -373.2675) (xy 162.519743 -373.284699)
			(xy 162.51936 -373.293894) (xy 162.51936 -373.451374) (xy 162.518852 -373.461499) (xy 162.511133 -373.48022)
			(xy 162.496853 -373.494577) (xy 162.478174 -373.502397) (xy 162.468052 -373.502936) (xy 161.751772 -373.502936)
			(xy 161.741621 -373.502502) (xy 161.722874 -373.494704) (xy 161.708553 -373.480312) (xy 161.700848 -373.461527)
			(xy 161.700464 -373.451374) (xy 161.700464 -373.293894) (xy 161.700042 -373.284708) (xy 161.693535 -373.267525)
			(xy 161.687764 -373.260366) (xy 161.665935 -373.234673) (xy 161.627847 -373.179041) (xy 161.596697 -373.119249)
			(xy 161.572933 -373.056155) (xy 161.556896 -372.99067) (xy 161.548818 -372.923736) (xy 161.548815 -372.856315)
			(xy 161.556887 -372.78938) (xy 161.572918 -372.723893) (xy 161.596676 -372.660798) (xy 161.627821 -372.601003)
			(xy 161.665903 -372.545368) (xy 161.687764 -372.519702) (xy 161.69355 -372.51255) (xy 161.700069 -372.495364)
			(xy 161.700464 -372.486174) (xy 161.700464 -371.993922) (xy 161.700029 -371.984738) (xy 161.693531 -371.967554)
			(xy 161.687764 -371.960394) (xy 161.665864 -371.934759) (xy 161.627779 -371.879119) (xy 161.596632 -371.819319)
			(xy 161.572871 -371.756218) (xy 161.55684 -371.690725) (xy 161.548767 -371.623784) (xy 160.44667 -371.623784)
			(xy 160.446882 -371.624348) (xy 160.462856 -371.689733) (xy 160.470899 -371.756557) (xy 160.470898 -371.823864)
			(xy 160.462852 -371.890688) (xy 160.446876 -371.956072) (xy 160.4232 -372.019077) (xy 160.392163 -372.078801)
			(xy 160.35421 -372.134386) (xy 160.33242 -372.160038) (xy 160.326627 -372.167186) (xy 160.32011 -372.184374)
			(xy 160.31972 -372.193566) (xy 160.31972 -372.351554) (xy 160.319297 -372.361728) (xy 160.31152 -372.38053)
			(xy 160.297133 -372.394918) (xy 160.278332 -372.402697) (xy 160.268158 -372.403116) (xy 159.551878 -372.403116)
			(xy 159.541699 -372.402753) (xy 159.522895 -372.394952) (xy 159.50851 -372.380547) (xy 159.500734 -372.361733)
			(xy 159.500316 -372.351554) (xy 159.500316 -372.193566) (xy 159.499919 -372.184378) (xy 159.493396 -372.167193)
			(xy 159.487616 -372.160038) (xy 159.465843 -372.134374) (xy 159.427895 -372.078789) (xy 159.396862 -372.019067)
			(xy 159.37319 -371.956064) (xy 159.357216 -371.890683) (xy 159.349172 -371.823862) (xy 159.34917 -371.756559)
			(xy 159.357213 -371.689738) (xy 159.373184 -371.624356) (xy 159.396854 -371.561353) (xy 159.427884 -371.501629)
			(xy 159.46583 -371.446042) (xy 159.487616 -371.42039) (xy 159.493401 -371.413237) (xy 159.499922 -371.396052)
			(xy 159.500316 -371.386862) (xy 159.500316 -370.89334) (xy 159.499883 -370.884155) (xy 159.493385 -370.866971)
			(xy 159.487616 -370.859812) (xy 159.465817 -370.834169) (xy 159.42787 -370.778581) (xy 159.396839 -370.718856)
			(xy 159.373168 -370.65585) (xy 159.357196 -370.590467) (xy 159.349153 -370.523644) (xy 129.670828 -370.523644)
			(xy 129.662785 -370.590464) (xy 129.646814 -370.655846) (xy 129.623143 -370.71885) (xy 129.592113 -370.778573)
			(xy 129.554166 -370.83416) (xy 129.53238 -370.859812) (xy 129.526594 -370.866964) (xy 129.520073 -370.884149)
			(xy 129.51968 -370.89334) (xy 129.51968 -371.386862) (xy 129.520113 -371.396047) (xy 129.526611 -371.413231)
			(xy 129.53238 -371.42039) (xy 129.554181 -371.446031) (xy 129.592128 -371.50162) (xy 129.62316 -371.561345)
			(xy 129.646596 -371.623725) (xy 130.749241 -371.623725) (xy 130.749245 -371.556418) (xy 130.757292 -371.489593)
			(xy 130.773269 -371.424208) (xy 130.796945 -371.361202) (xy 130.827982 -371.301478) (xy 130.865934 -371.24589)
			(xy 130.887724 -371.220238) (xy 130.893532 -371.213101) (xy 130.900039 -371.195904) (xy 130.900424 -371.18671)
			(xy 130.900424 -371.028722) (xy 130.900882 -371.018554) (xy 130.908657 -370.999762) (xy 130.923032 -370.985377)
			(xy 130.941818 -370.977589) (xy 130.951986 -370.97716) (xy 131.668266 -370.97716) (xy 131.678438 -370.977592)
			(xy 131.697236 -370.98537) (xy 131.711623 -370.999754) (xy 131.719405 -371.01855) (xy 131.719828 -371.028722)
			(xy 131.719828 -371.18671) (xy 131.720227 -371.195898) (xy 131.726748 -371.213083) (xy 131.732528 -371.220238)
			(xy 131.754279 -371.24592) (xy 131.792231 -371.301502) (xy 131.823268 -371.361221) (xy 131.846945 -371.424221)
			(xy 131.862921 -371.4896) (xy 131.870969 -371.55642) (xy 131.870972 -371.623723) (xy 131.862931 -371.690543)
			(xy 131.846961 -371.755924) (xy 131.823291 -371.818927) (xy 131.792261 -371.878649) (xy 131.754314 -371.934234)
			(xy 131.732528 -371.959886) (xy 131.726704 -371.967011) (xy 131.720208 -371.984217) (xy 131.719828 -371.993414)
			(xy 131.719828 -372.486682) (xy 131.72024 -372.495869) (xy 131.726752 -372.513054) (xy 131.732528 -372.52021)
			(xy 131.75435 -372.545834) (xy 131.7923 -372.601424) (xy 131.823334 -372.661151) (xy 131.847006 -372.724159)
			(xy 131.862978 -372.789545) (xy 131.87102 -372.856371) (xy 131.871017 -372.92368) (xy 131.862969 -372.990505)
			(xy 131.846991 -373.05589) (xy 131.823313 -373.118896) (xy 131.792274 -373.17862) (xy 131.754319 -373.234206)
			(xy 131.732528 -373.259858) (xy 131.726716 -373.266992) (xy 131.720212 -373.284191) (xy 131.719828 -373.293386)
			(xy 131.719828 -373.451374) (xy 131.719414 -373.461548) (xy 131.711631 -373.480349) (xy 131.697242 -373.494736)
			(xy 131.67844 -373.502515) (xy 131.668266 -373.502936) (xy 130.951986 -373.502936) (xy 130.94181 -373.502547)
			(xy 130.92301 -373.494752) (xy 130.908625 -373.480356) (xy 130.900845 -373.46155) (xy 130.900424 -373.451374)
			(xy 130.900424 -373.293386) (xy 130.900015 -373.284199) (xy 130.8935 -373.267015) (xy 130.887724 -373.259858)
			(xy 130.86597 -373.234178) (xy 130.828022 -373.178595) (xy 130.796988 -373.118875) (xy 130.773314 -373.055874)
			(xy 130.757339 -372.990496) (xy 130.749292 -372.923677) (xy 130.749289 -372.856375) (xy 130.75733 -372.789555)
			(xy 130.773299 -372.724174) (xy 130.796967 -372.661171) (xy 130.827995 -372.601449) (xy 130.865939 -372.545863)
			(xy 130.887724 -372.52021) (xy 130.893544 -372.513082) (xy 130.900044 -372.495878) (xy 130.900424 -372.486682)
			(xy 130.900424 -371.993414) (xy 130.900002 -371.984228) (xy 130.893496 -371.967044) (xy 130.887724 -371.959886)
			(xy 130.865899 -371.934264) (xy 130.827953 -371.878673) (xy 130.796922 -371.818945) (xy 130.773252 -371.755937)
			(xy 130.757282 -371.690551) (xy 130.749241 -371.623725) (xy 129.646596 -371.623725) (xy 129.646831 -371.624351)
			(xy 129.662802 -371.689734) (xy 129.670845 -371.756558) (xy 129.670844 -371.823863) (xy 129.662799 -371.890687)
			(xy 129.646825 -371.956069) (xy 129.623151 -372.019074) (xy 129.592117 -372.078799) (xy 129.554168 -372.134386)
			(xy 129.53238 -372.160038) (xy 129.526582 -372.167182) (xy 129.520069 -372.184374) (xy 129.51968 -372.193566)
			(xy 129.51968 -372.351554) (xy 129.519199 -372.36172) (xy 129.511432 -372.380511) (xy 129.497064 -372.394896)
			(xy 129.478284 -372.402686) (xy 129.468118 -372.403116) (xy 128.751838 -372.403116) (xy 128.741663 -372.402704)
			(xy 128.722861 -372.394923) (xy 128.708473 -372.380533) (xy 128.700695 -372.361729) (xy 128.700276 -372.351554)
			(xy 128.700276 -372.193566) (xy 128.699887 -372.184376) (xy 128.693359 -372.167192) (xy 128.687576 -372.160038)
			(xy 128.665801 -372.134375) (xy 128.627849 -372.078791) (xy 128.596813 -372.019069) (xy 128.573138 -371.956066)
			(xy 128.557163 -371.890685) (xy 128.549117 -371.823863) (xy 128.549116 -371.756558) (xy 128.557159 -371.689736)
			(xy 128.573132 -371.624354) (xy 128.596805 -371.56135) (xy 128.627838 -371.501627) (xy 128.665788 -371.446042)
			(xy 128.687576 -371.42039) (xy 128.693357 -371.413233) (xy 128.699882 -371.396052) (xy 128.700276 -371.386862)
			(xy 128.700276 -370.89334) (xy 128.699852 -370.884154) (xy 128.693349 -370.866969) (xy 128.687576 -370.859812)
			(xy 128.665775 -370.83417) (xy 128.627825 -370.778583) (xy 128.59679 -370.718858) (xy 128.573116 -370.655852)
			(xy 128.557143 -370.590469) (xy 128.549099 -370.523644) (xy 125.271037 -370.523644) (xy 125.262994 -370.590464)
			(xy 125.247024 -370.655845) (xy 125.223354 -370.718849) (xy 125.192323 -370.778573) (xy 125.154378 -370.834159)
			(xy 125.132592 -370.859812) (xy 125.126807 -370.866965) (xy 125.120286 -370.88415) (xy 125.119892 -370.89334)
			(xy 125.119892 -371.386862) (xy 125.120322 -371.396047) (xy 125.126822 -371.413231) (xy 125.132592 -371.42039)
			(xy 125.154393 -371.446031) (xy 125.192339 -371.50162) (xy 125.22337 -371.561345) (xy 125.246828 -371.623785)
			(xy 126.348921 -371.623785) (xy 126.348925 -371.556358) (xy 126.357005 -371.489416) (xy 126.373046 -371.423925)
			(xy 126.396816 -371.360826) (xy 126.427973 -371.301029) (xy 126.466069 -371.245395) (xy 126.487936 -371.21973)
			(xy 126.493749 -371.212597) (xy 126.500253 -371.195397) (xy 126.500636 -371.186202) (xy 126.500636 -371.028722)
			(xy 126.501144 -371.018597) (xy 126.508864 -370.999877) (xy 126.523144 -370.98552) (xy 126.541822 -370.9777)
			(xy 126.551944 -370.97716) (xy 127.268224 -370.97716) (xy 127.278375 -370.977601) (xy 127.29712 -370.985397)
			(xy 127.311441 -370.999787) (xy 127.319147 -371.018569) (xy 127.319532 -371.028722) (xy 127.319532 -371.186202)
			(xy 127.319956 -371.195387) (xy 127.326462 -371.212571) (xy 127.332232 -371.21973) (xy 127.354058 -371.245427)
			(xy 127.392145 -371.301057) (xy 127.423296 -371.36085) (xy 127.447061 -371.423942) (xy 127.463098 -371.489427)
			(xy 127.471176 -371.556361) (xy 127.47118 -371.623781) (xy 127.463108 -371.690717) (xy 127.447078 -371.756203)
			(xy 127.423319 -371.819298) (xy 127.392175 -371.879094) (xy 127.354093 -371.934728) (xy 127.332232 -371.960394)
			(xy 127.326447 -371.967547) (xy 127.319927 -371.984732) (xy 127.319532 -371.993922) (xy 127.319532 -372.486174)
			(xy 127.31997 -372.495358) (xy 127.326466 -372.512542) (xy 127.332232 -372.519702) (xy 127.354128 -372.54534)
			(xy 127.392214 -372.600979) (xy 127.423361 -372.66078) (xy 127.447122 -372.72388) (xy 127.463154 -372.789372)
			(xy 127.471227 -372.856313) (xy 127.471224 -372.923738) (xy 127.463145 -372.990678) (xy 127.447107 -373.056169)
			(xy 127.42334 -373.119267) (xy 127.392188 -373.179064) (xy 127.354097 -373.2347) (xy 127.332232 -373.260366)
			(xy 127.326417 -373.267498) (xy 127.319915 -373.284699) (xy 127.319532 -373.293894) (xy 127.319532 -373.451374)
			(xy 127.319051 -373.461503) (xy 127.311327 -373.480228) (xy 127.297038 -373.494587) (xy 127.27835 -373.502402)
			(xy 127.268224 -373.502936) (xy 126.551944 -373.502936) (xy 126.541797 -373.502443) (xy 126.523053 -373.494669)
			(xy 126.508729 -373.480294) (xy 126.501021 -373.461522) (xy 126.500636 -373.451374) (xy 126.500636 -373.293894)
			(xy 126.500221 -373.284708) (xy 126.49371 -373.267524) (xy 126.487936 -373.260366) (xy 126.466104 -373.234674)
			(xy 126.428012 -373.179044) (xy 126.396858 -373.119252) (xy 126.37309 -373.056158) (xy 126.357051 -372.990672)
			(xy 126.348972 -372.923736) (xy 126.348969 -372.856315) (xy 126.357042 -372.789378) (xy 126.373075 -372.72389)
			(xy 126.396837 -372.660795) (xy 126.427986 -372.601) (xy 126.466073 -372.545367) (xy 126.487936 -372.519702)
			(xy 126.493719 -372.512547) (xy 126.500241 -372.495364) (xy 126.500636 -372.486174) (xy 126.500636 -371.993922)
			(xy 126.500207 -371.984737) (xy 126.493706 -371.967553) (xy 126.487936 -371.960394) (xy 126.466033 -371.93476)
			(xy 126.427943 -371.879122) (xy 126.396792 -371.819322) (xy 126.373029 -371.756221) (xy 126.356995 -371.690727)
			(xy 126.348921 -371.623785) (xy 125.246828 -371.623785) (xy 125.247041 -371.624351) (xy 125.263012 -371.689734)
			(xy 125.271054 -371.756558) (xy 125.271053 -371.823863) (xy 125.263008 -371.890686) (xy 125.247034 -371.956069)
			(xy 125.223361 -372.019074) (xy 125.192328 -372.078798) (xy 125.15438 -372.134385) (xy 125.132592 -372.160038)
			(xy 125.126796 -372.167183) (xy 125.120281 -372.184374) (xy 125.119892 -372.193566) (xy 125.119892 -372.351554)
			(xy 125.119399 -372.361719) (xy 125.111635 -372.380507) (xy 125.097271 -372.394892) (xy 125.078494 -372.402684)
			(xy 125.06833 -372.403116) (xy 124.35205 -372.403116) (xy 124.341876 -372.402694) (xy 124.323073 -372.394917)
			(xy 124.308685 -372.38053) (xy 124.300907 -372.361728) (xy 124.300488 -372.351554) (xy 124.300488 -372.193566)
			(xy 124.300097 -372.184377) (xy 124.29357 -372.167192) (xy 124.287788 -372.160038) (xy 124.266013 -372.134375)
			(xy 124.22806 -372.078791) (xy 124.197024 -372.01907) (xy 124.173348 -371.956067) (xy 124.157372 -371.890685)
			(xy 124.149326 -371.823863) (xy 124.149325 -371.756558) (xy 124.157369 -371.689736) (xy 124.173342 -371.624354)
			(xy 124.197015 -371.561349) (xy 124.228049 -371.501627) (xy 124.266 -371.446041) (xy 124.287788 -371.42039)
			(xy 124.29357 -371.413234) (xy 124.300094 -371.396052) (xy 124.300488 -371.386862) (xy 124.300488 -370.89334)
			(xy 124.300061 -370.884154) (xy 124.29356 -370.86697) (xy 124.287788 -370.859812) (xy 124.265987 -370.83417)
			(xy 124.228035 -370.778583) (xy 124.197 -370.718859) (xy 124.173326 -370.655853) (xy 124.157352 -370.590469)
			(xy 124.149308 -370.523644) (xy 120.871269 -370.523644) (xy 120.871269 -370.523702) (xy 120.863194 -370.59064)
			(xy 120.847159 -370.656128) (xy 120.823396 -370.719225) (xy 120.792247 -370.779021) (xy 120.754159 -370.834655)
			(xy 120.732296 -370.86032) (xy 120.726508 -370.867471) (xy 120.719988 -370.884657) (xy 120.719596 -370.893848)
			(xy 120.719596 -371.386354) (xy 120.720029 -371.395539) (xy 120.726527 -371.412723) (xy 120.732296 -371.419882)
			(xy 120.754174 -371.445536) (xy 120.792262 -371.501172) (xy 120.823413 -371.56097) (xy 120.847047 -371.623725)
			(xy 121.949153 -371.623725) (xy 121.949157 -371.556417) (xy 121.957205 -371.489592) (xy 121.973182 -371.424208)
			(xy 121.996859 -371.361202) (xy 122.027896 -371.301477) (xy 122.06585 -371.24589) (xy 122.08764 -371.220238)
			(xy 122.09345 -371.213103) (xy 122.099956 -371.195904) (xy 122.10034 -371.18671) (xy 122.10034 -371.028722)
			(xy 122.100782 -371.018552) (xy 122.10856 -370.999757) (xy 122.12294 -370.985371) (xy 122.141732 -370.977586)
			(xy 122.151902 -370.97716) (xy 122.868182 -370.97716) (xy 122.878355 -370.977579) (xy 122.897154 -370.985362)
			(xy 122.91154 -370.99975) (xy 122.919322 -371.018549) (xy 122.919744 -371.028722) (xy 122.919744 -371.18671)
			(xy 122.920162 -371.195896) (xy 122.926672 -371.21308) (xy 122.932444 -371.220238) (xy 122.954195 -371.245921)
			(xy 122.992146 -371.301502) (xy 123.023182 -371.361222) (xy 123.046857 -371.424222) (xy 123.062833 -371.489601)
			(xy 123.070881 -371.55642) (xy 123.070884 -371.623723) (xy 123.062844 -371.690543) (xy 123.046874 -371.755923)
			(xy 123.023205 -371.818926) (xy 122.992175 -371.878648) (xy 122.95423 -371.934234) (xy 122.932444 -371.959886)
			(xy 122.926622 -371.967013) (xy 122.920124 -371.984218) (xy 122.919744 -371.993414) (xy 122.919744 -372.486682)
			(xy 122.920175 -372.495867) (xy 122.926676 -372.513051) (xy 122.932444 -372.52021) (xy 122.954266 -372.545834)
			(xy 122.992215 -372.601424) (xy 123.023248 -372.661152) (xy 123.046919 -372.72416) (xy 123.06289 -372.789546)
			(xy 123.070932 -372.856372) (xy 123.070929 -372.92368) (xy 123.062881 -372.990505) (xy 123.046904 -373.055889)
			(xy 123.023227 -373.118895) (xy 122.992188 -373.17862) (xy 122.954234 -373.234206) (xy 122.932444 -373.259858)
			(xy 122.926633 -373.266993) (xy 122.920129 -373.284192) (xy 122.919744 -373.293386) (xy 122.919744 -373.451374)
			(xy 122.919314 -373.461546) (xy 122.911534 -373.480344) (xy 122.89715 -373.49473) (xy 122.878354 -373.502513)
			(xy 122.868182 -373.502936) (xy 122.151902 -373.502936) (xy 122.141727 -373.502534) (xy 122.122928 -373.494745)
			(xy 122.108542 -373.480352) (xy 122.100761 -373.461549) (xy 122.10034 -373.451374) (xy 122.10034 -373.293386)
			(xy 122.099928 -373.284199) (xy 122.093415 -373.267015) (xy 122.08764 -373.259858) (xy 122.065886 -373.234178)
			(xy 122.027936 -373.178596) (xy 121.996901 -373.118876) (xy 121.973226 -373.055875) (xy 121.957251 -372.990496)
			(xy 121.949204 -372.923677) (xy 121.949201 -372.856374) (xy 121.957242 -372.789554) (xy 121.973211 -372.724174)
			(xy 121.99688 -372.661171) (xy 122.02791 -372.601448) (xy 122.065855 -372.545862) (xy 122.08764 -372.52021)
			(xy 122.093462 -372.513083) (xy 122.099961 -372.495878) (xy 122.10034 -372.486682) (xy 122.10034 -371.993414)
			(xy 122.099914 -371.984229) (xy 122.093411 -371.967045) (xy 122.08764 -371.959886) (xy 122.065815 -371.934265)
			(xy 122.027867 -371.878674) (xy 121.996835 -371.818946) (xy 121.973165 -371.755937) (xy 121.957194 -371.690551)
			(xy 121.949153 -371.623725) (xy 120.847047 -371.623725) (xy 120.847176 -371.624068) (xy 120.863211 -371.689558)
			(xy 120.871286 -371.756498) (xy 120.871284 -371.823923) (xy 120.863207 -371.890862) (xy 120.84717 -371.956352)
			(xy 120.823404 -372.01945) (xy 120.792252 -372.079246) (xy 120.754161 -372.134881) (xy 120.732296 -372.160546)
			(xy 120.726497 -372.167689) (xy 120.719984 -372.184881) (xy 120.719596 -372.194074) (xy 120.719596 -372.351554)
			(xy 120.719037 -372.361673) (xy 120.711331 -372.380387) (xy 120.697067 -372.394743) (xy 120.678404 -372.40257)
			(xy 120.668288 -372.403116) (xy 119.952008 -372.403116) (xy 119.941856 -372.402672) (xy 119.923107 -372.394882)
			(xy 119.908784 -372.380493) (xy 119.901081 -372.361707) (xy 119.9007 -372.351554) (xy 119.9007 -372.194074)
			(xy 119.900303 -372.184885) (xy 119.89378 -372.167701) (xy 119.888 -372.160546) (xy 119.86615 -372.134869)
			(xy 119.828061 -372.079237) (xy 119.796909 -372.019442) (xy 119.773144 -371.956346) (xy 119.757108 -371.890859)
			(xy 119.749031 -371.823922) (xy 119.74903 -371.756499) (xy 119.757104 -371.689562) (xy 119.773138 -371.624074)
			(xy 119.796901 -371.560977) (xy 119.82805 -371.501182) (xy 119.866137 -371.445547) (xy 119.888 -371.419882)
			(xy 119.893787 -371.41273) (xy 119.900307 -371.395545) (xy 119.9007 -371.386354) (xy 119.9007 -370.893848)
			(xy 119.900267 -370.884663) (xy 119.893769 -370.867479) (xy 119.888 -370.86032) (xy 119.866124 -370.834664)
			(xy 119.828036 -370.779029) (xy 119.796886 -370.719231) (xy 119.773122 -370.656133) (xy 119.757088 -370.590643)
			(xy 119.749013 -370.523703) (xy 116.470966 -370.523703) (xy 116.462929 -370.590466) (xy 116.446956 -370.655848)
			(xy 116.423282 -370.718853) (xy 116.392247 -370.778575) (xy 116.354297 -370.834161) (xy 116.332508 -370.859812)
			(xy 116.326725 -370.866967) (xy 116.320202 -370.88415) (xy 116.319808 -370.89334) (xy 116.319808 -371.386862)
			(xy 116.320235 -371.396047) (xy 116.326737 -371.413232) (xy 116.332508 -371.42039) (xy 116.354311 -371.44603)
			(xy 116.392263 -371.501617) (xy 116.423299 -371.561342) (xy 116.446761 -371.623785) (xy 117.548834 -371.623785)
			(xy 117.548837 -371.556358) (xy 117.556917 -371.489416) (xy 117.572959 -371.423924) (xy 117.596729 -371.360825)
			(xy 117.627887 -371.301028) (xy 117.665984 -371.245394) (xy 117.687852 -371.21973) (xy 117.693667 -371.212598)
			(xy 117.700169 -371.195397) (xy 117.700552 -371.186202) (xy 117.700552 -371.028722) (xy 117.701045 -371.018595)
			(xy 117.708768 -370.999872) (xy 117.723052 -370.985515) (xy 117.741736 -370.977697) (xy 117.75186 -370.97716)
			(xy 118.46814 -370.97716) (xy 118.478292 -370.977588) (xy 118.497037 -370.985389) (xy 118.511358 -370.999783)
			(xy 118.519063 -371.018568) (xy 118.519448 -371.028722) (xy 118.519448 -371.186202) (xy 118.519869 -371.195388)
			(xy 118.526376 -371.212572) (xy 118.532148 -371.21973) (xy 118.553976 -371.245425) (xy 118.59207 -371.301054)
			(xy 118.623225 -371.360846) (xy 118.646994 -371.423939) (xy 118.663033 -371.489425) (xy 118.671113 -371.556361)
			(xy 118.671116 -371.623782) (xy 118.663044 -371.690719) (xy 118.647011 -371.756207) (xy 118.623248 -371.819302)
			(xy 118.592099 -371.879097) (xy 118.554012 -371.93473) (xy 118.532148 -371.960394) (xy 118.526365 -371.967549)
			(xy 118.519844 -371.984732) (xy 118.519448 -371.993922) (xy 118.519448 -372.486174) (xy 118.519882 -372.495358)
			(xy 118.52638 -372.512542) (xy 118.532148 -372.519702) (xy 118.554047 -372.545339) (xy 118.592138 -372.600976)
			(xy 118.62329 -372.660776) (xy 118.647055 -372.723877) (xy 118.66309 -372.78937) (xy 118.671164 -372.856312)
			(xy 118.671161 -372.923739) (xy 118.663081 -372.990681) (xy 118.64704 -373.056172) (xy 118.62327 -373.119271)
			(xy 118.592112 -373.179068) (xy 118.554016 -373.234702) (xy 118.532148 -373.260366) (xy 118.526334 -373.267499)
			(xy 118.519831 -373.284699) (xy 118.519448 -373.293894) (xy 118.519448 -373.451374) (xy 118.518952 -373.461501)
			(xy 118.51123 -373.480223) (xy 118.496947 -373.494581) (xy 118.478264 -373.502399) (xy 118.46814 -373.502936)
			(xy 117.75186 -373.502936) (xy 117.741708 -373.502512) (xy 117.722961 -373.49471) (xy 117.708641 -373.480315)
			(xy 117.700936 -373.461528) (xy 117.700552 -373.451374) (xy 117.700552 -373.293894) (xy 117.700133 -373.284708)
			(xy 117.693624 -373.267524) (xy 117.687852 -373.260366) (xy 117.66602 -373.234674) (xy 117.627926 -373.179045)
			(xy 117.596771 -373.119253) (xy 117.573003 -373.056159) (xy 117.556964 -372.990673) (xy 117.548884 -372.923737)
			(xy 117.548881 -372.856315) (xy 117.556954 -372.789378) (xy 117.572988 -372.72389) (xy 117.596751 -372.660794)
			(xy 117.6279 -372.600999) (xy 117.665988 -372.545366) (xy 117.687852 -372.519702) (xy 117.693637 -372.512549)
			(xy 117.700157 -372.495364) (xy 117.700552 -372.486174) (xy 117.700552 -371.993922) (xy 117.70012 -371.984737)
			(xy 117.69362 -371.967553) (xy 117.687852 -371.960394) (xy 117.665949 -371.93476) (xy 117.627858 -371.879123)
			(xy 117.596706 -371.819323) (xy 117.572942 -371.756221) (xy 117.556907 -371.690728) (xy 117.548834 -371.623785)
			(xy 116.446761 -371.623785) (xy 116.446973 -371.624348) (xy 116.462946 -371.689732) (xy 116.47099 -371.756557)
			(xy 116.470989 -371.823864) (xy 116.462943 -371.890689) (xy 116.446967 -371.956072) (xy 116.42329 -372.019077)
			(xy 116.392252 -372.078801) (xy 116.354298 -372.134387) (xy 116.332508 -372.160038) (xy 116.326714 -372.167185)
			(xy 116.320197 -372.184374) (xy 116.319808 -372.193566) (xy 116.319808 -372.351554) (xy 116.31923 -372.361703)
			(xy 116.311479 -372.380462) (xy 116.29714 -372.394828) (xy 116.278394 -372.402612) (xy 116.268246 -372.403116)
			(xy 115.551966 -372.403116) (xy 115.541786 -372.402763) (xy 115.522982 -372.394958) (xy 115.508597 -372.380551)
			(xy 115.500821 -372.361734) (xy 115.500404 -372.351554) (xy 115.500404 -372.193566) (xy 115.500009 -372.184377)
			(xy 115.493485 -372.167193) (xy 115.487704 -372.160038) (xy 115.465931 -372.134374) (xy 115.427984 -372.078788)
			(xy 115.396952 -372.019066) (xy 115.37328 -371.956063) (xy 115.357307 -371.890683) (xy 115.349263 -371.823862)
			(xy 115.349261 -371.756559) (xy 115.357303 -371.689738) (xy 115.373274 -371.624357) (xy 115.396944 -371.561353)
			(xy 115.427973 -371.50163) (xy 115.465918 -371.446043) (xy 115.487704 -371.42039) (xy 115.493488 -371.413236)
			(xy 115.50001 -371.396052) (xy 115.500404 -371.386862) (xy 115.500404 -370.89334) (xy 115.499974 -370.884155)
			(xy 115.493474 -370.86697) (xy 115.487704 -370.859812) (xy 115.465906 -370.834169) (xy 115.427959 -370.77858)
			(xy 115.396929 -370.718855) (xy 115.373258 -370.65585) (xy 115.357287 -370.590467) (xy 115.349244 -370.523644)
			(xy 85.670941 -370.523644) (xy 85.670941 -370.523703) (xy 85.662866 -370.590641) (xy 85.646831 -370.65613)
			(xy 85.623066 -370.719226) (xy 85.591915 -370.779022) (xy 85.553825 -370.834655) (xy 85.53196 -370.86032)
			(xy 85.526167 -370.867468) (xy 85.519651 -370.884656) (xy 85.51926 -370.893848) (xy 85.51926 -371.386354)
			(xy 85.519701 -371.395538) (xy 85.526194 -371.412722) (xy 85.53196 -371.419882) (xy 85.553839 -371.445535)
			(xy 85.59193 -371.501171) (xy 85.623082 -371.560968) (xy 85.646742 -371.623785) (xy 86.748803 -371.623785)
			(xy 86.748807 -371.556358) (xy 86.756887 -371.489417) (xy 86.772927 -371.423926) (xy 86.796696 -371.360827)
			(xy 86.827851 -371.30103) (xy 86.865945 -371.245395) (xy 86.887812 -371.21973) (xy 86.893622 -371.212594)
			(xy 86.900128 -371.195397) (xy 86.900512 -371.186202) (xy 86.900512 -371.028722) (xy 86.901044 -371.0186)
			(xy 86.908759 -370.999885) (xy 86.923031 -370.985529) (xy 86.941701 -370.977704) (xy 86.95182 -370.97716)
			(xy 87.6681 -370.97716) (xy 87.678249 -370.977621) (xy 87.696994 -370.985409) (xy 87.711316 -370.999793)
			(xy 87.719023 -371.018571) (xy 87.719408 -371.028722) (xy 87.719408 -371.186202) (xy 87.719815 -371.195389)
			(xy 87.726331 -371.212574) (xy 87.732108 -371.21973) (xy 87.753934 -371.245426) (xy 87.792024 -371.301056)
			(xy 87.823176 -371.360848) (xy 87.846942 -371.423941) (xy 87.862979 -371.489426) (xy 87.871058 -371.556361)
			(xy 87.871062 -371.623782) (xy 87.86299 -371.690717) (xy 87.846958 -371.756204) (xy 87.823199 -371.819299)
			(xy 87.792053 -371.879095) (xy 87.753969 -371.934729) (xy 87.732108 -371.960394) (xy 87.726332 -371.967554)
			(xy 87.719805 -371.984733) (xy 87.719408 -371.993922) (xy 87.719408 -372.486174) (xy 87.719829 -372.49536)
			(xy 87.726335 -372.512545) (xy 87.732108 -372.519702) (xy 87.754005 -372.54534) (xy 87.792092 -372.600978)
			(xy 87.823241 -372.660779) (xy 87.847003 -372.723879) (xy 87.863036 -372.789371) (xy 87.871109 -372.856312)
			(xy 87.871106 -372.923739) (xy 87.863027 -372.990679) (xy 87.846988 -373.05617) (xy 87.82322 -373.119268)
			(xy 87.792066 -373.179065) (xy 87.753974 -373.234701) (xy 87.732108 -373.260366) (xy 87.726302 -373.267504)
			(xy 87.719793 -373.2847) (xy 87.719408 -373.293894) (xy 87.719408 -373.451374) (xy 87.718854 -373.461493)
			(xy 87.711143 -373.480205) (xy 87.696878 -373.49456) (xy 87.678216 -373.502389) (xy 87.6681 -373.502936)
			(xy 86.95182 -373.502936) (xy 86.941672 -373.502463) (xy 86.922927 -373.494681) (xy 86.908604 -373.4803)
			(xy 86.900897 -373.461524) (xy 86.900512 -373.451374) (xy 86.900512 -373.293894) (xy 86.900102 -373.284707)
			(xy 86.893588 -373.267523) (xy 86.887812 -373.260366) (xy 86.865981 -373.234673) (xy 86.82789 -373.179043)
			(xy 86.796738 -373.119251) (xy 86.772971 -373.056157) (xy 86.756933 -372.990672) (xy 86.748854 -372.923736)
			(xy 86.748851 -372.856315) (xy 86.756924 -372.789379) (xy 86.772956 -372.723891) (xy 86.796717 -372.660796)
			(xy 86.827864 -372.601001) (xy 86.86595 -372.545367) (xy 86.887812 -372.519702) (xy 86.893592 -372.512545)
			(xy 86.900116 -372.495363) (xy 86.900512 -372.486174) (xy 86.900512 -371.993922) (xy 86.900088 -371.984736)
			(xy 86.893584 -371.967552) (xy 86.887812 -371.960394) (xy 86.86591 -371.93476) (xy 86.827822 -371.879121)
			(xy 86.796672 -371.819321) (xy 86.77291 -371.75622) (xy 86.756876 -371.690727) (xy 86.748803 -371.623785)
			(xy 85.646742 -371.623785) (xy 85.646848 -371.624067) (xy 85.662883 -371.689557) (xy 85.670959 -371.756498)
			(xy 85.670957 -371.823923) (xy 85.662879 -371.890863) (xy 85.646841 -371.956354) (xy 85.623074 -372.019451)
			(xy 85.591919 -372.079248) (xy 85.553826 -372.134881) (xy 85.53196 -372.160546) (xy 85.526156 -372.167686)
			(xy 85.519647 -372.184881) (xy 85.51926 -372.194074) (xy 85.51926 -372.351554) (xy 85.518736 -372.361678)
			(xy 85.511023 -372.380398) (xy 85.496748 -372.394756) (xy 85.478073 -372.402576) (xy 85.467952 -372.403116)
			(xy 84.751672 -372.403116) (xy 84.741518 -372.402702) (xy 84.722768 -372.3949) (xy 84.708446 -372.380501)
			(xy 84.700745 -372.36171) (xy 84.700364 -372.351554) (xy 84.700364 -372.194074) (xy 84.699952 -372.184887)
			(xy 84.693438 -372.167704) (xy 84.687664 -372.160546) (xy 84.665815 -372.134869) (xy 84.627728 -372.079235)
			(xy 84.596579 -372.01944) (xy 84.572816 -371.956345) (xy 84.55678 -371.890858) (xy 84.548704 -371.823921)
			(xy 84.548703 -371.7565) (xy 84.556776 -371.689563) (xy 84.572809 -371.624075) (xy 84.59657 -371.560979)
			(xy 84.627717 -371.501183) (xy 84.665802 -371.445548) (xy 84.687664 -371.419882) (xy 84.693459 -371.412736)
			(xy 84.699973 -371.395546) (xy 84.700364 -371.386354) (xy 84.700364 -370.893848) (xy 84.699917 -370.884665)
			(xy 84.693427 -370.867481) (xy 84.687664 -370.86032) (xy 84.66579 -370.834664) (xy 84.627704 -370.779027)
			(xy 84.596555 -370.719229) (xy 84.572793 -370.656131) (xy 84.55676 -370.590642) (xy 84.548686 -370.523703)
			(xy 81.27115 -370.523703) (xy 81.263075 -370.590641) (xy 81.24704 -370.656129) (xy 81.223276 -370.719226)
			(xy 81.192125 -370.779021) (xy 81.154036 -370.834655) (xy 81.132172 -370.86032) (xy 81.126381 -370.867469)
			(xy 81.119864 -370.884657) (xy 81.119472 -370.893848) (xy 81.119472 -371.386354) (xy 81.119911 -371.395538)
			(xy 81.126405 -371.412722) (xy 81.132172 -371.419882) (xy 81.154051 -371.445535) (xy 81.192141 -371.501171)
			(xy 81.223293 -371.560969) (xy 81.246928 -371.623725) (xy 82.349035 -371.623725) (xy 82.349038 -371.556418)
			(xy 82.357086 -371.489593) (xy 82.373062 -371.424209) (xy 82.396738 -371.361203) (xy 82.427775 -371.301478)
			(xy 82.465727 -371.24589) (xy 82.487516 -371.220238) (xy 82.493323 -371.2131) (xy 82.499831 -371.195904)
			(xy 82.500216 -371.18671) (xy 82.500216 -371.028722) (xy 82.500751 -371.018568) (xy 82.508514 -370.999804)
			(xy 82.522867 -370.985439) (xy 82.541625 -370.977659) (xy 82.551778 -370.97716) (xy 83.268058 -370.97716)
			(xy 83.27823 -370.977599) (xy 83.297028 -370.985374) (xy 83.311415 -370.999756) (xy 83.319197 -371.018551)
			(xy 83.31962 -371.028722) (xy 83.31962 -371.18671) (xy 83.320021 -371.195898) (xy 83.326541 -371.213083)
			(xy 83.33232 -371.220238) (xy 83.354072 -371.24592) (xy 83.392024 -371.301501) (xy 83.423061 -371.361221)
			(xy 83.446738 -371.424221) (xy 83.462715 -371.4896) (xy 83.470763 -371.55642) (xy 83.470766 -371.623723)
			(xy 83.462725 -371.690544) (xy 83.446755 -371.755924) (xy 83.423085 -371.818927) (xy 83.392054 -371.878649)
			(xy 83.354107 -371.934234) (xy 83.33232 -371.959886) (xy 83.326507 -371.96702) (xy 83.320001 -371.984219)
			(xy 83.31962 -371.993414) (xy 83.31962 -372.486682) (xy 83.320034 -372.495869) (xy 83.326545 -372.513054)
			(xy 83.33232 -372.52021) (xy 83.354142 -372.545834) (xy 83.392093 -372.601424) (xy 83.423127 -372.661151)
			(xy 83.446799 -372.724159) (xy 83.462771 -372.789545) (xy 83.470813 -372.856371) (xy 83.47081 -372.92368)
			(xy 83.462762 -372.990505) (xy 83.446784 -373.05589) (xy 83.423106 -373.118896) (xy 83.392066 -373.17862)
			(xy 83.354111 -373.234206) (xy 83.33232 -373.259858) (xy 83.326519 -373.267) (xy 83.320006 -373.284193)
			(xy 83.31962 -373.293386) (xy 83.31962 -373.451374) (xy 83.319214 -373.461549) (xy 83.311429 -373.480351)
			(xy 83.297038 -373.494738) (xy 83.278233 -373.502517) (xy 83.268058 -373.502936) (xy 82.551778 -373.502936)
			(xy 82.541602 -373.502553) (xy 82.522802 -373.494756) (xy 82.508417 -373.480358) (xy 82.500637 -373.461551)
			(xy 82.500216 -373.451374) (xy 82.500216 -373.293386) (xy 82.499809 -373.284199) (xy 82.493293 -373.267014)
			(xy 82.487516 -373.259858) (xy 82.465763 -373.234178) (xy 82.427814 -373.178595) (xy 82.396781 -373.118875)
			(xy 82.373107 -373.055874) (xy 82.357133 -372.990496) (xy 82.349086 -372.923677) (xy 82.349083 -372.856375)
			(xy 82.357123 -372.789555) (xy 82.373092 -372.724175) (xy 82.39676 -372.661172) (xy 82.427788 -372.601449)
			(xy 82.465731 -372.545863) (xy 82.487516 -372.52021) (xy 82.493335 -372.513081) (xy 82.499836 -372.495878)
			(xy 82.500216 -372.486682) (xy 82.500216 -371.993414) (xy 82.499795 -371.984228) (xy 82.493288 -371.967044)
			(xy 82.487516 -371.959886) (xy 82.465692 -371.934264) (xy 82.427745 -371.878673) (xy 82.396715 -371.818945)
			(xy 82.373045 -371.755936) (xy 82.357076 -371.690551) (xy 82.349035 -371.623725) (xy 81.246928 -371.623725)
			(xy 81.247057 -371.624067) (xy 81.263092 -371.689558) (xy 81.271168 -371.756498) (xy 81.271166 -371.823923)
			(xy 81.263089 -371.890863) (xy 81.247051 -371.956353) (xy 81.223284 -372.019451) (xy 81.19213 -372.079247)
			(xy 81.154038 -372.134881) (xy 81.132172 -372.160546) (xy 81.12637 -372.167687) (xy 81.119859 -372.184881)
			(xy 81.119472 -372.194074) (xy 81.119472 -372.351554) (xy 81.118936 -372.361676) (xy 81.111226 -372.380394)
			(xy 81.096954 -372.394752) (xy 81.078283 -372.402574) (xy 81.068164 -372.403116) (xy 80.351884 -372.403116)
			(xy 80.341731 -372.402692) (xy 80.322981 -372.394894) (xy 80.308659 -372.380499) (xy 80.300957 -372.361709)
			(xy 80.300576 -372.351554) (xy 80.300576 -372.194074) (xy 80.300184 -372.184885) (xy 80.293658 -372.1677)
			(xy 80.287876 -372.160546) (xy 80.266027 -372.134869) (xy 80.227939 -372.079236) (xy 80.196789 -372.019441)
			(xy 80.173025 -371.956346) (xy 80.156989 -371.890858) (xy 80.148913 -371.823922) (xy 80.148912 -371.756499)
			(xy 80.156986 -371.689563) (xy 80.173019 -371.624075) (xy 80.196781 -371.560978) (xy 80.227928 -371.501182)
			(xy 80.266014 -371.445548) (xy 80.287876 -371.419882) (xy 80.29366 -371.412728) (xy 80.300183 -371.395544)
			(xy 80.300576 -371.386354) (xy 80.300576 -370.893848) (xy 80.300148 -370.884663) (xy 80.293647 -370.867478)
			(xy 80.287876 -370.86032) (xy 80.266001 -370.834664) (xy 80.227914 -370.779028) (xy 80.196765 -370.71923)
			(xy 80.173003 -370.656132) (xy 80.156969 -370.590642) (xy 80.148895 -370.523703) (xy 76.870824 -370.523703)
			(xy 76.862788 -370.590464) (xy 76.846817 -370.655845) (xy 76.823147 -370.718849) (xy 76.792116 -370.778573)
			(xy 76.75417 -370.83416) (xy 76.732384 -370.859812) (xy 76.726598 -370.866965) (xy 76.720078 -370.88415)
			(xy 76.719684 -370.89334) (xy 76.719684 -371.386862) (xy 76.720116 -371.396047) (xy 76.726615 -371.413231)
			(xy 76.732384 -371.42039) (xy 76.754185 -371.446031) (xy 76.792132 -371.50162) (xy 76.823163 -371.561345)
			(xy 76.846621 -371.623785) (xy 77.948715 -371.623785) (xy 77.948719 -371.556358) (xy 77.956799 -371.489417)
			(xy 77.972839 -371.423925) (xy 77.996609 -371.360826) (xy 78.027766 -371.301029) (xy 78.065861 -371.245395)
			(xy 78.087728 -371.21973) (xy 78.09354 -371.212596) (xy 78.100045 -371.195397) (xy 78.100428 -371.186202)
			(xy 78.100428 -371.028722) (xy 78.100944 -371.018598) (xy 78.108662 -370.99988) (xy 78.12294 -370.985523)
			(xy 78.141615 -370.977701) (xy 78.151736 -370.97716) (xy 78.868016 -370.97716) (xy 78.878166 -370.977607)
			(xy 78.896911 -370.985401) (xy 78.911233 -370.999789) (xy 78.918939 -371.01857) (xy 78.919324 -371.028722)
			(xy 78.919324 -371.186202) (xy 78.919728 -371.19539) (xy 78.926245 -371.212575) (xy 78.932024 -371.21973)
			(xy 78.95385 -371.245426) (xy 78.991938 -371.301057) (xy 79.023089 -371.360849) (xy 79.046854 -371.423942)
			(xy 79.062892 -371.489427) (xy 79.07097 -371.556361) (xy 79.070974 -371.623782) (xy 79.062902 -371.690717)
			(xy 79.046871 -371.756203) (xy 79.023112 -371.819299) (xy 78.991967 -371.879094) (xy 78.953885 -371.934728)
			(xy 78.932024 -371.960394) (xy 78.92625 -371.967556) (xy 78.919721 -371.984733) (xy 78.919324 -371.993922)
			(xy 78.919324 -372.486174) (xy 78.919741 -372.495361) (xy 78.926249 -372.512545) (xy 78.932024 -372.519702)
			(xy 78.953921 -372.54534) (xy 78.992007 -372.600979) (xy 79.023155 -372.660779) (xy 79.046916 -372.72388)
			(xy 79.062948 -372.789372) (xy 79.071021 -372.856313) (xy 79.071018 -372.923738) (xy 79.062939 -372.990679)
			(xy 79.046901 -373.056169) (xy 79.023134 -373.119267) (xy 78.99198 -373.179065) (xy 78.953889 -373.2347)
			(xy 78.932024 -373.260366) (xy 78.92622 -373.267506) (xy 78.919709 -373.2847) (xy 78.919324 -373.293894)
			(xy 78.919324 -373.451374) (xy 78.918851 -373.461504) (xy 78.911125 -373.480231) (xy 78.896834 -373.49459)
			(xy 78.878143 -373.502403) (xy 78.868016 -373.502936) (xy 78.151736 -373.502936) (xy 78.141589 -373.502449)
			(xy 78.122844 -373.494673) (xy 78.108521 -373.480296) (xy 78.100813 -373.461523) (xy 78.100428 -373.451374)
			(xy 78.100428 -373.293894) (xy 78.100015 -373.284707) (xy 78.093503 -373.267523) (xy 78.087728 -373.260366)
			(xy 78.065896 -373.234674) (xy 78.027805 -373.179044) (xy 77.996651 -373.119251) (xy 77.972884 -373.056158)
			(xy 77.956845 -372.990672) (xy 77.948766 -372.923736) (xy 77.948763 -372.856315) (xy 77.956836 -372.789378)
			(xy 77.972869 -372.723891) (xy 77.99663 -372.660795) (xy 78.027779 -372.601) (xy 78.065865 -372.545367)
			(xy 78.087728 -372.519702) (xy 78.09351 -372.512547) (xy 78.100033 -372.495364) (xy 78.100428 -372.486174)
			(xy 78.100428 -371.993922) (xy 78.100001 -371.984737) (xy 78.093498 -371.967553) (xy 78.087728 -371.960394)
			(xy 78.065826 -371.93476) (xy 78.027736 -371.879122) (xy 77.996586 -371.819321) (xy 77.972822 -371.75622)
			(xy 77.956789 -371.690727) (xy 77.948715 -371.623785) (xy 76.846621 -371.623785) (xy 76.846834 -371.624351)
			(xy 76.862805 -371.689734) (xy 76.870848 -371.756558) (xy 76.870847 -371.823863) (xy 76.862802 -371.890687)
			(xy 76.846828 -371.956069) (xy 76.823155 -372.019074) (xy 76.792121 -372.078798) (xy 76.754172 -372.134386)
			(xy 76.732384 -372.160038) (xy 76.726587 -372.167183) (xy 76.720073 -372.184374) (xy 76.719684 -372.193566)
			(xy 76.719684 -372.351554) (xy 76.719199 -372.36172) (xy 76.711433 -372.380509) (xy 76.697067 -372.394895)
			(xy 76.678287 -372.402686) (xy 76.668122 -372.403116) (xy 75.951842 -372.403116) (xy 75.941667 -372.402701)
			(xy 75.922865 -372.394921) (xy 75.908477 -372.380532) (xy 75.900699 -372.361729) (xy 75.90028 -372.351554)
			(xy 75.90028 -372.193566) (xy 75.899891 -372.184377) (xy 75.893363 -372.167192) (xy 75.88758 -372.160038)
			(xy 75.865805 -372.134375) (xy 75.827853 -372.078791) (xy 75.796817 -372.019069) (xy 75.773141 -371.956066)
			(xy 75.757166 -371.890685) (xy 75.74912 -371.823863) (xy 75.749119 -371.756558) (xy 75.757162 -371.689736)
			(xy 75.773135 -371.624354) (xy 75.796808 -371.56135) (xy 75.827842 -371.501627) (xy 75.865792 -371.446042)
			(xy 75.88758 -371.42039) (xy 75.893361 -371.413234) (xy 75.899886 -371.396052) (xy 75.90028 -371.386862)
			(xy 75.90028 -370.89334) (xy 75.899855 -370.884154) (xy 75.893352 -370.866969) (xy 75.88758 -370.859812)
			(xy 75.865779 -370.83417) (xy 75.827828 -370.778583) (xy 75.796793 -370.718859) (xy 75.773119 -370.655853)
			(xy 75.757146 -370.590469) (xy 75.749102 -370.523644) (xy 72.471063 -370.523644) (xy 72.471063 -370.523702)
			(xy 72.462988 -370.59064) (xy 72.446953 -370.656129) (xy 72.42319 -370.719225) (xy 72.39204 -370.779021)
			(xy 72.353952 -370.834655) (xy 72.332088 -370.86032) (xy 72.326299 -370.867471) (xy 72.31978 -370.884657)
			(xy 72.319388 -370.893848) (xy 72.319388 -371.386354) (xy 72.319823 -371.395539) (xy 72.32632 -371.412723)
			(xy 72.332088 -371.419882) (xy 72.353966 -371.445536) (xy 72.392055 -371.501172) (xy 72.423206 -371.560969)
			(xy 72.446841 -371.623725) (xy 73.548947 -371.623725) (xy 73.548951 -371.556417) (xy 73.556998 -371.489592)
			(xy 73.572975 -371.424208) (xy 73.596652 -371.361202) (xy 73.627689 -371.301477) (xy 73.665642 -371.24589)
			(xy 73.687432 -371.220238) (xy 73.693242 -371.213102) (xy 73.699748 -371.195904) (xy 73.700132 -371.18671)
			(xy 73.700132 -371.028722) (xy 73.700582 -371.018553) (xy 73.708359 -370.99976) (xy 73.722736 -370.985374)
			(xy 73.741525 -370.977587) (xy 73.751694 -370.97716) (xy 74.467974 -370.97716) (xy 74.478147 -370.977586)
			(xy 74.496945 -370.985366) (xy 74.511331 -370.999752) (xy 74.519113 -371.018549) (xy 74.519536 -371.028722)
			(xy 74.519536 -371.18671) (xy 74.519956 -371.195896) (xy 74.526464 -371.21308) (xy 74.532236 -371.220238)
			(xy 74.553987 -371.245921) (xy 74.591939 -371.301502) (xy 74.622975 -371.361221) (xy 74.646651 -371.424222)
			(xy 74.662627 -371.489601) (xy 74.670675 -371.55642) (xy 74.670678 -371.623723) (xy 74.662638 -371.690543)
			(xy 74.646668 -371.755924) (xy 74.622998 -371.818926) (xy 74.591968 -371.878649) (xy 74.554022 -371.934234)
			(xy 74.532236 -371.959886) (xy 74.526413 -371.967012) (xy 74.519916 -371.984217) (xy 74.519536 -371.993414)
			(xy 74.519536 -372.486682) (xy 74.519969 -372.495866) (xy 74.526468 -372.51305) (xy 74.532236 -372.52021)
			(xy 74.554058 -372.545834) (xy 74.592008 -372.601424) (xy 74.623041 -372.661151) (xy 74.646713 -372.724159)
			(xy 74.662684 -372.789545) (xy 74.670726 -372.856371) (xy 74.670723 -372.92368) (xy 74.662675 -372.990505)
			(xy 74.646698 -373.055889) (xy 74.62302 -373.118896) (xy 74.591981 -373.17862) (xy 74.554027 -373.234206)
			(xy 74.532236 -373.259858) (xy 74.526425 -373.266992) (xy 74.519921 -373.284191) (xy 74.519536 -373.293386)
			(xy 74.519536 -373.451374) (xy 74.519114 -373.461547) (xy 74.511333 -373.480346) (xy 74.496946 -373.494733)
			(xy 74.478147 -373.502514) (xy 74.467974 -373.502936) (xy 73.751694 -373.502936) (xy 73.741519 -373.50254)
			(xy 73.722719 -373.494749) (xy 73.708333 -373.480354) (xy 73.700553 -373.461549) (xy 73.700132 -373.451374)
			(xy 73.700132 -373.293386) (xy 73.699722 -373.284199) (xy 73.693207 -373.267015) (xy 73.687432 -373.259858)
			(xy 73.665678 -373.234178) (xy 73.627729 -373.178595) (xy 73.596694 -373.118876) (xy 73.57302 -373.055875)
			(xy 73.557045 -372.990496) (xy 73.548998 -372.923677) (xy 73.548995 -372.856374) (xy 73.557036 -372.789554)
			(xy 73.573005 -372.724174) (xy 73.596674 -372.661171) (xy 73.627702 -372.601448) (xy 73.665647 -372.545862)
			(xy 73.687432 -372.52021) (xy 73.693253 -372.513083) (xy 73.699753 -372.495878) (xy 73.700132 -372.486682)
			(xy 73.700132 -371.993414) (xy 73.699708 -371.984228) (xy 73.693203 -371.967044) (xy 73.687432 -371.959886)
			(xy 73.665607 -371.934265) (xy 73.62766 -371.878674) (xy 73.596629 -371.818946) (xy 73.572958 -371.755937)
			(xy 73.556988 -371.690551) (xy 73.548947 -371.623725) (xy 72.446841 -371.623725) (xy 72.44697 -371.624068)
			(xy 72.463005 -371.689558) (xy 72.47108 -371.756498) (xy 72.471078 -371.823923) (xy 72.463001 -371.890862)
			(xy 72.446964 -371.956352) (xy 72.423197 -372.01945) (xy 72.392044 -372.079246) (xy 72.353953 -372.134881)
			(xy 72.332088 -372.160546) (xy 72.326288 -372.167689) (xy 72.319776 -372.184881) (xy 72.319388 -372.194074)
			(xy 72.319388 -372.351554) (xy 72.318836 -372.361674) (xy 72.311129 -372.380389) (xy 72.296863 -372.394746)
			(xy 72.278197 -372.402572) (xy 72.26808 -372.403116) (xy 71.5518 -372.403116) (xy 71.541648 -372.402679)
			(xy 71.522899 -372.394886) (xy 71.508576 -372.380494) (xy 71.500873 -372.361708) (xy 71.500492 -372.351554)
			(xy 71.500492 -372.194074) (xy 71.500096 -372.184885) (xy 71.493573 -372.167701) (xy 71.487792 -372.160546)
			(xy 71.465942 -372.134869) (xy 71.427853 -372.079236) (xy 71.396703 -372.019442) (xy 71.372938 -371.956346)
			(xy 71.356902 -371.890859) (xy 71.348825 -371.823922) (xy 71.348824 -371.756499) (xy 71.356898 -371.689562)
			(xy 71.372932 -371.624074) (xy 71.396694 -371.560978) (xy 71.427843 -371.501182) (xy 71.465929 -371.445547)
			(xy 71.487792 -371.419882) (xy 71.493578 -371.412729) (xy 71.500099 -371.395545) (xy 71.500492 -371.386354)
			(xy 71.500492 -370.893848) (xy 71.500061 -370.884663) (xy 71.493562 -370.867478) (xy 71.487792 -370.86032)
			(xy 71.465917 -370.834664) (xy 71.427829 -370.779028) (xy 71.396679 -370.719231) (xy 71.372916 -370.656133)
			(xy 71.356881 -370.590642) (xy 71.348807 -370.523703) (xy 58.103008 -370.523703) (xy 58.103008 -371.310662)
			(xy 58.102522 -371.337931) (xy 58.09476 -371.391915) (xy 58.079395 -371.444245) (xy 58.056738 -371.493855)
			(xy 58.027252 -371.539736) (xy 57.991537 -371.580953) (xy 57.95032 -371.616668) (xy 57.904439 -371.646154)
			(xy 57.854829 -371.668811) (xy 57.802499 -371.684176) (xy 57.748515 -371.691938) (xy 57.693977 -371.691938)
			(xy 57.639993 -371.684176) (xy 57.587663 -371.668811) (xy 57.538053 -371.646154) (xy 57.492172 -371.616668)
			(xy 57.450955 -371.580953) (xy 57.41524 -371.539736) (xy 57.385754 -371.493855) (xy 57.363097 -371.444245)
			(xy 57.347732 -371.391915) (xy 57.33997 -371.337931) (xy 57.339484 -371.310662) (xy 54.729888 -371.310662)
			(xy 54.729402 -371.337931) (xy 54.72164 -371.391915) (xy 54.706275 -371.444245) (xy 54.683618 -371.493855)
			(xy 54.654132 -371.539736) (xy 54.618417 -371.580953) (xy 54.5772 -371.616668) (xy 54.531319 -371.646154)
			(xy 54.481709 -371.668811) (xy 54.429379 -371.684176) (xy 54.375395 -371.691938) (xy 54.320857 -371.691938)
			(xy 54.266873 -371.684176) (xy 54.214543 -371.668811) (xy 54.164933 -371.646154) (xy 54.119052 -371.616668)
			(xy 54.077835 -371.580953) (xy 54.04212 -371.539736) (xy 54.012634 -371.493855) (xy 53.989977 -371.444245)
			(xy 53.974612 -371.391915) (xy 53.96685 -371.337931) (xy 53.966364 -371.310662) (xy 48.196948 -371.310662)
			(xy 48.223223 -371.361224) (xy 48.246896 -371.424224) (xy 48.262871 -371.489602) (xy 48.270918 -371.556421)
			(xy 48.270921 -371.623722) (xy 48.262881 -371.690542) (xy 48.246913 -371.755921) (xy 48.223246 -371.818924)
			(xy 48.192219 -371.878647) (xy 48.154277 -371.934234) (xy 48.132492 -371.959886) (xy 48.126675 -371.967017)
			(xy 48.120173 -371.984218) (xy 48.119792 -371.993414) (xy 48.119792 -372.486682) (xy 48.120213 -372.495868)
			(xy 48.126719 -372.513052) (xy 48.132492 -372.52021) (xy 48.154312 -372.545835) (xy 48.192258 -372.601426)
			(xy 48.223288 -372.661154) (xy 48.246958 -372.724162) (xy 48.262927 -372.789547) (xy 48.270968 -372.856372)
			(xy 48.270965 -372.923679) (xy 48.262918 -372.990504) (xy 48.246942 -373.055887) (xy 48.223267 -373.118893)
			(xy 48.192232 -373.178618) (xy 48.154281 -373.234205) (xy 48.132492 -373.259858) (xy 48.126687 -373.266997)
			(xy 48.120178 -373.284192) (xy 48.119792 -373.293386) (xy 48.119792 -373.451374) (xy 48.119246 -373.461526)
			(xy 48.111486 -373.480289) (xy 48.097136 -373.494655) (xy 48.078382 -373.502435) (xy 48.06823 -373.502936)
			(xy 47.35195 -373.502936) (xy 47.341778 -373.502495) (xy 47.32298 -373.494721) (xy 47.308592 -373.48034)
			(xy 47.30081 -373.461545) (xy 47.300388 -373.451374) (xy 47.300388 -373.293386) (xy 47.299987 -373.284198)
			(xy 47.293467 -373.267013) (xy 47.287688 -373.259858) (xy 47.265932 -373.234179) (xy 47.227979 -373.178598)
			(xy 47.196942 -373.118878) (xy 47.173265 -373.055877) (xy 47.157288 -372.990498) (xy 47.14924 -372.923677)
			(xy 47.149237 -372.856374) (xy 47.157279 -372.789553) (xy 47.17325 -372.724172) (xy 47.196921 -372.661169)
			(xy 47.227953 -372.601446) (xy 47.265901 -372.545861) (xy 47.287688 -372.52021) (xy 47.293504 -372.513078)
			(xy 47.300007 -372.495878) (xy 47.300388 -372.486682) (xy 47.300388 -371.993414) (xy 47.299974 -371.984227)
			(xy 47.293463 -371.967043) (xy 47.287688 -371.959886) (xy 47.265861 -371.934265) (xy 47.227911 -371.878675)
			(xy 47.196876 -371.818948) (xy 47.173204 -371.755939) (xy 47.157232 -371.690553) (xy 47.14919 -371.623726)
			(xy 46.046568 -371.623726) (xy 46.046802 -371.624349) (xy 46.062775 -371.689733) (xy 46.070818 -371.756557)
			(xy 46.070817 -371.823864) (xy 46.062771 -371.890688) (xy 46.046796 -371.956071) (xy 46.023121 -372.019076)
			(xy 45.992085 -372.0788) (xy 45.954133 -372.134386) (xy 45.932344 -372.160038) (xy 45.926542 -372.167179)
			(xy 45.920032 -372.184373) (xy 45.919644 -372.193566) (xy 45.919644 -372.351554) (xy 45.919198 -372.361725)
			(xy 45.911425 -372.380522) (xy 45.897046 -372.394909) (xy 45.878253 -372.402693) (xy 45.868082 -372.403116)
			(xy 45.151802 -372.403116) (xy 45.141625 -372.402733) (xy 45.122821 -372.394941) (xy 45.108435 -372.380542)
			(xy 45.100658 -372.361732) (xy 45.10024 -372.351554) (xy 45.10024 -372.193566) (xy 45.099837 -372.184378)
			(xy 45.093317 -372.167194) (xy 45.08754 -372.160038) (xy 45.065766 -372.134374) (xy 45.027817 -372.07879)
			(xy 44.996783 -372.019068) (xy 44.973109 -371.956065) (xy 44.957135 -371.890684) (xy 44.94909 -371.823862)
			(xy 44.949089 -371.756559) (xy 44.957132 -371.689737) (xy 44.973103 -371.624356) (xy 44.996774 -371.561352)
			(xy 45.027806 -371.501628) (xy 45.065753 -371.446042) (xy 45.08754 -371.42039) (xy 45.093328 -371.413239)
			(xy 45.099847 -371.396053) (xy 45.10024 -371.386862) (xy 45.10024 -370.89334) (xy 45.099801 -370.884156)
			(xy 45.093306 -370.866972) (xy 45.08754 -370.859812) (xy 45.06574 -370.83417) (xy 45.027792 -370.778582)
			(xy 44.996759 -370.718857) (xy 44.973087 -370.655851) (xy 44.957115 -370.590468) (xy 44.949071 -370.523644)
			(xy 41.671032 -370.523644) (xy 41.671032 -370.523703) (xy 41.662957 -370.590641) (xy 41.646921 -370.65613)
			(xy 41.623156 -370.719227) (xy 41.592004 -370.779022) (xy 41.553913 -370.834656) (xy 41.532048 -370.86032)
			(xy 41.526254 -370.867467) (xy 41.519739 -370.884656) (xy 41.519348 -370.893848) (xy 41.519348 -371.386354)
			(xy 41.519792 -371.395537) (xy 41.526284 -371.412721) (xy 41.532048 -371.419882) (xy 41.553928 -371.445535)
			(xy 41.592019 -371.50117) (xy 41.623172 -371.560967) (xy 41.646832 -371.623785) (xy 42.748894 -371.623785)
			(xy 42.748898 -371.556358) (xy 42.756977 -371.489417) (xy 42.773017 -371.423926) (xy 42.796785 -371.360828)
			(xy 42.827941 -371.30103) (xy 42.866034 -371.245395) (xy 42.8879 -371.21973) (xy 42.893709 -371.212593)
			(xy 42.900216 -371.195396) (xy 42.9006 -371.186202) (xy 42.9006 -371.028722) (xy 42.901143 -371.018602)
			(xy 42.908856 -370.999888) (xy 42.923125 -370.985533) (xy 42.941791 -370.977706) (xy 42.951908 -370.97716)
			(xy 43.668188 -370.97716) (xy 43.678336 -370.977631) (xy 43.697081 -370.985415) (xy 43.711403 -370.999796)
			(xy 43.71911 -371.018572) (xy 43.719496 -371.028722) (xy 43.719496 -371.186202) (xy 43.719906 -371.195389)
			(xy 43.72642 -371.212573) (xy 43.732196 -371.21973) (xy 43.754023 -371.245426) (xy 43.792113 -371.301056)
			(xy 43.823265 -371.360848) (xy 43.847032 -371.423941) (xy 43.86307 -371.489426) (xy 43.871149 -371.556361)
			(xy 43.871153 -371.623782) (xy 43.86308 -371.690718) (xy 43.847049 -371.756205) (xy 43.823289 -371.8193)
			(xy 43.792142 -371.879095) (xy 43.754058 -371.934729) (xy 43.732196 -371.960394) (xy 43.726419 -371.967553)
			(xy 43.719893 -371.984733) (xy 43.719496 -371.993922) (xy 43.719496 -372.486174) (xy 43.71992 -372.49536)
			(xy 43.726424 -372.512544) (xy 43.732196 -372.519702) (xy 43.754094 -372.54534) (xy 43.792181 -372.600978)
			(xy 43.823331 -372.660778) (xy 43.847093 -372.723878) (xy 43.863127 -372.789371) (xy 43.8712 -372.856312)
			(xy 43.871197 -372.923739) (xy 43.863117 -372.990679) (xy 43.847078 -373.05617) (xy 43.82331 -373.119269)
			(xy 43.792155 -373.179066) (xy 43.754062 -373.234701) (xy 43.732196 -373.260366) (xy 43.726388 -373.267503)
			(xy 43.71988 -373.2847) (xy 43.719496 -373.293894) (xy 43.719496 -373.451374) (xy 43.718953 -373.461495)
			(xy 43.711241 -373.480208) (xy 43.696972 -373.494564) (xy 43.678306 -373.502391) (xy 43.668188 -373.502936)
			(xy 42.951908 -373.502936) (xy 42.941759 -373.502473) (xy 42.923014 -373.494686) (xy 42.908691 -373.480303)
			(xy 42.900985 -373.461525) (xy 42.9006 -373.451374) (xy 42.9006 -373.293894) (xy 42.900193 -373.284707)
			(xy 42.893677 -373.267522) (xy 42.8879 -373.260366) (xy 42.866069 -373.234673) (xy 42.82798 -373.179043)
			(xy 42.796828 -373.11925) (xy 42.773061 -373.056157) (xy 42.757024 -372.990671) (xy 42.748945 -372.923736)
			(xy 42.748942 -372.856315) (xy 42.757014 -372.789379) (xy 42.773046 -372.723892) (xy 42.796807 -372.660796)
			(xy 42.827953 -372.601001) (xy 42.866038 -372.545367) (xy 42.8879 -372.519702) (xy 42.893678 -372.512544)
			(xy 42.900204 -372.495363) (xy 42.9006 -372.486174) (xy 42.9006 -371.993922) (xy 42.900179 -371.984736)
			(xy 42.893673 -371.967551) (xy 42.8879 -371.960394) (xy 42.865999 -371.93476) (xy 42.827911 -371.879121)
			(xy 42.796762 -371.81932) (xy 42.773 -371.756219) (xy 42.756967 -371.690726) (xy 42.748894 -371.623785)
			(xy 41.646832 -371.623785) (xy 41.646938 -371.624066) (xy 41.662974 -371.689557) (xy 41.67105 -371.756498)
			(xy 41.671048 -371.823923) (xy 41.66297 -371.890864) (xy 41.646932 -371.956354) (xy 41.623164 -372.019452)
			(xy 41.592008 -372.079248) (xy 41.553915 -372.134882) (xy 41.532048 -372.160546) (xy 41.526243 -372.167685)
			(xy 41.519735 -372.18488) (xy 41.519348 -372.194074) (xy 41.519348 -372.351554) (xy 41.518835 -372.361679)
			(xy 41.51112 -372.380402) (xy 41.496842 -372.39476) (xy 41.478162 -372.402579) (xy 41.46804 -372.403116)
			(xy 40.75176 -372.403116) (xy 40.741605 -372.402711) (xy 40.722855 -372.394906) (xy 40.708534 -372.380504)
			(xy 40.700833 -372.361711) (xy 40.700452 -372.351554) (xy 40.700452 -372.194074) (xy 40.700043 -372.184887)
			(xy 40.693527 -372.167703) (xy 40.687752 -372.160546) (xy 40.6659 -372.13487) (xy 40.627807 -372.079238)
			(xy 40.596653 -372.019444) (xy 40.572886 -371.956349) (xy 40.556848 -371.89086) (xy 40.54877 -371.823922)
			(xy 40.548769 -371.756499) (xy 40.556844 -371.68956) (xy 40.57288 -371.624072) (xy 40.596645 -371.560975)
			(xy 40.627797 -371.50118) (xy 40.665887 -371.445546) (xy 40.687752 -371.419882) (xy 40.693545 -371.412735)
			(xy 40.70006 -371.395546) (xy 40.700452 -371.386354) (xy 40.700452 -370.893848) (xy 40.700007 -370.884665)
			(xy 40.693516 -370.867481) (xy 40.687752 -370.86032) (xy 40.665874 -370.834665) (xy 40.627783 -370.779031)
			(xy 40.59663 -370.719233) (xy 40.572864 -370.656135) (xy 40.556828 -370.590644) (xy 40.548752 -370.523704)
			(xy 37.271241 -370.523704) (xy 37.263166 -370.590641) (xy 37.247131 -370.65613) (xy 37.223366 -370.719226)
			(xy 37.192215 -370.779022) (xy 37.154125 -370.834655) (xy 37.13226 -370.86032) (xy 37.126467 -370.867468)
			(xy 37.119951 -370.884656) (xy 37.11956 -370.893848) (xy 37.11956 -371.386354) (xy 37.120001 -371.395538)
			(xy 37.126494 -371.412722) (xy 37.13226 -371.419882) (xy 37.154139 -371.445535) (xy 37.19223 -371.501171)
			(xy 37.223382 -371.560968) (xy 37.247019 -371.623725) (xy 38.349126 -371.623725) (xy 38.349129 -371.556418)
			(xy 38.357177 -371.489593) (xy 38.373153 -371.424209) (xy 38.396828 -371.361203) (xy 38.427864 -371.301478)
			(xy 38.465815 -371.245891) (xy 38.487604 -371.220238) (xy 38.49341 -371.213099) (xy 38.499919 -371.195904)
			(xy 38.500304 -371.18671) (xy 38.500304 -371.028722) (xy 38.50085 -371.01857) (xy 38.508611 -370.999808)
			(xy 38.522961 -370.985443) (xy 38.541714 -370.977661) (xy 38.551866 -370.97716) (xy 39.268146 -370.97716)
			(xy 39.278309 -370.977596) (xy 39.297084 -370.98539) (xy 39.311448 -370.999773) (xy 39.319217 -371.018558)
			(xy 39.319708 -371.028722) (xy 39.319708 -371.18671) (xy 39.320112 -371.195898) (xy 39.32663 -371.213082)
			(xy 39.332408 -371.220238) (xy 39.35416 -371.24592) (xy 39.392113 -371.301501) (xy 39.423151 -371.36122)
			(xy 39.446829 -371.424221) (xy 39.462806 -371.4896) (xy 39.470854 -371.55642) (xy 39.470857 -371.623723)
			(xy 39.462816 -371.690544) (xy 39.446845 -371.755925) (xy 39.423175 -371.818928) (xy 39.392143 -371.87865)
			(xy 39.354195 -371.934235) (xy 39.332408 -371.959886) (xy 39.326593 -371.967018) (xy 39.320089 -371.984219)
			(xy 39.319708 -371.993414) (xy 39.319708 -372.486682) (xy 39.320125 -372.495868) (xy 39.326634 -372.513053)
			(xy 39.332408 -372.52021) (xy 39.354231 -372.545834) (xy 39.392182 -372.601423) (xy 39.423217 -372.66115)
			(xy 39.44689 -372.724158) (xy 39.462862 -372.789545) (xy 39.470904 -372.856371) (xy 39.470901 -372.92368)
			(xy 39.462853 -372.990506) (xy 39.446875 -373.05589) (xy 39.423196 -373.118897) (xy 39.392156 -373.178621)
			(xy 39.354199 -373.234207) (xy 39.332408 -373.259858) (xy 39.326605 -373.266999) (xy 39.320094 -373.284193)
			(xy 39.319708 -373.293386) (xy 39.319708 -373.451374) (xy 39.319147 -373.461525) (xy 39.311389 -373.480284)
			(xy 39.297045 -373.494649) (xy 39.278296 -373.502432) (xy 39.268146 -373.502936) (xy 38.551866 -373.502936)
			(xy 38.541703 -373.502494) (xy 38.522928 -373.494703) (xy 38.508563 -373.480322) (xy 38.500794 -373.461538)
			(xy 38.500304 -373.451374) (xy 38.500304 -373.293386) (xy 38.4999 -373.284198) (xy 38.493382 -373.267014)
			(xy 38.487604 -373.259858) (xy 38.465851 -373.234178) (xy 38.427903 -373.178595) (xy 38.39687 -373.118875)
			(xy 38.373197 -373.055874) (xy 38.357223 -372.990495) (xy 38.349177 -372.923676) (xy 38.349174 -372.856375)
			(xy 38.357214 -372.789555) (xy 38.373182 -372.724175) (xy 38.396849 -372.661172) (xy 38.427877 -372.601449)
			(xy 38.465819 -372.545863) (xy 38.487604 -372.52021) (xy 38.493422 -372.51308) (xy 38.499924 -372.495878)
			(xy 38.500304 -372.486682) (xy 38.500304 -371.993414) (xy 38.499886 -371.984228) (xy 38.493378 -371.967043)
			(xy 38.487604 -371.959886) (xy 38.46578 -371.934264) (xy 38.427835 -371.878672) (xy 38.396805 -371.818944)
			(xy 38.373136 -371.755936) (xy 38.357167 -371.69055) (xy 38.349126 -371.623725) (xy 37.247019 -371.623725)
			(xy 37.247148 -371.624067) (xy 37.263183 -371.689557) (xy 37.271259 -371.756498) (xy 37.271257 -371.823923)
			(xy 37.263179 -371.890863) (xy 37.247141 -371.956354) (xy 37.223374 -372.019451) (xy 37.192219 -372.079248)
			(xy 37.154126 -372.134881) (xy 37.13226 -372.160546) (xy 37.126456 -372.167686) (xy 37.119947 -372.184881)
			(xy 37.11956 -372.194074) (xy 37.11956 -372.351554) (xy 37.119036 -372.361678) (xy 37.111323 -372.380398)
			(xy 37.097048 -372.394756) (xy 37.078373 -372.402576) (xy 37.068252 -372.403116) (xy 36.351972 -372.403116)
			(xy 36.341818 -372.402702) (xy 36.323068 -372.3949) (xy 36.308746 -372.380501) (xy 36.301045 -372.36171)
			(xy 36.300664 -372.351554) (xy 36.300664 -372.194074) (xy 36.300252 -372.184887) (xy 36.293738 -372.167704)
			(xy 36.287964 -372.160546) (xy 36.266115 -372.134869) (xy 36.228028 -372.079235) (xy 36.196879 -372.01944)
			(xy 36.173116 -371.956345) (xy 36.15708 -371.890858) (xy 36.149004 -371.823921) (xy 36.149003 -371.7565)
			(xy 36.157076 -371.689563) (xy 36.173109 -371.624075) (xy 36.19687 -371.560979) (xy 36.228017 -371.501183)
			(xy 36.266102 -371.445548) (xy 36.287964 -371.419882) (xy 36.293759 -371.412736) (xy 36.300273 -371.395546)
			(xy 36.300664 -371.386354) (xy 36.300664 -370.893848) (xy 36.300217 -370.884665) (xy 36.293727 -370.867481)
			(xy 36.287964 -370.86032) (xy 36.26609 -370.834664) (xy 36.228004 -370.779027) (xy 36.196855 -370.719229)
			(xy 36.173093 -370.656131) (xy 36.15706 -370.590642) (xy 36.148986 -370.523703) (xy 32.870915 -370.523703)
			(xy 32.862879 -370.590465) (xy 32.846908 -370.655846) (xy 32.823237 -370.71885) (xy 32.792205 -370.778573)
			(xy 32.754259 -370.83416) (xy 32.732472 -370.859812) (xy 32.726684 -370.866963) (xy 32.720165 -370.884149)
			(xy 32.719772 -370.89334) (xy 32.719772 -371.386862) (xy 32.720207 -371.396046) (xy 32.726704 -371.413231)
			(xy 32.732472 -371.42039) (xy 32.754273 -371.446031) (xy 32.792221 -371.501619) (xy 32.823253 -371.561344)
			(xy 32.846713 -371.623785) (xy 33.948806 -371.623785) (xy 33.94881 -371.556358) (xy 33.95689 -371.489417)
			(xy 33.97293 -371.423925) (xy 33.996699 -371.360827) (xy 34.027855 -371.30103) (xy 34.065949 -371.245395)
			(xy 34.087816 -371.21973) (xy 34.093627 -371.212595) (xy 34.100132 -371.195397) (xy 34.100516 -371.186202)
			(xy 34.100516 -371.028722) (xy 34.101044 -371.0186) (xy 34.10876 -370.999883) (xy 34.123033 -370.985527)
			(xy 34.141705 -370.977703) (xy 34.151824 -370.97716) (xy 34.868104 -370.97716) (xy 34.878253 -370.977618)
			(xy 34.896998 -370.985407) (xy 34.91132 -370.999792) (xy 34.919027 -371.018571) (xy 34.919412 -371.028722)
			(xy 34.919412 -371.186202) (xy 34.919819 -371.19539) (xy 34.926334 -371.212574) (xy 34.932112 -371.21973)
			(xy 34.953938 -371.245426) (xy 34.992027 -371.301057) (xy 35.023179 -371.360849) (xy 35.046945 -371.423941)
			(xy 35.062982 -371.489427) (xy 35.071061 -371.556361) (xy 35.071065 -371.623782) (xy 35.062993 -371.690717)
			(xy 35.046962 -371.756204) (xy 35.023202 -371.819299) (xy 34.992057 -371.879094) (xy 34.953973 -371.934729)
			(xy 34.932112 -371.960394) (xy 34.926337 -371.967555) (xy 34.919809 -371.984733) (xy 34.919412 -371.993922)
			(xy 34.919412 -372.486174) (xy 34.919832 -372.49536) (xy 34.926338 -372.512545) (xy 34.932112 -372.519702)
			(xy 34.954009 -372.54534) (xy 34.992096 -372.600979) (xy 35.023244 -372.660779) (xy 35.047006 -372.723879)
			(xy 35.063039 -372.789371) (xy 35.071112 -372.856312) (xy 35.071109 -372.923739) (xy 35.06303 -372.990679)
			(xy 35.046991 -373.05617) (xy 35.023224 -373.119268) (xy 34.99207 -373.179065) (xy 34.953978 -373.234701)
			(xy 34.932112 -373.260366) (xy 34.926306 -373.267505) (xy 34.919797 -373.2847) (xy 34.919412 -373.293894)
			(xy 34.919412 -373.451374) (xy 34.918854 -373.461493) (xy 34.911144 -373.480203) (xy 34.89688 -373.494559)
			(xy 34.878219 -373.502388) (xy 34.868104 -373.502936) (xy 34.151824 -373.502936) (xy 34.141676 -373.50246)
			(xy 34.122931 -373.494679) (xy 34.108608 -373.480299) (xy 34.100901 -373.461524) (xy 34.100516 -373.451374)
			(xy 34.100516 -373.293894) (xy 34.100105 -373.284707) (xy 34.093592 -373.267523) (xy 34.087816 -373.260366)
			(xy 34.065985 -373.234673) (xy 34.027894 -373.179043) (xy 33.996741 -373.119251) (xy 33.972974 -373.056158)
			(xy 33.956936 -372.990672) (xy 33.948857 -372.923736) (xy 33.948854 -372.856315) (xy 33.956927 -372.789379)
			(xy 33.972959 -372.723891) (xy 33.99672 -372.660796) (xy 34.027868 -372.601001) (xy 34.065953 -372.545367)
			(xy 34.087816 -372.519702) (xy 34.093596 -372.512545) (xy 34.10012 -372.495364) (xy 34.100516 -372.486174)
			(xy 34.100516 -371.993922) (xy 34.100092 -371.984736) (xy 34.093587 -371.967552) (xy 34.087816 -371.960394)
			(xy 34.065914 -371.93476) (xy 34.027826 -371.879121) (xy 33.996676 -371.819321) (xy 33.972913 -371.75622)
			(xy 33.956879 -371.690727) (xy 33.948806 -371.623785) (xy 32.846713 -371.623785) (xy 32.846925 -371.62435)
			(xy 32.862896 -371.689734) (xy 32.870939 -371.756558) (xy 32.870938 -371.823864) (xy 32.862892 -371.890687)
			(xy 32.846918 -371.95607) (xy 32.823244 -372.019075) (xy 32.79221 -372.078799) (xy 32.75426 -372.134386)
			(xy 32.732472 -372.160038) (xy 32.726673 -372.167181) (xy 32.72016 -372.184373) (xy 32.719772 -372.193566)
			(xy 32.719772 -372.351554) (xy 32.719299 -372.361721) (xy 32.711531 -372.380513) (xy 32.69716 -372.394899)
			(xy 32.678377 -372.402688) (xy 32.66821 -372.403116) (xy 31.95193 -372.403116) (xy 31.941755 -372.40271)
			(xy 31.922952 -372.394927) (xy 31.908564 -372.380535) (xy 31.900787 -372.361729) (xy 31.900368 -372.351554)
			(xy 31.900368 -372.193566) (xy 31.899959 -372.184379) (xy 31.893443 -372.167195) (xy 31.887668 -372.160038)
			(xy 31.865893 -372.134375) (xy 31.827942 -372.078791) (xy 31.796907 -372.019069) (xy 31.773232 -371.956066)
			(xy 31.757257 -371.890685) (xy 31.749211 -371.823863) (xy 31.74921 -371.756558) (xy 31.757253 -371.689736)
			(xy 31.773226 -371.624354) (xy 31.796898 -371.56135) (xy 31.827931 -371.501627) (xy 31.86588 -371.446042)
			(xy 31.887668 -371.42039) (xy 31.89346 -371.413242) (xy 31.899975 -371.396053) (xy 31.900368 -371.386862)
			(xy 31.900368 -370.89334) (xy 31.899923 -370.884157) (xy 31.893432 -370.866973) (xy 31.887668 -370.859812)
			(xy 31.865868 -370.83417) (xy 31.827917 -370.778583) (xy 31.796883 -370.718858) (xy 31.77321 -370.655852)
			(xy 31.757237 -370.590468) (xy 31.749193 -370.523644) (xy 28.471153 -370.523644) (xy 28.471153 -370.523703)
			(xy 28.463078 -370.59064) (xy 28.447043 -370.656129) (xy 28.42328 -370.719226) (xy 28.392129 -370.779021)
			(xy 28.35404 -370.834655) (xy 28.332176 -370.86032) (xy 28.326386 -370.867469) (xy 28.319868 -370.884657)
			(xy 28.319476 -370.893848) (xy 28.319476 -371.386354) (xy 28.319914 -371.395538) (xy 28.326409 -371.412722)
			(xy 28.332176 -371.419882) (xy 28.354055 -371.445535) (xy 28.392144 -371.501171) (xy 28.423296 -371.560969)
			(xy 28.446931 -371.623725) (xy 29.549038 -371.623725) (xy 29.549042 -371.556418) (xy 29.557089 -371.489593)
			(xy 29.573066 -371.424209) (xy 29.596742 -371.361203) (xy 29.627778 -371.301478) (xy 29.665731 -371.24589)
			(xy 29.68752 -371.220238) (xy 29.693328 -371.213101) (xy 29.699835 -371.195904) (xy 29.70022 -371.18671)
			(xy 29.70022 -371.028722) (xy 29.700682 -371.018554) (xy 29.708456 -370.999763) (xy 29.72283 -370.985378)
			(xy 29.741614 -370.97759) (xy 29.751782 -370.97716) (xy 30.468062 -370.97716) (xy 30.478234 -370.977596)
			(xy 30.497032 -370.985372) (xy 30.511419 -370.999755) (xy 30.519201 -371.01855) (xy 30.519624 -371.028722)
			(xy 30.519624 -371.18671) (xy 30.520024 -371.195898) (xy 30.526544 -371.213083) (xy 30.532324 -371.220238)
			(xy 30.554075 -371.24592) (xy 30.592028 -371.301502) (xy 30.623065 -371.361221) (xy 30.646741 -371.424221)
			(xy 30.662718 -371.4896) (xy 30.670766 -371.55642) (xy 30.670769 -371.623723) (xy 30.662728 -371.690543)
			(xy 30.646758 -371.755924) (xy 30.623088 -371.818927) (xy 30.592057 -371.878649) (xy 30.554111 -371.934234)
			(xy 30.532324 -371.959886) (xy 30.526511 -371.96702) (xy 30.520005 -371.984219) (xy 30.519624 -371.993414)
			(xy 30.519624 -372.486682) (xy 30.520037 -372.495869) (xy 30.526548 -372.513054) (xy 30.532324 -372.52021)
			(xy 30.554146 -372.545834) (xy 30.592096 -372.601424) (xy 30.62313 -372.661151) (xy 30.646803 -372.724159)
			(xy 30.662774 -372.789545) (xy 30.670816 -372.856371) (xy 30.670813 -372.92368) (xy 30.662765 -372.990505)
			(xy 30.646788 -373.05589) (xy 30.623109 -373.118896) (xy 30.59207 -373.17862) (xy 30.554115 -373.234206)
			(xy 30.532324 -373.259858) (xy 30.526523 -373.267) (xy 30.52001 -373.284193) (xy 30.519624 -373.293386)
			(xy 30.519624 -373.451374) (xy 30.519214 -373.461549) (xy 30.51143 -373.48035) (xy 30.49704 -373.494737)
			(xy 30.478237 -373.502516) (xy 30.468062 -373.502936) (xy 29.751782 -373.502936) (xy 29.741606 -373.50255)
			(xy 29.722806 -373.494754) (xy 29.708421 -373.480357) (xy 29.700641 -373.46155) (xy 29.70022 -373.451374)
			(xy 29.70022 -373.293386) (xy 29.699812 -373.284199) (xy 29.693297 -373.267015) (xy 29.68752 -373.259858)
			(xy 29.665767 -373.234178) (xy 29.627818 -373.178595) (xy 29.596784 -373.118875) (xy 29.57311 -373.055874)
			(xy 29.557136 -372.990496) (xy 29.549089 -372.923677) (xy 29.549086 -372.856375) (xy 29.557127 -372.789555)
			(xy 29.573095 -372.724175) (xy 29.596763 -372.661172) (xy 29.627792 -372.601449) (xy 29.665735 -372.545863)
			(xy 29.68752 -372.52021) (xy 29.69334 -372.513081) (xy 29.69984 -372.495878) (xy 29.70022 -372.486682)
			(xy 29.70022 -371.993414) (xy 29.699798 -371.984228) (xy 29.693292 -371.967044) (xy 29.68752 -371.959886)
			(xy 29.665695 -371.934264) (xy 29.627749 -371.878673) (xy 29.596718 -371.818945) (xy 29.573049 -371.755937)
			(xy 29.557079 -371.690551) (xy 29.549038 -371.623725) (xy 28.446931 -371.623725) (xy 28.44706 -371.624067)
			(xy 28.463096 -371.689558) (xy 28.471171 -371.756498) (xy 28.471169 -371.823923) (xy 28.463092 -371.890863)
			(xy 28.447054 -371.956353) (xy 28.423287 -372.01945) (xy 28.392134 -372.079247) (xy 28.354042 -372.134881)
			(xy 28.332176 -372.160546) (xy 28.326375 -372.167688) (xy 28.319864 -372.184881) (xy 28.319476 -372.194074)
			(xy 28.319476 -372.351554) (xy 28.318936 -372.361676) (xy 28.311226 -372.380393) (xy 28.296956 -372.39475)
			(xy 28.278287 -372.402574) (xy 28.268168 -372.403116) (xy 27.551888 -372.403116) (xy 27.541735 -372.402689)
			(xy 27.522985 -372.394892) (xy 27.508663 -372.380498) (xy 27.500961 -372.361709) (xy 27.50058 -372.351554)
			(xy 27.50058 -372.194074) (xy 27.500187 -372.184885) (xy 27.493662 -372.167701) (xy 27.48788 -372.160546)
			(xy 27.46603 -372.134869) (xy 27.427943 -372.079236) (xy 27.396792 -372.019441) (xy 27.373028 -371.956346)
			(xy 27.356993 -371.890858) (xy 27.348916 -371.823922) (xy 27.348915 -371.756499) (xy 27.356989 -371.689562)
			(xy 27.373022 -371.624074) (xy 27.396784 -371.560978) (xy 27.427932 -371.501182) (xy 27.466018 -371.445548)
			(xy 27.48788 -371.419882) (xy 27.493664 -371.412728) (xy 27.500187 -371.395544) (xy 27.50058 -371.386354)
			(xy 27.50058 -370.893848) (xy 27.500151 -370.884663) (xy 27.493651 -370.867478) (xy 27.48788 -370.86032)
			(xy 27.466005 -370.834664) (xy 27.427918 -370.779028) (xy 27.396769 -370.71923) (xy 27.373006 -370.656132)
			(xy 27.356972 -370.590642) (xy 27.348898 -370.523703) (xy 1.524 -370.523703) (xy 1.524 -372.100847)
			(xy 8.642336 -372.100847) (xy 8.642336 -372.040913) (xy 8.650159 -371.981491) (xy 8.665671 -371.923598)
			(xy 8.688607 -371.868226) (xy 8.718575 -371.81632) (xy 8.755061 -371.768771) (xy 8.797441 -371.726391)
			(xy 8.84499 -371.689905) (xy 8.896896 -371.659937) (xy 8.952268 -371.637001) (xy 9.010161 -371.621489)
			(xy 9.069583 -371.613666) (xy 9.09955 -371.613176) (xy 9.96315 -371.613176) (xy 9.993118 -371.613658)
			(xy 10.052541 -371.621481) (xy 10.110435 -371.636994) (xy 10.165808 -371.65993) (xy 10.217714 -371.689898)
			(xy 10.265264 -371.726385) (xy 10.307645 -371.768766) (xy 10.344132 -371.816316) (xy 10.3741 -371.868222)
			(xy 10.397036 -371.923595) (xy 10.412549 -371.981489) (xy 10.420372 -372.040912) (xy 10.420372 -372.100848)
			(xy 10.412549 -372.160271) (xy 10.397036 -372.218165) (xy 10.3741 -372.273538) (xy 10.344132 -372.325444)
			(xy 10.307645 -372.372994) (xy 10.265264 -372.415375) (xy 10.217714 -372.451862) (xy 10.165808 -372.48183)
			(xy 10.110435 -372.504766) (xy 10.052541 -372.520279) (xy 9.993118 -372.528102) (xy 9.96315 -372.528592)
			(xy 9.09955 -372.528592) (xy 9.069583 -372.528094) (xy 9.010161 -372.520271) (xy 8.952268 -372.504759)
			(xy 8.896896 -372.481823) (xy 8.84499 -372.451855) (xy 8.797441 -372.415369) (xy 8.755061 -372.372989)
			(xy 8.718575 -372.32544) (xy 8.688607 -372.273534) (xy 8.665671 -372.218162) (xy 8.650159 -372.160269)
			(xy 8.642336 -372.100847) (xy 1.524 -372.100847) (xy 1.524 -374.423871) (xy 27.348897 -374.423871)
			(xy 27.348897 -374.356446) (xy 27.356974 -374.289508) (xy 27.37301 -374.224019) (xy 27.396774 -374.160922)
			(xy 27.427926 -374.101125) (xy 27.466016 -374.045491) (xy 27.48788 -374.019826) (xy 27.493688 -374.012689)
			(xy 27.500197 -373.995492) (xy 27.50058 -373.986298) (xy 27.50058 -373.828818) (xy 27.501042 -373.818688)
			(xy 27.508772 -373.799959) (xy 27.523066 -373.785601) (xy 27.54176 -373.777788) (xy 27.551888 -373.777256)
			(xy 28.268168 -373.777256) (xy 28.278315 -373.777747) (xy 28.297058 -373.785523) (xy 28.311381 -373.799899)
			(xy 28.31909 -373.81867) (xy 28.319476 -373.828818) (xy 28.319476 -373.986298) (xy 28.319892 -373.995484)
			(xy 28.326402 -374.012669) (xy 28.332176 -374.019826) (xy 28.354038 -374.045493) (xy 28.392127 -374.101127)
			(xy 28.423278 -374.160923) (xy 28.447043 -374.22402) (xy 28.463078 -374.289509) (xy 28.471154 -374.356447)
			(xy 28.471155 -374.423823) (xy 31.749171 -374.423823) (xy 31.749175 -374.356514) (xy 31.757224 -374.289688)
			(xy 31.773202 -374.224303) (xy 31.796881 -374.161297) (xy 31.827921 -374.101572) (xy 31.865877 -374.045986)
			(xy 31.887668 -374.020334) (xy 31.893483 -374.013202) (xy 31.899985 -373.996001) (xy 31.900368 -373.986806)
			(xy 31.900368 -373.828818) (xy 31.900779 -373.818644) (xy 31.908564 -373.799844) (xy 31.922954 -373.785457)
			(xy 31.941756 -373.777677) (xy 31.95193 -373.777256) (xy 32.66821 -373.777256) (xy 32.678384 -373.777656)
			(xy 32.697183 -373.785448) (xy 32.711568 -373.799841) (xy 32.719349 -373.818643) (xy 32.719772 -373.828818)
			(xy 32.719772 -373.986806) (xy 32.720185 -373.995993) (xy 32.726697 -374.013177) (xy 32.732472 -374.020334)
			(xy 32.754218 -374.04602) (xy 32.792167 -374.101602) (xy 32.823202 -374.161321) (xy 32.846876 -374.224321)
			(xy 32.862852 -374.289699) (xy 32.870899 -374.356518) (xy 32.870903 -374.423819) (xy 32.870895 -374.423882)
			(xy 36.148964 -374.423882) (xy 36.148968 -374.356455) (xy 36.157048 -374.289515) (xy 36.173087 -374.224024)
			(xy 36.196854 -374.160925) (xy 36.228007 -374.101128) (xy 36.266099 -374.045492) (xy 36.287964 -374.019826)
			(xy 36.293782 -374.012697) (xy 36.300282 -373.995494) (xy 36.300664 -373.986298) (xy 36.300664 -373.828818)
			(xy 36.301142 -373.818689) (xy 36.308868 -373.799964) (xy 36.323158 -373.785606) (xy 36.341846 -373.777791)
			(xy 36.351972 -373.777256) (xy 37.068252 -373.777256) (xy 37.078398 -373.77776) (xy 37.09714 -373.785532)
			(xy 37.111464 -373.799903) (xy 37.119173 -373.818671) (xy 37.11956 -373.828818) (xy 37.11956 -373.986298)
			(xy 37.11998 -373.995484) (xy 37.126488 -374.012668) (xy 37.13226 -374.019826) (xy 37.154084 -374.045525)
			(xy 37.192177 -374.101153) (xy 37.223331 -374.160945) (xy 37.2471 -374.224037) (xy 37.263139 -374.289523)
			(xy 37.271219 -374.356458) (xy 37.271223 -374.423879) (xy 37.271223 -374.423882) (xy 40.548731 -374.423882)
			(xy 40.548735 -374.356454) (xy 40.556815 -374.289512) (xy 40.572857 -374.22402) (xy 40.596628 -374.160921)
			(xy 40.627787 -374.101124) (xy 40.665884 -374.04549) (xy 40.687752 -374.019826) (xy 40.693569 -374.012695)
			(xy 40.70007 -373.995494) (xy 40.700452 -373.986298) (xy 40.700452 -373.828818) (xy 40.700942 -373.818691)
			(xy 40.708666 -373.799968) (xy 40.722951 -373.785611) (xy 40.741636 -373.777793) (xy 40.75176 -373.777256)
			(xy 41.46804 -373.777256) (xy 41.478191 -373.777688) (xy 41.496936 -373.785489) (xy 41.511256 -373.799881)
			(xy 41.518963 -373.818665) (xy 41.519348 -373.828818) (xy 41.519348 -373.986298) (xy 41.519771 -373.995484)
			(xy 41.526277 -374.012667) (xy 41.532048 -374.019826) (xy 41.553873 -374.045524) (xy 41.591966 -374.101153)
			(xy 41.623121 -374.160944) (xy 41.64689 -374.224037) (xy 41.66293 -374.289522) (xy 41.67101 -374.356458)
			(xy 41.671014 -374.423823) (xy 44.94905 -374.423823) (xy 44.949054 -374.356514) (xy 44.957102 -374.289689)
			(xy 44.97308 -374.224304) (xy 44.996757 -374.161298) (xy 45.027796 -374.101573) (xy 45.06575 -374.045986)
			(xy 45.08754 -374.020334) (xy 45.093352 -374.0132) (xy 45.099857 -373.996001) (xy 45.10024 -373.986806)
			(xy 45.10024 -373.828818) (xy 45.100678 -373.818647) (xy 45.108458 -373.799853) (xy 45.122839 -373.785467)
			(xy 45.141631 -373.777682) (xy 45.151802 -373.777256) (xy 45.868082 -373.777256) (xy 45.878255 -373.777679)
			(xy 45.897053 -373.785461) (xy 45.911439 -373.799847) (xy 45.919221 -373.818645) (xy 45.919644 -373.828818)
			(xy 45.919644 -373.986806) (xy 45.920064 -373.995992) (xy 45.926572 -374.013176) (xy 45.932344 -374.020334)
			(xy 45.954091 -374.04602) (xy 45.992042 -374.101601) (xy 46.023078 -374.16132) (xy 46.046754 -374.22432)
			(xy 46.06273 -374.289698) (xy 46.070778 -374.356517) (xy 46.070782 -374.423819) (xy 46.070774 -374.423882)
			(xy 71.348786 -374.423882) (xy 71.348789 -374.356455) (xy 71.356869 -374.289514) (xy 71.372909 -374.224023)
			(xy 71.396677 -374.160924) (xy 71.427833 -374.101127) (xy 71.465926 -374.045491) (xy 71.487792 -374.019826)
			(xy 71.493602 -374.01269) (xy 71.500109 -373.995492) (xy 71.500492 -373.986298) (xy 71.500492 -373.828818)
			(xy 71.50104 -373.818698) (xy 71.508753 -373.799987) (xy 71.52302 -373.785631) (xy 71.541684 -373.777803)
			(xy 71.5518 -373.777256) (xy 72.26808 -373.777256) (xy 72.278227 -373.777737) (xy 72.296971 -373.785518)
			(xy 72.311293 -373.799896) (xy 72.319002 -373.818669) (xy 72.319388 -373.828818) (xy 72.319388 -373.986298)
			(xy 72.319802 -373.995485) (xy 72.326313 -374.012669) (xy 72.332088 -374.019826) (xy 72.353911 -374.045525)
			(xy 72.392002 -374.101154) (xy 72.423155 -374.160946) (xy 72.446922 -374.224038) (xy 72.462961 -374.289523)
			(xy 72.47104 -374.356458) (xy 72.471044 -374.423823) (xy 75.749081 -374.423823) (xy 75.749084 -374.356514)
			(xy 75.757133 -374.289688) (xy 75.773112 -374.224303) (xy 75.796791 -374.161296) (xy 75.827832 -374.101572)
			(xy 75.865788 -374.045985) (xy 75.88758 -374.020334) (xy 75.893385 -374.013194) (xy 75.899895 -373.996)
			(xy 75.90028 -373.986806) (xy 75.90028 -373.828818) (xy 75.900679 -373.818642) (xy 75.908466 -373.79984)
			(xy 75.92286 -373.785453) (xy 75.941666 -373.777675) (xy 75.951842 -373.777256) (xy 76.668122 -373.777256)
			(xy 76.678283 -373.777716) (xy 76.697057 -373.785501) (xy 76.711422 -373.799877) (xy 76.719192 -373.818656)
			(xy 76.719684 -373.828818) (xy 76.719684 -373.986806) (xy 76.720095 -373.995993) (xy 76.726608 -374.013177)
			(xy 76.732384 -374.020334) (xy 76.754129 -374.046021) (xy 76.792078 -374.101603) (xy 76.823112 -374.161322)
			(xy 76.846786 -374.224322) (xy 76.862761 -374.289699) (xy 76.870808 -374.356518) (xy 76.870812 -374.423819)
			(xy 76.870804 -374.423882) (xy 80.148873 -374.423882) (xy 80.148877 -374.356455) (xy 80.156957 -374.289515)
			(xy 80.172996 -374.224023) (xy 80.196764 -374.160925) (xy 80.227918 -374.101127) (xy 80.26601 -374.045492)
			(xy 80.287876 -374.019826) (xy 80.293684 -374.012689) (xy 80.300193 -373.995492) (xy 80.300576 -373.986298)
			(xy 80.300576 -373.828818) (xy 80.301042 -373.818688) (xy 80.308771 -373.79996) (xy 80.323064 -373.785602)
			(xy 80.341756 -373.777789) (xy 80.351884 -373.777256) (xy 81.068164 -373.777256) (xy 81.07831 -373.77775)
			(xy 81.097053 -373.785526) (xy 81.111376 -373.7999) (xy 81.119085 -373.81867) (xy 81.119472 -373.828818)
			(xy 81.119472 -373.986298) (xy 81.119889 -373.995484) (xy 81.126399 -374.012668) (xy 81.132172 -374.019826)
			(xy 81.153996 -374.045525) (xy 81.192087 -374.101154) (xy 81.223242 -374.160945) (xy 81.247009 -374.224038)
			(xy 81.263049 -374.289523) (xy 81.271128 -374.356458) (xy 81.271132 -374.423879) (xy 81.271132 -374.423882)
			(xy 84.548664 -374.423882) (xy 84.548668 -374.356455) (xy 84.556748 -374.289515) (xy 84.572787 -374.224024)
			(xy 84.596554 -374.160925) (xy 84.627707 -374.101128) (xy 84.665799 -374.045492) (xy 84.687664 -374.019826)
			(xy 84.693482 -374.012697) (xy 84.699982 -373.995494) (xy 84.700364 -373.986298) (xy 84.700364 -373.828818)
			(xy 84.700842 -373.818689) (xy 84.708568 -373.799964) (xy 84.722858 -373.785606) (xy 84.741546 -373.777791)
			(xy 84.751672 -373.777256) (xy 85.467952 -373.777256) (xy 85.478098 -373.77776) (xy 85.49684 -373.785532)
			(xy 85.511164 -373.799903) (xy 85.518873 -373.818671) (xy 85.51926 -373.828818) (xy 85.51926 -373.986298)
			(xy 85.51968 -373.995484) (xy 85.526188 -374.012668) (xy 85.53196 -374.019826) (xy 85.553784 -374.045525)
			(xy 85.591877 -374.101153) (xy 85.623031 -374.160945) (xy 85.6468 -374.224037) (xy 85.662839 -374.289523)
			(xy 85.670919 -374.356458) (xy 85.670923 -374.423822) (xy 115.349223 -374.423822) (xy 115.349227 -374.356515)
			(xy 115.357275 -374.28969) (xy 115.373251 -374.224306) (xy 115.396927 -374.1613) (xy 115.427963 -374.101574)
			(xy 115.465915 -374.045987) (xy 115.487704 -374.020334) (xy 115.493512 -374.013197) (xy 115.50002 -373.996)
			(xy 115.500404 -373.986806) (xy 115.500404 -373.828818) (xy 115.500947 -373.818666) (xy 115.508709 -373.799903)
			(xy 115.52306 -373.785539) (xy 115.541814 -373.777757) (xy 115.551966 -373.777256) (xy 116.268246 -373.777256)
			(xy 116.278409 -373.777696) (xy 116.297183 -373.785489) (xy 116.311547 -373.799871) (xy 116.319316 -373.818654)
			(xy 116.319808 -373.828818) (xy 116.319808 -373.986806) (xy 116.320214 -373.995994) (xy 116.32673 -374.013178)
			(xy 116.332508 -374.020334) (xy 116.354256 -374.046019) (xy 116.39221 -374.1016) (xy 116.423248 -374.161318)
			(xy 116.446925 -374.224319) (xy 116.462903 -374.289697) (xy 116.470951 -374.356517) (xy 116.470955 -374.42382)
			(xy 116.470948 -374.423882) (xy 119.748992 -374.423882) (xy 119.748995 -374.356455) (xy 119.757075 -374.289514)
			(xy 119.773115 -374.224022) (xy 119.796884 -374.160924) (xy 119.82804 -374.101126) (xy 119.866134 -374.045491)
			(xy 119.888 -374.019826) (xy 119.89381 -374.012691) (xy 119.900317 -373.995493) (xy 119.9007 -373.986298)
			(xy 119.9007 -373.828818) (xy 119.90124 -373.818697) (xy 119.908955 -373.799984) (xy 119.923224 -373.785629)
			(xy 119.94189 -373.777802) (xy 119.952008 -373.777256) (xy 120.668288 -373.777256) (xy 120.678436 -373.777731)
			(xy 120.69718 -373.785514) (xy 120.711502 -373.799894) (xy 120.71921 -373.818669) (xy 120.719596 -373.828818)
			(xy 120.719596 -373.986298) (xy 120.720008 -373.995485) (xy 120.726521 -374.012669) (xy 120.732296 -374.019826)
			(xy 120.754119 -374.045525) (xy 120.792209 -374.101155) (xy 120.823362 -374.160946) (xy 120.847129 -374.224039)
			(xy 120.863167 -374.289524) (xy 120.871246 -374.356458) (xy 120.87125 -374.423823) (xy 124.149287 -374.423823)
			(xy 124.149291 -374.356514) (xy 124.15734 -374.289688) (xy 124.173319 -374.224302) (xy 124.196998 -374.161296)
			(xy 124.228039 -374.101572) (xy 124.265996 -374.045986) (xy 124.287788 -374.020334) (xy 124.293594 -374.013195)
			(xy 124.300103 -373.996) (xy 124.300488 -373.986806) (xy 124.300488 -373.828818) (xy 124.30088 -373.818641)
			(xy 124.308668 -373.799837) (xy 124.323064 -373.78545) (xy 124.341873 -373.777673) (xy 124.35205 -373.777256)
			(xy 125.06833 -373.777256) (xy 125.078492 -373.777709) (xy 125.097265 -373.785497) (xy 125.11163 -373.799875)
			(xy 125.1194 -373.818656) (xy 125.119892 -373.828818) (xy 125.119892 -373.986806) (xy 125.120301 -373.995993)
			(xy 125.126816 -374.013177) (xy 125.132592 -374.020334) (xy 125.154338 -374.04602) (xy 125.192286 -374.101603)
			(xy 125.223319 -374.161322) (xy 125.246993 -374.224322) (xy 125.262968 -374.2897) (xy 125.271015 -374.356518)
			(xy 125.271019 -374.423819) (xy 125.271019 -374.423823) (xy 128.549078 -374.423823) (xy 128.549081 -374.356514)
			(xy 128.55713 -374.289688) (xy 128.573109 -374.224303) (xy 128.596788 -374.161296) (xy 128.627828 -374.101572)
			(xy 128.665784 -374.045985) (xy 128.687576 -374.020334) (xy 128.69338 -374.013194) (xy 128.699891 -373.996)
			(xy 128.700276 -373.986806) (xy 128.700276 -373.828818) (xy 128.700679 -373.818643) (xy 128.708465 -373.799841)
			(xy 128.722858 -373.785454) (xy 128.741663 -373.777675) (xy 128.751838 -373.777256) (xy 129.468118 -373.777256)
			(xy 129.478279 -373.777719) (xy 129.497052 -373.785503) (xy 129.511418 -373.799878) (xy 129.519188 -373.818656)
			(xy 129.51968 -373.828818) (xy 129.51968 -373.986806) (xy 129.520092 -373.995993) (xy 129.526605 -374.013177)
			(xy 129.53238 -374.020334) (xy 129.554126 -374.046021) (xy 129.592074 -374.101603) (xy 129.623108 -374.161322)
			(xy 129.646783 -374.224321) (xy 129.662758 -374.289699) (xy 129.670805 -374.356518) (xy 129.670809 -374.423819)
			(xy 129.670809 -374.423822) (xy 159.349132 -374.423822) (xy 159.349136 -374.356514) (xy 159.357184 -374.289689)
			(xy 159.373161 -374.224305) (xy 159.396837 -374.161299) (xy 159.427874 -374.101574) (xy 159.465826 -374.045986)
			(xy 159.487616 -374.020334) (xy 159.493425 -374.013198) (xy 159.499932 -373.996) (xy 159.500316 -373.986806)
			(xy 159.500316 -373.828818) (xy 159.500847 -373.818664) (xy 159.508612 -373.799899) (xy 159.522966 -373.785534)
			(xy 159.541724 -373.777755) (xy 159.551878 -373.777256) (xy 160.268158 -373.777256) (xy 160.278329 -373.777699)
			(xy 160.297126 -373.785473) (xy 160.311513 -373.799854) (xy 160.319297 -373.818647) (xy 160.31972 -373.828818)
			(xy 160.31972 -373.986806) (xy 160.320123 -373.995994) (xy 160.326641 -374.013179) (xy 160.33242 -374.020334)
			(xy 160.354168 -374.04602) (xy 160.39212 -374.1016) (xy 160.423158 -374.161319) (xy 160.446835 -374.224319)
			(xy 160.462812 -374.289698) (xy 160.47086 -374.356517) (xy 160.470864 -374.42382) (xy 160.470857 -374.423882)
			(xy 163.748901 -374.423882) (xy 163.748904 -374.356455) (xy 163.756985 -374.289514) (xy 163.773025 -374.224022)
			(xy 163.796794 -374.160923) (xy 163.827951 -374.101126) (xy 163.866045 -374.045491) (xy 163.887912 -374.019826)
			(xy 163.893724 -374.012692) (xy 163.900229 -373.995493) (xy 163.900612 -373.986298) (xy 163.900612 -373.828818)
			(xy 163.90114 -373.818696) (xy 163.908857 -373.79998) (xy 163.92313 -373.785624) (xy 163.941801 -373.7778)
			(xy 163.95192 -373.777256) (xy 164.6682 -373.777256) (xy 164.678349 -373.777721) (xy 164.697092 -373.785508)
			(xy 164.711414 -373.799891) (xy 164.719122 -373.818668) (xy 164.719508 -373.828818) (xy 164.719508 -373.986298)
			(xy 164.719917 -373.995485) (xy 164.726431 -374.01267) (xy 164.732208 -374.019826) (xy 164.75403 -374.045525)
			(xy 164.79212 -374.101155) (xy 164.823272 -374.160947) (xy 164.847038 -374.224039) (xy 164.863076 -374.289524)
			(xy 164.871155 -374.356458) (xy 164.871159 -374.423822) (xy 168.14922 -374.423822) (xy 168.149224 -374.356515)
			(xy 168.157272 -374.28969) (xy 168.173248 -374.224306) (xy 168.196924 -374.1613) (xy 168.22796 -374.101575)
			(xy 168.265911 -374.045987) (xy 168.2877 -374.020334) (xy 168.293507 -374.013196) (xy 168.300015 -373.996)
			(xy 168.3004 -373.986806) (xy 168.3004 -373.828818) (xy 168.300947 -373.818666) (xy 168.308709 -373.799905)
			(xy 168.323058 -373.78554) (xy 168.341811 -373.777758) (xy 168.351962 -373.777256) (xy 169.068242 -373.777256)
			(xy 169.078405 -373.777699) (xy 169.097178 -373.785491) (xy 169.111543 -373.799872) (xy 169.119312 -373.818655)
			(xy 169.119804 -373.828818) (xy 169.119804 -373.986806) (xy 169.120211 -373.995994) (xy 169.126727 -374.013178)
			(xy 169.132504 -374.020334) (xy 169.154249 -374.046021) (xy 169.192196 -374.101603) (xy 169.223229 -374.161322)
			(xy 169.246902 -374.224322) (xy 169.262877 -374.2897) (xy 169.270924 -374.356518) (xy 169.270928 -374.423819)
			(xy 169.270928 -374.423823) (xy 172.548987 -374.423823) (xy 172.548991 -374.356514) (xy 172.55704 -374.289688)
			(xy 172.573019 -374.224302) (xy 172.596698 -374.161296) (xy 172.627739 -374.101572) (xy 172.665696 -374.045986)
			(xy 172.687488 -374.020334) (xy 172.693294 -374.013195) (xy 172.699803 -373.996) (xy 172.700188 -373.986806)
			(xy 172.700188 -373.828818) (xy 172.70058 -373.818641) (xy 172.708368 -373.799837) (xy 172.722764 -373.78545)
			(xy 172.741573 -373.777673) (xy 172.75175 -373.777256) (xy 173.46803 -373.777256) (xy 173.478192 -373.777709)
			(xy 173.496965 -373.785497) (xy 173.51133 -373.799875) (xy 173.5191 -373.818656) (xy 173.519592 -373.828818)
			(xy 173.519592 -373.986806) (xy 173.520001 -373.995993) (xy 173.526516 -374.013177) (xy 173.532292 -374.020334)
			(xy 173.554038 -374.04602) (xy 173.591986 -374.101603) (xy 173.623019 -374.161322) (xy 173.646693 -374.224322)
			(xy 173.662668 -374.2897) (xy 173.670715 -374.356518) (xy 173.670719 -374.423819) (xy 173.662679 -374.490638)
			(xy 173.646712 -374.556018) (xy 173.623045 -374.61902) (xy 173.592018 -374.678743) (xy 173.554076 -374.73433)
			(xy 173.532292 -374.759982) (xy 173.526477 -374.767114) (xy 173.519974 -374.784315) (xy 173.519592 -374.79351)
			(xy 173.519592 -375.286778) (xy 173.520015 -375.295964) (xy 173.52652 -375.313148) (xy 173.532292 -375.320306)
			(xy 173.554108 -375.345934) (xy 173.592054 -375.401525) (xy 173.623084 -375.461252) (xy 173.646754 -375.52426)
			(xy 173.662724 -375.589644) (xy 173.670765 -375.656469) (xy 173.670763 -375.723776) (xy 173.662716 -375.7906)
			(xy 173.646741 -375.855984) (xy 173.623066 -375.918989) (xy 173.592031 -375.978714) (xy 173.554081 -376.034301)
			(xy 173.532292 -376.059954) (xy 173.526489 -376.067095) (xy 173.519978 -376.084289) (xy 173.519592 -376.093482)
			(xy 173.519592 -376.25147) (xy 173.519043 -376.261622) (xy 173.511284 -376.280385) (xy 173.496935 -376.29475)
			(xy 173.478182 -376.302531) (xy 173.46803 -376.303032) (xy 172.75175 -376.303032) (xy 172.741578 -376.302595)
			(xy 172.722779 -376.29482) (xy 172.708391 -376.280438) (xy 172.700609 -376.261642) (xy 172.700188 -376.25147)
			(xy 172.700188 -376.093482) (xy 172.699789 -376.084294) (xy 172.693268 -376.067109) (xy 172.687488 -376.059954)
			(xy 172.665728 -376.034278) (xy 172.627775 -375.978696) (xy 172.596738 -375.918976) (xy 172.573061 -375.855975)
			(xy 172.557085 -375.790595) (xy 172.549038 -375.723774) (xy 172.549035 -375.656471) (xy 172.557077 -375.589649)
			(xy 172.573048 -375.524268) (xy 172.59672 -375.461265) (xy 172.627752 -375.401542) (xy 172.665701 -375.345957)
			(xy 172.687488 -375.320306) (xy 172.693263 -375.313145) (xy 172.699791 -375.295967) (xy 172.700188 -375.286778)
			(xy 172.700188 -374.79351) (xy 172.699776 -374.784323) (xy 172.693264 -374.767138) (xy 172.687488 -374.759982)
			(xy 172.665658 -374.734364) (xy 172.627707 -374.678774) (xy 172.596673 -374.619046) (xy 172.573 -374.556037)
			(xy 172.557029 -374.49065) (xy 172.548987 -374.423823) (xy 169.270928 -374.423823) (xy 169.262888 -374.490638)
			(xy 169.246921 -374.556017) (xy 169.223255 -374.61902) (xy 169.192229 -374.678743) (xy 169.154288 -374.734329)
			(xy 169.132504 -374.759982) (xy 169.126691 -374.767115) (xy 169.120186 -374.784315) (xy 169.119804 -374.79351)
			(xy 169.119804 -375.286778) (xy 169.120224 -375.295964) (xy 169.126731 -375.313149) (xy 169.132504 -375.320306)
			(xy 169.15432 -375.345935) (xy 169.192265 -375.401525) (xy 169.223295 -375.461253) (xy 169.246964 -375.52426)
			(xy 169.262933 -375.589645) (xy 169.270974 -375.656469) (xy 169.270972 -375.723776) (xy 169.262925 -375.7906)
			(xy 169.24695 -375.855983) (xy 169.223276 -375.918989) (xy 169.192242 -375.978713) (xy 169.154292 -376.034301)
			(xy 169.132504 -376.059954) (xy 169.126702 -376.067096) (xy 169.120191 -376.084289) (xy 169.119804 -376.093482)
			(xy 169.119804 -376.25147) (xy 169.119243 -376.261621) (xy 169.111487 -376.280381) (xy 169.097142 -376.294746)
			(xy 169.078392 -376.302529) (xy 169.068242 -376.303032) (xy 168.351962 -376.303032) (xy 168.341798 -376.302597)
			(xy 168.323022 -376.294804) (xy 168.308657 -376.280421) (xy 168.30089 -376.261635) (xy 168.3004 -376.25147)
			(xy 168.3004 -376.093482) (xy 168.299998 -376.084294) (xy 168.293479 -376.06711) (xy 168.2877 -376.059954)
			(xy 168.265943 -376.034277) (xy 168.227996 -375.978693) (xy 168.196963 -375.918973) (xy 168.173291 -375.855972)
			(xy 168.157317 -375.790593) (xy 168.149271 -375.723774) (xy 168.149268 -375.656472) (xy 168.157309 -375.589652)
			(xy 168.173277 -375.524272) (xy 168.196945 -375.461269) (xy 168.227973 -375.401546) (xy 168.265915 -375.345959)
			(xy 168.2877 -375.320306) (xy 168.293477 -375.313147) (xy 168.300003 -375.295967) (xy 168.3004 -375.286778)
			(xy 168.3004 -374.79351) (xy 168.299985 -374.784323) (xy 168.293475 -374.767139) (xy 168.2877 -374.759982)
			(xy 168.265872 -374.734363) (xy 168.227927 -374.678771) (xy 168.196898 -374.619043) (xy 168.173229 -374.556034)
			(xy 168.15726 -374.490648) (xy 168.14922 -374.423822) (xy 164.871159 -374.423822) (xy 164.871159 -374.423879)
			(xy 164.863088 -374.490814) (xy 164.847057 -374.5563) (xy 164.823298 -374.619396) (xy 164.792152 -374.679191)
			(xy 164.754069 -374.734825) (xy 164.732208 -374.76049) (xy 164.726392 -374.767621) (xy 164.719889 -374.784822)
			(xy 164.719508 -374.794018) (xy 164.719508 -375.28627) (xy 164.719931 -375.295456) (xy 164.726435 -375.31264)
			(xy 164.732208 -375.319798) (xy 164.754101 -375.345439) (xy 164.792188 -375.401077) (xy 164.823337 -375.460877)
			(xy 164.8471 -375.523977) (xy 164.863133 -375.589469) (xy 164.871206 -375.65641) (xy 164.871203 -375.723835)
			(xy 164.863125 -375.790776) (xy 164.847086 -375.856266) (xy 164.823319 -375.919364) (xy 164.792165 -375.979161)
			(xy 164.754073 -376.034797) (xy 164.732208 -376.060462) (xy 164.726404 -376.067602) (xy 164.719893 -376.084796)
			(xy 164.719508 -376.09399) (xy 164.719508 -376.25147) (xy 164.71895 -376.261589) (xy 164.711241 -376.2803)
			(xy 164.696977 -376.294656) (xy 164.678316 -376.302485) (xy 164.6682 -376.303032) (xy 163.95192 -376.303032)
			(xy 163.941771 -376.302563) (xy 163.923025 -376.29478) (xy 163.908702 -376.280398) (xy 163.900996 -376.26162)
			(xy 163.900612 -376.25147) (xy 163.900612 -376.09399) (xy 163.900204 -376.084803) (xy 163.893689 -376.067618)
			(xy 163.887912 -376.060462) (xy 163.866077 -376.034773) (xy 163.827987 -375.979142) (xy 163.796834 -375.919349)
			(xy 163.773068 -375.856255) (xy 163.75703 -375.790769) (xy 163.748951 -375.723833) (xy 163.748949 -375.656412)
			(xy 163.757022 -375.589475) (xy 163.773054 -375.523988) (xy 163.796816 -375.460892) (xy 163.827963 -375.401097)
			(xy 163.866049 -375.345463) (xy 163.887912 -375.319798) (xy 163.893693 -375.312642) (xy 163.900217 -375.29546)
			(xy 163.900612 -375.28627) (xy 163.900612 -374.794018) (xy 163.90019 -374.784832) (xy 163.893684 -374.767648)
			(xy 163.887912 -374.76049) (xy 163.866006 -374.734859) (xy 163.827918 -374.67922) (xy 163.796769 -374.619419)
			(xy 163.773006 -374.556318) (xy 163.756973 -374.490824) (xy 163.748901 -374.423882) (xy 160.470857 -374.423882)
			(xy 160.462823 -374.49064) (xy 160.446853 -374.556021) (xy 160.423184 -374.619023) (xy 160.392153 -374.678745)
			(xy 160.354206 -374.73433) (xy 160.33242 -374.759982) (xy 160.326608 -374.767117) (xy 160.320102 -374.784315)
			(xy 160.31972 -374.79351) (xy 160.31972 -375.286778) (xy 160.320136 -375.295965) (xy 160.326645 -375.313149)
			(xy 160.33242 -375.320306) (xy 160.354238 -375.345933) (xy 160.392189 -375.401522) (xy 160.423223 -375.461249)
			(xy 160.446896 -375.524257) (xy 160.462868 -375.589643) (xy 160.470911 -375.656468) (xy 160.470908 -375.723777)
			(xy 160.46286 -375.790602) (xy 160.446883 -375.855986) (xy 160.423205 -375.918992) (xy 160.392166 -375.978716)
			(xy 160.354211 -376.034302) (xy 160.33242 -376.059954) (xy 160.32662 -376.067097) (xy 160.320107 -376.084289)
			(xy 160.31972 -376.093482) (xy 160.31972 -376.25147) (xy 160.31931 -376.261645) (xy 160.311528 -376.280447)
			(xy 160.297137 -376.294834) (xy 160.278333 -376.302613) (xy 160.268158 -376.303032) (xy 159.551878 -376.303032)
			(xy 159.541701 -376.302653) (xy 159.5229 -376.294855) (xy 159.508515 -376.280456) (xy 159.500737 -376.261647)
			(xy 159.500316 -376.25147) (xy 159.500316 -376.093482) (xy 159.499911 -376.084294) (xy 159.493393 -376.06711)
			(xy 159.487616 -376.059954) (xy 159.465858 -376.034277) (xy 159.42791 -375.978694) (xy 159.396877 -375.918973)
			(xy 159.373203 -375.855972) (xy 159.357229 -375.790593) (xy 159.349183 -375.723774) (xy 159.34918 -375.656471)
			(xy 159.357221 -375.589651) (xy 159.37319 -375.524271) (xy 159.396858 -375.461268) (xy 159.427887 -375.401545)
			(xy 159.465831 -375.345958) (xy 159.487616 -375.320306) (xy 159.493394 -375.313148) (xy 159.499919 -375.295967)
			(xy 159.500316 -375.286778) (xy 159.500316 -374.79351) (xy 159.499897 -374.784324) (xy 159.493389 -374.76714)
			(xy 159.487616 -374.759982) (xy 159.465788 -374.734364) (xy 159.427842 -374.678772) (xy 159.396811 -374.619043)
			(xy 159.373142 -374.556034) (xy 159.357173 -374.490648) (xy 159.349132 -374.423822) (xy 129.670809 -374.423822)
			(xy 129.662769 -374.490638) (xy 129.646801 -374.556018) (xy 129.623134 -374.619021) (xy 129.592107 -374.678743)
			(xy 129.554164 -374.734329) (xy 129.53238 -374.759982) (xy 129.526564 -374.767113) (xy 129.520062 -374.784315)
			(xy 129.51968 -374.79351) (xy 129.51968 -375.286778) (xy 129.520105 -375.295963) (xy 129.526609 -375.313148)
			(xy 129.53238 -375.320306) (xy 129.554197 -375.345934) (xy 129.592143 -375.401524) (xy 129.623174 -375.461252)
			(xy 129.646845 -375.524259) (xy 129.662815 -375.589644) (xy 129.670856 -375.656469) (xy 129.670854 -375.723776)
			(xy 129.662807 -375.7906) (xy 129.646831 -375.855984) (xy 129.623156 -375.91899) (xy 129.59212 -375.978714)
			(xy 129.554169 -376.034302) (xy 129.53238 -376.059954) (xy 129.526576 -376.067094) (xy 129.520066 -376.084288)
			(xy 129.51968 -376.093482) (xy 129.51968 -376.25147) (xy 129.519212 -376.261637) (xy 129.51144 -376.280428)
			(xy 129.497068 -376.294813) (xy 129.478285 -376.302602) (xy 129.468118 -376.303032) (xy 128.751838 -376.303032)
			(xy 128.741665 -376.302604) (xy 128.722866 -376.294826) (xy 128.708478 -376.280441) (xy 128.700697 -376.261643)
			(xy 128.700276 -376.25147) (xy 128.700276 -376.093482) (xy 128.69988 -376.084293) (xy 128.693357 -376.067109)
			(xy 128.687576 -376.059954) (xy 128.665817 -376.034278) (xy 128.627865 -375.978696) (xy 128.596828 -375.918976)
			(xy 128.573152 -375.855974) (xy 128.557176 -375.790595) (xy 128.549129 -375.723774) (xy 128.549126 -375.656471)
			(xy 128.557168 -375.58965) (xy 128.573138 -375.524269) (xy 128.59681 -375.461265) (xy 128.627841 -375.401543)
			(xy 128.665789 -375.345958) (xy 128.687576 -375.320306) (xy 128.69335 -375.313144) (xy 128.699879 -375.295967)
			(xy 128.700276 -375.286778) (xy 128.700276 -374.79351) (xy 128.699866 -374.784323) (xy 128.693353 -374.767138)
			(xy 128.687576 -374.759982) (xy 128.665746 -374.734365) (xy 128.627796 -374.678774) (xy 128.596762 -374.619046)
			(xy 128.57309 -374.556037) (xy 128.557119 -374.49065) (xy 128.549078 -374.423823) (xy 125.271019 -374.423823)
			(xy 125.262979 -374.490638) (xy 125.247012 -374.556018) (xy 125.223345 -374.61902) (xy 125.192318 -374.678743)
			(xy 125.154376 -374.73433) (xy 125.132592 -374.759982) (xy 125.126777 -374.767114) (xy 125.120274 -374.784315)
			(xy 125.119892 -374.79351) (xy 125.119892 -375.286778) (xy 125.120315 -375.295964) (xy 125.12682 -375.313148)
			(xy 125.132592 -375.320306) (xy 125.154408 -375.345934) (xy 125.192354 -375.401525) (xy 125.223384 -375.461252)
			(xy 125.247054 -375.52426) (xy 125.263024 -375.589644) (xy 125.271065 -375.656469) (xy 125.271063 -375.723776)
			(xy 125.263016 -375.7906) (xy 125.247041 -375.855984) (xy 125.223366 -375.918989) (xy 125.192331 -375.978714)
			(xy 125.154381 -376.034301) (xy 125.132592 -376.059954) (xy 125.126789 -376.067095) (xy 125.120278 -376.084289)
			(xy 125.119892 -376.093482) (xy 125.119892 -376.25147) (xy 125.119343 -376.261622) (xy 125.111584 -376.280385)
			(xy 125.097235 -376.29475) (xy 125.078482 -376.302531) (xy 125.06833 -376.303032) (xy 124.35205 -376.303032)
			(xy 124.341878 -376.302595) (xy 124.323079 -376.29482) (xy 124.308691 -376.280438) (xy 124.300909 -376.261642)
			(xy 124.300488 -376.25147) (xy 124.300488 -376.093482) (xy 124.300089 -376.084294) (xy 124.293568 -376.067109)
			(xy 124.287788 -376.059954) (xy 124.266028 -376.034278) (xy 124.228075 -375.978696) (xy 124.197038 -375.918976)
			(xy 124.173361 -375.855975) (xy 124.157385 -375.790595) (xy 124.149338 -375.723774) (xy 124.149335 -375.656471)
			(xy 124.157377 -375.589649) (xy 124.173348 -375.524268) (xy 124.19702 -375.461265) (xy 124.228052 -375.401542)
			(xy 124.266001 -375.345957) (xy 124.287788 -375.320306) (xy 124.293563 -375.313145) (xy 124.300091 -375.295967)
			(xy 124.300488 -375.286778) (xy 124.300488 -374.79351) (xy 124.300076 -374.784323) (xy 124.293564 -374.767138)
			(xy 124.287788 -374.759982) (xy 124.265958 -374.734364) (xy 124.228007 -374.678774) (xy 124.196973 -374.619046)
			(xy 124.1733 -374.556037) (xy 124.157329 -374.49065) (xy 124.149287 -374.423823) (xy 120.87125 -374.423823)
			(xy 120.87125 -374.423879) (xy 120.863178 -374.490814) (xy 120.847147 -374.556301) (xy 120.823388 -374.619396)
			(xy 120.792242 -374.679191) (xy 120.754158 -374.734825) (xy 120.732296 -374.76049) (xy 120.726478 -374.76762)
			(xy 120.719976 -374.784822) (xy 120.719596 -374.794018) (xy 120.719596 -375.28627) (xy 120.720022 -375.295456)
			(xy 120.726525 -375.31264) (xy 120.732296 -375.319798) (xy 120.75419 -375.345439) (xy 120.792278 -375.401077)
			(xy 120.823427 -375.460876) (xy 120.84719 -375.523976) (xy 120.863223 -375.589468) (xy 120.871297 -375.656409)
			(xy 120.871294 -375.723836) (xy 120.863215 -375.790776) (xy 120.847177 -375.856267) (xy 120.823409 -375.919365)
			(xy 120.792254 -375.979162) (xy 120.754162 -376.034797) (xy 120.732296 -376.060462) (xy 120.72649 -376.067601)
			(xy 120.719981 -376.084796) (xy 120.719596 -376.09399) (xy 120.719596 -376.25147) (xy 120.71905 -376.26159)
			(xy 120.711339 -376.280304) (xy 120.697071 -376.29466) (xy 120.678405 -376.302487) (xy 120.668288 -376.303032)
			(xy 119.952008 -376.303032) (xy 119.941858 -376.302572) (xy 119.923112 -376.294786) (xy 119.90879 -376.280401)
			(xy 119.901084 -376.261621) (xy 119.9007 -376.25147) (xy 119.9007 -376.09399) (xy 119.900294 -376.084802)
			(xy 119.893777 -376.067618) (xy 119.888 -376.060462) (xy 119.866166 -376.034772) (xy 119.828076 -375.979141)
			(xy 119.796924 -375.919349) (xy 119.773158 -375.856255) (xy 119.75712 -375.790769) (xy 119.749042 -375.723833)
			(xy 119.749039 -375.656412) (xy 119.757112 -375.589476) (xy 119.773145 -375.523988) (xy 119.796905 -375.460893)
			(xy 119.828053 -375.401097) (xy 119.866138 -375.345463) (xy 119.888 -375.319798) (xy 119.89378 -375.312641)
			(xy 119.900305 -375.29546) (xy 119.9007 -375.28627) (xy 119.9007 -374.794018) (xy 119.900281 -374.784832)
			(xy 119.893773 -374.767647) (xy 119.888 -374.76049) (xy 119.866095 -374.734859) (xy 119.828007 -374.679219)
			(xy 119.796858 -374.619418) (xy 119.773097 -374.556317) (xy 119.757064 -374.490824) (xy 119.748992 -374.423882)
			(xy 116.470948 -374.423882) (xy 116.462914 -374.49064) (xy 116.446944 -374.556021) (xy 116.423273 -374.619024)
			(xy 116.392242 -374.678746) (xy 116.354295 -374.734331) (xy 116.332508 -374.759982) (xy 116.326695 -374.767116)
			(xy 116.32019 -374.784315) (xy 116.319808 -374.79351) (xy 116.319808 -375.286778) (xy 116.320227 -375.295964)
			(xy 116.326734 -375.313149) (xy 116.332508 -375.320306) (xy 116.354327 -375.345933) (xy 116.392278 -375.401522)
			(xy 116.423313 -375.461249) (xy 116.446986 -375.524256) (xy 116.462959 -375.589642) (xy 116.471001 -375.656468)
			(xy 116.470999 -375.723777) (xy 116.462951 -375.790602) (xy 116.446973 -375.855987) (xy 116.423295 -375.918993)
			(xy 116.392255 -375.978717) (xy 116.354299 -376.034303) (xy 116.332508 -376.059954) (xy 116.326707 -376.067096)
			(xy 116.320195 -376.084289) (xy 116.319808 -376.093482) (xy 116.319808 -376.25147) (xy 116.319243 -376.26162)
			(xy 116.311487 -376.28038) (xy 116.297144 -376.294745) (xy 116.278395 -376.302528) (xy 116.268246 -376.303032)
			(xy 115.551966 -376.303032) (xy 115.541802 -376.302594) (xy 115.523027 -376.294803) (xy 115.508662 -376.28042)
			(xy 115.500894 -376.261634) (xy 115.500404 -376.25147) (xy 115.500404 -376.093482) (xy 115.500002 -376.084294)
			(xy 115.493483 -376.06711) (xy 115.487704 -376.059954) (xy 115.465947 -376.034277) (xy 115.427999 -375.978693)
			(xy 115.396967 -375.918973) (xy 115.373294 -375.855972) (xy 115.35732 -375.790593) (xy 115.349274 -375.723774)
			(xy 115.349271 -375.656472) (xy 115.357312 -375.589652) (xy 115.37328 -375.524271) (xy 115.396948 -375.461268)
			(xy 115.427976 -375.401545) (xy 115.465919 -375.345959) (xy 115.487704 -375.320306) (xy 115.493481 -375.313147)
			(xy 115.500007 -375.295967) (xy 115.500404 -375.286778) (xy 115.500404 -374.79351) (xy 115.499988 -374.784323)
			(xy 115.493478 -374.767139) (xy 115.487704 -374.759982) (xy 115.465876 -374.734363) (xy 115.427931 -374.678771)
			(xy 115.396901 -374.619043) (xy 115.373232 -374.556034) (xy 115.357263 -374.490648) (xy 115.349223 -374.423822)
			(xy 85.670923 -374.423822) (xy 85.670923 -374.423879) (xy 85.662851 -374.490815) (xy 85.646818 -374.556302)
			(xy 85.623057 -374.619398) (xy 85.591909 -374.679192) (xy 85.553823 -374.734826) (xy 85.53196 -374.76049)
			(xy 85.526138 -374.767617) (xy 85.519639 -374.784822) (xy 85.51926 -374.794018) (xy 85.51926 -375.28627)
			(xy 85.519694 -375.295454) (xy 85.526192 -375.312639) (xy 85.53196 -375.319798) (xy 85.553855 -375.345438)
			(xy 85.591945 -375.401075) (xy 85.623097 -375.460875) (xy 85.646861 -375.523975) (xy 85.662896 -375.589467)
			(xy 85.67097 -375.656409) (xy 85.670967 -375.723836) (xy 85.662888 -375.790777) (xy 85.646848 -375.856268)
			(xy 85.623079 -375.919367) (xy 85.591922 -375.979163) (xy 85.553827 -376.034797) (xy 85.53196 -376.060462)
			(xy 85.52615 -376.067597) (xy 85.519644 -376.084796) (xy 85.51926 -376.09399) (xy 85.51926 -376.25147)
			(xy 85.518749 -376.261595) (xy 85.511031 -376.280315) (xy 85.496752 -376.294673) (xy 85.478074 -376.302493)
			(xy 85.467952 -376.303032) (xy 84.751672 -376.303032) (xy 84.74152 -376.302602) (xy 84.722773 -376.294803)
			(xy 84.708452 -376.28041) (xy 84.700747 -376.261624) (xy 84.700364 -376.25147) (xy 84.700364 -376.09399)
			(xy 84.699944 -376.084804) (xy 84.693436 -376.06762) (xy 84.687664 -376.060462) (xy 84.665831 -376.034772)
			(xy 84.627744 -375.97914) (xy 84.596594 -375.919347) (xy 84.572829 -375.856253) (xy 84.556793 -375.790768)
			(xy 84.548715 -375.723833) (xy 84.548712 -375.656412) (xy 84.556785 -375.589477) (xy 84.572816 -375.52399)
			(xy 84.596575 -375.460894) (xy 84.62772 -375.401099) (xy 84.665803 -375.345464) (xy 84.687664 -375.319798)
			(xy 84.693452 -375.312647) (xy 84.69997 -375.295461) (xy 84.700364 -375.28627) (xy 84.700364 -374.794018)
			(xy 84.699931 -374.784834) (xy 84.693432 -374.76765) (xy 84.687664 -374.76049) (xy 84.66576 -374.734858)
			(xy 84.627675 -374.679218) (xy 84.596528 -374.619417) (xy 84.572768 -374.556316) (xy 84.556736 -374.490823)
			(xy 84.548664 -374.423882) (xy 81.271132 -374.423882) (xy 81.26306 -374.490815) (xy 81.247028 -374.556302)
			(xy 81.223267 -374.619397) (xy 81.19212 -374.679192) (xy 81.154034 -374.734825) (xy 81.132172 -374.76049)
			(xy 81.126351 -374.767618) (xy 81.119852 -374.784822) (xy 81.119472 -374.794018) (xy 81.119472 -375.28627)
			(xy 81.119903 -375.295455) (xy 81.126403 -375.312639) (xy 81.132172 -375.319798) (xy 81.154066 -375.345438)
			(xy 81.192156 -375.401076) (xy 81.223307 -375.460875) (xy 81.247071 -375.523975) (xy 81.263105 -375.589468)
			(xy 81.271179 -375.656409) (xy 81.271176 -375.723836) (xy 81.263097 -375.790777) (xy 81.247057 -375.856268)
			(xy 81.223289 -375.919366) (xy 81.192133 -375.979163) (xy 81.154039 -376.034797) (xy 81.132172 -376.060462)
			(xy 81.126363 -376.067598) (xy 81.119856 -376.084796) (xy 81.119472 -376.09399) (xy 81.119472 -376.25147)
			(xy 81.118949 -376.261593) (xy 81.111234 -376.280312) (xy 81.096958 -376.294669) (xy 81.078284 -376.302491)
			(xy 81.068164 -376.303032) (xy 80.351884 -376.303032) (xy 80.341733 -376.302592) (xy 80.322986 -376.294797)
			(xy 80.308664 -376.280407) (xy 80.300959 -376.261623) (xy 80.300576 -376.25147) (xy 80.300576 -376.09399)
			(xy 80.300176 -376.084802) (xy 80.293656 -376.067617) (xy 80.287876 -376.060462) (xy 80.266042 -376.034772)
			(xy 80.227954 -375.97914) (xy 80.196804 -375.919347) (xy 80.173039 -375.856254) (xy 80.157002 -375.790768)
			(xy 80.148924 -375.723833) (xy 80.148921 -375.656412) (xy 80.156994 -375.589476) (xy 80.173025 -375.523989)
			(xy 80.196785 -375.460894) (xy 80.227931 -375.401098) (xy 80.266015 -375.345464) (xy 80.287876 -375.319798)
			(xy 80.293653 -375.312639) (xy 80.30018 -375.295459) (xy 80.300576 -375.28627) (xy 80.300576 -374.794018)
			(xy 80.300163 -374.784831) (xy 80.293652 -374.767646) (xy 80.287876 -374.76049) (xy 80.265972 -374.734858)
			(xy 80.227886 -374.679218) (xy 80.196738 -374.619417) (xy 80.172977 -374.556316) (xy 80.156946 -374.490823)
			(xy 80.148873 -374.423882) (xy 76.870804 -374.423882) (xy 76.862772 -374.490638) (xy 76.846805 -374.556018)
			(xy 76.823138 -374.619021) (xy 76.79211 -374.678743) (xy 76.754168 -374.734329) (xy 76.732384 -374.759982)
			(xy 76.726568 -374.767114) (xy 76.720066 -374.784315) (xy 76.719684 -374.79351) (xy 76.719684 -375.286778)
			(xy 76.720108 -375.295964) (xy 76.726613 -375.313148) (xy 76.732384 -375.320306) (xy 76.754201 -375.345934)
			(xy 76.792147 -375.401525) (xy 76.823178 -375.461252) (xy 76.846848 -375.524259) (xy 76.862818 -375.589644)
			(xy 76.870859 -375.656469) (xy 76.870857 -375.723776) (xy 76.86281 -375.7906) (xy 76.846834 -375.855984)
			(xy 76.823159 -375.91899) (xy 76.792124 -375.978714) (xy 76.754173 -376.034302) (xy 76.732384 -376.059954)
			(xy 76.72658 -376.067094) (xy 76.72007 -376.084289) (xy 76.719684 -376.093482) (xy 76.719684 -376.25147)
			(xy 76.719212 -376.261637) (xy 76.711441 -376.280427) (xy 76.69707 -376.294812) (xy 76.678288 -376.302602)
			(xy 76.668122 -376.303032) (xy 75.951842 -376.303032) (xy 75.941669 -376.302601) (xy 75.92287 -376.294824)
			(xy 75.908482 -376.28044) (xy 75.900701 -376.261643) (xy 75.90028 -376.25147) (xy 75.90028 -376.093482)
			(xy 75.899883 -376.084293) (xy 75.893361 -376.067109) (xy 75.88758 -376.059954) (xy 75.865821 -376.034278)
			(xy 75.827868 -375.978696) (xy 75.796831 -375.918976) (xy 75.773155 -375.855975) (xy 75.757179 -375.790595)
			(xy 75.749132 -375.723774) (xy 75.749129 -375.656471) (xy 75.757171 -375.58965) (xy 75.773142 -375.524269)
			(xy 75.796813 -375.461265) (xy 75.827845 -375.401543) (xy 75.865793 -375.345958) (xy 75.88758 -375.320306)
			(xy 75.893354 -375.313145) (xy 75.899883 -375.295967) (xy 75.90028 -375.286778) (xy 75.90028 -374.79351)
			(xy 75.89987 -374.784323) (xy 75.893357 -374.767138) (xy 75.88758 -374.759982) (xy 75.865749 -374.734365)
			(xy 75.827799 -374.678774) (xy 75.796765 -374.619046) (xy 75.773093 -374.556037) (xy 75.757122 -374.49065)
			(xy 75.749081 -374.423823) (xy 72.471044 -374.423823) (xy 72.471044 -374.423879) (xy 72.462972 -374.490814)
			(xy 72.446941 -374.556301) (xy 72.423181 -374.619396) (xy 72.392034 -374.679191) (xy 72.35395 -374.734825)
			(xy 72.332088 -374.76049) (xy 72.326269 -374.76762) (xy 72.319768 -374.784822) (xy 72.319388 -374.794018)
			(xy 72.319388 -375.28627) (xy 72.319815 -375.295455) (xy 72.326317 -375.31264) (xy 72.332088 -375.319798)
			(xy 72.353982 -375.345439) (xy 72.39207 -375.401076) (xy 72.423221 -375.460876) (xy 72.446984 -375.523976)
			(xy 72.463017 -375.589468) (xy 72.471091 -375.656409) (xy 72.471088 -375.723836) (xy 72.463009 -375.790776)
			(xy 72.44697 -375.856267) (xy 72.423202 -375.919365) (xy 72.392047 -375.979162) (xy 72.353954 -376.034797)
			(xy 72.332088 -376.060462) (xy 72.326281 -376.0676) (xy 72.319773 -376.084796) (xy 72.319388 -376.09399)
			(xy 72.319388 -376.25147) (xy 72.31885 -376.261591) (xy 72.311137 -376.280307) (xy 72.296867 -376.294663)
			(xy 72.278198 -376.302488) (xy 72.26808 -376.303032) (xy 71.5518 -376.303032) (xy 71.54165 -376.302579)
			(xy 71.522904 -376.294789) (xy 71.508582 -376.280403) (xy 71.500876 -376.261622) (xy 71.500492 -376.25147)
			(xy 71.500492 -376.09399) (xy 71.500088 -376.084802) (xy 71.49357 -376.067618) (xy 71.487792 -376.060462)
			(xy 71.465958 -376.034772) (xy 71.427869 -375.979141) (xy 71.396717 -375.919348) (xy 71.372952 -375.856255)
			(xy 71.356914 -375.790769) (xy 71.348836 -375.723833) (xy 71.348833 -375.656412) (xy 71.356906 -375.589476)
			(xy 71.372938 -375.523989) (xy 71.396699 -375.460893) (xy 71.427845 -375.401098) (xy 71.46593 -375.345463)
			(xy 71.487792 -375.319798) (xy 71.493571 -375.31264) (xy 71.500096 -375.295459) (xy 71.500492 -375.28627)
			(xy 71.500492 -374.794018) (xy 71.500075 -374.784832) (xy 71.493566 -374.767647) (xy 71.487792 -374.76049)
			(xy 71.465887 -374.734859) (xy 71.4278 -374.679219) (xy 71.396652 -374.619418) (xy 71.37289 -374.556317)
			(xy 71.356858 -374.490824) (xy 71.348786 -374.423882) (xy 46.070774 -374.423882) (xy 46.062742 -374.490639)
			(xy 46.046773 -374.55602) (xy 46.023104 -374.619022) (xy 45.992075 -374.678745) (xy 45.95413 -374.73433)
			(xy 45.932344 -374.759982) (xy 45.926523 -374.76711) (xy 45.920025 -374.784314) (xy 45.919644 -374.79351)
			(xy 45.919644 -375.286778) (xy 45.920077 -375.295962) (xy 45.926576 -375.313146) (xy 45.932344 -375.320306)
			(xy 45.954162 -375.345934) (xy 45.992111 -375.401523) (xy 46.023144 -375.46125) (xy 46.046816 -375.524258)
			(xy 46.062787 -375.589643) (xy 46.070829 -375.656469) (xy 46.070826 -375.723776) (xy 46.062779 -375.790601)
			(xy 46.046802 -375.855985) (xy 46.023125 -375.918991) (xy 45.992088 -375.978716) (xy 45.954134 -376.034302)
			(xy 45.932344 -376.059954) (xy 45.926535 -376.06709) (xy 45.920029 -376.084288) (xy 45.919644 -376.093482)
			(xy 45.919644 -376.25147) (xy 45.919211 -376.261642) (xy 45.911433 -376.280439) (xy 45.897049 -376.294826)
			(xy 45.878254 -376.302609) (xy 45.868082 -376.303032) (xy 45.151802 -376.303032) (xy 45.141627 -376.302634)
			(xy 45.122826 -376.294844) (xy 45.10844 -376.28045) (xy 45.100661 -376.261645) (xy 45.10024 -376.25147)
			(xy 45.10024 -376.093482) (xy 45.09983 -376.084295) (xy 45.093315 -376.067111) (xy 45.08754 -376.059954)
			(xy 45.065782 -376.034277) (xy 45.027832 -375.978695) (xy 44.996798 -375.918974) (xy 44.973123 -375.855973)
			(xy 44.957148 -375.790594) (xy 44.949101 -375.723774) (xy 44.949099 -375.656471) (xy 44.95714 -375.589651)
			(xy 44.97311 -375.52427) (xy 44.996779 -375.461267) (xy 45.027809 -375.401544) (xy 45.065754 -375.345958)
			(xy 45.08754 -375.320306) (xy 45.093322 -375.31315) (xy 45.099844 -375.295968) (xy 45.10024 -375.286778)
			(xy 45.10024 -374.79351) (xy 45.099816 -374.784324) (xy 45.093311 -374.76714) (xy 45.08754 -374.759982)
			(xy 45.065711 -374.734364) (xy 45.027763 -374.678773) (xy 44.996732 -374.619044) (xy 44.973061 -374.556035)
			(xy 44.957091 -374.490649) (xy 44.94905 -374.423823) (xy 41.671014 -374.423823) (xy 41.671014 -374.423879)
			(xy 41.662941 -374.490816) (xy 41.646909 -374.556303) (xy 41.623147 -374.619398) (xy 41.591998 -374.679193)
			(xy 41.553911 -374.734826) (xy 41.532048 -374.76049) (xy 41.526224 -374.767616) (xy 41.519727 -374.784821)
			(xy 41.519348 -374.794018) (xy 41.519348 -375.28627) (xy 41.519784 -375.295454) (xy 41.526281 -375.312638)
			(xy 41.532048 -375.319798) (xy 41.553943 -375.345438) (xy 41.592035 -375.401075) (xy 41.623187 -375.460874)
			(xy 41.646952 -375.523974) (xy 41.662987 -375.589467) (xy 41.671061 -375.656409) (xy 41.671058 -375.723836)
			(xy 41.662978 -375.790777) (xy 41.646938 -375.856269) (xy 41.623168 -375.919367) (xy 41.592011 -375.979164)
			(xy 41.553916 -376.034798) (xy 41.532048 -376.060462) (xy 41.526236 -376.067596) (xy 41.519732 -376.084795)
			(xy 41.519348 -376.09399) (xy 41.519348 -376.25147) (xy 41.518849 -376.261596) (xy 41.511129 -376.280319)
			(xy 41.496846 -376.294677) (xy 41.478164 -376.302495) (xy 41.46804 -376.303032) (xy 40.75176 -376.303032)
			(xy 40.741607 -376.302612) (xy 40.72286 -376.294809) (xy 40.708539 -376.280413) (xy 40.700835 -376.261625)
			(xy 40.700452 -376.25147) (xy 40.700452 -376.09399) (xy 40.700035 -376.084804) (xy 40.693525 -376.06762)
			(xy 40.687752 -376.060462) (xy 40.665916 -376.034773) (xy 40.627823 -375.979143) (xy 40.596668 -375.919351)
			(xy 40.5729 -375.856257) (xy 40.55686 -375.79077) (xy 40.548781 -375.723834) (xy 40.548779 -375.656411)
			(xy 40.556852 -375.589474) (xy 40.572886 -375.523986) (xy 40.596649 -375.46089) (xy 40.627799 -375.401095)
			(xy 40.665888 -375.345462) (xy 40.687752 -375.319798) (xy 40.693538 -375.312646) (xy 40.700058 -375.29546)
			(xy 40.700452 -375.28627) (xy 40.700452 -374.794018) (xy 40.700022 -374.784833) (xy 40.693521 -374.767649)
			(xy 40.687752 -374.76049) (xy 40.665845 -374.73486) (xy 40.627754 -374.679221) (xy 40.596602 -374.619421)
			(xy 40.572838 -374.556319) (xy 40.556804 -374.490825) (xy 40.548731 -374.423882) (xy 37.271223 -374.423882)
			(xy 37.263151 -374.490815) (xy 37.247118 -374.556302) (xy 37.223357 -374.619398) (xy 37.192209 -374.679192)
			(xy 37.154123 -374.734826) (xy 37.13226 -374.76049) (xy 37.126438 -374.767617) (xy 37.119939 -374.784822)
			(xy 37.11956 -374.794018) (xy 37.11956 -375.28627) (xy 37.119994 -375.295454) (xy 37.126492 -375.312639)
			(xy 37.13226 -375.319798) (xy 37.154155 -375.345438) (xy 37.192245 -375.401075) (xy 37.223397 -375.460875)
			(xy 37.247161 -375.523975) (xy 37.263196 -375.589467) (xy 37.27127 -375.656409) (xy 37.271267 -375.723836)
			(xy 37.263188 -375.790777) (xy 37.247148 -375.856268) (xy 37.223379 -375.919367) (xy 37.192222 -375.979163)
			(xy 37.154127 -376.034797) (xy 37.13226 -376.060462) (xy 37.12645 -376.067597) (xy 37.119944 -376.084796)
			(xy 37.11956 -376.09399) (xy 37.11956 -376.25147) (xy 37.119049 -376.261595) (xy 37.111331 -376.280315)
			(xy 37.097052 -376.294673) (xy 37.078374 -376.302493) (xy 37.068252 -376.303032) (xy 36.351972 -376.303032)
			(xy 36.34182 -376.302602) (xy 36.323073 -376.294803) (xy 36.308752 -376.28041) (xy 36.301047 -376.261624)
			(xy 36.300664 -376.25147) (xy 36.300664 -376.09399) (xy 36.300244 -376.084804) (xy 36.293736 -376.06762)
			(xy 36.287964 -376.060462) (xy 36.266131 -376.034772) (xy 36.228044 -375.97914) (xy 36.196894 -375.919347)
			(xy 36.173129 -375.856253) (xy 36.157093 -375.790768) (xy 36.149015 -375.723833) (xy 36.149012 -375.656412)
			(xy 36.157085 -375.589477) (xy 36.173116 -375.52399) (xy 36.196875 -375.460894) (xy 36.22802 -375.401099)
			(xy 36.266103 -375.345464) (xy 36.287964 -375.319798) (xy 36.293752 -375.312647) (xy 36.30027 -375.295461)
			(xy 36.300664 -375.28627) (xy 36.300664 -374.794018) (xy 36.300231 -374.784834) (xy 36.293732 -374.76765)
			(xy 36.287964 -374.76049) (xy 36.26606 -374.734858) (xy 36.227975 -374.679218) (xy 36.196828 -374.619417)
			(xy 36.173068 -374.556316) (xy 36.157036 -374.490823) (xy 36.148964 -374.423882) (xy 32.870895 -374.423882)
			(xy 32.862863 -374.490639) (xy 32.846895 -374.556018) (xy 32.823227 -374.619021) (xy 32.7922 -374.678743)
			(xy 32.754257 -374.73433) (xy 32.732472 -374.759982) (xy 32.726654 -374.767112) (xy 32.720153 -374.784314)
			(xy 32.719772 -374.79351) (xy 32.719772 -375.286778) (xy 32.720199 -375.295963) (xy 32.726702 -375.313147)
			(xy 32.732472 -375.320306) (xy 32.754289 -375.345934) (xy 32.792236 -375.401524) (xy 32.823268 -375.461251)
			(xy 32.846938 -375.524259) (xy 32.862909 -375.589644) (xy 32.87095 -375.656469) (xy 32.870948 -375.723776)
			(xy 32.862901 -375.790601) (xy 32.846925 -375.855984) (xy 32.823249 -375.91899) (xy 32.792213 -375.978715)
			(xy 32.754261 -376.034302) (xy 32.732472 -376.059954) (xy 32.726666 -376.067093) (xy 32.720158 -376.084288)
			(xy 32.719772 -376.093482) (xy 32.719772 -376.25147) (xy 32.719312 -376.261638) (xy 32.711538 -376.28043)
			(xy 32.697164 -376.294816) (xy 32.678378 -376.302604) (xy 32.66821 -376.303032) (xy 31.95193 -376.303032)
			(xy 31.941757 -376.302611) (xy 31.922957 -376.29483) (xy 31.90857 -376.280443) (xy 31.900789 -376.261643)
			(xy 31.900368 -376.25147) (xy 31.900368 -376.093482) (xy 31.899951 -376.084296) (xy 31.89344 -376.067112)
			(xy 31.887668 -376.059954) (xy 31.865909 -376.034278) (xy 31.827957 -375.978696) (xy 31.796921 -375.918976)
			(xy 31.773245 -375.855974) (xy 31.75727 -375.790595) (xy 31.749223 -375.723774) (xy 31.74922 -375.656471)
			(xy 31.757261 -375.58965) (xy 31.773232 -375.524269) (xy 31.796903 -375.461266) (xy 31.827934 -375.401543)
			(xy 31.865881 -375.345958) (xy 31.887668 -375.320306) (xy 31.893453 -375.313153) (xy 31.899973 -375.295968)
			(xy 31.900368 -375.286778) (xy 31.900368 -374.79351) (xy 31.899938 -374.784325) (xy 31.893436 -374.767142)
			(xy 31.887668 -374.759982) (xy 31.865838 -374.734364) (xy 31.827888 -374.678774) (xy 31.796855 -374.619046)
			(xy 31.773184 -374.556036) (xy 31.757213 -374.49065) (xy 31.749171 -374.423823) (xy 28.471155 -374.423823)
			(xy 28.471155 -374.42387) (xy 28.463079 -374.490809) (xy 28.447044 -374.556297) (xy 28.423279 -374.619394)
			(xy 28.392129 -374.67919) (xy 28.35404 -374.734825) (xy 28.332176 -374.76049) (xy 28.326356 -374.767618)
			(xy 28.319856 -374.784822) (xy 28.319476 -374.794018) (xy 28.319476 -375.28627) (xy 28.319906 -375.295455)
			(xy 28.326407 -375.312639) (xy 28.332176 -375.319798) (xy 28.35407 -375.345439) (xy 28.39216 -375.401076)
			(xy 28.42331 -375.460875) (xy 28.447074 -375.523976) (xy 28.463108 -375.589468) (xy 28.471182 -375.656409)
			(xy 28.471179 -375.723836) (xy 28.4631 -375.790777) (xy 28.447061 -375.856268) (xy 28.423292 -375.919366)
			(xy 28.392136 -375.979163) (xy 28.354043 -376.034797) (xy 28.332176 -376.060462) (xy 28.326368 -376.067599)
			(xy 28.319861 -376.084796) (xy 28.319476 -376.09399) (xy 28.319476 -376.25147) (xy 28.31895 -376.261593)
			(xy 28.311235 -376.28031) (xy 28.29696 -376.294667) (xy 28.278288 -376.30249) (xy 28.268168 -376.303032)
			(xy 27.551888 -376.303032) (xy 27.541737 -376.302589) (xy 27.52299 -376.294796) (xy 27.508669 -376.280406)
			(xy 27.500964 -376.261623) (xy 27.50058 -376.25147) (xy 27.50058 -376.09399) (xy 27.500179 -376.084802)
			(xy 27.493659 -376.067617) (xy 27.48788 -376.060462) (xy 27.466046 -376.034772) (xy 27.427958 -375.979141)
			(xy 27.396807 -375.919348) (xy 27.373042 -375.856254) (xy 27.357005 -375.790768) (xy 27.348927 -375.723833)
			(xy 27.348924 -375.656412) (xy 27.356997 -375.589476) (xy 27.373029 -375.523989) (xy 27.396789 -375.460894)
			(xy 27.427935 -375.401098) (xy 27.466019 -375.345464) (xy 27.48788 -375.319798) (xy 27.493658 -375.312639)
			(xy 27.500184 -375.295459) (xy 27.50058 -375.28627) (xy 27.50058 -374.794018) (xy 27.500166 -374.784831)
			(xy 27.493655 -374.767646) (xy 27.48788 -374.76049) (xy 27.466014 -374.734827) (xy 27.427924 -374.679192)
			(xy 27.396773 -374.619396) (xy 27.373009 -374.556299) (xy 27.356973 -374.490809) (xy 27.348897 -374.423871)
			(xy 1.524 -374.423871) (xy 1.524 -376.756551) (xy 29.549067 -376.756551) (xy 29.557111 -376.689729)
			(xy 29.573083 -376.624347) (xy 29.596754 -376.561343) (xy 29.627786 -376.501619) (xy 29.665733 -376.446032)
			(xy 29.68752 -376.42038) (xy 29.69331 -376.41323) (xy 29.699828 -376.396043) (xy 29.70022 -376.386852)
			(xy 29.70022 -375.893584) (xy 29.699813 -375.884397) (xy 29.693297 -375.867212) (xy 29.68752 -375.860056)
			(xy 29.665765 -375.834378) (xy 29.627816 -375.778794) (xy 29.596782 -375.719074) (xy 29.573109 -375.656073)
			(xy 29.557134 -375.590694) (xy 29.549088 -375.523875) (xy 29.549085 -375.456573) (xy 29.557126 -375.389753)
			(xy 29.573095 -375.324373) (xy 29.596763 -375.26137) (xy 29.627791 -375.201647) (xy 29.665735 -375.146061)
			(xy 29.68752 -375.120408) (xy 29.693298 -375.11325) (xy 29.699823 -375.096069) (xy 29.70022 -375.08688)
			(xy 29.70022 -374.928638) (xy 29.700695 -374.918471) (xy 29.708464 -374.899681) (xy 29.722834 -374.885295)
			(xy 29.741616 -374.877506) (xy 29.751782 -374.877076) (xy 30.468062 -374.877076) (xy 30.478236 -374.877496)
			(xy 30.497037 -374.885276) (xy 30.511424 -374.899663) (xy 30.519204 -374.918464) (xy 30.519624 -374.928638)
			(xy 30.519624 -375.08688) (xy 30.520038 -375.096067) (xy 30.526548 -375.113252) (xy 30.532324 -375.120408)
			(xy 30.554144 -375.146034) (xy 30.592094 -375.201623) (xy 30.623128 -375.26135) (xy 30.646801 -375.324358)
			(xy 30.662773 -375.389744) (xy 30.670815 -375.45657) (xy 30.670812 -375.523878) (xy 30.662764 -375.590704)
			(xy 30.646787 -375.656088) (xy 30.623109 -375.719094) (xy 30.59207 -375.778818) (xy 30.554115 -375.834404)
			(xy 30.532324 -375.860056) (xy 30.526524 -375.867199) (xy 30.520011 -375.884391) (xy 30.519624 -375.893584)
			(xy 30.519624 -376.386852) (xy 30.520052 -376.396037) (xy 30.526553 -376.413222) (xy 30.532324 -376.42038)
			(xy 30.554117 -376.446028) (xy 30.592068 -376.501615) (xy 30.623103 -376.561338) (xy 30.646777 -376.624343)
			(xy 30.662751 -376.689726) (xy 30.670795 -376.75655) (xy 30.670795 -376.823856) (xy 30.670788 -376.823915)
			(xy 33.948836 -376.823915) (xy 33.948836 -376.756491) (xy 33.956911 -376.689553) (xy 33.972947 -376.624064)
			(xy 33.996711 -376.560967) (xy 34.027862 -376.501171) (xy 34.065952 -376.445537) (xy 34.087816 -376.419872)
			(xy 34.093609 -376.412724) (xy 34.100125 -376.395536) (xy 34.100516 -376.386344) (xy 34.100516 -375.894092)
			(xy 34.100106 -375.884905) (xy 34.093592 -375.867721) (xy 34.087816 -375.860564) (xy 34.065983 -375.834873)
			(xy 34.027892 -375.779243) (xy 33.996739 -375.71945) (xy 33.972973 -375.656357) (xy 33.956934 -375.59087)
			(xy 33.948856 -375.523935) (xy 33.948853 -375.456513) (xy 33.956926 -375.389577) (xy 33.972958 -375.324089)
			(xy 33.99672 -375.260994) (xy 34.027867 -375.201199) (xy 34.065953 -375.145565) (xy 34.087816 -375.1199)
			(xy 34.093597 -375.112744) (xy 34.10012 -375.095562) (xy 34.100516 -375.086372) (xy 34.100516 -374.928638)
			(xy 34.101057 -374.918517) (xy 34.108768 -374.899801) (xy 34.123038 -374.885444) (xy 34.141706 -374.87762)
			(xy 34.151824 -374.877076) (xy 34.868104 -374.877076) (xy 34.878255 -374.877518) (xy 34.897003 -374.88531)
			(xy 34.911325 -374.8997) (xy 34.919029 -374.918485) (xy 34.919412 -374.928638) (xy 34.919412 -375.086372)
			(xy 34.919833 -375.095558) (xy 34.926339 -375.112743) (xy 34.932112 -375.1199) (xy 34.954007 -375.14554)
			(xy 34.992094 -375.201178) (xy 35.023243 -375.260978) (xy 35.047004 -375.324078) (xy 35.063037 -375.38957)
			(xy 35.07111 -375.456511) (xy 35.071108 -375.523937) (xy 35.063029 -375.590877) (xy 35.04699 -375.656368)
			(xy 35.023223 -375.719466) (xy 34.992069 -375.779263) (xy 34.953977 -375.834899) (xy 34.932112 -375.860564)
			(xy 34.926307 -375.867703) (xy 34.919797 -375.884898) (xy 34.919412 -375.894092) (xy 34.919412 -376.386344)
			(xy 34.919798 -376.395534) (xy 34.926328 -376.412718) (xy 34.932112 -376.419872) (xy 34.953979 -376.445534)
			(xy 34.992067 -376.501169) (xy 35.023217 -376.560966) (xy 35.046981 -376.624063) (xy 35.063015 -376.689553)
			(xy 35.071091 -376.756491) (xy 35.071091 -376.756551) (xy 38.349155 -376.756551) (xy 38.357198 -376.689729)
			(xy 38.37317 -376.624348) (xy 38.396841 -376.561343) (xy 38.427872 -376.50162) (xy 38.465818 -376.446033)
			(xy 38.487604 -376.42038) (xy 38.493392 -376.413229) (xy 38.499912 -376.396043) (xy 38.500304 -376.386852)
			(xy 38.500304 -375.893584) (xy 38.499901 -375.884396) (xy 38.493382 -375.867212) (xy 38.487604 -375.860056)
			(xy 38.465849 -375.834378) (xy 38.427901 -375.778794) (xy 38.396869 -375.719074) (xy 38.373195 -375.656073)
			(xy 38.357221 -375.590694) (xy 38.349175 -375.523875) (xy 38.349172 -375.456573) (xy 38.357213 -375.389753)
			(xy 38.373181 -375.324373) (xy 38.396849 -375.26137) (xy 38.427876 -375.201647) (xy 38.465819 -375.146061)
			(xy 38.487604 -375.120408) (xy 38.49338 -375.113248) (xy 38.499907 -375.096069) (xy 38.500304 -375.08688)
			(xy 38.500304 -374.928638) (xy 38.500794 -374.918473) (xy 38.50856 -374.899686) (xy 38.522925 -374.885301)
			(xy 38.541702 -374.877508) (xy 38.551866 -374.877076) (xy 39.268146 -374.877076) (xy 39.278311 -374.877497)
			(xy 39.297089 -374.885293) (xy 39.311454 -374.899682) (xy 39.31922 -374.918472) (xy 39.319708 -374.928638)
			(xy 39.319708 -375.08688) (xy 39.320126 -375.096066) (xy 39.326634 -375.113251) (xy 39.332408 -375.120408)
			(xy 39.354229 -375.146034) (xy 39.39218 -375.201623) (xy 39.423215 -375.261349) (xy 39.446888 -375.324357)
			(xy 39.462861 -375.389743) (xy 39.470903 -375.45657) (xy 39.4709 -375.523878) (xy 39.462852 -375.590704)
			(xy 39.446874 -375.656089) (xy 39.423195 -375.719095) (xy 39.392155 -375.778819) (xy 39.354199 -375.834405)
			(xy 39.332408 -375.860056) (xy 39.326606 -375.867197) (xy 39.320094 -375.884391) (xy 39.319708 -375.893584)
			(xy 39.319708 -376.386852) (xy 39.320139 -376.396037) (xy 39.326638 -376.413222) (xy 39.332408 -376.42038)
			(xy 39.354201 -376.446028) (xy 39.392153 -376.501614) (xy 39.423189 -376.561338) (xy 39.446864 -376.624343)
			(xy 39.462839 -376.689726) (xy 39.470883 -376.75655) (xy 39.470883 -376.823856) (xy 39.470876 -376.823915)
			(xy 42.748924 -376.823915) (xy 42.748924 -376.756491) (xy 42.756999 -376.689553) (xy 42.773034 -376.624064)
			(xy 42.796798 -376.560968) (xy 42.827948 -376.501172) (xy 42.866036 -376.445537) (xy 42.8879 -376.419872)
			(xy 42.893691 -376.412723) (xy 42.900209 -376.395535) (xy 42.9006 -376.386344) (xy 42.9006 -375.894092)
			(xy 42.900194 -375.884904) (xy 42.893677 -375.86772) (xy 42.8879 -375.860564) (xy 42.866067 -375.834873)
			(xy 42.827978 -375.779242) (xy 42.796826 -375.719449) (xy 42.77306 -375.656356) (xy 42.757022 -375.59087)
			(xy 42.748944 -375.523935) (xy 42.748941 -375.456513) (xy 42.757013 -375.389577) (xy 42.773045 -375.32409)
			(xy 42.796806 -375.260995) (xy 42.827953 -375.201199) (xy 42.866038 -375.145565) (xy 42.8879 -375.1199)
			(xy 42.893679 -375.112742) (xy 42.900204 -375.095561) (xy 42.9006 -375.086372) (xy 42.9006 -374.928638)
			(xy 42.901157 -374.918519) (xy 42.908865 -374.899806) (xy 42.923129 -374.88545) (xy 42.941792 -374.877622)
			(xy 42.951908 -374.877076) (xy 43.668188 -374.877076) (xy 43.678338 -374.877531) (xy 43.697086 -374.885318)
			(xy 43.711409 -374.899704) (xy 43.719113 -374.918486) (xy 43.719496 -374.928638) (xy 43.719496 -375.086372)
			(xy 43.719921 -375.095558) (xy 43.726424 -375.112742) (xy 43.732196 -375.1199) (xy 43.754092 -375.145539)
			(xy 43.79218 -375.201177) (xy 43.823329 -375.260977) (xy 43.847092 -375.324077) (xy 43.863125 -375.38957)
			(xy 43.871198 -375.456511) (xy 43.871196 -375.523937) (xy 43.863116 -375.590878) (xy 43.847077 -375.656369)
			(xy 43.823309 -375.719467) (xy 43.792155 -375.779264) (xy 43.754062 -375.834899) (xy 43.732196 -375.860564)
			(xy 43.726389 -375.867702) (xy 43.719881 -375.884898) (xy 43.719496 -375.894092) (xy 43.719496 -376.386344)
			(xy 43.719886 -376.395533) (xy 43.726414 -376.412717) (xy 43.732196 -376.419872) (xy 43.754064 -376.445534)
			(xy 43.792153 -376.501169) (xy 43.823304 -376.560965) (xy 43.847068 -376.624063) (xy 43.863103 -376.689552)
			(xy 43.871179 -376.756491) (xy 43.871178 -376.823856) (xy 47.149219 -376.823856) (xy 47.149219 -376.75655)
			(xy 47.157264 -376.689727) (xy 47.173238 -376.624344) (xy 47.196912 -376.56134) (xy 47.227948 -376.501617)
			(xy 47.265899 -376.446031) (xy 47.287688 -376.42038) (xy 47.293474 -376.413227) (xy 47.299995 -376.396043)
			(xy 47.300388 -376.386852) (xy 47.300388 -375.893584) (xy 47.299988 -375.884396) (xy 47.293468 -375.867211)
			(xy 47.287688 -375.860056) (xy 47.26593 -375.834379) (xy 47.227977 -375.778797) (xy 47.19694 -375.719077)
			(xy 47.173263 -375.656076) (xy 47.157287 -375.590696) (xy 47.149239 -375.523876) (xy 47.149236 -375.456572)
			(xy 47.157278 -375.389751) (xy 47.173249 -375.32437) (xy 47.19692 -375.261367) (xy 47.227952 -375.201644)
			(xy 47.265901 -375.146059) (xy 47.287688 -375.120408) (xy 47.293462 -375.113247) (xy 47.299991 -375.096069)
			(xy 47.300388 -375.08688) (xy 47.300388 -374.928892) (xy 47.300815 -374.918739) (xy 47.308611 -374.899989)
			(xy 47.323006 -374.885666) (xy 47.341795 -374.877965) (xy 47.35195 -374.877584) (xy 48.06823 -374.877584)
			(xy 48.078364 -374.878003) (xy 48.097094 -374.885749) (xy 48.111451 -374.900056) (xy 48.119261 -374.91876)
			(xy 48.119792 -374.928892) (xy 48.119792 -375.08688) (xy 48.120214 -375.096066) (xy 48.12672 -375.11325)
			(xy 48.132492 -375.120408) (xy 48.15431 -375.146035) (xy 48.192256 -375.201626) (xy 48.223286 -375.261353)
			(xy 48.246956 -375.324361) (xy 48.262926 -375.389746) (xy 48.270967 -375.456571) (xy 48.270964 -375.523878)
			(xy 48.262917 -375.590702) (xy 48.246942 -375.656085) (xy 48.223267 -375.719091) (xy 48.192231 -375.778816)
			(xy 48.154281 -375.834403) (xy 48.132492 -375.860056) (xy 48.126688 -375.867196) (xy 48.120178 -375.884391)
			(xy 48.119792 -375.893584) (xy 48.119792 -376.386852) (xy 48.120227 -376.396037) (xy 48.126724 -376.413221)
			(xy 48.132492 -376.42038) (xy 48.154283 -376.446029) (xy 48.192229 -376.501617) (xy 48.223261 -376.561341)
			(xy 48.246932 -376.624346) (xy 48.262904 -376.689728) (xy 48.270947 -376.756551) (xy 73.548976 -376.756551)
			(xy 73.55702 -376.689728) (xy 73.572992 -376.624347) (xy 73.596664 -376.561342) (xy 73.627697 -376.501619)
			(xy 73.665645 -376.446032) (xy 73.687432 -376.42038) (xy 73.693224 -376.413231) (xy 73.699741 -376.396043)
			(xy 73.700132 -376.386852) (xy 73.700132 -375.893584) (xy 73.699722 -375.884397) (xy 73.693208 -375.867213)
			(xy 73.687432 -375.860056) (xy 73.665676 -375.834378) (xy 73.627727 -375.778795) (xy 73.596693 -375.719075)
			(xy 73.573018 -375.656074) (xy 73.557043 -375.590695) (xy 73.548997 -375.523875) (xy 73.548994 -375.456573)
			(xy 73.557035 -375.389753) (xy 73.573004 -375.324372) (xy 73.596673 -375.261369) (xy 73.627702 -375.201647)
			(xy 73.665647 -375.14606) (xy 73.687432 -375.120408) (xy 73.693212 -375.113251) (xy 73.699736 -375.096069)
			(xy 73.700132 -375.08688) (xy 73.700132 -374.928638) (xy 73.700595 -374.91847) (xy 73.708366 -374.899677)
			(xy 73.72274 -374.885291) (xy 73.741526 -374.877504) (xy 73.751694 -374.877076) (xy 74.467974 -374.877076)
			(xy 74.478149 -374.877486) (xy 74.49695 -374.88527) (xy 74.511337 -374.89966) (xy 74.519116 -374.918463)
			(xy 74.519536 -374.928638) (xy 74.519536 -375.08688) (xy 74.51997 -375.096064) (xy 74.526469 -375.113248)
			(xy 74.532236 -375.120408) (xy 74.554056 -375.146034) (xy 74.592006 -375.201623) (xy 74.623039 -375.26135)
			(xy 74.646711 -375.324358) (xy 74.662683 -375.389744) (xy 74.670725 -375.45657) (xy 74.670722 -375.523878)
			(xy 74.662674 -375.590703) (xy 74.646697 -375.656088) (xy 74.623019 -375.719094) (xy 74.591981 -375.778818)
			(xy 74.554027 -375.834404) (xy 74.532236 -375.860056) (xy 74.526425 -375.867191) (xy 74.519921 -375.88439)
			(xy 74.519536 -375.893584) (xy 74.519536 -376.386852) (xy 74.519983 -376.396035) (xy 74.526473 -376.413219)
			(xy 74.532236 -376.42038) (xy 74.554028 -376.446029) (xy 74.591979 -376.501615) (xy 74.623013 -376.561339)
			(xy 74.646687 -376.624344) (xy 74.66266 -376.689727) (xy 74.670704 -376.75655) (xy 74.670704 -376.823856)
			(xy 74.670697 -376.823915) (xy 77.948745 -376.823915) (xy 77.948745 -376.756491) (xy 77.956821 -376.689553)
			(xy 77.972856 -376.624063) (xy 77.996621 -376.560967) (xy 78.027773 -376.501171) (xy 78.065863 -376.445537)
			(xy 78.087728 -376.419872) (xy 78.093523 -376.412726) (xy 78.100038 -376.395536) (xy 78.100428 -376.386344)
			(xy 78.100428 -375.894092) (xy 78.100016 -375.884905) (xy 78.093503 -375.867721) (xy 78.087728 -375.860564)
			(xy 78.065894 -375.834873) (xy 78.027803 -375.779243) (xy 77.996649 -375.719451) (xy 77.972882 -375.656357)
			(xy 77.956844 -375.590871) (xy 77.948765 -375.523935) (xy 77.948762 -375.456513) (xy 77.956835 -375.389577)
			(xy 77.972868 -375.324089) (xy 77.99663 -375.260993) (xy 78.027778 -375.201198) (xy 78.065865 -375.145565)
			(xy 78.087728 -375.1199) (xy 78.093511 -375.112745) (xy 78.100033 -375.095562) (xy 78.100428 -375.086372)
			(xy 78.100428 -374.928638) (xy 78.100958 -374.918515) (xy 78.108671 -374.899797) (xy 78.122944 -374.88544)
			(xy 78.141616 -374.877618) (xy 78.151736 -374.877076) (xy 78.868016 -374.877076) (xy 78.878168 -374.877508)
			(xy 78.896916 -374.885304) (xy 78.911238 -374.899697) (xy 78.918942 -374.918484) (xy 78.919324 -374.928638)
			(xy 78.919324 -375.086372) (xy 78.919742 -375.095558) (xy 78.92625 -375.112743) (xy 78.932024 -375.1199)
			(xy 78.953919 -375.14554) (xy 78.992005 -375.201178) (xy 79.023153 -375.260978) (xy 79.046914 -375.324079)
			(xy 79.062947 -375.38957) (xy 79.07102 -375.456511) (xy 79.071017 -375.523937) (xy 79.062938 -375.590877)
			(xy 79.0469 -375.656367) (xy 79.023133 -375.719466) (xy 78.99198 -375.779263) (xy 78.953889 -375.834898)
			(xy 78.932024 -375.860564) (xy 78.926221 -375.867704) (xy 78.919709 -375.884898) (xy 78.919324 -375.894092)
			(xy 78.919324 -376.386344) (xy 78.919708 -376.395534) (xy 78.926239 -376.412718) (xy 78.932024 -376.419872)
			(xy 78.953891 -376.445534) (xy 78.991978 -376.50117) (xy 79.023127 -376.560967) (xy 79.04689 -376.624064)
			(xy 79.062925 -376.689553) (xy 79.071 -376.756491) (xy 79.071 -376.756551) (xy 82.349064 -376.756551)
			(xy 82.357108 -376.689729) (xy 82.373079 -376.624347) (xy 82.396751 -376.561343) (xy 82.427782 -376.501619)
			(xy 82.465729 -376.446032) (xy 82.487516 -376.42038) (xy 82.493305 -376.41323) (xy 82.499824 -376.396043)
			(xy 82.500216 -376.386852) (xy 82.500216 -375.893584) (xy 82.49981 -375.884396) (xy 82.493293 -375.867212)
			(xy 82.487516 -375.860056) (xy 82.46576 -375.834378) (xy 82.427812 -375.778795) (xy 82.396779 -375.719074)
			(xy 82.373105 -375.656073) (xy 82.357131 -375.590694) (xy 82.349084 -375.523875) (xy 82.349081 -375.456573)
			(xy 82.357122 -375.389753) (xy 82.373091 -375.324373) (xy 82.396759 -375.26137) (xy 82.427787 -375.201647)
			(xy 82.465731 -375.14606) (xy 82.487516 -375.120408) (xy 82.493294 -375.113249) (xy 82.499819 -375.096069)
			(xy 82.500216 -375.08688) (xy 82.500216 -374.928638) (xy 82.500694 -374.918472) (xy 82.508463 -374.899682)
			(xy 82.522832 -374.885297) (xy 82.541612 -374.877506) (xy 82.551778 -374.877076) (xy 83.268058 -374.877076)
			(xy 83.278232 -374.877499) (xy 83.297033 -374.885277) (xy 83.31142 -374.899664) (xy 83.3192 -374.918464)
			(xy 83.31962 -374.928638) (xy 83.31962 -375.08688) (xy 83.320035 -375.096067) (xy 83.326545 -375.113251)
			(xy 83.33232 -375.120408) (xy 83.35414 -375.146034) (xy 83.392091 -375.201623) (xy 83.423125 -375.26135)
			(xy 83.446798 -375.324358) (xy 83.46277 -375.389744) (xy 83.470812 -375.45657) (xy 83.470809 -375.523878)
			(xy 83.462761 -375.590704) (xy 83.446784 -375.656088) (xy 83.423105 -375.719094) (xy 83.392066 -375.778818)
			(xy 83.354111 -375.834404) (xy 83.33232 -375.860056) (xy 83.326519 -375.867199) (xy 83.320007 -375.884391)
			(xy 83.31962 -375.893584) (xy 83.31962 -376.386852) (xy 83.320049 -376.396037) (xy 83.326549 -376.413222)
			(xy 83.33232 -376.42038) (xy 83.354113 -376.446028) (xy 83.392064 -376.501614) (xy 83.4231 -376.561338)
			(xy 83.446774 -376.624343) (xy 83.462748 -376.689726) (xy 83.470792 -376.75655) (xy 83.470792 -376.823856)
			(xy 83.470785 -376.823915) (xy 86.748833 -376.823915) (xy 86.748833 -376.756491) (xy 86.756908 -376.689553)
			(xy 86.772944 -376.624064) (xy 86.796708 -376.560967) (xy 86.827859 -376.501171) (xy 86.865948 -376.445537)
			(xy 86.887812 -376.419872) (xy 86.893604 -376.412724) (xy 86.900121 -376.395536) (xy 86.900512 -376.386344)
			(xy 86.900512 -375.894092) (xy 86.900103 -375.884905) (xy 86.893588 -375.86772) (xy 86.887812 -375.860564)
			(xy 86.865979 -375.834873) (xy 86.827889 -375.779242) (xy 86.796736 -375.71945) (xy 86.772969 -375.656356)
			(xy 86.756931 -375.59087) (xy 86.748853 -375.523935) (xy 86.74885 -375.456513) (xy 86.756923 -375.389577)
			(xy 86.772955 -375.32409) (xy 86.796716 -375.260994) (xy 86.827864 -375.201199) (xy 86.86595 -375.145565)
			(xy 86.887812 -375.1199) (xy 86.893592 -375.112743) (xy 86.900116 -375.095562) (xy 86.900512 -375.086372)
			(xy 86.900512 -374.928638) (xy 86.901057 -374.918517) (xy 86.908767 -374.899802) (xy 86.923035 -374.885446)
			(xy 86.941702 -374.87762) (xy 86.95182 -374.877076) (xy 87.6681 -374.877076) (xy 87.678251 -374.877521)
			(xy 87.696999 -374.885312) (xy 87.711321 -374.899701) (xy 87.719025 -374.918485) (xy 87.719408 -374.928638)
			(xy 87.719408 -375.086372) (xy 87.71983 -375.095558) (xy 87.726335 -375.112743) (xy 87.732108 -375.1199)
			(xy 87.754003 -375.145539) (xy 87.79209 -375.201178) (xy 87.798441 -375.213371) (xy 104.681961 -375.213371)
			(xy 104.681961 -375.153429) (xy 104.689785 -375.094001) (xy 104.7053 -375.036103) (xy 104.72824 -374.980725)
			(xy 104.758212 -374.928815) (xy 104.794703 -374.881262) (xy 104.837089 -374.838879) (xy 104.884645 -374.802391)
			(xy 104.936557 -374.772424) (xy 104.991937 -374.749489) (xy 105.049837 -374.733978) (xy 105.109265 -374.726159)
			(xy 105.139236 -374.725692) (xy 106.002836 -374.725692) (xy 106.032802 -374.726184) (xy 106.092221 -374.734011)
			(xy 106.15011 -374.749527) (xy 106.205479 -374.772465) (xy 106.25738 -374.802434) (xy 106.304926 -374.838921)
			(xy 106.347303 -374.881301) (xy 106.383786 -374.92885) (xy 106.413751 -374.980753) (xy 106.436685 -375.036124)
			(xy 106.452196 -375.094014) (xy 106.460018 -375.153434) (xy 106.460018 -375.213366) (xy 106.452196 -375.272786)
			(xy 106.436685 -375.330676) (xy 106.413751 -375.386047) (xy 106.383786 -375.43795) (xy 106.347303 -375.485499)
			(xy 106.304926 -375.527879) (xy 106.25738 -375.564366) (xy 106.205479 -375.594335) (xy 106.15011 -375.617273)
			(xy 106.092221 -375.632789) (xy 106.032802 -375.640616) (xy 106.002836 -375.641108) (xy 105.139236 -375.641108)
			(xy 105.109265 -375.640641) (xy 105.049837 -375.632822) (xy 104.991937 -375.617311) (xy 104.936557 -375.594376)
			(xy 104.884645 -375.564409) (xy 104.837089 -375.527921) (xy 104.794703 -375.485538) (xy 104.758212 -375.437985)
			(xy 104.72824 -375.386075) (xy 104.7053 -375.330697) (xy 104.689785 -375.272799) (xy 104.681961 -375.213371)
			(xy 87.798441 -375.213371) (xy 87.823239 -375.260978) (xy 87.847001 -375.324078) (xy 87.863034 -375.38957)
			(xy 87.871107 -375.456511) (xy 87.871105 -375.523937) (xy 87.863026 -375.590877) (xy 87.846987 -375.656368)
			(xy 87.82322 -375.719466) (xy 87.792066 -375.779263) (xy 87.753974 -375.834899) (xy 87.732108 -375.860564)
			(xy 87.726303 -375.867703) (xy 87.719793 -375.884898) (xy 87.719408 -375.894092) (xy 87.719408 -376.386344)
			(xy 87.719795 -376.395534) (xy 87.726324 -376.412718) (xy 87.732108 -376.419872) (xy 87.753976 -376.445534)
			(xy 87.792064 -376.501169) (xy 87.823214 -376.560966) (xy 87.846977 -376.624063) (xy 87.863012 -376.689553)
			(xy 87.871088 -376.756491) (xy 87.871087 -376.823915) (xy 117.548863 -376.823915) (xy 117.548863 -376.756491)
			(xy 117.556939 -376.689552) (xy 117.572976 -376.624062) (xy 117.596742 -376.560965) (xy 117.627895 -376.50117)
			(xy 117.665986 -376.445536) (xy 117.687852 -376.419872) (xy 117.693649 -376.412728) (xy 117.700162 -376.395536)
			(xy 117.700552 -376.386344) (xy 117.700552 -375.894092) (xy 117.700134 -375.884906) (xy 117.693625 -375.867722)
			(xy 117.687852 -375.860564) (xy 117.666018 -375.834874) (xy 117.627925 -375.779244) (xy 117.59677 -375.719452)
			(xy 117.573001 -375.656358) (xy 117.556962 -375.590871) (xy 117.548883 -375.523935) (xy 117.54888 -375.456513)
			(xy 117.556953 -375.389576) (xy 117.572987 -375.324088) (xy 117.59675 -375.260992) (xy 117.6279 -375.201197)
			(xy 117.665988 -375.145564) (xy 117.687852 -375.1199) (xy 117.693638 -375.112747) (xy 117.700157 -375.095562)
			(xy 117.700552 -375.086372) (xy 117.700552 -374.928638) (xy 117.701058 -374.918512) (xy 117.708776 -374.89979)
			(xy 117.723056 -374.885432) (xy 117.741737 -374.877613) (xy 117.75186 -374.877076) (xy 118.46814 -374.877076)
			(xy 118.478294 -374.877488) (xy 118.497042 -374.885293) (xy 118.511363 -374.899691) (xy 118.519066 -374.918482)
			(xy 118.519448 -374.928638) (xy 118.519448 -375.086372) (xy 118.519883 -375.095556) (xy 118.526381 -375.11274)
			(xy 118.532148 -375.1199) (xy 118.554045 -375.145538) (xy 118.592136 -375.201176) (xy 118.623289 -375.260975)
			(xy 118.647053 -375.324075) (xy 118.663088 -375.389568) (xy 118.671162 -375.45651) (xy 118.671159 -375.523938)
			(xy 118.66308 -375.590879) (xy 118.647039 -375.656371) (xy 118.623269 -375.719469) (xy 118.592112 -375.779266)
			(xy 118.554016 -375.8349) (xy 118.532148 -375.860564) (xy 118.526335 -375.867698) (xy 118.519832 -375.884897)
			(xy 118.519448 -375.894092) (xy 118.519448 -376.386344) (xy 118.519849 -376.395532) (xy 118.52637 -376.412715)
			(xy 118.532148 -376.419872) (xy 118.554018 -376.445533) (xy 118.59211 -376.501167) (xy 118.623263 -376.560963)
			(xy 118.647029 -376.624061) (xy 118.663066 -376.689551) (xy 118.671143 -376.75649) (xy 118.671143 -376.756551)
			(xy 121.949182 -376.756551) (xy 121.957226 -376.689728) (xy 121.973199 -376.624346) (xy 121.996871 -376.561342)
			(xy 122.027904 -376.501618) (xy 122.065852 -376.446032) (xy 122.08764 -376.42038) (xy 122.093433 -376.413232)
			(xy 122.099949 -376.396044) (xy 122.10034 -376.386852) (xy 122.10034 -375.893584) (xy 122.099929 -375.884397)
			(xy 122.093415 -375.867213) (xy 122.08764 -375.860056) (xy 122.065884 -375.834378) (xy 122.027934 -375.778795)
			(xy 121.996899 -375.719075) (xy 121.973225 -375.656074) (xy 121.95725 -375.590695) (xy 121.949203 -375.523875)
			(xy 121.9492 -375.456573) (xy 121.957241 -375.389752) (xy 121.973211 -375.324372) (xy 121.99688 -375.261369)
			(xy 122.027909 -375.201646) (xy 122.065854 -375.14606) (xy 122.08764 -375.120408) (xy 122.093421 -375.113252)
			(xy 122.099944 -375.09607) (xy 122.10034 -375.08688) (xy 122.10034 -374.928638) (xy 122.100795 -374.918469)
			(xy 122.108568 -374.899674) (xy 122.122944 -374.885288) (xy 122.141733 -374.877502) (xy 122.151902 -374.877076)
			(xy 122.868182 -374.877076) (xy 122.878357 -374.877479) (xy 122.897159 -374.885265) (xy 122.911546 -374.899658)
			(xy 122.919325 -374.918463) (xy 122.919744 -374.928638) (xy 122.919744 -375.08688) (xy 122.920176 -375.096065)
			(xy 122.926676 -375.113249) (xy 122.932444 -375.120408) (xy 122.954264 -375.146034) (xy 122.992213 -375.201624)
			(xy 123.023246 -375.261351) (xy 123.046917 -375.324359) (xy 123.062889 -375.389744) (xy 123.070931 -375.45657)
			(xy 123.070928 -375.523878) (xy 123.06288 -375.590703) (xy 123.046903 -375.656087) (xy 123.023226 -375.719093)
			(xy 122.992188 -375.778818) (xy 122.954234 -375.834404) (xy 122.932444 -375.860056) (xy 122.926634 -375.867192)
			(xy 122.920129 -375.88439) (xy 122.919744 -375.893584) (xy 122.919744 -376.386852) (xy 122.92019 -376.396035)
			(xy 122.92668 -376.413219) (xy 122.932444 -376.42038) (xy 122.954236 -376.446029) (xy 122.992186 -376.501615)
			(xy 123.02322 -376.561339) (xy 123.046893 -376.624344) (xy 123.062866 -376.689727) (xy 123.07091 -376.75655)
			(xy 123.07091 -376.823856) (xy 123.070903 -376.823915) (xy 126.348951 -376.823915) (xy 126.348951 -376.756491)
			(xy 126.357027 -376.689552) (xy 126.373063 -376.624063) (xy 126.396828 -376.560966) (xy 126.42798 -376.50117)
			(xy 126.466071 -376.445537) (xy 126.487936 -376.419872) (xy 126.493732 -376.412726) (xy 126.500246 -376.395536)
			(xy 126.500636 -376.386344) (xy 126.500636 -375.894092) (xy 126.500222 -375.884905) (xy 126.49371 -375.867721)
			(xy 126.487936 -375.860564) (xy 126.466102 -375.834873) (xy 126.42801 -375.779243) (xy 126.396856 -375.719451)
			(xy 126.373088 -375.656357) (xy 126.35705 -375.590871) (xy 126.348971 -375.523935) (xy 126.348968 -375.456513)
			(xy 126.357041 -375.389576) (xy 126.373074 -375.324089) (xy 126.396836 -375.260993) (xy 126.427985 -375.201198)
			(xy 126.466073 -375.145565) (xy 126.487936 -375.1199) (xy 126.49372 -375.112746) (xy 126.500241 -375.095562)
			(xy 126.500636 -375.086372) (xy 126.500636 -374.928638) (xy 126.501158 -374.918514) (xy 126.508872 -374.899795)
			(xy 126.523148 -374.885437) (xy 126.541823 -374.877616) (xy 126.551944 -374.877076) (xy 127.268224 -374.877076)
			(xy 127.278377 -374.877501) (xy 127.297125 -374.8853) (xy 127.311447 -374.899695) (xy 127.31915 -374.918483)
			(xy 127.319532 -374.928638) (xy 127.319532 -375.086372) (xy 127.319971 -375.095556) (xy 127.326466 -375.11274)
			(xy 127.332232 -375.1199) (xy 127.354126 -375.14554) (xy 127.392212 -375.201179) (xy 127.423359 -375.260979)
			(xy 127.44712 -375.324079) (xy 127.463153 -375.389571) (xy 127.471226 -375.456511) (xy 127.471223 -375.523937)
			(xy 127.463144 -375.590877) (xy 127.447106 -375.656367) (xy 127.42334 -375.719465) (xy 127.392187 -375.779263)
			(xy 127.354097 -375.834898) (xy 127.332232 -375.860564) (xy 127.326417 -375.867696) (xy 127.319915 -375.884897)
			(xy 127.319532 -375.894092) (xy 127.319532 -376.386344) (xy 127.319936 -376.395532) (xy 127.326456 -376.412715)
			(xy 127.332232 -376.419872) (xy 127.354099 -376.445535) (xy 127.392185 -376.50117) (xy 127.423334 -376.560967)
			(xy 127.447097 -376.624064) (xy 127.463131 -376.689553) (xy 127.471206 -376.756491) (xy 127.471206 -376.756551)
			(xy 130.74927 -376.756551) (xy 130.757314 -376.689729) (xy 130.773286 -376.624347) (xy 130.796958 -376.561343)
			(xy 130.827989 -376.501619) (xy 130.865937 -376.446032) (xy 130.887724 -376.42038) (xy 130.893514 -376.413231)
			(xy 130.900032 -376.396043) (xy 130.900424 -376.386852) (xy 130.900424 -375.893584) (xy 130.900016 -375.884397)
			(xy 130.8935 -375.867213) (xy 130.887724 -375.860056) (xy 130.865968 -375.834378) (xy 130.82802 -375.778795)
			(xy 130.796986 -375.719074) (xy 130.773312 -375.656073) (xy 130.757337 -375.590695) (xy 130.749291 -375.523875)
			(xy 130.749288 -375.456573) (xy 130.757329 -375.389753) (xy 130.773298 -375.324373) (xy 130.796966 -375.26137)
			(xy 130.827995 -375.201647) (xy 130.865939 -375.146061) (xy 130.887724 -375.120408) (xy 130.893502 -375.11325)
			(xy 130.900027 -375.096069) (xy 130.900424 -375.08688) (xy 130.900424 -374.928638) (xy 130.900895 -374.918471)
			(xy 130.908665 -374.899679) (xy 130.923036 -374.885294) (xy 130.941819 -374.877505) (xy 130.951986 -374.877076)
			(xy 131.668266 -374.877076) (xy 131.67844 -374.877493) (xy 131.697241 -374.885274) (xy 131.711629 -374.899662)
			(xy 131.719408 -374.918464) (xy 131.719828 -374.928638) (xy 131.719828 -375.08688) (xy 131.720241 -375.096067)
			(xy 131.726752 -375.113252) (xy 131.732528 -375.120408) (xy 131.754348 -375.146034) (xy 131.792298 -375.201623)
			(xy 131.823332 -375.26135) (xy 131.847005 -375.324358) (xy 131.862976 -375.389744) (xy 131.871018 -375.45657)
			(xy 131.871016 -375.523878) (xy 131.862968 -375.590704) (xy 131.84699 -375.656088) (xy 131.823313 -375.719094)
			(xy 131.792274 -375.778818) (xy 131.754319 -375.834404) (xy 131.732528 -375.860056) (xy 131.726716 -375.86719)
			(xy 131.720213 -375.884389) (xy 131.719828 -375.893584) (xy 131.719828 -376.386852) (xy 131.720255 -376.396037)
			(xy 131.726756 -376.413222) (xy 131.732528 -376.42038) (xy 131.754321 -376.446029) (xy 131.792271 -376.501615)
			(xy 131.823306 -376.561338) (xy 131.84698 -376.624344) (xy 131.862954 -376.689727) (xy 131.870991 -376.756492)
			(xy 161.548796 -376.756492) (xy 161.556871 -376.689554) (xy 161.572905 -376.624066) (xy 161.596667 -376.560969)
			(xy 161.627816 -376.501173) (xy 161.665902 -376.445538) (xy 161.687764 -376.419872) (xy 161.693563 -376.412729)
			(xy 161.700074 -376.395536) (xy 161.700464 -376.386344) (xy 161.700464 -375.894092) (xy 161.700043 -375.884906)
			(xy 161.693535 -375.867723) (xy 161.687764 -375.860564) (xy 161.665933 -375.834872) (xy 161.627845 -375.779241)
			(xy 161.596695 -375.719448) (xy 161.572931 -375.656354) (xy 161.556894 -375.590869) (xy 161.548816 -375.523934)
			(xy 161.548814 -375.456514) (xy 161.556886 -375.389578) (xy 161.572917 -375.324092) (xy 161.596676 -375.260996)
			(xy 161.627821 -375.201201) (xy 161.665903 -375.145566) (xy 161.687764 -375.1199) (xy 161.693551 -375.112748)
			(xy 161.70007 -375.095562) (xy 161.700464 -375.086372) (xy 161.700464 -374.928638) (xy 161.700959 -374.918511)
			(xy 161.708678 -374.899786) (xy 161.722963 -374.885428) (xy 161.741647 -374.877611) (xy 161.751772 -374.877076)
			(xy 162.468052 -374.877076) (xy 162.4782 -374.877561) (xy 162.496947 -374.885336) (xy 162.511271 -374.899713)
			(xy 162.518977 -374.918489) (xy 162.51936 -374.928638) (xy 162.51936 -375.086372) (xy 162.519793 -375.095557)
			(xy 162.526292 -375.112741) (xy 162.53206 -375.1199) (xy 162.553957 -375.145539) (xy 162.592047 -375.201176)
			(xy 162.623199 -375.260976) (xy 162.646963 -375.324076) (xy 162.662997 -375.389569) (xy 162.671071 -375.456511)
			(xy 162.671068 -375.523938) (xy 162.662989 -375.590879) (xy 162.646949 -375.65637) (xy 162.623179 -375.719468)
			(xy 162.592022 -375.779265) (xy 162.553927 -375.834899) (xy 162.53206 -375.860564) (xy 162.526249 -375.867699)
			(xy 162.519744 -375.884897) (xy 162.51936 -375.894092) (xy 162.51936 -376.386344) (xy 162.519758 -376.395532)
			(xy 162.526281 -376.412716) (xy 162.53206 -376.419872) (xy 162.553929 -376.445533) (xy 162.592021 -376.501167)
			(xy 162.623173 -376.560964) (xy 162.646939 -376.624061) (xy 162.662975 -376.689551) (xy 162.671052 -376.756491)
			(xy 162.671051 -376.823855) (xy 165.949092 -376.823855) (xy 165.949092 -376.756551) (xy 165.957136 -376.689728)
			(xy 165.973109 -376.624346) (xy 165.996782 -376.561342) (xy 166.027815 -376.501618) (xy 166.065764 -376.446032)
			(xy 166.087552 -376.42038) (xy 166.093346 -376.413233) (xy 166.099861 -376.396044) (xy 166.100252 -376.386852)
			(xy 166.100252 -375.893584) (xy 166.099838 -375.884397) (xy 166.093326 -375.867214) (xy 166.087552 -375.860056)
			(xy 166.065795 -375.834378) (xy 166.027845 -375.778796) (xy 165.996809 -375.719076) (xy 165.973134 -375.656075)
			(xy 165.957159 -375.590695) (xy 165.949112 -375.523875) (xy 165.949109 -375.456573) (xy 165.95715 -375.389752)
			(xy 165.97312 -375.324371) (xy 165.99679 -375.261368) (xy 166.02782 -375.201646) (xy 166.065766 -375.14606)
			(xy 166.087552 -375.120408) (xy 166.093334 -375.113253) (xy 166.099856 -375.09607) (xy 166.100252 -375.08688)
			(xy 166.100252 -374.928638) (xy 166.100695 -374.918467) (xy 166.10847 -374.899671) (xy 166.12285 -374.885284)
			(xy 166.141643 -374.8775) (xy 166.151814 -374.877076) (xy 166.868094 -374.877076) (xy 166.87827 -374.87747)
			(xy 166.897072 -374.88526) (xy 166.911458 -374.899655) (xy 166.919237 -374.918462) (xy 166.919656 -374.928638)
			(xy 166.919656 -375.08688) (xy 166.920085 -375.096065) (xy 166.926587 -375.113249) (xy 166.932356 -375.120408)
			(xy 166.954175 -375.146034) (xy 166.992124 -375.201624) (xy 167.023156 -375.261351) (xy 167.046827 -375.324359)
			(xy 167.062798 -375.389745) (xy 167.07084 -375.45657) (xy 167.070837 -375.523878) (xy 167.062789 -375.590703)
			(xy 167.046813 -375.656087) (xy 167.023136 -375.719093) (xy 166.992099 -375.778817) (xy 166.954146 -375.834404)
			(xy 166.932356 -375.860056) (xy 166.926548 -375.867193) (xy 166.920041 -375.88439) (xy 166.919656 -375.893584)
			(xy 166.919656 -376.386852) (xy 166.920099 -376.396035) (xy 166.926591 -376.41322) (xy 166.932356 -376.42038)
			(xy 166.954148 -376.446029) (xy 166.992097 -376.501616) (xy 167.02313 -376.56134) (xy 167.046803 -376.624345)
			(xy 167.062776 -376.689727) (xy 167.07082 -376.75655) (xy 167.07082 -376.823856) (xy 167.070813 -376.823915)
			(xy 170.34886 -376.823915) (xy 170.34886 -376.756491) (xy 170.356936 -376.689552) (xy 170.372972 -376.624063)
			(xy 170.396738 -376.560966) (xy 170.427891 -376.50117) (xy 170.465983 -376.445536) (xy 170.487848 -376.419872)
			(xy 170.493645 -376.412727) (xy 170.500158 -376.395536) (xy 170.500548 -376.386344) (xy 170.500548 -375.894092)
			(xy 170.500131 -375.884906) (xy 170.493621 -375.867722) (xy 170.487848 -375.860564) (xy 170.466014 -375.834874)
			(xy 170.427921 -375.779244) (xy 170.396766 -375.719452) (xy 170.372998 -375.656358) (xy 170.356959 -375.590871)
			(xy 170.34888 -375.523935) (xy 170.348877 -375.456513) (xy 170.35695 -375.389576) (xy 170.372984 -375.324088)
			(xy 170.396747 -375.260992) (xy 170.427896 -375.201197) (xy 170.465984 -375.145564) (xy 170.487848 -375.1199)
			(xy 170.493633 -375.112747) (xy 170.500153 -375.095562) (xy 170.500548 -375.086372) (xy 170.500548 -374.928638)
			(xy 170.501058 -374.918513) (xy 170.508775 -374.899791) (xy 170.523054 -374.885433) (xy 170.541734 -374.877614)
			(xy 170.551856 -374.877076) (xy 171.268136 -374.877076) (xy 171.278289 -374.877492) (xy 171.297038 -374.885295)
			(xy 171.311359 -374.899692) (xy 171.319062 -374.918482) (xy 171.319444 -374.928638) (xy 171.319444 -375.086372)
			(xy 171.31988 -375.095556) (xy 171.326377 -375.11274) (xy 171.332144 -375.1199) (xy 171.354041 -375.145538)
			(xy 171.392133 -375.201175) (xy 171.423285 -375.260975) (xy 171.44705 -375.324075) (xy 171.463085 -375.389568)
			(xy 171.471159 -375.45651) (xy 171.471156 -375.523938) (xy 171.463076 -375.590879) (xy 171.447036 -375.656371)
			(xy 171.423266 -375.719469) (xy 171.392108 -375.779266) (xy 171.354012 -375.8349) (xy 171.332144 -375.860564)
			(xy 171.326331 -375.867697) (xy 171.319828 -375.884897) (xy 171.319444 -375.894092) (xy 171.319444 -376.386344)
			(xy 171.319845 -376.395532) (xy 171.326366 -376.412716) (xy 171.332144 -376.419872) (xy 171.354014 -376.445533)
			(xy 171.392106 -376.501167) (xy 171.42326 -376.560963) (xy 171.447026 -376.624061) (xy 171.463063 -376.689551)
			(xy 171.47114 -376.75649) (xy 171.47114 -376.756551) (xy 174.749179 -376.756551) (xy 174.757223 -376.689728)
			(xy 174.773195 -376.624346) (xy 174.796868 -376.561342) (xy 174.8279 -376.501619) (xy 174.865848 -376.446032)
			(xy 174.887636 -376.42038) (xy 174.893428 -376.413232) (xy 174.899945 -376.396043) (xy 174.900336 -376.386852)
			(xy 174.900336 -375.893584) (xy 174.899926 -375.884397) (xy 174.893411 -375.867213) (xy 174.887636 -375.860056)
			(xy 174.86588 -375.834378) (xy 174.82793 -375.778795) (xy 174.796896 -375.719075) (xy 174.773222 -375.656074)
			(xy 174.757246 -375.590695) (xy 174.7492 -375.523875) (xy 174.749197 -375.456573) (xy 174.757238 -375.389752)
			(xy 174.773207 -375.324372) (xy 174.796876 -375.261369) (xy 174.827906 -375.201646) (xy 174.865851 -375.14606)
			(xy 174.887636 -375.120408) (xy 174.893416 -375.113251) (xy 174.89994 -375.096069) (xy 174.900336 -375.08688)
			(xy 174.900336 -374.928638) (xy 174.900795 -374.918469) (xy 174.908567 -374.899676) (xy 174.922942 -374.88529)
			(xy 174.941729 -374.877503) (xy 174.951898 -374.877076) (xy 175.668178 -374.877076) (xy 175.678353 -374.877483)
			(xy 175.697154 -374.885268) (xy 175.711541 -374.899659) (xy 175.71932 -374.918463) (xy 175.71974 -374.928638)
			(xy 175.71974 -375.08688) (xy 175.720173 -375.096064) (xy 175.726672 -375.113248) (xy 175.73244 -375.120408)
			(xy 175.75426 -375.146034) (xy 175.792209 -375.201624) (xy 175.823242 -375.261351) (xy 175.846914 -375.324359)
			(xy 175.862886 -375.389744) (xy 175.870928 -375.45657) (xy 175.870925 -375.523878) (xy 175.862877 -375.590703)
			(xy 175.8469 -375.656087) (xy 175.823223 -375.719093) (xy 175.792185 -375.778818) (xy 175.754231 -375.834404)
			(xy 175.73244 -375.860056) (xy 175.72663 -375.867191) (xy 175.720125 -375.88439) (xy 175.71974 -375.893584)
			(xy 175.71974 -376.386852) (xy 175.720186 -376.396035) (xy 175.726676 -376.413219) (xy 175.73244 -376.42038)
			(xy 175.754232 -376.446029) (xy 175.792182 -376.501615) (xy 175.823216 -376.561339) (xy 175.84689 -376.624344)
			(xy 175.862863 -376.689727) (xy 175.870907 -376.75655) (xy 175.870907 -376.823856) (xy 175.862862 -376.890679)
			(xy 175.846888 -376.956062) (xy 175.823214 -377.019066) (xy 175.792179 -377.07879) (xy 175.754228 -377.134376)
			(xy 175.73244 -377.160028) (xy 175.726642 -377.167172) (xy 175.72013 -377.184364) (xy 175.71974 -377.193556)
			(xy 175.71974 -377.35129) (xy 175.719328 -377.361464) (xy 175.711542 -377.380262) (xy 175.697152 -377.394648)
			(xy 175.678352 -377.40243) (xy 175.668178 -377.402852) (xy 174.951898 -377.402852) (xy 174.941725 -377.402438)
			(xy 174.922928 -377.39465) (xy 174.908543 -377.380262) (xy 174.90076 -377.361463) (xy 174.900336 -377.35129)
			(xy 174.900336 -377.193556) (xy 174.899939 -377.184368) (xy 174.893415 -377.167184) (xy 174.887636 -377.160028)
			(xy 174.865852 -377.134373) (xy 174.827903 -377.078787) (xy 174.79687 -377.019063) (xy 174.773197 -376.956059)
			(xy 174.757224 -376.890678) (xy 174.74918 -376.823855) (xy 174.749179 -376.756551) (xy 171.47114 -376.756551)
			(xy 171.471139 -376.823916) (xy 171.463062 -376.890855) (xy 171.447024 -376.956345) (xy 171.423257 -377.019442)
			(xy 171.392103 -377.079238) (xy 171.35401 -377.134872) (xy 171.332144 -377.160536) (xy 171.326343 -377.167678)
			(xy 171.319832 -377.184871) (xy 171.319444 -377.194064) (xy 171.319444 -377.35129) (xy 171.318965 -377.361418)
			(xy 171.311237 -377.380142) (xy 171.296948 -377.394499) (xy 171.278262 -377.402316) (xy 171.268136 -377.402852)
			(xy 170.551856 -377.402852) (xy 170.541706 -377.402415) (xy 170.522962 -377.394615) (xy 170.508642 -377.380224)
			(xy 170.500935 -377.361442) (xy 170.500548 -377.35129) (xy 170.500548 -377.194064) (xy 170.500144 -377.184876)
			(xy 170.493625 -377.167693) (xy 170.487848 -377.160536) (xy 170.465986 -377.134868) (xy 170.427894 -377.079235)
			(xy 170.396741 -377.01944) (xy 170.372974 -376.956343) (xy 170.356937 -376.890854) (xy 170.34886 -376.823915)
			(xy 167.070813 -376.823915) (xy 167.062775 -376.890679) (xy 167.046801 -376.956061) (xy 167.023128 -377.019066)
			(xy 166.992094 -377.07879) (xy 166.954144 -377.134376) (xy 166.932356 -377.160028) (xy 166.92656 -377.167173)
			(xy 166.920046 -377.184364) (xy 166.919656 -377.193556) (xy 166.919656 -377.35129) (xy 166.919228 -377.361462)
			(xy 166.911445 -377.380257) (xy 166.897061 -377.394643) (xy 166.878266 -377.402427) (xy 166.868094 -377.402852)
			(xy 166.151814 -377.402852) (xy 166.141642 -377.402425) (xy 166.122846 -377.394642) (xy 166.10846 -377.380258)
			(xy 166.100676 -377.361462) (xy 166.100252 -377.35129) (xy 166.100252 -377.193556) (xy 166.099851 -377.184368)
			(xy 166.09333 -377.167185) (xy 166.087552 -377.160028) (xy 166.065768 -377.134373) (xy 166.027818 -377.078787)
			(xy 165.996784 -377.019064) (xy 165.97311 -376.95606) (xy 165.957137 -376.890678) (xy 165.949092 -376.823855)
			(xy 162.671051 -376.823855) (xy 162.671051 -376.823915) (xy 162.662974 -376.890855) (xy 162.646937 -376.956344)
			(xy 162.623171 -377.019442) (xy 162.592017 -377.079238) (xy 162.553926 -377.134871) (xy 162.53206 -377.160536)
			(xy 162.526261 -377.167679) (xy 162.519749 -377.184871) (xy 162.51936 -377.194064) (xy 162.51936 -377.35129)
			(xy 162.518865 -377.361416) (xy 162.511141 -377.380137) (xy 162.496857 -377.394494) (xy 162.478175 -377.402313)
			(xy 162.468052 -377.402852) (xy 161.751772 -377.402852) (xy 161.741623 -377.402402) (xy 161.72288 -377.394607)
			(xy 161.708559 -377.38022) (xy 161.700851 -377.361441) (xy 161.700464 -377.35129) (xy 161.700464 -377.194064)
			(xy 161.700057 -377.184877) (xy 161.69354 -377.167693) (xy 161.687764 -377.160536) (xy 161.665905 -377.134867)
			(xy 161.627819 -377.079232) (xy 161.59667 -377.019436) (xy 161.572907 -376.95634) (xy 161.556872 -376.890852)
			(xy 161.548797 -376.823914) (xy 161.548796 -376.756492) (xy 131.870991 -376.756492) (xy 131.870998 -376.75655)
			(xy 131.870998 -376.823856) (xy 131.862953 -376.890679) (xy 131.846979 -376.956062) (xy 131.823304 -377.019067)
			(xy 131.792268 -377.07879) (xy 131.754317 -377.134376) (xy 131.732528 -377.160028) (xy 131.726728 -377.167171)
			(xy 131.720218 -377.184363) (xy 131.719828 -377.193556) (xy 131.719828 -377.35129) (xy 131.719427 -377.361465)
			(xy 131.711639 -377.380266) (xy 131.697246 -377.394653) (xy 131.678441 -377.402432) (xy 131.668266 -377.402852)
			(xy 130.951986 -377.402852) (xy 130.941826 -377.402378) (xy 130.923055 -377.394597) (xy 130.90869 -377.380225)
			(xy 130.900918 -377.36145) (xy 130.900424 -377.35129) (xy 130.900424 -377.193556) (xy 130.90003 -377.184367)
			(xy 130.893504 -377.167183) (xy 130.887724 -377.160028) (xy 130.865941 -377.134372) (xy 130.827993 -377.078786)
			(xy 130.79696 -377.019063) (xy 130.773288 -376.956059) (xy 130.757315 -376.890677) (xy 130.749271 -376.823855)
			(xy 130.74927 -376.756551) (xy 127.471206 -376.756551) (xy 127.471205 -376.823915) (xy 127.46313 -376.890853)
			(xy 127.447095 -376.956342) (xy 127.423332 -377.019438) (xy 127.392182 -377.079235) (xy 127.354095 -377.13487)
			(xy 127.332232 -377.160536) (xy 127.326429 -377.167677) (xy 127.31992 -377.184871) (xy 127.319532 -377.194064)
			(xy 127.319532 -377.35129) (xy 127.319064 -377.36142) (xy 127.311335 -377.380146) (xy 127.297042 -377.394503)
			(xy 127.278351 -377.402318) (xy 127.268224 -377.402852) (xy 126.551944 -377.402852) (xy 126.541799 -377.402343)
			(xy 126.523058 -377.394572) (xy 126.508735 -377.380202) (xy 126.501024 -377.361436) (xy 126.500636 -377.35129)
			(xy 126.500636 -377.194064) (xy 126.500235 -377.184876) (xy 126.493714 -377.167692) (xy 126.487936 -377.160536)
			(xy 126.466075 -377.134868) (xy 126.427984 -377.079235) (xy 126.396831 -377.019439) (xy 126.373065 -376.956343)
			(xy 126.357028 -376.890854) (xy 126.348951 -376.823915) (xy 123.070903 -376.823915) (xy 123.062865 -376.890679)
			(xy 123.046891 -376.956062) (xy 123.023217 -377.019066) (xy 122.992183 -377.07879) (xy 122.954232 -377.134376)
			(xy 122.932444 -377.160028) (xy 122.926646 -377.167172) (xy 122.920134 -377.184364) (xy 122.919744 -377.193556)
			(xy 122.919744 -377.35129) (xy 122.919328 -377.361463) (xy 122.911543 -377.380261) (xy 122.897154 -377.394647)
			(xy 122.878355 -377.402429) (xy 122.868182 -377.402852) (xy 122.151902 -377.402852) (xy 122.141729 -377.402434)
			(xy 122.122933 -377.394648) (xy 122.108547 -377.380261) (xy 122.100764 -377.361463) (xy 122.10034 -377.35129)
			(xy 122.10034 -377.193556) (xy 122.099942 -377.184368) (xy 122.093419 -377.167184) (xy 122.08764 -377.160028)
			(xy 122.065856 -377.134373) (xy 122.027907 -377.078787) (xy 121.996873 -377.019064) (xy 121.9732 -376.95606)
			(xy 121.957227 -376.890678) (xy 121.949183 -376.823855) (xy 121.949182 -376.756551) (xy 118.671143 -376.756551)
			(xy 118.671142 -376.823916) (xy 118.663065 -376.890855) (xy 118.647028 -376.956345) (xy 118.623261 -377.019442)
			(xy 118.592107 -377.079238) (xy 118.554014 -377.134872) (xy 118.532148 -377.160536) (xy 118.526347 -377.167678)
			(xy 118.519836 -377.184871) (xy 118.519448 -377.194064) (xy 118.519448 -377.35129) (xy 118.518965 -377.361418)
			(xy 118.511238 -377.380141) (xy 118.496951 -377.394498) (xy 118.478265 -377.402315) (xy 118.46814 -377.402852)
			(xy 117.75186 -377.402852) (xy 117.74171 -377.402412) (xy 117.722967 -377.394613) (xy 117.708647 -377.380223)
			(xy 117.700939 -377.361442) (xy 117.700552 -377.35129) (xy 117.700552 -377.194064) (xy 117.700147 -377.184876)
			(xy 117.693628 -377.167693) (xy 117.687852 -377.160536) (xy 117.66599 -377.134868) (xy 117.627898 -377.079235)
			(xy 117.596744 -377.01944) (xy 117.572977 -376.956343) (xy 117.55694 -376.890854) (xy 117.548863 -376.823915)
			(xy 87.871087 -376.823915) (xy 87.863011 -376.890853) (xy 87.846976 -376.956342) (xy 87.823211 -377.019439)
			(xy 87.792061 -377.079236) (xy 87.753972 -377.134871) (xy 87.732108 -377.160536) (xy 87.726315 -377.167684)
			(xy 87.719798 -377.184872) (xy 87.719408 -377.194064) (xy 87.719408 -377.35129) (xy 87.718867 -377.36141)
			(xy 87.711151 -377.380122) (xy 87.696882 -377.394477) (xy 87.678217 -377.402305) (xy 87.6681 -377.402852)
			(xy 86.95182 -377.402852) (xy 86.941674 -377.402363) (xy 86.922932 -377.394584) (xy 86.908609 -377.380209)
			(xy 86.9009 -377.361438) (xy 86.900512 -377.35129) (xy 86.900512 -377.194064) (xy 86.900117 -377.184875)
			(xy 86.893592 -377.167691) (xy 86.887812 -377.160536) (xy 86.865952 -377.134868) (xy 86.827862 -377.079234)
			(xy 86.79671 -377.019438) (xy 86.772945 -376.956342) (xy 86.756909 -376.890853) (xy 86.748833 -376.823915)
			(xy 83.470785 -376.823915) (xy 83.462747 -376.89068) (xy 83.446772 -376.956063) (xy 83.423097 -377.019067)
			(xy 83.392061 -377.078791) (xy 83.354109 -377.134376) (xy 83.33232 -377.160028) (xy 83.326531 -377.167179)
			(xy 83.320011 -377.184365) (xy 83.31962 -377.193556) (xy 83.31962 -377.35129) (xy 83.319227 -377.361466)
			(xy 83.311438 -377.380269) (xy 83.297042 -377.394655) (xy 83.278234 -377.402433) (xy 83.268058 -377.402852)
			(xy 82.551778 -377.402852) (xy 82.541618 -377.402385) (xy 82.522846 -377.394601) (xy 82.508481 -377.380227)
			(xy 82.500709 -377.361451) (xy 82.500216 -377.35129) (xy 82.500216 -377.193556) (xy 82.499823 -377.184367)
			(xy 82.493297 -377.167183) (xy 82.487516 -377.160028) (xy 82.465733 -377.134372) (xy 82.427785 -377.078786)
			(xy 82.396753 -377.019063) (xy 82.373081 -376.956059) (xy 82.357109 -376.890677) (xy 82.349065 -376.823855)
			(xy 82.349064 -376.756551) (xy 79.071 -376.756551) (xy 79.070999 -376.823915) (xy 79.062924 -376.890853)
			(xy 79.046888 -376.956342) (xy 79.023125 -377.019439) (xy 78.991975 -377.079235) (xy 78.953887 -377.13487)
			(xy 78.932024 -377.160536) (xy 78.926232 -377.167685) (xy 78.919714 -377.184872) (xy 78.919324 -377.194064)
			(xy 78.919324 -377.35129) (xy 78.918864 -377.36142) (xy 78.911133 -377.380148) (xy 78.896838 -377.394506)
			(xy 78.878144 -377.402319) (xy 78.868016 -377.402852) (xy 78.151736 -377.402852) (xy 78.141591 -377.40235)
			(xy 78.122849 -377.394576) (xy 78.108526 -377.380204) (xy 78.100816 -377.361437) (xy 78.100428 -377.35129)
			(xy 78.100428 -377.194064) (xy 78.100029 -377.184876) (xy 78.093507 -377.167692) (xy 78.087728 -377.160536)
			(xy 78.065867 -377.134868) (xy 78.027776 -377.079235) (xy 77.996624 -377.019439) (xy 77.972858 -376.956342)
			(xy 77.956822 -376.890853) (xy 77.948745 -376.823915) (xy 74.670697 -376.823915) (xy 74.662659 -376.890679)
			(xy 74.646685 -376.956062) (xy 74.623011 -377.019067) (xy 74.591976 -377.07879) (xy 74.554025 -377.134376)
			(xy 74.532236 -377.160028) (xy 74.526437 -377.167171) (xy 74.519926 -377.184364) (xy 74.519536 -377.193556)
			(xy 74.519536 -377.35129) (xy 74.519127 -377.361464) (xy 74.511341 -377.380264) (xy 74.49695 -377.39465)
			(xy 74.478148 -377.402431) (xy 74.467974 -377.402852) (xy 73.751694 -377.402852) (xy 73.741521 -377.402441)
			(xy 73.722724 -377.394652) (xy 73.708339 -377.380263) (xy 73.700556 -377.361463) (xy 73.700132 -377.35129)
			(xy 73.700132 -377.193556) (xy 73.699736 -377.184367) (xy 73.693212 -377.167184) (xy 73.687432 -377.160028)
			(xy 73.665648 -377.134373) (xy 73.6277 -377.078786) (xy 73.596667 -377.019063) (xy 73.572994 -376.956059)
			(xy 73.557021 -376.890677) (xy 73.548977 -376.823855) (xy 73.548976 -376.756551) (xy 48.270947 -376.756551)
			(xy 48.270947 -376.823855) (xy 48.262903 -376.890678) (xy 48.24693 -376.95606) (xy 48.223258 -377.019064)
			(xy 48.192226 -377.078788) (xy 48.154279 -377.134375) (xy 48.132492 -377.160028) (xy 48.1267 -377.167176)
			(xy 48.120183 -377.184365) (xy 48.119792 -377.193556) (xy 48.119792 -377.351544) (xy 48.119414 -377.361702)
			(xy 48.111603 -377.380457) (xy 48.097193 -377.394779) (xy 48.07839 -377.402476) (xy 48.06823 -377.402852)
			(xy 47.35195 -377.402852) (xy 47.341825 -377.402332) (xy 47.323104 -377.394619) (xy 47.308746 -377.380343)
			(xy 47.300926 -377.361666) (xy 47.300388 -377.351544) (xy 47.300388 -377.193556) (xy 47.300002 -377.184366)
			(xy 47.293472 -377.167182) (xy 47.287688 -377.160028) (xy 47.265903 -377.134373) (xy 47.227951 -377.078788)
			(xy 47.196914 -377.019066) (xy 47.173239 -376.956061) (xy 47.157265 -376.890679) (xy 47.149219 -376.823856)
			(xy 43.871178 -376.823856) (xy 43.871178 -376.823915) (xy 43.863102 -376.890854) (xy 43.847066 -376.956343)
			(xy 43.823301 -377.01944) (xy 43.79215 -377.079236) (xy 43.75406 -377.134871) (xy 43.732196 -377.160536)
			(xy 43.726401 -377.167682) (xy 43.719886 -377.184872) (xy 43.719496 -377.194064) (xy 43.719496 -377.35129)
			(xy 43.718966 -377.361412) (xy 43.711248 -377.380126) (xy 43.696976 -377.394481) (xy 43.678307 -377.402307)
			(xy 43.668188 -377.402852) (xy 42.951908 -377.402852) (xy 42.941761 -377.402373) (xy 42.923019 -377.39459)
			(xy 42.908697 -377.380211) (xy 42.900988 -377.361439) (xy 42.9006 -377.35129) (xy 42.9006 -377.194064)
			(xy 42.900207 -377.184875) (xy 42.893682 -377.167691) (xy 42.8879 -377.160536) (xy 42.86604 -377.134868)
			(xy 42.827951 -377.079233) (xy 42.7968 -377.019438) (xy 42.773036 -376.956341) (xy 42.757 -376.890853)
			(xy 42.748924 -376.823915) (xy 39.470876 -376.823915) (xy 39.462838 -376.89068) (xy 39.446863 -376.956063)
			(xy 39.423187 -377.019068) (xy 39.39215 -377.078791) (xy 39.354198 -377.134377) (xy 39.332408 -377.160028)
			(xy 39.326618 -377.167178) (xy 39.320099 -377.184365) (xy 39.319708 -377.193556) (xy 39.319708 -377.35129)
			(xy 39.31916 -377.361441) (xy 39.311397 -377.380202) (xy 39.297049 -377.394566) (xy 39.278297 -377.402349)
			(xy 39.268146 -377.402852) (xy 38.551866 -377.402852) (xy 38.541705 -377.402394) (xy 38.522933 -377.394607)
			(xy 38.508569 -377.38023) (xy 38.500797 -377.361452) (xy 38.500304 -377.35129) (xy 38.500304 -377.193556)
			(xy 38.499914 -377.184367) (xy 38.493386 -377.167183) (xy 38.487604 -377.160028) (xy 38.465821 -377.134372)
			(xy 38.427875 -377.078785) (xy 38.396843 -377.019062) (xy 38.373172 -376.956058) (xy 38.357199 -376.890677)
			(xy 38.349156 -376.823855) (xy 38.349155 -376.756551) (xy 35.071091 -376.756551) (xy 35.07109 -376.823915)
			(xy 35.063014 -376.890853) (xy 35.046979 -376.956342) (xy 35.023215 -377.019439) (xy 34.992064 -377.079236)
			(xy 34.953976 -377.134871) (xy 34.932112 -377.160536) (xy 34.926319 -377.167684) (xy 34.919802 -377.184872)
			(xy 34.919412 -377.194064) (xy 34.919412 -377.35129) (xy 34.918867 -377.36141) (xy 34.911152 -377.380121)
			(xy 34.896884 -377.394476) (xy 34.878221 -377.402304) (xy 34.868104 -377.402852) (xy 34.151824 -377.402852)
			(xy 34.141678 -377.40236) (xy 34.122936 -377.394582) (xy 34.108614 -377.380208) (xy 34.100904 -377.361438)
			(xy 34.100516 -377.35129) (xy 34.100516 -377.194064) (xy 34.10012 -377.184875) (xy 34.093596 -377.167691)
			(xy 34.087816 -377.160536) (xy 34.065955 -377.134868) (xy 34.027866 -377.079234) (xy 33.996714 -377.019438)
			(xy 33.972949 -376.956342) (xy 33.956912 -376.890853) (xy 33.948836 -376.823915) (xy 30.670788 -376.823915)
			(xy 30.66275 -376.89068) (xy 30.646775 -376.956062) (xy 30.6231 -377.019067) (xy 30.592065 -377.078791)
			(xy 30.554113 -377.134376) (xy 30.532324 -377.160028) (xy 30.526536 -377.167179) (xy 30.520015 -377.184365)
			(xy 30.519624 -377.193556) (xy 30.519624 -377.35129) (xy 30.519227 -377.361466) (xy 30.511438 -377.380267)
			(xy 30.497044 -377.394654) (xy 30.478238 -377.402433) (xy 30.468062 -377.402852) (xy 29.751782 -377.402852)
			(xy 29.741622 -377.402381) (xy 29.72285 -377.394599) (xy 29.708485 -377.380226) (xy 29.700713 -377.36145)
			(xy 29.70022 -377.35129) (xy 29.70022 -377.193556) (xy 29.699827 -377.184367) (xy 29.693301 -377.167183)
			(xy 29.68752 -377.160028) (xy 29.665737 -377.134372) (xy 29.627789 -377.078786) (xy 29.596757 -377.019063)
			(xy 29.573084 -376.956059) (xy 29.557112 -376.890677) (xy 29.549068 -376.823855) (xy 29.549067 -376.756551)
			(xy 1.524 -376.756551) (xy 1.524 -378.323793) (xy 27.348888 -378.323793) (xy 27.34889 -378.256368)
			(xy 27.356968 -378.189428) (xy 27.373006 -378.123938) (xy 27.396772 -378.06084) (xy 27.427925 -378.001043)
			(xy 27.466015 -377.945408) (xy 27.48788 -377.919742) (xy 27.493681 -377.9126) (xy 27.500194 -377.895407)
			(xy 27.50058 -377.886214) (xy 27.50058 -377.728734) (xy 27.501056 -377.718605) (xy 27.50878 -377.699877)
			(xy 27.52307 -377.685518) (xy 27.541761 -377.677705) (xy 27.551888 -377.677172) (xy 28.268168 -377.677172)
			(xy 28.278317 -377.677647) (xy 28.297063 -377.685427) (xy 28.311387 -377.699807) (xy 28.319092 -377.718584)
			(xy 28.319476 -377.728734) (xy 28.319476 -377.886214) (xy 28.319885 -377.895401) (xy 28.3264 -377.912585)
			(xy 28.332176 -377.919742) (xy 28.354015 -377.945428) (xy 28.392106 -378.001059) (xy 28.42326 -378.060852)
			(xy 28.447026 -378.123946) (xy 28.463064 -378.189433) (xy 28.471143 -378.256369) (xy 28.471145 -378.323734)
			(xy 31.749183 -378.323734) (xy 31.749186 -378.256427) (xy 31.757233 -378.189602) (xy 31.773209 -378.124218)
			(xy 31.796886 -378.061212) (xy 31.827924 -378.001488) (xy 31.865878 -377.945902) (xy 31.887668 -377.92025)
			(xy 31.893477 -377.913114) (xy 31.899982 -377.895916) (xy 31.900368 -377.886722) (xy 31.900368 -377.728734)
			(xy 31.900793 -377.718561) (xy 31.908572 -377.699761) (xy 31.922958 -377.685374) (xy 31.941757 -377.677593)
			(xy 31.95193 -377.677172) (xy 32.66821 -377.677172) (xy 32.678386 -377.677557) (xy 32.697188 -377.685351)
			(xy 32.711574 -377.699749) (xy 32.719352 -377.718557) (xy 32.719772 -377.728734) (xy 32.719772 -377.886722)
			(xy 32.720178 -377.89591) (xy 32.726695 -377.913094) (xy 32.732472 -377.92025) (xy 32.754234 -377.945924)
			(xy 32.792182 -378.001507) (xy 32.823216 -378.061228) (xy 32.84689 -378.12423) (xy 32.862864 -378.189609)
			(xy 32.87091 -378.256429) (xy 32.870913 -378.323732) (xy 32.870906 -378.323793) (xy 36.148976 -378.323793)
			(xy 36.148978 -378.256368) (xy 36.157056 -378.189429) (xy 36.173093 -378.123939) (xy 36.196859 -378.060841)
			(xy 36.22801 -378.001044) (xy 36.2661 -377.945408) (xy 36.287964 -377.919742) (xy 36.293775 -377.912608)
			(xy 36.300279 -377.895409) (xy 36.300664 -377.886214) (xy 36.300664 -377.728734) (xy 36.301155 -377.718607)
			(xy 36.308876 -377.699882) (xy 36.323162 -377.685523) (xy 36.341847 -377.677707) (xy 36.351972 -377.677172)
			(xy 37.068252 -377.677172) (xy 37.0784 -377.67766) (xy 37.097145 -377.685435) (xy 37.11147 -377.699811)
			(xy 37.119176 -377.718585) (xy 37.11956 -377.728734) (xy 37.11956 -377.886214) (xy 37.119972 -377.895401)
			(xy 37.126485 -377.912585) (xy 37.13226 -377.919742) (xy 37.1541 -377.945428) (xy 37.192192 -378.001058)
			(xy 37.223346 -378.060851) (xy 37.247113 -378.123946) (xy 37.263152 -378.189433) (xy 37.27123 -378.256369)
			(xy 37.271233 -378.323792) (xy 37.271233 -378.323794) (xy 40.548742 -378.323794) (xy 40.548744 -378.256367)
			(xy 40.556824 -378.189426) (xy 40.572863 -378.123935) (xy 40.596633 -378.060837) (xy 40.627789 -378.00104)
			(xy 40.665885 -377.945406) (xy 40.687752 -377.919742) (xy 40.693562 -377.912607) (xy 40.700067 -377.895408)
			(xy 40.700452 -377.886214) (xy 40.700452 -377.728734) (xy 40.700955 -377.718608) (xy 40.708674 -377.699885)
			(xy 40.722955 -377.685528) (xy 40.741637 -377.677709) (xy 40.75176 -377.677172) (xy 41.46804 -377.677172)
			(xy 41.478193 -377.677588) (xy 41.496941 -377.685392) (xy 41.511262 -377.699789) (xy 41.518965 -377.718579)
			(xy 41.519348 -377.728734) (xy 41.519348 -377.886214) (xy 41.519763 -377.8954) (xy 41.526275 -377.912584)
			(xy 41.532048 -377.919742) (xy 41.553888 -377.945427) (xy 41.591981 -378.001058) (xy 41.623136 -378.060851)
			(xy 41.646904 -378.123945) (xy 41.662943 -378.189432) (xy 41.671021 -378.256369) (xy 41.671024 -378.323792)
			(xy 41.671024 -378.323793) (xy 71.348797 -378.323793) (xy 71.348799 -378.256368) (xy 71.356877 -378.189428)
			(xy 71.372915 -378.123937) (xy 71.396682 -378.060839) (xy 71.427835 -378.001042) (xy 71.465927 -377.945407)
			(xy 71.487792 -377.919742) (xy 71.493595 -377.912601) (xy 71.500106 -377.895407) (xy 71.500492 -377.886214)
			(xy 71.500492 -377.728734) (xy 71.501053 -377.718615) (xy 71.508761 -377.699904) (xy 71.523024 -377.685548)
			(xy 71.541685 -377.67772) (xy 71.5518 -377.677172) (xy 72.26808 -377.677172) (xy 72.278229 -377.677637)
			(xy 72.296976 -377.685421) (xy 72.311299 -377.699804) (xy 72.319005 -377.718583) (xy 72.319388 -377.728734)
			(xy 72.319388 -377.886214) (xy 72.319794 -377.895402) (xy 72.326311 -377.912586) (xy 72.332088 -377.919742)
			(xy 72.353927 -377.945428) (xy 72.392017 -378.001059) (xy 72.42317 -378.060853) (xy 72.446936 -378.123947)
			(xy 72.462973 -378.189433) (xy 72.471052 -378.25637) (xy 72.471054 -378.323734) (xy 75.749092 -378.323734)
			(xy 75.749095 -378.256427) (xy 75.757142 -378.189601) (xy 75.773119 -378.124217) (xy 75.796796 -378.061212)
			(xy 75.827835 -378.001488) (xy 75.86579 -377.945902) (xy 75.88758 -377.92025) (xy 75.893378 -377.913106)
			(xy 75.899892 -377.895915) (xy 75.90028 -377.886722) (xy 75.90028 -377.728734) (xy 75.900693 -377.718559)
			(xy 75.908474 -377.699757) (xy 75.922864 -377.68537) (xy 75.941667 -377.677591) (xy 75.951842 -377.677172)
			(xy 76.668122 -377.677172) (xy 76.678299 -377.677547) (xy 76.697101 -377.685345) (xy 76.711486 -377.699746)
			(xy 76.719264 -377.718556) (xy 76.719684 -377.728734) (xy 76.719684 -377.886722) (xy 76.720087 -377.89591)
			(xy 76.726606 -377.913094) (xy 76.732384 -377.92025) (xy 76.754146 -377.945923) (xy 76.792094 -378.001507)
			(xy 76.823127 -378.061228) (xy 76.8468 -378.12423) (xy 76.862774 -378.189609) (xy 76.87082 -378.256429)
			(xy 76.870822 -378.323732) (xy 76.870815 -378.323793) (xy 80.148885 -378.323793) (xy 80.148887 -378.256368)
			(xy 80.156965 -378.189428) (xy 80.173003 -378.123938) (xy 80.196769 -378.06084) (xy 80.227921 -378.001043)
			(xy 80.266011 -377.945408) (xy 80.287876 -377.919742) (xy 80.293677 -377.9126) (xy 80.30019 -377.895407)
			(xy 80.300576 -377.886214) (xy 80.300576 -377.728734) (xy 80.301056 -377.718605) (xy 80.308779 -377.699878)
			(xy 80.323068 -377.685519) (xy 80.341758 -377.677705) (xy 80.351884 -377.677172) (xy 81.068164 -377.677172)
			(xy 81.078312 -377.677651) (xy 81.097058 -377.685429) (xy 81.111382 -377.699808) (xy 81.119088 -377.718584)
			(xy 81.119472 -377.728734) (xy 81.119472 -377.886214) (xy 81.119882 -377.895401) (xy 81.126396 -377.912585)
			(xy 81.132172 -377.919742) (xy 81.154011 -377.945428) (xy 81.192103 -378.001059) (xy 81.223256 -378.060852)
			(xy 81.247023 -378.123946) (xy 81.263061 -378.189433) (xy 81.27114 -378.256369) (xy 81.271142 -378.323792)
			(xy 81.271142 -378.323793) (xy 84.548676 -378.323793) (xy 84.548678 -378.256368) (xy 84.556756 -378.189429)
			(xy 84.572793 -378.123939) (xy 84.596559 -378.060841) (xy 84.62771 -378.001044) (xy 84.6658 -377.945408)
			(xy 84.687664 -377.919742) (xy 84.693475 -377.912608) (xy 84.699979 -377.895409) (xy 84.700364 -377.886214)
			(xy 84.700364 -377.728734) (xy 84.700855 -377.718607) (xy 84.708576 -377.699882) (xy 84.722862 -377.685523)
			(xy 84.741547 -377.677707) (xy 84.751672 -377.677172) (xy 85.467952 -377.677172) (xy 85.4781 -377.67766)
			(xy 85.496845 -377.685435) (xy 85.51117 -377.699811) (xy 85.518876 -377.718585) (xy 85.51926 -377.728734)
			(xy 85.51926 -377.886214) (xy 85.519672 -377.895401) (xy 85.526185 -377.912585) (xy 85.53196 -377.919742)
			(xy 85.5538 -377.945428) (xy 85.591892 -378.001058) (xy 85.623046 -378.060851) (xy 85.646813 -378.123946)
			(xy 85.662852 -378.189433) (xy 85.67093 -378.256369) (xy 85.670933 -378.323734) (xy 115.349234 -378.323734)
			(xy 115.349237 -378.256427) (xy 115.357283 -378.189603) (xy 115.373258 -378.12422) (xy 115.396932 -378.061215)
			(xy 115.427966 -378.00149) (xy 115.465916 -377.945903) (xy 115.487704 -377.92025) (xy 115.493505 -377.913108)
			(xy 115.500017 -377.895915) (xy 115.500404 -377.886722) (xy 115.500404 -377.728734) (xy 115.500961 -377.718583)
			(xy 115.508717 -377.699821) (xy 115.523064 -377.685456) (xy 115.541815 -377.677674) (xy 115.551966 -377.677172)
			(xy 116.268246 -377.677172) (xy 116.278411 -377.677597) (xy 116.297188 -377.685393) (xy 116.311552 -377.69978)
			(xy 116.319319 -377.718568) (xy 116.319808 -377.728734) (xy 116.319808 -377.886722) (xy 116.320206 -377.895911)
			(xy 116.326728 -377.913095) (xy 116.332508 -377.92025) (xy 116.354272 -377.945922) (xy 116.392225 -378.001505)
			(xy 116.423262 -378.061225) (xy 116.446939 -378.124227) (xy 116.462915 -378.189607) (xy 116.470962 -378.256428)
			(xy 116.470964 -378.323732) (xy 116.470957 -378.323793) (xy 119.749003 -378.323793) (xy 119.749005 -378.256368)
			(xy 119.757084 -378.189428) (xy 119.773122 -378.123937) (xy 119.796889 -378.060839) (xy 119.828043 -378.001042)
			(xy 119.866134 -377.945407) (xy 119.888 -377.919742) (xy 119.893804 -377.912602) (xy 119.900314 -377.895407)
			(xy 119.9007 -377.886214) (xy 119.9007 -377.728734) (xy 119.901253 -377.718614) (xy 119.908963 -377.699902)
			(xy 119.923228 -377.685546) (xy 119.941892 -377.677718) (xy 119.952008 -377.677172) (xy 120.668288 -377.677172)
			(xy 120.678438 -377.677631) (xy 120.697185 -377.685417) (xy 120.711507 -377.699802) (xy 120.719213 -377.718582)
			(xy 120.719596 -377.728734) (xy 120.719596 -377.886214) (xy 120.72 -377.895402) (xy 120.726518 -377.912586)
			(xy 120.732296 -377.919742) (xy 120.754135 -377.945428) (xy 120.792224 -378.00106) (xy 120.823376 -378.060853)
			(xy 120.847142 -378.123947) (xy 120.86318 -378.189434) (xy 120.871258 -378.25637) (xy 120.87126 -378.323734)
			(xy 124.149298 -378.323734) (xy 124.149301 -378.256426) (xy 124.157348 -378.189601) (xy 124.173325 -378.124217)
			(xy 124.197003 -378.061211) (xy 124.228042 -378.001487) (xy 124.265997 -377.945902) (xy 124.287788 -377.92025)
			(xy 124.293587 -377.913106) (xy 124.300101 -377.895915) (xy 124.300488 -377.886722) (xy 124.300488 -377.728734)
			(xy 124.300893 -377.718558) (xy 124.308676 -377.699755) (xy 124.323068 -377.685367) (xy 124.341874 -377.67759)
			(xy 124.35205 -377.677172) (xy 125.06833 -377.677172) (xy 125.078508 -377.67754) (xy 125.09731 -377.685341)
			(xy 125.111695 -377.699744) (xy 125.119473 -377.718556) (xy 125.119892 -377.728734) (xy 125.119892 -377.886722)
			(xy 125.120293 -377.89591) (xy 125.126813 -377.913094) (xy 125.132592 -377.92025) (xy 125.154353 -377.945924)
			(xy 125.192301 -378.001508) (xy 125.223334 -378.061229) (xy 125.247006 -378.12423) (xy 125.26298 -378.189609)
			(xy 125.271026 -378.256429) (xy 125.271028 -378.323732) (xy 125.271028 -378.323734) (xy 128.549089 -378.323734)
			(xy 128.549092 -378.256427) (xy 128.557139 -378.189602) (xy 128.573116 -378.124218) (xy 128.596793 -378.061212)
			(xy 128.627831 -378.001488) (xy 128.665786 -377.945902) (xy 128.687576 -377.92025) (xy 128.693374 -377.913105)
			(xy 128.699888 -377.895915) (xy 128.700276 -377.886722) (xy 128.700276 -377.728734) (xy 128.700693 -377.71856)
			(xy 128.708474 -377.699759) (xy 128.722862 -377.685371) (xy 128.741664 -377.677592) (xy 128.751838 -377.677172)
			(xy 129.468118 -377.677172) (xy 129.478295 -377.67755) (xy 129.497097 -377.685347) (xy 129.511482 -377.699747)
			(xy 129.51926 -377.718557) (xy 129.51968 -377.728734) (xy 129.51968 -377.886722) (xy 129.520084 -377.89591)
			(xy 129.526602 -377.913094) (xy 129.53238 -377.92025) (xy 129.554142 -377.945923) (xy 129.59209 -378.001507)
			(xy 129.623123 -378.061228) (xy 129.646797 -378.12423) (xy 129.662771 -378.189609) (xy 129.670817 -378.256429)
			(xy 129.670819 -378.323732) (xy 129.670819 -378.323734) (xy 159.349143 -378.323734) (xy 159.349146 -378.256427)
			(xy 159.357192 -378.189603) (xy 159.373167 -378.12422) (xy 159.396842 -378.061214) (xy 159.427877 -378.00149)
			(xy 159.465827 -377.945902) (xy 159.487616 -377.92025) (xy 159.493418 -377.913109) (xy 159.499929 -377.895915)
			(xy 159.500316 -377.886722) (xy 159.500316 -377.728734) (xy 159.500791 -377.718567) (xy 159.508561 -377.699778)
			(xy 159.522931 -377.685392) (xy 159.541712 -377.677602) (xy 159.551878 -377.677172) (xy 160.268158 -377.677172)
			(xy 160.278331 -377.677599) (xy 160.297131 -377.685377) (xy 160.311519 -377.699762) (xy 160.319299 -377.718561)
			(xy 160.31972 -377.728734) (xy 160.31972 -377.886722) (xy 160.320115 -377.895911) (xy 160.326639 -377.913095)
			(xy 160.33242 -377.92025) (xy 160.354183 -377.945923) (xy 160.392136 -378.001505) (xy 160.423172 -378.061226)
			(xy 160.446848 -378.124227) (xy 160.462824 -378.189608) (xy 160.470871 -378.256429) (xy 160.470874 -378.323732)
			(xy 160.470867 -378.323793) (xy 163.748912 -378.323793) (xy 163.748914 -378.256367) (xy 163.756993 -378.189427)
			(xy 163.773031 -378.123937) (xy 163.796799 -378.060839) (xy 163.827953 -378.001042) (xy 163.866046 -377.945407)
			(xy 163.887912 -377.919742) (xy 163.893717 -377.912603) (xy 163.900226 -377.895408) (xy 163.900612 -377.886214)
			(xy 163.900612 -377.728734) (xy 163.901154 -377.718613) (xy 163.908865 -377.699898) (xy 163.923134 -377.685542)
			(xy 163.941802 -377.677716) (xy 163.95192 -377.677172) (xy 164.6682 -377.677172) (xy 164.678351 -377.677621)
			(xy 164.697098 -377.685411) (xy 164.71142 -377.699799) (xy 164.719125 -377.718582) (xy 164.719508 -377.728734)
			(xy 164.719508 -377.886214) (xy 164.71991 -377.895402) (xy 164.726429 -377.912586) (xy 164.732208 -377.919742)
			(xy 164.754046 -377.945428) (xy 164.792135 -378.00106) (xy 164.823286 -378.060853) (xy 164.847052 -378.123948)
			(xy 164.863089 -378.189434) (xy 164.871167 -378.25637) (xy 164.871169 -378.323734) (xy 168.149231 -378.323734)
			(xy 168.149234 -378.256427) (xy 168.15728 -378.189604) (xy 168.173254 -378.12422) (xy 168.196928 -378.061215)
			(xy 168.227963 -378.00149) (xy 168.265912 -377.945903) (xy 168.2877 -377.92025) (xy 168.2935 -377.913107)
			(xy 168.300013 -377.895915) (xy 168.3004 -377.886722) (xy 168.3004 -377.728734) (xy 168.30096 -377.718583)
			(xy 168.308717 -377.699822) (xy 168.323062 -377.685457) (xy 168.341812 -377.677675) (xy 168.351962 -377.677172)
			(xy 169.068242 -377.677172) (xy 169.078407 -377.6776) (xy 169.097183 -377.685394) (xy 169.111548 -377.699781)
			(xy 169.119315 -377.718569) (xy 169.119804 -377.728734) (xy 169.119804 -377.886722) (xy 169.120203 -377.89591)
			(xy 169.126724 -377.913095) (xy 169.132504 -377.92025) (xy 169.154265 -377.945924) (xy 169.192212 -378.001508)
			(xy 169.223244 -378.061229) (xy 169.246916 -378.124231) (xy 169.26289 -378.18961) (xy 169.270935 -378.256429)
			(xy 169.270937 -378.323732) (xy 169.270937 -378.323734) (xy 172.548998 -378.323734) (xy 172.549001 -378.256426)
			(xy 172.557048 -378.189601) (xy 172.573025 -378.124217) (xy 172.596703 -378.061211) (xy 172.627742 -378.001487)
			(xy 172.665697 -377.945902) (xy 172.687488 -377.92025) (xy 172.693287 -377.913106) (xy 172.699801 -377.895915)
			(xy 172.700188 -377.886722) (xy 172.700188 -377.728734) (xy 172.700593 -377.718558) (xy 172.708376 -377.699755)
			(xy 172.722768 -377.685367) (xy 172.741574 -377.67759) (xy 172.75175 -377.677172) (xy 173.46803 -377.677172)
			(xy 173.478208 -377.67754) (xy 173.49701 -377.685341) (xy 173.511395 -377.699744) (xy 173.519173 -377.718556)
			(xy 173.519592 -377.728734) (xy 173.519592 -377.886722) (xy 173.519993 -377.89591) (xy 173.526513 -377.913094)
			(xy 173.532292 -377.92025) (xy 173.554053 -377.945924) (xy 173.592001 -378.001508) (xy 173.623034 -378.061229)
			(xy 173.646706 -378.12423) (xy 173.66268 -378.189609) (xy 173.670726 -378.256429) (xy 173.670728 -378.323732)
			(xy 173.662687 -378.390552) (xy 173.646718 -378.455932) (xy 173.623049 -378.518936) (xy 173.592021 -378.578659)
			(xy 173.554077 -378.634245) (xy 173.532292 -378.659898) (xy 173.526513 -378.667056) (xy 173.519988 -378.684237)
			(xy 173.519592 -378.693426) (xy 173.519592 -378.70003) (xy 190.444636 -378.70003) (xy 190.448637 -378.494991)
			(xy 190.460635 -378.290263) (xy 190.480612 -378.08616) (xy 190.508537 -377.882992) (xy 190.544367 -377.681068)
			(xy 190.588049 -377.480695) (xy 190.639515 -377.28218) (xy 190.698687 -377.085823) (xy 190.765475 -376.891925)
			(xy 190.839777 -376.70078) (xy 190.92148 -376.51268) (xy 191.010461 -376.327911) (xy 191.106582 -376.146754)
			(xy 191.209698 -375.969485) (xy 191.319652 -375.796375) (xy 191.436277 -375.627686) (xy 191.559394 -375.463676)
			(xy 191.688817 -375.304594) (xy 191.824347 -375.150683) (xy 191.96578 -375.002177) (xy 192.112899 -374.859302)
			(xy 192.26548 -374.722277) (xy 192.423292 -374.591308) (xy 192.586093 -374.466597) (xy 192.753636 -374.348332)
			(xy 192.925665 -374.236694) (xy 193.10192 -374.131853) (xy 193.28213 -374.033969) (xy 193.466022 -373.94319)
			(xy 193.653317 -373.859656) (xy 193.843727 -373.783492) (xy 194.036965 -373.714815) (xy 194.232735 -373.65373)
			(xy 194.430739 -373.60033) (xy 194.630675 -373.554696) (xy 194.83224 -373.516897) (xy 195.035126 -373.486991)
			(xy 195.239025 -373.465024) (xy 195.443625 -373.451029) (xy 195.648616 -373.445028) (xy 195.853685 -373.447028)
			(xy 196.058519 -373.457029) (xy 196.262807 -373.475013) (xy 196.466239 -373.500955) (xy 196.668503 -373.534813)
			(xy 196.869292 -373.576538) (xy 197.0683 -373.626064) (xy 197.265224 -373.683318) (xy 197.459765 -373.748211)
			(xy 197.651626 -373.820645) (xy 197.840514 -373.900509) (xy 198.026143 -373.987683) (xy 198.208229 -374.082032)
			(xy 198.386495 -374.183414) (xy 198.56067 -374.291674) (xy 198.730489 -374.406647) (xy 198.895692 -374.528158)
			(xy 199.056029 -374.656022) (xy 199.211255 -374.790045) (xy 199.361134 -374.930022) (xy 199.505437 -375.07574)
			(xy 199.643945 -375.226977) (xy 199.776447 -375.383504) (xy 199.902741 -375.54508) (xy 200.022634 -375.711461)
			(xy 200.135945 -375.882393) (xy 200.242501 -376.057616) (xy 200.342138 -376.236863) (xy 200.434707 -376.419861)
			(xy 200.520065 -376.606332) (xy 200.598083 -376.79599) (xy 200.668641 -376.988548) (xy 200.731633 -377.183713)
			(xy 200.786963 -377.381187) (xy 200.834546 -377.580669) (xy 200.874309 -377.781855) (xy 200.906193 -377.98444)
			(xy 200.930148 -378.188114) (xy 200.946139 -378.392568) (xy 200.95414 -378.597491) (xy 200.95464 -378.70003)
			(xy 200.95414 -378.802569) (xy 200.946139 -379.007492) (xy 200.930148 -379.211946) (xy 200.906193 -379.41562)
			(xy 200.874309 -379.618205) (xy 200.834546 -379.819391) (xy 200.786963 -380.018873) (xy 200.731633 -380.216347)
			(xy 200.668641 -380.411512) (xy 200.598083 -380.60407) (xy 200.520065 -380.793728) (xy 200.434707 -380.980199)
			(xy 200.342138 -381.163197) (xy 200.242501 -381.342444) (xy 200.135945 -381.517667) (xy 200.022634 -381.688599)
			(xy 199.902741 -381.85498) (xy 199.776447 -382.016556) (xy 199.643945 -382.173083) (xy 199.505437 -382.32432)
			(xy 199.361134 -382.470038) (xy 199.211255 -382.610015) (xy 199.056029 -382.744038) (xy 198.895692 -382.871902)
			(xy 198.730489 -382.993413) (xy 198.56067 -383.108386) (xy 198.386495 -383.216646) (xy 198.208229 -383.318028)
			(xy 198.026143 -383.412377) (xy 197.840514 -383.499551) (xy 197.651626 -383.579415) (xy 197.459765 -383.651849)
			(xy 197.265224 -383.716742) (xy 197.0683 -383.773996) (xy 196.869292 -383.823522) (xy 196.668503 -383.865247)
			(xy 196.466239 -383.899105) (xy 196.262807 -383.925047) (xy 196.058519 -383.943031) (xy 195.853685 -383.953032)
			(xy 195.648616 -383.955032) (xy 195.443625 -383.949031) (xy 195.239025 -383.935036) (xy 195.035126 -383.913069)
			(xy 194.83224 -383.883163) (xy 194.630675 -383.845364) (xy 194.430739 -383.79973) (xy 194.232735 -383.74633)
			(xy 194.036965 -383.685245) (xy 193.843727 -383.616568) (xy 193.653317 -383.540404) (xy 193.466022 -383.45687)
			(xy 193.28213 -383.366091) (xy 193.10192 -383.268207) (xy 192.925665 -383.163366) (xy 192.753636 -383.051728)
			(xy 192.586093 -382.933463) (xy 192.423292 -382.808752) (xy 192.26548 -382.677783) (xy 192.112899 -382.540758)
			(xy 191.96578 -382.397883) (xy 191.824347 -382.249377) (xy 191.688817 -382.095466) (xy 191.559394 -381.936384)
			(xy 191.436277 -381.772374) (xy 191.319652 -381.603685) (xy 191.209698 -381.430575) (xy 191.106582 -381.253306)
			(xy 191.010461 -381.072149) (xy 190.92148 -380.88738) (xy 190.839777 -380.69928) (xy 190.765475 -380.508135)
			(xy 190.698687 -380.314237) (xy 190.639515 -380.11788) (xy 190.588049 -379.919365) (xy 190.544367 -379.718992)
			(xy 190.508537 -379.517068) (xy 190.480612 -379.3139) (xy 190.460635 -379.109797) (xy 190.448637 -378.905069)
			(xy 190.444636 -378.70003) (xy 173.519592 -378.70003) (xy 173.519592 -379.186694) (xy 173.520007 -379.195881)
			(xy 173.526518 -379.213065) (xy 173.532292 -379.220222) (xy 173.554124 -379.245837) (xy 173.592069 -379.30143)
			(xy 173.623099 -379.361159) (xy 173.646768 -379.424168) (xy 173.662737 -379.489554) (xy 173.670777 -379.556381)
			(xy 173.670772 -379.623689) (xy 173.662724 -379.690514) (xy 173.646747 -379.755898) (xy 173.623071 -379.818905)
			(xy 173.592034 -379.87863) (xy 173.554082 -379.934217) (xy 173.532292 -379.95987) (xy 173.526482 -379.967006)
			(xy 173.519976 -379.984204) (xy 173.519592 -379.993398) (xy 173.519592 -380.151386) (xy 173.519056 -380.161539)
			(xy 173.511292 -380.180302) (xy 173.496939 -380.194667) (xy 173.478183 -380.202447) (xy 173.46803 -380.202948)
			(xy 172.75175 -380.202948) (xy 172.74158 -380.202495) (xy 172.722784 -380.194724) (xy 172.708396 -380.180347)
			(xy 172.700612 -380.161556) (xy 172.700188 -380.151386) (xy 172.700188 -379.993398) (xy 172.699781 -379.98421)
			(xy 172.693266 -379.967026) (xy 172.687488 -379.95987) (xy 172.665744 -379.934181) (xy 172.627791 -379.878601)
			(xy 172.596753 -379.818883) (xy 172.573075 -379.755883) (xy 172.557097 -379.690505) (xy 172.549049 -379.623686)
			(xy 172.549045 -379.556383) (xy 172.557085 -379.489563) (xy 172.573055 -379.424183) (xy 172.596724 -379.36118)
			(xy 172.627755 -379.301458) (xy 172.665702 -379.245873) (xy 172.687488 -379.220222) (xy 172.693299 -379.213087)
			(xy 172.699805 -379.195889) (xy 172.700188 -379.186694) (xy 172.700188 -378.693426) (xy 172.699768 -378.68424)
			(xy 172.693262 -378.667055) (xy 172.687488 -378.659898) (xy 172.665673 -378.634268) (xy 172.627722 -378.578679)
			(xy 172.596687 -378.518953) (xy 172.573014 -378.455946) (xy 172.557041 -378.39056) (xy 172.548998 -378.323734)
			(xy 169.270937 -378.323734) (xy 169.262897 -378.390552) (xy 169.246928 -378.455932) (xy 169.22326 -378.518935)
			(xy 169.192232 -378.578658) (xy 169.154289 -378.634245) (xy 169.132504 -378.659898) (xy 169.126726 -378.667057)
			(xy 169.1202 -378.684237) (xy 169.119804 -378.693426) (xy 169.119804 -379.186694) (xy 169.120216 -379.195881)
			(xy 169.126728 -379.213065) (xy 169.132504 -379.220222) (xy 169.154336 -379.245838) (xy 169.19228 -379.30143)
			(xy 169.223309 -379.361159) (xy 169.246977 -379.424169) (xy 169.262946 -379.489555) (xy 169.270986 -379.556381)
			(xy 169.270982 -379.623689) (xy 169.262933 -379.690513) (xy 169.246957 -379.755898) (xy 169.223281 -379.818904)
			(xy 169.192245 -379.878629) (xy 169.154293 -379.934217) (xy 169.132504 -379.95987) (xy 169.126696 -379.967007)
			(xy 169.120188 -379.984204) (xy 169.119804 -379.993398) (xy 169.119804 -380.151386) (xy 169.119256 -380.161538)
			(xy 169.111494 -380.180299) (xy 169.097146 -380.194663) (xy 169.078393 -380.202445) (xy 169.068242 -380.202948)
			(xy 168.351962 -380.202948) (xy 168.3418 -380.202497) (xy 168.323027 -380.194708) (xy 168.308663 -380.180329)
			(xy 168.300892 -380.161548) (xy 168.3004 -380.151386) (xy 168.3004 -379.993398) (xy 168.299991 -379.984211)
			(xy 168.293476 -379.967026) (xy 168.2877 -379.95987) (xy 168.265959 -379.93418) (xy 168.228011 -379.878598)
			(xy 168.196978 -379.818879) (xy 168.173304 -379.75588) (xy 168.157329 -379.690503) (xy 168.149282 -379.623685)
			(xy 168.149278 -379.556384) (xy 168.157317 -379.489565) (xy 168.173284 -379.424186) (xy 168.19695 -379.361184)
			(xy 168.227975 -379.301461) (xy 168.265916 -379.245875) (xy 168.2877 -379.220222) (xy 168.293512 -379.213088)
			(xy 168.300018 -379.195889) (xy 168.3004 -379.186694) (xy 168.3004 -378.693426) (xy 168.299977 -378.68424)
			(xy 168.293472 -378.667056) (xy 168.2877 -378.659898) (xy 168.265888 -378.634266) (xy 168.227942 -378.578676)
			(xy 168.196912 -378.518949) (xy 168.173243 -378.455942) (xy 168.157273 -378.390558) (xy 168.149231 -378.323734)
			(xy 164.871169 -378.323734) (xy 164.871169 -378.323791) (xy 164.863096 -378.390728) (xy 164.847063 -378.456215)
			(xy 164.823302 -378.519311) (xy 164.792155 -378.579106) (xy 164.75407 -378.634741) (xy 164.732208 -378.660406)
			(xy 164.726427 -378.667563) (xy 164.719903 -378.684744) (xy 164.719508 -378.693934) (xy 164.719508 -379.186186)
			(xy 164.719923 -379.195373) (xy 164.726433 -379.212557) (xy 164.732208 -379.219714) (xy 164.754117 -379.245342)
			(xy 164.792204 -379.300982) (xy 164.823352 -379.360784) (xy 164.847113 -379.423885) (xy 164.863145 -379.489379)
			(xy 164.871217 -379.556321) (xy 164.871213 -379.623748) (xy 164.863133 -379.690689) (xy 164.847093 -379.756181)
			(xy 164.823324 -379.81928) (xy 164.792168 -379.879077) (xy 164.754074 -379.934713) (xy 164.732208 -379.960378)
			(xy 164.726397 -379.967513) (xy 164.719891 -379.984711) (xy 164.719508 -379.993906) (xy 164.719508 -380.151386)
			(xy 164.718963 -380.161506) (xy 164.711249 -380.180218) (xy 164.696981 -380.194573) (xy 164.678317 -380.202401)
			(xy 164.6682 -380.202948) (xy 163.95192 -380.202948) (xy 163.941773 -380.202463) (xy 163.92303 -380.194683)
			(xy 163.908708 -380.180306) (xy 163.900999 -380.161534) (xy 163.900612 -380.151386) (xy 163.900612 -379.993906)
			(xy 163.900196 -379.98472) (xy 163.893686 -379.967535) (xy 163.887912 -379.960378) (xy 163.866093 -379.934676)
			(xy 163.828002 -379.879047) (xy 163.796849 -379.819256) (xy 163.773081 -379.756164) (xy 163.757042 -379.690679)
			(xy 163.748963 -379.623745) (xy 163.748958 -379.556324) (xy 163.75703 -379.489389) (xy 163.773061 -379.423902)
			(xy 163.79682 -379.360807) (xy 163.827966 -379.301013) (xy 163.86605 -379.245379) (xy 163.887912 -379.219714)
			(xy 163.893729 -379.212583) (xy 163.900231 -379.195382) (xy 163.900612 -379.186186) (xy 163.900612 -378.693934)
			(xy 163.900183 -378.684749) (xy 163.893682 -378.667565) (xy 163.887912 -378.660406) (xy 163.866022 -378.634762)
			(xy 163.827933 -378.579125) (xy 163.796783 -378.519326) (xy 163.77302 -378.456226) (xy 163.756986 -378.390734)
			(xy 163.748912 -378.323793) (xy 160.470867 -378.323793) (xy 160.462831 -378.390554) (xy 160.44686 -378.455935)
			(xy 160.423188 -378.518939) (xy 160.392156 -378.578661) (xy 160.354207 -378.634246) (xy 160.33242 -378.659898)
			(xy 160.326644 -378.667058) (xy 160.320116 -378.684237) (xy 160.31972 -378.693426) (xy 160.31972 -379.186694)
			(xy 160.320129 -379.195881) (xy 160.326643 -379.213066) (xy 160.33242 -379.220222) (xy 160.354254 -379.245836)
			(xy 160.392205 -379.301427) (xy 160.423238 -379.361156) (xy 160.44691 -379.424165) (xy 160.462881 -379.489552)
			(xy 160.470922 -379.55638) (xy 160.470918 -379.623689) (xy 160.462869 -379.690516) (xy 160.44689 -379.755901)
			(xy 160.42321 -379.818908) (xy 160.392169 -379.878632) (xy 160.354212 -379.934219) (xy 160.33242 -379.95987)
			(xy 160.326614 -379.967008) (xy 160.320104 -379.984204) (xy 160.31972 -379.993398) (xy 160.31972 -380.151386)
			(xy 160.319324 -380.161562) (xy 160.311536 -380.180364) (xy 160.297141 -380.194751) (xy 160.278334 -380.202529)
			(xy 160.268158 -380.202948) (xy 159.551878 -380.202948) (xy 159.541717 -380.202484) (xy 159.522945 -380.1947)
			(xy 159.50858 -380.180325) (xy 159.500808 -380.161547) (xy 159.500316 -380.151386) (xy 159.500316 -379.993398)
			(xy 159.499903 -379.984211) (xy 159.493391 -379.967027) (xy 159.487616 -379.95987) (xy 159.465874 -379.93418)
			(xy 159.427926 -379.878599) (xy 159.396892 -379.81888) (xy 159.373217 -379.75588) (xy 159.357242 -379.690503)
			(xy 159.349195 -379.623685) (xy 159.34919 -379.556384) (xy 159.35723 -379.489565) (xy 159.373197 -379.424186)
			(xy 159.396864 -379.361183) (xy 159.42789 -379.301461) (xy 159.465832 -379.245875) (xy 159.487616 -379.220222)
			(xy 159.49343 -379.213089) (xy 159.499934 -379.195889) (xy 159.500316 -379.186694) (xy 159.500316 -378.693426)
			(xy 159.49989 -378.684241) (xy 159.493387 -378.667056) (xy 159.487616 -378.659898) (xy 159.465803 -378.634267)
			(xy 159.427857 -378.578677) (xy 159.396826 -378.51895) (xy 159.373156 -378.455943) (xy 159.357185 -378.390558)
			(xy 159.349143 -378.323734) (xy 129.670819 -378.323734) (xy 129.662778 -378.390552) (xy 129.646808 -378.455933)
			(xy 129.623139 -378.518936) (xy 129.59211 -378.578659) (xy 129.554166 -378.634246) (xy 129.53238 -378.659898)
			(xy 129.526599 -378.667054) (xy 129.520076 -378.684236) (xy 129.51968 -378.693426) (xy 129.51968 -379.186694)
			(xy 129.520098 -379.19588) (xy 129.526607 -379.213064) (xy 129.53238 -379.220222) (xy 129.554212 -379.245837)
			(xy 129.592159 -379.301429) (xy 129.623189 -379.361158) (xy 129.646858 -379.424168) (xy 129.662827 -379.489554)
			(xy 129.670868 -379.55638) (xy 129.670863 -379.623689) (xy 129.662815 -379.690514) (xy 129.646838 -379.755899)
			(xy 129.623161 -379.818905) (xy 129.592123 -379.87863) (xy 129.55417 -379.934218) (xy 129.53238 -379.95987)
			(xy 129.526569 -379.967005) (xy 129.520064 -379.984203) (xy 129.51968 -379.993398) (xy 129.51968 -380.151386)
			(xy 129.519156 -380.161541) (xy 129.511389 -380.180306) (xy 129.497033 -380.194671) (xy 129.478272 -380.202449)
			(xy 129.468118 -380.202948) (xy 128.751838 -380.202948) (xy 128.741667 -380.202505) (xy 128.722871 -380.19473)
			(xy 128.708484 -380.18035) (xy 128.7007 -380.161557) (xy 128.700276 -380.151386) (xy 128.700276 -379.993398)
			(xy 128.699872 -379.98421) (xy 128.693355 -379.967025) (xy 128.687576 -379.95987) (xy 128.665832 -379.934181)
			(xy 128.62788 -379.878601) (xy 128.596842 -379.818883) (xy 128.573165 -379.755883) (xy 128.557188 -379.690505)
			(xy 128.54914 -379.623686) (xy 128.549136 -379.556384) (xy 128.557176 -379.489563) (xy 128.573145 -379.424183)
			(xy 128.596814 -379.361181) (xy 128.627844 -379.301459) (xy 128.66579 -379.245874) (xy 128.687576 -379.220222)
			(xy 128.693385 -379.213086) (xy 128.699893 -379.195889) (xy 128.700276 -379.186694) (xy 128.700276 -378.693426)
			(xy 128.699859 -378.684239) (xy 128.693351 -378.667055) (xy 128.687576 -378.659898) (xy 128.665762 -378.634267)
			(xy 128.627811 -378.578679) (xy 128.596777 -378.518952) (xy 128.573104 -378.455945) (xy 128.557132 -378.39056)
			(xy 128.549089 -378.323734) (xy 125.271028 -378.323734) (xy 125.262987 -378.390552) (xy 125.247018 -378.455932)
			(xy 125.223349 -378.518936) (xy 125.192321 -378.578659) (xy 125.154377 -378.634245) (xy 125.132592 -378.659898)
			(xy 125.126813 -378.667056) (xy 125.120288 -378.684237) (xy 125.119892 -378.693426) (xy 125.119892 -379.186694)
			(xy 125.120307 -379.195881) (xy 125.126818 -379.213065) (xy 125.132592 -379.220222) (xy 125.154424 -379.245837)
			(xy 125.192369 -379.30143) (xy 125.223399 -379.361159) (xy 125.247068 -379.424168) (xy 125.263037 -379.489554)
			(xy 125.271077 -379.556381) (xy 125.271072 -379.623689) (xy 125.263024 -379.690514) (xy 125.247047 -379.755898)
			(xy 125.223371 -379.818905) (xy 125.192334 -379.87863) (xy 125.154382 -379.934217) (xy 125.132592 -379.95987)
			(xy 125.126782 -379.967006) (xy 125.120276 -379.984204) (xy 125.119892 -379.993398) (xy 125.119892 -380.151386)
			(xy 125.119356 -380.161539) (xy 125.111592 -380.180302) (xy 125.097239 -380.194667) (xy 125.078483 -380.202447)
			(xy 125.06833 -380.202948) (xy 124.35205 -380.202948) (xy 124.34188 -380.202495) (xy 124.323084 -380.194724)
			(xy 124.308696 -380.180347) (xy 124.300912 -380.161556) (xy 124.300488 -380.151386) (xy 124.300488 -379.993398)
			(xy 124.300081 -379.98421) (xy 124.293566 -379.967026) (xy 124.287788 -379.95987) (xy 124.266044 -379.934181)
			(xy 124.228091 -379.878601) (xy 124.197053 -379.818883) (xy 124.173375 -379.755883) (xy 124.157397 -379.690505)
			(xy 124.149349 -379.623686) (xy 124.149345 -379.556383) (xy 124.157385 -379.489563) (xy 124.173355 -379.424183)
			(xy 124.197024 -379.36118) (xy 124.228055 -379.301458) (xy 124.266002 -379.245873) (xy 124.287788 -379.220222)
			(xy 124.293599 -379.213087) (xy 124.300105 -379.195889) (xy 124.300488 -379.186694) (xy 124.300488 -378.693426)
			(xy 124.300068 -378.68424) (xy 124.293562 -378.667055) (xy 124.287788 -378.659898) (xy 124.265973 -378.634268)
			(xy 124.228022 -378.578679) (xy 124.196987 -378.518953) (xy 124.173314 -378.455946) (xy 124.157341 -378.39056)
			(xy 124.149298 -378.323734) (xy 120.87126 -378.323734) (xy 120.87126 -378.323791) (xy 120.863187 -378.390728)
			(xy 120.847154 -378.456216) (xy 120.823392 -378.519311) (xy 120.792244 -378.579107) (xy 120.754159 -378.634741)
			(xy 120.732296 -378.660406) (xy 120.726514 -378.667561) (xy 120.719991 -378.684744) (xy 120.719596 -378.693934)
			(xy 120.719596 -379.186186) (xy 120.720014 -379.195372) (xy 120.726522 -379.212557) (xy 120.732296 -379.219714)
			(xy 120.754205 -379.245342) (xy 120.792293 -379.300982) (xy 120.823442 -379.360783) (xy 120.847204 -379.423885)
			(xy 120.863236 -379.489378) (xy 120.871308 -379.556321) (xy 120.871304 -379.623748) (xy 120.863224 -379.69069)
			(xy 120.847183 -379.756181) (xy 120.823414 -379.81928) (xy 120.792257 -379.879078) (xy 120.754163 -379.934713)
			(xy 120.732296 -379.960378) (xy 120.726483 -379.967512) (xy 120.719978 -379.984711) (xy 120.719596 -379.993906)
			(xy 120.719596 -380.151386) (xy 120.719063 -380.161507) (xy 120.711347 -380.180221) (xy 120.697075 -380.194577)
			(xy 120.678406 -380.202403) (xy 120.668288 -380.202948) (xy 119.952008 -380.202948) (xy 119.94186 -380.202473)
			(xy 119.923117 -380.194689) (xy 119.908795 -380.180309) (xy 119.901087 -380.161535) (xy 119.9007 -380.151386)
			(xy 119.9007 -379.993906) (xy 119.900287 -379.984719) (xy 119.893775 -379.967535) (xy 119.888 -379.960378)
			(xy 119.866181 -379.934675) (xy 119.828091 -379.879046) (xy 119.796938 -379.819255) (xy 119.773172 -379.756163)
			(xy 119.757133 -379.690679) (xy 119.749053 -379.623745) (xy 119.749049 -379.556325) (xy 119.757121 -379.489389)
			(xy 119.773151 -379.423903) (xy 119.79691 -379.360808) (xy 119.828056 -379.301013) (xy 119.866139 -379.245379)
			(xy 119.888 -379.219714) (xy 119.893816 -379.212582) (xy 119.900319 -379.195381) (xy 119.9007 -379.186186)
			(xy 119.9007 -378.693934) (xy 119.900273 -378.684749) (xy 119.893771 -378.667564) (xy 119.888 -378.660406)
			(xy 119.86611 -378.634762) (xy 119.828023 -378.579124) (xy 119.796873 -378.519325) (xy 119.77311 -378.456226)
			(xy 119.757077 -378.390734) (xy 119.749003 -378.323793) (xy 116.470957 -378.323793) (xy 116.462922 -378.390554)
			(xy 116.44695 -378.455936) (xy 116.423278 -378.518939) (xy 116.392245 -378.578662) (xy 116.354296 -378.634247)
			(xy 116.332508 -378.659898) (xy 116.326731 -378.667057) (xy 116.320204 -378.684237) (xy 116.319808 -378.693426)
			(xy 116.319808 -379.186694) (xy 116.320219 -379.195881) (xy 116.326732 -379.213066) (xy 116.332508 -379.220222)
			(xy 116.354343 -379.245836) (xy 116.392293 -379.301427) (xy 116.423328 -379.361155) (xy 116.447 -379.424165)
			(xy 116.462971 -379.489552) (xy 116.471013 -379.55638) (xy 116.471009 -379.623689) (xy 116.462959 -379.690516)
			(xy 116.44698 -379.755901) (xy 116.423299 -379.818908) (xy 116.392258 -379.878633) (xy 116.3543 -379.934219)
			(xy 116.332508 -379.95987) (xy 116.3267 -379.967007) (xy 116.320192 -379.984204) (xy 116.319808 -379.993398)
			(xy 116.319808 -380.151386) (xy 116.319256 -380.161537) (xy 116.311495 -380.180297) (xy 116.297148 -380.194661)
			(xy 116.278397 -380.202445) (xy 116.268246 -380.202948) (xy 115.551966 -380.202948) (xy 115.541804 -380.202494)
			(xy 115.523032 -380.194706) (xy 115.508667 -380.180328) (xy 115.500896 -380.161548) (xy 115.500404 -380.151386)
			(xy 115.500404 -379.993398) (xy 115.499994 -379.984211) (xy 115.49348 -379.967027) (xy 115.487704 -379.95987)
			(xy 115.465963 -379.93418) (xy 115.428015 -379.878598) (xy 115.396981 -379.81888) (xy 115.373307 -379.75588)
			(xy 115.357332 -379.690503) (xy 115.349285 -379.623685) (xy 115.349281 -379.556384) (xy 115.35732 -379.489565)
			(xy 115.373287 -379.424186) (xy 115.396953 -379.361184) (xy 115.427979 -379.301461) (xy 115.46592 -379.245875)
			(xy 115.487704 -379.220222) (xy 115.493517 -379.213088) (xy 115.500022 -379.195889) (xy 115.500404 -379.186694)
			(xy 115.500404 -378.693426) (xy 115.49998 -378.68424) (xy 115.493476 -378.667056) (xy 115.487704 -378.659898)
			(xy 115.465892 -378.634266) (xy 115.427946 -378.578676) (xy 115.396916 -378.518949) (xy 115.373246 -378.455942)
			(xy 115.357276 -378.390558) (xy 115.349234 -378.323734) (xy 85.670933 -378.323734) (xy 85.670933 -378.323792)
			(xy 85.662859 -378.390729) (xy 85.646825 -378.456217) (xy 85.623062 -378.519313) (xy 85.591912 -378.579108)
			(xy 85.553824 -378.634741) (xy 85.53196 -378.660406) (xy 85.526173 -378.667558) (xy 85.519654 -378.684743)
			(xy 85.51926 -378.693934) (xy 85.51926 -379.186186) (xy 85.519686 -379.195371) (xy 85.526189 -379.212555)
			(xy 85.53196 -379.219714) (xy 85.553871 -379.245341) (xy 85.591961 -379.30098) (xy 85.623111 -379.360781)
			(xy 85.646875 -379.423883) (xy 85.662908 -379.489377) (xy 85.670981 -379.55632) (xy 85.670977 -379.623749)
			(xy 85.662896 -379.690691) (xy 85.646854 -379.756183) (xy 85.623083 -379.819282) (xy 85.591925 -379.879079)
			(xy 85.553828 -379.934713) (xy 85.53196 -379.960378) (xy 85.526143 -379.967508) (xy 85.519641 -379.98471)
			(xy 85.51926 -379.993906) (xy 85.51926 -380.151386) (xy 85.518762 -380.161512) (xy 85.511039 -380.180233)
			(xy 85.496756 -380.194589) (xy 85.478075 -380.202409) (xy 85.467952 -380.202948) (xy 84.751672 -380.202948)
			(xy 84.741522 -380.202502) (xy 84.722778 -380.194707) (xy 84.708458 -380.180318) (xy 84.70075 -380.161538)
			(xy 84.700364 -380.151386) (xy 84.700364 -379.993906) (xy 84.699937 -379.984721) (xy 84.693433 -379.967537)
			(xy 84.687664 -379.960378) (xy 84.665846 -379.934675) (xy 84.627759 -379.879045) (xy 84.596608 -379.819254)
			(xy 84.572843 -379.756162) (xy 84.556805 -379.690678) (xy 84.548726 -379.623744) (xy 84.548722 -379.556325)
			(xy 84.556793 -379.48939) (xy 84.572822 -379.423904) (xy 84.59658 -379.36081) (xy 84.627723 -379.301014)
			(xy 84.665804 -379.24538) (xy 84.687664 -379.219714) (xy 84.693487 -379.212588) (xy 84.699984 -379.195383)
			(xy 84.700364 -379.186186) (xy 84.700364 -378.693934) (xy 84.699923 -378.68475) (xy 84.693429 -378.667566)
			(xy 84.687664 -378.660406) (xy 84.665776 -378.634761) (xy 84.62769 -378.579123) (xy 84.596543 -378.519324)
			(xy 84.572781 -378.456224) (xy 84.556749 -378.390733) (xy 84.548676 -378.323793) (xy 81.271142 -378.323793)
			(xy 81.263068 -378.390729) (xy 81.247035 -378.456217) (xy 81.223272 -378.519312) (xy 81.192123 -378.579108)
			(xy 81.154035 -378.634741) (xy 81.132172 -378.660406) (xy 81.126387 -378.667559) (xy 81.119866 -378.684744)
			(xy 81.119472 -378.693934) (xy 81.119472 -379.186186) (xy 81.119895 -379.195372) (xy 81.126401 -379.212556)
			(xy 81.132172 -379.219714) (xy 81.154082 -379.245341) (xy 81.192171 -379.300981) (xy 81.223322 -379.360782)
			(xy 81.247084 -379.423884) (xy 81.263118 -379.489378) (xy 81.27119 -379.556321) (xy 81.271186 -379.623748)
			(xy 81.263105 -379.69069) (xy 81.247064 -379.756182) (xy 81.223293 -379.819281) (xy 81.192136 -379.879079)
			(xy 81.15404 -379.934713) (xy 81.132172 -379.960378) (xy 81.126356 -379.967509) (xy 81.119854 -379.984711)
			(xy 81.119472 -379.993906) (xy 81.119472 -380.151386) (xy 81.118962 -380.16151) (xy 81.111241 -380.180229)
			(xy 81.096962 -380.194585) (xy 81.078286 -380.202407) (xy 81.068164 -380.202948) (xy 80.351884 -380.202948)
			(xy 80.341735 -380.202493) (xy 80.322991 -380.194701) (xy 80.30867 -380.180315) (xy 80.300962 -380.161537)
			(xy 80.300576 -380.151386) (xy 80.300576 -379.993906) (xy 80.300168 -379.984718) (xy 80.293654 -379.967534)
			(xy 80.287876 -379.960378) (xy 80.266058 -379.934675) (xy 80.22797 -379.879045) (xy 80.196818 -379.819254)
			(xy 80.173052 -379.756162) (xy 80.157015 -379.690678) (xy 80.148935 -379.623744) (xy 80.148931 -379.556325)
			(xy 80.157002 -379.48939) (xy 80.173032 -379.423904) (xy 80.19679 -379.360809) (xy 80.227934 -379.301014)
			(xy 80.266016 -379.24538) (xy 80.287876 -379.219714) (xy 80.293689 -379.21258) (xy 80.300195 -379.195381)
			(xy 80.300576 -379.186186) (xy 80.300576 -378.693934) (xy 80.300155 -378.684748) (xy 80.29365 -378.667563)
			(xy 80.287876 -378.660406) (xy 80.265987 -378.634761) (xy 80.227901 -378.579123) (xy 80.196753 -378.519324)
			(xy 80.172991 -378.456225) (xy 80.156958 -378.390733) (xy 80.148885 -378.323793) (xy 76.870815 -378.323793)
			(xy 76.862781 -378.390552) (xy 76.846812 -378.455933) (xy 76.823143 -378.518936) (xy 76.792114 -378.578659)
			(xy 76.75417 -378.634246) (xy 76.732384 -378.659898) (xy 76.726604 -378.667055) (xy 76.72008 -378.684236)
			(xy 76.719684 -378.693426) (xy 76.719684 -379.186694) (xy 76.720101 -379.19588) (xy 76.72661 -379.213065)
			(xy 76.732384 -379.220222) (xy 76.754216 -379.245837) (xy 76.792162 -379.30143) (xy 76.823192 -379.361158)
			(xy 76.846861 -379.424168) (xy 76.86283 -379.489554) (xy 76.870871 -379.55638) (xy 76.870866 -379.623689)
			(xy 76.862818 -379.690514) (xy 76.846841 -379.755899) (xy 76.823164 -379.818905) (xy 76.792127 -379.87863)
			(xy 76.754174 -379.934218) (xy 76.732384 -379.95987) (xy 76.726573 -379.967005) (xy 76.720068 -379.984203)
			(xy 76.719684 -379.993398) (xy 76.719684 -380.151386) (xy 76.719156 -380.16154) (xy 76.71139 -380.180305)
			(xy 76.697035 -380.19467) (xy 76.678276 -380.202449) (xy 76.668122 -380.202948) (xy 75.951842 -380.202948)
			(xy 75.941671 -380.202501) (xy 75.922875 -380.194728) (xy 75.908488 -380.180349) (xy 75.900704 -380.161556)
			(xy 75.90028 -380.151386) (xy 75.90028 -379.993398) (xy 75.899875 -379.98421) (xy 75.893358 -379.967026)
			(xy 75.88758 -379.95987) (xy 75.865836 -379.934181) (xy 75.827883 -379.878601) (xy 75.796846 -379.818883)
			(xy 75.773169 -379.755883) (xy 75.757191 -379.690505) (xy 75.749143 -379.623686) (xy 75.749139 -379.556383)
			(xy 75.757179 -379.489563) (xy 75.773148 -379.424183) (xy 75.796818 -379.36118) (xy 75.827848 -379.301458)
			(xy 75.865794 -379.245874) (xy 75.88758 -379.220222) (xy 75.89339 -379.213086) (xy 75.899897 -379.195889)
			(xy 75.90028 -379.186694) (xy 75.90028 -378.693426) (xy 75.899862 -378.68424) (xy 75.893354 -378.667055)
			(xy 75.88758 -378.659898) (xy 75.865766 -378.634267) (xy 75.827815 -378.578679) (xy 75.79678 -378.518953)
			(xy 75.773107 -378.455945) (xy 75.757135 -378.39056) (xy 75.749092 -378.323734) (xy 72.471054 -378.323734)
			(xy 72.471054 -378.323791) (xy 72.46298 -378.390728) (xy 72.446947 -378.456216) (xy 72.423186 -378.519312)
			(xy 72.392037 -378.579107) (xy 72.353951 -378.634741) (xy 72.332088 -378.660406) (xy 72.326305 -378.667561)
			(xy 72.319783 -378.684744) (xy 72.319388 -378.693934) (xy 72.319388 -379.186186) (xy 72.319808 -379.195372)
			(xy 72.326315 -379.212556) (xy 72.332088 -379.219714) (xy 72.353998 -379.245342) (xy 72.392086 -379.300981)
			(xy 72.423235 -379.360783) (xy 72.446997 -379.423884) (xy 72.46303 -379.489378) (xy 72.471102 -379.556321)
			(xy 72.471098 -379.623748) (xy 72.463017 -379.69069) (xy 72.446977 -379.756182) (xy 72.423207 -379.819281)
			(xy 72.39205 -379.879078) (xy 72.353955 -379.934713) (xy 72.332088 -379.960378) (xy 72.326274 -379.967511)
			(xy 72.31977 -379.984711) (xy 72.319388 -379.993906) (xy 72.319388 -380.151386) (xy 72.318863 -380.161508)
			(xy 72.311145 -380.180224) (xy 72.296871 -380.19458) (xy 72.278199 -380.202404) (xy 72.26808 -380.202948)
			(xy 71.5518 -380.202948) (xy 71.541652 -380.202479) (xy 71.522909 -380.194693) (xy 71.508587 -380.180311)
			(xy 71.500879 -380.161536) (xy 71.500492 -380.151386) (xy 71.500492 -379.993906) (xy 71.500081 -379.984719)
			(xy 71.493568 -379.967534) (xy 71.487792 -379.960378) (xy 71.465974 -379.934675) (xy 71.427884 -379.879046)
			(xy 71.396732 -379.819255) (xy 71.372965 -379.756163) (xy 71.356927 -379.690678) (xy 71.348847 -379.623744)
			(xy 71.348843 -379.556325) (xy 71.356914 -379.48939) (xy 71.372945 -379.423903) (xy 71.396703 -379.360808)
			(xy 71.427848 -379.301013) (xy 71.465931 -379.245379) (xy 71.487792 -379.219714) (xy 71.493607 -379.212582)
			(xy 71.500111 -379.195381) (xy 71.500492 -379.186186) (xy 71.500492 -378.693934) (xy 71.500067 -378.684748)
			(xy 71.493564 -378.667564) (xy 71.487792 -378.660406) (xy 71.465903 -378.634762) (xy 71.427815 -378.579124)
			(xy 71.396666 -378.519325) (xy 71.372904 -378.456225) (xy 71.35687 -378.390734) (xy 71.348797 -378.323793)
			(xy 41.671024 -378.323793) (xy 41.66295 -378.390729) (xy 41.646915 -378.456218) (xy 41.623152 -378.519314)
			(xy 41.592001 -378.579109) (xy 41.553912 -378.634742) (xy 41.532048 -378.660406) (xy 41.52626 -378.667557)
			(xy 41.519742 -378.684743) (xy 41.519348 -378.693934) (xy 41.519348 -379.186186) (xy 41.519776 -379.195371)
			(xy 41.526279 -379.212555) (xy 41.532048 -379.219714) (xy 41.553959 -379.245341) (xy 41.59205 -379.30098)
			(xy 41.623201 -379.360781) (xy 41.646965 -379.423883) (xy 41.662999 -379.489377) (xy 41.671072 -379.55632)
			(xy 41.671068 -379.623749) (xy 41.662987 -379.690691) (xy 41.646945 -379.756183) (xy 41.623173 -379.819282)
			(xy 41.592014 -379.879079) (xy 41.553917 -379.934714) (xy 41.532048 -379.960378) (xy 41.526229 -379.967507)
			(xy 41.519729 -379.98471) (xy 41.519348 -379.993906) (xy 41.519348 -380.151386) (xy 41.518862 -380.161513)
			(xy 41.511136 -380.180236) (xy 41.49685 -380.194594) (xy 41.478165 -380.202411) (xy 41.46804 -380.202948)
			(xy 40.75176 -380.202948) (xy 40.741609 -380.202512) (xy 40.722865 -380.194712) (xy 40.708545 -380.180321)
			(xy 40.700838 -380.161539) (xy 40.700452 -380.151386) (xy 40.700452 -379.993906) (xy 40.700027 -379.984721)
			(xy 40.693523 -379.967537) (xy 40.687752 -379.960378) (xy 40.665931 -379.934676) (xy 40.627838 -379.879048)
			(xy 40.596682 -379.819258) (xy 40.572913 -379.756165) (xy 40.556873 -379.69068) (xy 40.548793 -379.623745)
			(xy 40.548788 -379.556324) (xy 40.556861 -379.489388) (xy 40.572893 -379.423901) (xy 40.596654 -379.360806)
			(xy 40.627802 -379.301011) (xy 40.665889 -379.245378) (xy 40.687752 -379.219714) (xy 40.693574 -379.212587)
			(xy 40.700072 -379.195382) (xy 40.700452 -379.186186) (xy 40.700452 -378.693934) (xy 40.700014 -378.68475)
			(xy 40.693519 -378.667566) (xy 40.687752 -378.660406) (xy 40.665861 -378.634763) (xy 40.627769 -378.579126)
			(xy 40.596617 -378.519328) (xy 40.572852 -378.456228) (xy 40.556817 -378.390735) (xy 40.548742 -378.323794)
			(xy 37.271233 -378.323794) (xy 37.263159 -378.390729) (xy 37.247125 -378.456217) (xy 37.223362 -378.519313)
			(xy 37.192212 -378.579108) (xy 37.154124 -378.634741) (xy 37.13226 -378.660406) (xy 37.126473 -378.667558)
			(xy 37.119954 -378.684743) (xy 37.11956 -378.693934) (xy 37.11956 -379.186186) (xy 37.119986 -379.195371)
			(xy 37.126489 -379.212555) (xy 37.13226 -379.219714) (xy 37.154171 -379.245341) (xy 37.192261 -379.30098)
			(xy 37.223411 -379.360781) (xy 37.247175 -379.423883) (xy 37.263208 -379.489377) (xy 37.271281 -379.55632)
			(xy 37.271277 -379.623749) (xy 37.263196 -379.690691) (xy 37.247154 -379.756183) (xy 37.223383 -379.819282)
			(xy 37.192225 -379.879079) (xy 37.154128 -379.934713) (xy 37.13226 -379.960378) (xy 37.126443 -379.967508)
			(xy 37.119941 -379.98471) (xy 37.11956 -379.993906) (xy 37.11956 -380.151386) (xy 37.119062 -380.161512)
			(xy 37.111339 -380.180233) (xy 37.097056 -380.194589) (xy 37.078375 -380.202409) (xy 37.068252 -380.202948)
			(xy 36.351972 -380.202948) (xy 36.341822 -380.202502) (xy 36.323078 -380.194707) (xy 36.308758 -380.180318)
			(xy 36.30105 -380.161538) (xy 36.300664 -380.151386) (xy 36.300664 -379.993906) (xy 36.300237 -379.984721)
			(xy 36.293733 -379.967537) (xy 36.287964 -379.960378) (xy 36.266146 -379.934675) (xy 36.228059 -379.879045)
			(xy 36.196908 -379.819254) (xy 36.173143 -379.756162) (xy 36.157105 -379.690678) (xy 36.149026 -379.623744)
			(xy 36.149022 -379.556325) (xy 36.157093 -379.48939) (xy 36.173122 -379.423904) (xy 36.19688 -379.36081)
			(xy 36.228023 -379.301014) (xy 36.266104 -379.24538) (xy 36.287964 -379.219714) (xy 36.293787 -379.212588)
			(xy 36.300284 -379.195383) (xy 36.300664 -379.186186) (xy 36.300664 -378.693934) (xy 36.300223 -378.68475)
			(xy 36.293729 -378.667566) (xy 36.287964 -378.660406) (xy 36.266076 -378.634761) (xy 36.22799 -378.579123)
			(xy 36.196843 -378.519324) (xy 36.173081 -378.456224) (xy 36.157049 -378.390733) (xy 36.148976 -378.323793)
			(xy 32.870906 -378.323793) (xy 32.862871 -378.390552) (xy 32.846902 -378.455933) (xy 32.823232 -378.518936)
			(xy 32.792203 -378.578659) (xy 32.754258 -378.634246) (xy 32.732472 -378.659898) (xy 32.72669 -378.667053)
			(xy 32.720167 -378.684236) (xy 32.719772 -378.693426) (xy 32.719772 -379.186694) (xy 32.720191 -379.19588)
			(xy 32.726699 -379.213064) (xy 32.732472 -379.220222) (xy 32.754305 -379.245837) (xy 32.792251 -379.301429)
			(xy 32.823282 -379.361158) (xy 32.846952 -379.424167) (xy 32.862921 -379.489554) (xy 32.870962 -379.55638)
			(xy 32.870957 -379.623689) (xy 32.862909 -379.690514) (xy 32.846931 -379.755899) (xy 32.823254 -379.818905)
			(xy 32.792216 -379.87863) (xy 32.754262 -379.934218) (xy 32.732472 -379.95987) (xy 32.72666 -379.967004)
			(xy 32.720155 -379.984203) (xy 32.719772 -379.993398) (xy 32.719772 -380.151386) (xy 32.719325 -380.161556)
			(xy 32.711547 -380.180348) (xy 32.697168 -380.194733) (xy 32.678379 -380.20252) (xy 32.66821 -380.202948)
			(xy 31.95193 -380.202948) (xy 31.941759 -380.202511) (xy 31.922962 -380.194733) (xy 31.908576 -380.180351)
			(xy 31.900792 -380.161557) (xy 31.900368 -380.151386) (xy 31.900368 -379.993398) (xy 31.899944 -379.984213)
			(xy 31.893438 -379.967029) (xy 31.887668 -379.95987) (xy 31.865925 -379.934181) (xy 31.827973 -379.878601)
			(xy 31.796936 -379.818882) (xy 31.773259 -379.755883) (xy 31.757282 -379.690505) (xy 31.749234 -379.623686)
			(xy 31.74923 -379.556384) (xy 31.75727 -379.489564) (xy 31.773239 -379.424184) (xy 31.796908 -379.361181)
			(xy 31.827937 -379.301459) (xy 31.865882 -379.245874) (xy 31.887668 -379.220222) (xy 31.893488 -379.213094)
			(xy 31.899987 -379.19589) (xy 31.900368 -379.186694) (xy 31.900368 -378.693426) (xy 31.89993 -378.684242)
			(xy 31.893434 -378.667058) (xy 31.887668 -378.659898) (xy 31.865854 -378.634267) (xy 31.827904 -378.578678)
			(xy 31.79687 -378.518952) (xy 31.773198 -378.455945) (xy 31.757226 -378.39056) (xy 31.749183 -378.323734)
			(xy 28.471145 -378.323734) (xy 28.471145 -378.323792) (xy 28.463071 -378.390728) (xy 28.447038 -378.456216)
			(xy 28.423275 -378.519312) (xy 28.392126 -378.579108) (xy 28.354039 -378.634741) (xy 28.332176 -378.660406)
			(xy 28.326392 -378.66756) (xy 28.31987 -378.684744) (xy 28.319476 -378.693934) (xy 28.319476 -379.186186)
			(xy 28.319898 -379.195372) (xy 28.326404 -379.212556) (xy 28.332176 -379.219714) (xy 28.354036 -379.245382)
			(xy 28.392125 -379.301016) (xy 28.423276 -379.360812) (xy 28.447 -379.423801) (xy 29.549058 -379.423801)
			(xy 29.549059 -379.356496) (xy 29.557103 -379.289673) (xy 29.573076 -379.224291) (xy 29.596749 -379.161286)
			(xy 29.627783 -379.101562) (xy 29.665732 -379.045976) (xy 29.68752 -379.020324) (xy 29.693334 -379.013191)
			(xy 29.699837 -378.995991) (xy 29.70022 -378.986796) (xy 29.70022 -378.828554) (xy 29.700695 -378.818396)
			(xy 29.708482 -378.799629) (xy 29.722852 -378.785266) (xy 29.741623 -378.77749) (xy 29.751782 -378.776992)
			(xy 30.468062 -378.776992) (xy 30.478212 -378.777564) (xy 30.496971 -378.785317) (xy 30.511336 -378.799658)
			(xy 30.51912 -378.818405) (xy 30.519624 -378.828554) (xy 30.519624 -378.986796) (xy 30.520031 -378.995984)
			(xy 30.526546 -379.013168) (xy 30.532324 -379.020324) (xy 30.55411 -379.045978) (xy 30.592059 -379.101564)
			(xy 30.623093 -379.161287) (xy 30.646766 -379.224291) (xy 30.662739 -379.289673) (xy 30.670784 -379.356496)
			(xy 30.670784 -379.423801) (xy 30.66274 -379.490624) (xy 30.646767 -379.556006) (xy 30.623094 -379.61901)
			(xy 30.592061 -379.678734) (xy 30.554112 -379.73432) (xy 30.532324 -379.759972) (xy 30.526517 -379.76711)
			(xy 30.520008 -379.784306) (xy 30.519624 -379.7935) (xy 30.519624 -380.286768) (xy 30.520044 -380.295954)
			(xy 30.52655 -380.313139) (xy 30.532324 -380.320296) (xy 30.554132 -380.345932) (xy 30.592083 -380.40152)
			(xy 30.623117 -380.461245) (xy 30.646791 -380.524252) (xy 30.662763 -380.589636) (xy 30.6708 -380.656404)
			(xy 33.948845 -380.656404) (xy 33.95692 -380.589467) (xy 33.972953 -380.523978) (xy 33.996716 -380.460882)
			(xy 34.027865 -380.401087) (xy 34.065953 -380.345453) (xy 34.087816 -380.319788) (xy 34.093602 -380.312635)
			(xy 34.100122 -380.29545) (xy 34.100516 -380.28626) (xy 34.100516 -379.794008) (xy 34.100098 -379.784822)
			(xy 34.093589 -379.767638) (xy 34.087816 -379.76048) (xy 34.065999 -379.734776) (xy 34.027907 -379.679148)
			(xy 33.996754 -379.619357) (xy 33.972986 -379.556265) (xy 33.956947 -379.49078) (xy 33.948867 -379.423846)
			(xy 33.948863 -379.356426) (xy 33.956934 -379.289491) (xy 33.972965 -379.224004) (xy 33.996724 -379.160909)
			(xy 34.02787 -379.101114) (xy 34.065954 -379.045481) (xy 34.087816 -379.019816) (xy 34.093633 -379.012685)
			(xy 34.100135 -378.995484) (xy 34.100516 -378.986288) (xy 34.100516 -378.828554) (xy 34.100988 -378.818427)
			(xy 34.108727 -378.79971) (xy 34.123017 -378.785356) (xy 34.1417 -378.777534) (xy 34.151824 -378.776992)
			(xy 34.868104 -378.776992) (xy 34.878257 -378.777418) (xy 34.897008 -378.785214) (xy 34.911331 -378.799609)
			(xy 34.919032 -378.818399) (xy 34.919412 -378.828554) (xy 34.919412 -378.986288) (xy 34.919825 -378.995475)
			(xy 34.926336 -379.012659) (xy 34.932112 -379.019816) (xy 34.954023 -379.045443) (xy 34.992109 -379.101083)
			(xy 35.023257 -379.160885) (xy 35.047018 -379.223986) (xy 35.06305 -379.28948) (xy 35.071122 -379.356422)
			(xy 35.071117 -379.42385) (xy 35.063037 -379.490791) (xy 35.046997 -379.556283) (xy 35.023228 -379.619381)
			(xy 34.992072 -379.679179) (xy 34.953978 -379.734815) (xy 34.932112 -379.76048) (xy 34.9263 -379.767615)
			(xy 34.919794 -379.784813) (xy 34.919412 -379.794008) (xy 34.919412 -380.28626) (xy 34.919839 -380.295446)
			(xy 34.92634 -380.31263) (xy 34.932112 -380.319788) (xy 34.953995 -380.345437) (xy 34.992083 -380.401074)
			(xy 35.023232 -380.460873) (xy 35.046994 -380.523972) (xy 35.063028 -380.589463) (xy 35.071102 -380.656403)
			(xy 35.071102 -380.656464) (xy 38.349165 -380.656464) (xy 38.357207 -380.589643) (xy 38.373176 -380.524262)
			(xy 38.396845 -380.461259) (xy 38.427874 -380.401536) (xy 38.465819 -380.345949) (xy 38.487604 -380.320296)
			(xy 38.493385 -380.31314) (xy 38.499909 -380.295958) (xy 38.500304 -380.286768) (xy 38.500304 -379.7935)
			(xy 38.499893 -379.784313) (xy 38.49338 -379.767129) (xy 38.487604 -379.759972) (xy 38.465865 -379.73428)
			(xy 38.427917 -379.678699) (xy 38.396884 -379.61898) (xy 38.37321 -379.555981) (xy 38.357234 -379.490604)
			(xy 38.349187 -379.423786) (xy 38.349183 -379.356486) (xy 38.357221 -379.289667) (xy 38.373188 -379.224288)
			(xy 38.396854 -379.161286) (xy 38.42788 -379.101563) (xy 38.465821 -379.045977) (xy 38.487604 -379.020324)
			(xy 38.493416 -379.01319) (xy 38.499921 -378.995991) (xy 38.500304 -378.986796) (xy 38.500304 -378.828554)
			(xy 38.500795 -378.818397) (xy 38.508578 -378.799634) (xy 38.522944 -378.785271) (xy 38.541709 -378.777493)
			(xy 38.551866 -378.776992) (xy 39.268146 -378.776992) (xy 39.278301 -378.777495) (xy 39.297062 -378.785276)
			(xy 39.311424 -378.799638) (xy 39.319205 -378.818399) (xy 39.319708 -378.828554) (xy 39.319708 -378.986796)
			(xy 39.320118 -378.995983) (xy 39.326632 -379.013168) (xy 39.332408 -379.020324) (xy 39.354244 -379.045937)
			(xy 39.392195 -379.101528) (xy 39.423229 -379.161256) (xy 39.446902 -379.224266) (xy 39.462873 -379.289653)
			(xy 39.470914 -379.356481) (xy 39.47091 -379.423791) (xy 39.46286 -379.490618) (xy 39.44688 -379.556003)
			(xy 39.4232 -379.61901) (xy 39.392158 -379.678735) (xy 39.3542 -379.734321) (xy 39.332408 -379.759972)
			(xy 39.326599 -379.767109) (xy 39.320092 -379.784306) (xy 39.319708 -379.7935) (xy 39.319708 -380.286768)
			(xy 39.320132 -380.295954) (xy 39.326636 -380.313138) (xy 39.332408 -380.320296) (xy 39.354217 -380.345931)
			(xy 39.392169 -380.401519) (xy 39.423204 -380.461244) (xy 39.446878 -380.524251) (xy 39.462851 -380.589636)
			(xy 39.470887 -380.656404) (xy 42.748933 -380.656404) (xy 42.757007 -380.589467) (xy 42.773041 -380.523979)
			(xy 42.796803 -380.460883) (xy 42.827951 -380.401087) (xy 42.866037 -380.345453) (xy 42.8879 -380.319788)
			(xy 42.893684 -380.312634) (xy 42.900206 -380.29545) (xy 42.9006 -380.28626) (xy 42.9006 -379.794008)
			(xy 42.900186 -379.784821) (xy 42.893675 -379.767637) (xy 42.8879 -379.76048) (xy 42.866083 -379.734776)
			(xy 42.827993 -379.679147) (xy 42.79684 -379.619356) (xy 42.773073 -379.556264) (xy 42.757035 -379.49078)
			(xy 42.748955 -379.423846) (xy 42.748951 -379.356426) (xy 42.757022 -379.289491) (xy 42.773052 -379.224005)
			(xy 42.796811 -379.16091) (xy 42.827956 -379.101115) (xy 42.866039 -379.045481) (xy 42.8879 -379.019816)
			(xy 42.893715 -379.012684) (xy 42.900219 -378.995483) (xy 42.9006 -378.986288) (xy 42.9006 -378.828554)
			(xy 42.901088 -378.818429) (xy 42.908823 -378.799715) (xy 42.923108 -378.785361) (xy 42.941786 -378.777537)
			(xy 42.951908 -378.776992) (xy 43.668188 -378.776992) (xy 43.67834 -378.777431) (xy 43.697091 -378.785221)
			(xy 43.711414 -378.799613) (xy 43.719116 -378.8184) (xy 43.719496 -378.828554) (xy 43.719496 -378.986288)
			(xy 43.719913 -378.995474) (xy 43.726422 -379.012659) (xy 43.732196 -379.019816) (xy 43.754107 -379.045442)
			(xy 43.792195 -379.101082) (xy 43.823344 -379.160884) (xy 43.847105 -379.223986) (xy 43.863138 -379.28948)
			(xy 43.87121 -379.356422) (xy 43.871205 -379.42385) (xy 43.863125 -379.490791) (xy 43.847084 -379.556283)
			(xy 43.823314 -379.619382) (xy 43.792158 -379.67918) (xy 43.754063 -379.734815) (xy 43.732196 -379.76048)
			(xy 43.726382 -379.767613) (xy 43.719878 -379.784813) (xy 43.719496 -379.794008) (xy 43.719496 -380.28626)
			(xy 43.719926 -380.295445) (xy 43.726426 -380.31263) (xy 43.732196 -380.319788) (xy 43.75408 -380.345437)
			(xy 43.792168 -380.401074) (xy 43.823318 -380.460872) (xy 43.847081 -380.523971) (xy 43.863116 -380.589462)
			(xy 43.87119 -380.656402) (xy 43.87119 -380.656463) (xy 73.548987 -380.656463) (xy 73.557029 -380.589642)
			(xy 73.572999 -380.524261) (xy 73.596669 -380.461258) (xy 73.6277 -380.401535) (xy 73.665646 -380.345948)
			(xy 73.687432 -380.320296) (xy 73.693217 -380.313143) (xy 73.699738 -380.295958) (xy 73.700132 -380.286768)
			(xy 73.700132 -379.7935) (xy 73.699715 -379.784314) (xy 73.693205 -379.76713) (xy 73.687432 -379.759972)
			(xy 73.665692 -379.734281) (xy 73.627742 -379.6787) (xy 73.596707 -379.618982) (xy 73.573032 -379.555982)
			(xy 73.557056 -379.490605) (xy 73.549008 -379.423787) (xy 73.549004 -379.356486) (xy 73.557043 -379.289666)
			(xy 73.573011 -379.224287) (xy 73.596678 -379.161285) (xy 73.627705 -379.101562) (xy 73.665648 -379.045976)
			(xy 73.687432 -379.020324) (xy 73.693247 -379.013192) (xy 73.69975 -378.995991) (xy 73.700132 -378.986796)
			(xy 73.700132 -378.828554) (xy 73.700596 -378.818394) (xy 73.708384 -378.799625) (xy 73.722759 -378.785262)
			(xy 73.741534 -378.777488) (xy 73.751694 -378.776992) (xy 74.467974 -378.776992) (xy 74.478125 -378.777553)
			(xy 74.496884 -378.785311) (xy 74.511249 -378.799655) (xy 74.519032 -378.818404) (xy 74.519536 -378.828554)
			(xy 74.519536 -378.986796) (xy 74.519962 -378.995981) (xy 74.526466 -379.013165) (xy 74.532236 -379.020324)
			(xy 74.554072 -379.045937) (xy 74.592021 -379.101528) (xy 74.623053 -379.161257) (xy 74.646725 -379.224267)
			(xy 74.662695 -379.289654) (xy 74.670736 -379.356481) (xy 74.670731 -379.423791) (xy 74.662682 -379.490617)
			(xy 74.646703 -379.556002) (xy 74.623024 -379.619009) (xy 74.591984 -379.678734) (xy 74.554028 -379.73432)
			(xy 74.532236 -379.759972) (xy 74.526419 -379.767102) (xy 74.519918 -379.784304) (xy 74.519536 -379.7935)
			(xy 74.519536 -380.286768) (xy 74.519976 -380.295952) (xy 74.52647 -380.313136) (xy 74.532236 -380.320296)
			(xy 74.554044 -380.345932) (xy 74.591994 -380.40152) (xy 74.623028 -380.461246) (xy 74.6467 -380.524252)
			(xy 74.662673 -380.589637) (xy 74.670709 -380.656404) (xy 77.948754 -380.656404) (xy 77.956829 -380.589466)
			(xy 77.972863 -380.523978) (xy 77.996626 -380.460882) (xy 78.027776 -380.401086) (xy 78.065864 -380.345453)
			(xy 78.087728 -380.319788) (xy 78.093516 -380.312637) (xy 78.100035 -380.295451) (xy 78.100428 -380.28626)
			(xy 78.100428 -379.794008) (xy 78.100008 -379.784822) (xy 78.093501 -379.767638) (xy 78.087728 -379.76048)
			(xy 78.06591 -379.734776) (xy 78.027818 -379.679148) (xy 77.996664 -379.619357) (xy 77.972896 -379.556265)
			(xy 77.956856 -379.490781) (xy 77.948776 -379.423846) (xy 77.948772 -379.356426) (xy 77.956843 -379.28949)
			(xy 77.972874 -379.224004) (xy 77.996634 -379.160909) (xy 78.027781 -379.101114) (xy 78.065866 -379.045481)
			(xy 78.087728 -379.019816) (xy 78.093546 -379.012686) (xy 78.100047 -378.995484) (xy 78.100428 -378.986288)
			(xy 78.100428 -378.828554) (xy 78.100889 -378.818426) (xy 78.108629 -378.799706) (xy 78.122923 -378.785352)
			(xy 78.14161 -378.777532) (xy 78.151736 -378.776992) (xy 78.868016 -378.776992) (xy 78.87817 -378.777408)
			(xy 78.896921 -378.785208) (xy 78.911244 -378.799606) (xy 78.918945 -378.818398) (xy 78.919324 -378.828554)
			(xy 78.919324 -378.986288) (xy 78.919734 -378.995475) (xy 78.926247 -379.01266) (xy 78.932024 -379.019816)
			(xy 78.953934 -379.045443) (xy 78.99202 -379.101083) (xy 79.023167 -379.160885) (xy 79.046928 -379.223987)
			(xy 79.062959 -379.28948) (xy 79.071031 -379.356423) (xy 79.071026 -379.42385) (xy 79.062946 -379.490791)
			(xy 79.046906 -379.556282) (xy 79.023138 -379.619381) (xy 78.991983 -379.679179) (xy 78.95389 -379.734814)
			(xy 78.932024 -379.76048) (xy 78.926214 -379.767616) (xy 78.919706 -379.784813) (xy 78.919324 -379.794008)
			(xy 78.919324 -380.28626) (xy 78.919748 -380.295446) (xy 78.926251 -380.312631) (xy 78.932024 -380.319788)
			(xy 78.953907 -380.345437) (xy 78.991993 -380.401075) (xy 79.023142 -380.460873) (xy 79.046904 -380.523972)
			(xy 79.062937 -380.589463) (xy 79.071011 -380.656403) (xy 79.071011 -380.656464) (xy 82.349074 -380.656464)
			(xy 82.357116 -380.589643) (xy 82.373086 -380.524262) (xy 82.396755 -380.461258) (xy 82.427785 -380.401535)
			(xy 82.46573 -380.345948) (xy 82.487516 -380.320296) (xy 82.493299 -380.313141) (xy 82.499821 -380.295958)
			(xy 82.500216 -380.286768) (xy 82.500216 -379.7935) (xy 82.499803 -379.784313) (xy 82.493291 -379.767129)
			(xy 82.487516 -379.759972) (xy 82.465776 -379.734281) (xy 82.427828 -379.678699) (xy 82.396794 -379.618981)
			(xy 82.373119 -379.555982) (xy 82.357144 -379.490604) (xy 82.349096 -379.423786) (xy 82.349092 -379.356486)
			(xy 82.357131 -379.289667) (xy 82.373098 -379.224288) (xy 82.396764 -379.161285) (xy 82.427791 -379.101563)
			(xy 82.465732 -379.045977) (xy 82.487516 -379.020324) (xy 82.493329 -379.013191) (xy 82.499833 -378.995991)
			(xy 82.500216 -378.986796) (xy 82.500216 -378.828554) (xy 82.500695 -378.818396) (xy 82.508481 -378.79963)
			(xy 82.52285 -378.785267) (xy 82.54162 -378.777491) (xy 82.551778 -378.776992) (xy 83.268058 -378.776992)
			(xy 83.278207 -378.777567) (xy 83.296967 -378.785319) (xy 83.311332 -378.799659) (xy 83.319116 -378.818405)
			(xy 83.31962 -378.828554) (xy 83.31962 -378.986796) (xy 83.320028 -378.995984) (xy 83.326543 -379.013168)
			(xy 83.33232 -379.020324) (xy 83.354156 -379.045937) (xy 83.392107 -379.101528) (xy 83.42314 -379.161256)
			(xy 83.446812 -379.224266) (xy 83.462783 -379.289654) (xy 83.470824 -379.356481) (xy 83.470819 -379.423791)
			(xy 83.46277 -379.490618) (xy 83.446791 -379.556003) (xy 83.423111 -379.61901) (xy 83.392069 -379.678734)
			(xy 83.354112 -379.734321) (xy 83.33232 -379.759972) (xy 83.326513 -379.76711) (xy 83.320004 -379.784306)
			(xy 83.31962 -379.7935) (xy 83.31962 -380.286768) (xy 83.320041 -380.295954) (xy 83.326547 -380.313139)
			(xy 83.33232 -380.320296) (xy 83.354129 -380.345931) (xy 83.392079 -380.401519) (xy 83.423114 -380.461245)
			(xy 83.446788 -380.524252) (xy 83.46276 -380.589636) (xy 83.470797 -380.656404) (xy 86.748842 -380.656404)
			(xy 86.756916 -380.589467) (xy 86.77295 -380.523979) (xy 86.796713 -380.460883) (xy 86.827862 -380.401087)
			(xy 86.865949 -380.345453) (xy 86.887812 -380.319788) (xy 86.893598 -380.312635) (xy 86.900118 -380.29545)
			(xy 86.900512 -380.28626) (xy 86.900512 -379.794008) (xy 86.900095 -379.784822) (xy 86.893586 -379.767637)
			(xy 86.887812 -379.76048) (xy 86.865995 -379.734776) (xy 86.827904 -379.679147) (xy 86.79675 -379.619357)
			(xy 86.772983 -379.556265) (xy 86.756944 -379.49078) (xy 86.748864 -379.423846) (xy 86.74886 -379.356426)
			(xy 86.756931 -379.289491) (xy 86.772962 -379.224004) (xy 86.796721 -379.160909) (xy 86.827867 -379.101115)
			(xy 86.86595 -379.045481) (xy 86.887812 -379.019816) (xy 86.893628 -379.012685) (xy 86.900131 -378.995483)
			(xy 86.900512 -378.986288) (xy 86.900512 -378.828554) (xy 86.900988 -378.818428) (xy 86.908726 -378.799711)
			(xy 86.923015 -378.785357) (xy 86.941696 -378.777535) (xy 86.95182 -378.776992) (xy 87.6681 -378.776992)
			(xy 87.678253 -378.777422) (xy 87.697004 -378.785216) (xy 87.711327 -378.79961) (xy 87.719028 -378.818399)
			(xy 87.719408 -378.828554) (xy 87.719408 -378.986288) (xy 87.719822 -378.995475) (xy 87.726333 -379.012659)
			(xy 87.732108 -379.019816) (xy 87.754019 -379.045442) (xy 87.792106 -379.101083) (xy 87.823254 -379.160884)
			(xy 87.847015 -379.223986) (xy 87.863047 -379.28948) (xy 87.871119 -379.356422) (xy 87.871114 -379.42385)
			(xy 87.863034 -379.490791) (xy 87.846994 -379.556283) (xy 87.823224 -379.619382) (xy 87.792068 -379.679179)
			(xy 87.753975 -379.734815) (xy 87.732108 -379.76048) (xy 87.726296 -379.767614) (xy 87.71979 -379.784813)
			(xy 87.719408 -379.794008) (xy 87.719408 -380.28626) (xy 87.719836 -380.295445) (xy 87.726337 -380.31263)
			(xy 87.732108 -380.319788) (xy 87.753991 -380.345437) (xy 87.792079 -380.401074) (xy 87.823228 -380.460873)
			(xy 87.846991 -380.523972) (xy 87.863025 -380.589463) (xy 87.871099 -380.656402) (xy 87.871097 -380.723828)
			(xy 87.863019 -380.790767) (xy 87.846982 -380.856257) (xy 87.838954 -380.877572) (xy 105.0036 -380.877572)
			(xy 105.0036 -380.013972) (xy 105.00409 -379.983988) (xy 105.011918 -379.924532) (xy 105.027439 -379.866607)
			(xy 105.050388 -379.811203) (xy 105.080372 -379.759269) (xy 105.116878 -379.711693) (xy 105.159283 -379.669288)
			(xy 105.206859 -379.632782) (xy 105.258793 -379.602798) (xy 105.314197 -379.579849) (xy 105.372122 -379.564328)
			(xy 105.431578 -379.5565) (xy 105.491546 -379.5565) (xy 105.551002 -379.564328) (xy 105.608927 -379.579849)
			(xy 105.664331 -379.602798) (xy 105.716265 -379.632782) (xy 105.763841 -379.669288) (xy 105.806246 -379.711693)
			(xy 105.842752 -379.759269) (xy 105.872736 -379.811203) (xy 105.895685 -379.866607) (xy 105.911206 -379.924532)
			(xy 105.919034 -379.983988) (xy 105.919524 -380.013972) (xy 105.919524 -380.656403) (xy 117.548873 -380.656403)
			(xy 117.556947 -380.589466) (xy 117.572982 -380.523977) (xy 117.596746 -380.460881) (xy 117.627898 -380.401085)
			(xy 117.665987 -380.345452) (xy 117.687852 -380.319788) (xy 117.693643 -380.312639) (xy 117.700159 -380.295451)
			(xy 117.700552 -380.28626) (xy 117.700552 -379.794008) (xy 117.700126 -379.784823) (xy 117.693622 -379.767639)
			(xy 117.687852 -379.76048) (xy 117.666033 -379.734777) (xy 117.62794 -379.679149) (xy 117.596784 -379.619358)
			(xy 117.573015 -379.556266) (xy 117.556975 -379.490781) (xy 117.548894 -379.423846) (xy 117.54889 -379.356426)
			(xy 117.556962 -379.28949) (xy 117.572994 -379.224003) (xy 117.596755 -379.160908) (xy 117.627903 -379.101113)
			(xy 117.665989 -379.04548) (xy 117.687852 -379.019816) (xy 117.693673 -379.012688) (xy 117.700172 -378.995484)
			(xy 117.700552 -378.986288) (xy 117.700552 -378.828554) (xy 117.700989 -378.818423) (xy 117.708734 -378.799698)
			(xy 117.723036 -378.785343) (xy 117.741731 -378.777528) (xy 117.75186 -378.776992) (xy 118.46814 -378.776992)
			(xy 118.478296 -378.777389) (xy 118.497047 -378.785196) (xy 118.511369 -378.7996) (xy 118.519069 -378.818396)
			(xy 118.519448 -378.828554) (xy 118.519448 -378.986288) (xy 118.519875 -378.995473) (xy 118.526378 -379.012657)
			(xy 118.532148 -379.019816) (xy 118.554061 -379.045441) (xy 118.592152 -379.10108) (xy 118.623303 -379.160882)
			(xy 118.647067 -379.223984) (xy 118.663101 -379.289478) (xy 118.671174 -379.356422) (xy 118.671169 -379.42385)
			(xy 118.663088 -379.490793) (xy 118.647046 -379.556285) (xy 118.623274 -379.619384) (xy 118.592115 -379.679181)
			(xy 118.554017 -379.734816) (xy 118.532148 -379.76048) (xy 118.526329 -379.767609) (xy 118.519829 -379.784812)
			(xy 118.519448 -379.794008) (xy 118.519448 -380.28626) (xy 118.519889 -380.295444) (xy 118.526382 -380.312628)
			(xy 118.532148 -380.319788) (xy 118.554033 -380.345436) (xy 118.592125 -380.401072) (xy 118.623278 -380.46087)
			(xy 118.647043 -380.523969) (xy 118.663079 -380.589461) (xy 118.671154 -380.656402) (xy 118.671154 -380.656463)
			(xy 121.949193 -380.656463) (xy 121.957235 -380.589642) (xy 121.973206 -380.524261) (xy 121.996876 -380.461257)
			(xy 122.027907 -380.401534) (xy 122.065854 -380.345948) (xy 122.08764 -380.320296) (xy 122.093426 -380.313143)
			(xy 122.099946 -380.295958) (xy 122.10034 -380.286768) (xy 122.10034 -379.7935) (xy 122.099921 -379.784314)
			(xy 122.093413 -379.76713) (xy 122.08764 -379.759972) (xy 122.0659 -379.734281) (xy 122.027949 -379.6787)
			(xy 121.996914 -379.618982) (xy 121.973238 -379.555982) (xy 121.957262 -379.490605) (xy 121.949214 -379.423787)
			(xy 121.94921 -379.356485) (xy 121.957249 -379.289666) (xy 121.973217 -379.224287) (xy 121.996884 -379.161284)
			(xy 122.027912 -379.101562) (xy 122.065855 -379.045976) (xy 122.08764 -379.020324) (xy 122.093456 -379.013193)
			(xy 122.099958 -378.995991) (xy 122.10034 -378.986796) (xy 122.10034 -378.828554) (xy 122.100796 -378.818393)
			(xy 122.108586 -378.799623) (xy 122.122963 -378.785259) (xy 122.141741 -378.777486) (xy 122.151902 -378.776992)
			(xy 122.868182 -378.776992) (xy 122.878333 -378.777547) (xy 122.897093 -378.785307) (xy 122.911457 -378.799653)
			(xy 122.919241 -378.818404) (xy 122.919744 -378.828554) (xy 122.919744 -378.986796) (xy 122.920169 -378.995981)
			(xy 122.926674 -379.013165) (xy 122.932444 -379.020324) (xy 122.95428 -379.045937) (xy 122.992228 -379.101529)
			(xy 123.02326 -379.161257) (xy 123.046931 -379.224267) (xy 123.062901 -379.289654) (xy 123.070942 -379.356482)
			(xy 123.070937 -379.423791) (xy 123.062888 -379.490617) (xy 123.04691 -379.556002) (xy 123.023231 -379.619009)
			(xy 122.992191 -379.678733) (xy 122.954235 -379.73432) (xy 122.932444 -379.759972) (xy 122.926627 -379.767103)
			(xy 122.920126 -379.784305) (xy 122.919744 -379.7935) (xy 122.919744 -380.286768) (xy 122.920182 -380.295952)
			(xy 122.926678 -380.313136) (xy 122.932444 -380.320296) (xy 122.954252 -380.345932) (xy 122.992201 -380.40152)
			(xy 123.023235 -380.461246) (xy 123.046907 -380.524252) (xy 123.062879 -380.589637) (xy 123.070915 -380.656404)
			(xy 126.34896 -380.656404) (xy 126.357035 -380.589466) (xy 126.373069 -380.523978) (xy 126.396833 -380.460881)
			(xy 126.427983 -380.401086) (xy 126.466072 -380.345453) (xy 126.487936 -380.319788) (xy 126.493725 -380.312637)
			(xy 126.500243 -380.295451) (xy 126.500636 -380.28626) (xy 126.500636 -379.794008) (xy 126.500214 -379.784822)
			(xy 126.493708 -379.767638) (xy 126.487936 -379.76048) (xy 126.466118 -379.734776) (xy 126.428025 -379.679148)
			(xy 126.396871 -379.619358) (xy 126.373102 -379.556266) (xy 126.357062 -379.490781) (xy 126.348982 -379.423846)
			(xy 126.348978 -379.356426) (xy 126.357049 -379.28949) (xy 126.373081 -379.224003) (xy 126.396841 -379.160908)
			(xy 126.427988 -379.101114) (xy 126.466074 -379.045481) (xy 126.487936 -379.019816) (xy 126.493755 -379.012687)
			(xy 126.500256 -378.995484) (xy 126.500636 -378.986288) (xy 126.500636 -378.828554) (xy 126.501089 -378.818425)
			(xy 126.508831 -378.799703) (xy 126.523127 -378.785349) (xy 126.541817 -378.777531) (xy 126.551944 -378.776992)
			(xy 127.268224 -378.776992) (xy 127.278379 -378.777402) (xy 127.29713 -378.785204) (xy 127.311452 -378.799604)
			(xy 127.319153 -378.818397) (xy 127.319532 -378.828554) (xy 127.319532 -378.986288) (xy 127.319963 -378.995473)
			(xy 127.326464 -379.012656) (xy 127.332232 -379.019816) (xy 127.354142 -379.045443) (xy 127.392227 -379.101084)
			(xy 127.423374 -379.160885) (xy 127.447134 -379.223987) (xy 127.463165 -379.289481) (xy 127.471237 -379.356423)
			(xy 127.471232 -379.423849) (xy 127.463152 -379.49079) (xy 127.447113 -379.556282) (xy 127.423345 -379.61938)
			(xy 127.39219 -379.679178) (xy 127.354098 -379.734814) (xy 127.332232 -379.76048) (xy 127.326411 -379.767607)
			(xy 127.319913 -379.784812) (xy 127.319532 -379.794008) (xy 127.319532 -380.28626) (xy 127.319977 -380.295443)
			(xy 127.326468 -380.312627) (xy 127.332232 -380.319788) (xy 127.354114 -380.345438) (xy 127.392201 -380.401075)
			(xy 127.423349 -380.460874) (xy 127.44711 -380.523973) (xy 127.463143 -380.589463) (xy 127.471217 -380.656403)
			(xy 127.471217 -380.656463) (xy 130.74928 -380.656463) (xy 130.757322 -380.589642) (xy 130.773292 -380.524262)
			(xy 130.796962 -380.461258) (xy 130.827992 -380.401535) (xy 130.865938 -380.345948) (xy 130.887724 -380.320296)
			(xy 130.893508 -380.313142) (xy 130.900029 -380.295958) (xy 130.900424 -380.286768) (xy 130.900424 -379.7935)
			(xy 130.900009 -379.784313) (xy 130.893498 -379.767129) (xy 130.887724 -379.759972) (xy 130.865984 -379.734281)
			(xy 130.828035 -379.678699) (xy 130.797 -379.618981) (xy 130.773326 -379.555982) (xy 130.75735 -379.490605)
			(xy 130.749302 -379.423787) (xy 130.749298 -379.356486) (xy 130.757337 -379.289667) (xy 130.773304 -379.224287)
			(xy 130.796971 -379.161285) (xy 130.827998 -379.101563) (xy 130.86594 -379.045977) (xy 130.887724 -379.020324)
			(xy 130.893538 -379.013191) (xy 130.900042 -378.995991) (xy 130.900424 -378.986796) (xy 130.900424 -378.828554)
			(xy 130.900895 -378.818395) (xy 130.908682 -378.799628) (xy 130.923054 -378.785264) (xy 130.941827 -378.777489)
			(xy 130.951986 -378.776992) (xy 131.668266 -378.776992) (xy 131.678416 -378.77756) (xy 131.697175 -378.785315)
			(xy 131.71154 -378.799657) (xy 131.719324 -378.818405) (xy 131.719828 -378.828554) (xy 131.719828 -378.986796)
			(xy 131.720234 -378.995984) (xy 131.72675 -379.013168) (xy 131.732528 -379.020324) (xy 131.754364 -379.045937)
			(xy 131.792314 -379.101528) (xy 131.823347 -379.161257) (xy 131.847018 -379.224267) (xy 131.862989 -379.289654)
			(xy 131.87103 -379.356481) (xy 131.871025 -379.423791) (xy 131.862976 -379.490617) (xy 131.846997 -379.556003)
			(xy 131.823317 -379.619009) (xy 131.792277 -379.678734) (xy 131.75432 -379.73432) (xy 131.732528 -379.759972)
			(xy 131.72671 -379.767101) (xy 131.72021 -379.784304) (xy 131.719828 -379.7935) (xy 131.719828 -380.286768)
			(xy 131.720247 -380.295954) (xy 131.726754 -380.313139) (xy 131.732528 -380.320296) (xy 131.754336 -380.345932)
			(xy 131.792287 -380.40152) (xy 131.823321 -380.461245) (xy 131.846994 -380.524252) (xy 131.862967 -380.589636)
			(xy 131.871003 -380.656404) (xy 161.548806 -380.656404) (xy 161.55688 -380.589468) (xy 161.572912 -380.523981)
			(xy 161.596672 -380.460885) (xy 161.627819 -380.401089) (xy 161.665902 -380.345454) (xy 161.687764 -380.319788)
			(xy 161.693556 -380.31264) (xy 161.700072 -380.295451) (xy 161.700464 -380.28626) (xy 161.700464 -379.794008)
			(xy 161.700036 -379.784823) (xy 161.693533 -379.767639) (xy 161.687764 -379.76048) (xy 161.665948 -379.734775)
			(xy 161.627861 -379.679146) (xy 161.59671 -379.619354) (xy 161.572945 -379.556263) (xy 161.556907 -379.490779)
			(xy 161.548828 -379.423846) (xy 161.548823 -379.356426) (xy 161.556894 -379.289492) (xy 161.572923 -379.224006)
			(xy 161.59668 -379.160911) (xy 161.627824 -379.101116) (xy 161.665904 -379.045482) (xy 161.687764 -379.019816)
			(xy 161.693587 -379.01269) (xy 161.700084 -378.995484) (xy 161.700464 -378.986288) (xy 161.700464 -378.828554)
			(xy 161.70089 -378.818421) (xy 161.708637 -378.799695) (xy 161.722942 -378.785339) (xy 161.741641 -378.777526)
			(xy 161.751772 -378.776992) (xy 162.468052 -378.776992) (xy 162.478202 -378.777461) (xy 162.496952 -378.785239)
			(xy 162.511277 -378.799622) (xy 162.518979 -378.818402) (xy 162.51936 -378.828554) (xy 162.51936 -378.986288)
			(xy 162.519785 -378.995473) (xy 162.526289 -379.012658) (xy 162.53206 -379.019816) (xy 162.553973 -379.045442)
			(xy 162.592062 -379.101081) (xy 162.623213 -379.160882) (xy 162.646977 -379.223984) (xy 162.66301 -379.289479)
			(xy 162.671083 -379.356422) (xy 162.671078 -379.42385) (xy 162.662997 -379.490792) (xy 162.646955 -379.556285)
			(xy 162.623184 -379.619384) (xy 162.592025 -379.679181) (xy 162.553928 -379.734815) (xy 162.53206 -379.76048)
			(xy 162.526242 -379.76761) (xy 162.519741 -379.784812) (xy 162.51936 -379.794008) (xy 162.51936 -380.28626)
			(xy 162.519799 -380.295444) (xy 162.526294 -380.312628) (xy 162.53206 -380.319788) (xy 162.553945 -380.345436)
			(xy 162.592036 -380.401072) (xy 162.623188 -380.460871) (xy 162.646953 -380.52397) (xy 162.662988 -380.589461)
			(xy 162.671063 -380.656402) (xy 162.671063 -380.656463) (xy 165.949102 -380.656463) (xy 165.957144 -380.589642)
			(xy 165.973115 -380.524261) (xy 165.996786 -380.461257) (xy 166.027818 -380.401534) (xy 166.065765 -380.345948)
			(xy 166.087552 -380.320296) (xy 166.093339 -380.313144) (xy 166.099858 -380.295959) (xy 166.100252 -380.286768)
			(xy 166.100252 -379.7935) (xy 166.09983 -379.784314) (xy 166.093323 -379.76713) (xy 166.087552 -379.759972)
			(xy 166.065811 -379.734281) (xy 166.02786 -379.678701) (xy 165.996824 -379.618982) (xy 165.973148 -379.555983)
			(xy 165.957171 -379.490605) (xy 165.949123 -379.423787) (xy 165.949119 -379.356485) (xy 165.957158 -379.289666)
			(xy 165.973127 -379.224286) (xy 165.996795 -379.161284) (xy 166.027823 -379.101562) (xy 166.065767 -379.045976)
			(xy 166.087552 -379.020324) (xy 166.09337 -379.013194) (xy 166.09987 -378.995992) (xy 166.100252 -378.986796)
			(xy 166.100252 -378.828554) (xy 166.100696 -378.818392) (xy 166.108488 -378.799619) (xy 166.122869 -378.785255)
			(xy 166.141651 -378.777484) (xy 166.151814 -378.776992) (xy 166.868094 -378.776992) (xy 166.878246 -378.777537)
			(xy 166.897006 -378.785301) (xy 166.91137 -378.79965) (xy 166.919153 -378.818403) (xy 166.919656 -378.828554)
			(xy 166.919656 -378.986796) (xy 166.920078 -378.995982) (xy 166.926584 -379.013166) (xy 166.932356 -379.020324)
			(xy 166.954191 -379.045937) (xy 166.992139 -379.101529) (xy 167.02317 -379.161258) (xy 167.046841 -379.224268)
			(xy 167.06281 -379.289655) (xy 167.070851 -379.356482) (xy 167.070847 -379.423791) (xy 167.062798 -379.490617)
			(xy 167.046819 -379.556001) (xy 167.023141 -379.619008) (xy 166.992102 -379.678733) (xy 166.954147 -379.73432)
			(xy 166.932356 -379.759972) (xy 166.926541 -379.767104) (xy 166.920038 -379.784305) (xy 166.919656 -379.7935)
			(xy 166.919656 -380.286768) (xy 166.920091 -380.295952) (xy 166.926588 -380.313137) (xy 166.932356 -380.320296)
			(xy 166.954164 -380.345932) (xy 166.992112 -380.40152) (xy 167.023145 -380.461246) (xy 167.046817 -380.524253)
			(xy 167.062789 -380.589637) (xy 167.070824 -380.656403) (xy 170.34887 -380.656403) (xy 170.356944 -380.589466)
			(xy 170.372979 -380.523977) (xy 170.396743 -380.460881) (xy 170.427894 -380.401086) (xy 170.465984 -380.345452)
			(xy 170.487848 -380.319788) (xy 170.493638 -380.312638) (xy 170.500155 -380.295451) (xy 170.500548 -380.28626)
			(xy 170.500548 -379.794008) (xy 170.500123 -379.784823) (xy 170.493619 -379.767639) (xy 170.487848 -379.76048)
			(xy 170.46603 -379.734777) (xy 170.427936 -379.679149) (xy 170.396781 -379.619358) (xy 170.373012 -379.556266)
			(xy 170.356971 -379.490781) (xy 170.348891 -379.423846) (xy 170.348887 -379.356426) (xy 170.356959 -379.28949)
			(xy 170.37299 -379.224003) (xy 170.396751 -379.160908) (xy 170.427899 -379.101113) (xy 170.465985 -379.04548)
			(xy 170.487848 -379.019816) (xy 170.493669 -379.012688) (xy 170.500168 -378.995484) (xy 170.500548 -378.986288)
			(xy 170.500548 -378.828554) (xy 170.500989 -378.818423) (xy 170.508734 -378.7997) (xy 170.523034 -378.785345)
			(xy 170.541727 -378.777529) (xy 170.551856 -378.776992) (xy 171.268136 -378.776992) (xy 171.278291 -378.777392)
			(xy 171.297043 -378.785198) (xy 171.311365 -378.799601) (xy 171.319065 -378.818396) (xy 171.319444 -378.828554)
			(xy 171.319444 -378.986288) (xy 171.319872 -378.995473) (xy 171.326375 -379.012657) (xy 171.332144 -379.019816)
			(xy 171.354057 -379.045441) (xy 171.392148 -379.10108) (xy 171.4233 -379.160881) (xy 171.447064 -379.223984)
			(xy 171.463098 -379.289478) (xy 171.47117 -379.356422) (xy 171.471166 -379.42385) (xy 171.463085 -379.490793)
			(xy 171.447042 -379.556285) (xy 171.42327 -379.619384) (xy 171.392111 -379.679182) (xy 171.354013 -379.734816)
			(xy 171.332144 -379.76048) (xy 171.326324 -379.767608) (xy 171.319825 -379.784812) (xy 171.319444 -379.794008)
			(xy 171.319444 -380.28626) (xy 171.319886 -380.295444) (xy 171.326379 -380.312628) (xy 171.332144 -380.319788)
			(xy 171.35403 -380.345436) (xy 171.392121 -380.401072) (xy 171.423274 -380.46087) (xy 171.44704 -380.523969)
			(xy 171.463076 -380.589461) (xy 171.471151 -380.656402) (xy 171.471151 -380.656463) (xy 174.74919 -380.656463)
			(xy 174.757232 -380.589642) (xy 174.773202 -380.524261) (xy 174.796873 -380.461258) (xy 174.827904 -380.401535)
			(xy 174.86585 -380.345948) (xy 174.887636 -380.320296) (xy 174.893421 -380.313143) (xy 174.899942 -380.295958)
			(xy 174.900336 -380.286768) (xy 174.900336 -379.7935) (xy 174.899918 -379.784314) (xy 174.893409 -379.76713)
			(xy 174.887636 -379.759972) (xy 174.865896 -379.734281) (xy 174.827946 -379.6787) (xy 174.796911 -379.618982)
			(xy 174.773235 -379.555982) (xy 174.757259 -379.490605) (xy 174.749211 -379.423787) (xy 174.749207 -379.356486)
			(xy 174.757246 -379.289666) (xy 174.773214 -379.224287) (xy 174.796881 -379.161284) (xy 174.827909 -379.101562)
			(xy 174.865851 -379.045976) (xy 174.887636 -379.020324) (xy 174.893452 -379.013193) (xy 174.899954 -378.995991)
			(xy 174.900336 -378.986796) (xy 174.900336 -378.828554) (xy 174.900796 -378.818394) (xy 174.908585 -378.799624)
			(xy 174.922961 -378.78526) (xy 174.941737 -378.777487) (xy 174.951898 -378.776992) (xy 175.668178 -378.776992)
			(xy 175.678329 -378.77755) (xy 175.697089 -378.785309) (xy 175.711453 -378.799654) (xy 175.719237 -378.818404)
			(xy 175.71974 -378.828554) (xy 175.71974 -378.986796) (xy 175.720166 -378.995981) (xy 175.72667 -379.013165)
			(xy 175.73244 -379.020324) (xy 175.754276 -379.045937) (xy 175.792225 -379.101529) (xy 175.823257 -379.161257)
			(xy 175.846928 -379.224267) (xy 175.862898 -379.289654) (xy 175.870939 -379.356481) (xy 175.870934 -379.423791)
			(xy 175.862885 -379.490617) (xy 175.846907 -379.556002) (xy 175.823227 -379.619009) (xy 175.792187 -379.678734)
			(xy 175.754231 -379.73432) (xy 175.73244 -379.759972) (xy 175.726623 -379.767102) (xy 175.720122 -379.784305)
			(xy 175.71974 -379.7935) (xy 175.71974 -380.286768) (xy 175.720179 -380.295952) (xy 175.726674 -380.313136)
			(xy 175.73244 -380.320296) (xy 175.754248 -380.345932) (xy 175.792198 -380.40152) (xy 175.823231 -380.461246)
			(xy 175.846904 -380.524252) (xy 175.862876 -380.589637) (xy 175.870919 -380.656462) (xy 175.870917 -380.723769)
			(xy 175.862871 -380.790593) (xy 175.846895 -380.855977) (xy 175.823219 -380.918982) (xy 175.792182 -380.978706)
			(xy 175.75423 -381.034292) (xy 175.73244 -381.059944) (xy 175.726635 -381.067083) (xy 175.720127 -381.084278)
			(xy 175.71974 -381.093472) (xy 175.71974 -381.251206) (xy 175.71934 -381.261381) (xy 175.711549 -381.28018)
			(xy 175.697156 -381.294565) (xy 175.678353 -381.302346) (xy 175.668178 -381.302768) (xy 174.951898 -381.302768)
			(xy 174.941741 -381.302268) (xy 174.922973 -381.294494) (xy 174.908608 -381.280131) (xy 174.900832 -381.261363)
			(xy 174.900336 -381.251206) (xy 174.900336 -381.093472) (xy 174.899931 -381.084284) (xy 174.893413 -381.067101)
			(xy 174.887636 -381.059944) (xy 174.865868 -381.034275) (xy 174.827919 -380.978691) (xy 174.796885 -380.91897)
			(xy 174.773211 -380.855968) (xy 174.757237 -380.790587) (xy 174.749191 -380.723767) (xy 174.74919 -380.656463)
			(xy 171.471151 -380.656463) (xy 171.471149 -380.723828) (xy 171.46307 -380.790769) (xy 171.447031 -380.85626)
			(xy 171.423262 -380.919358) (xy 171.392106 -380.979154) (xy 171.354011 -381.034788) (xy 171.332144 -381.060452)
			(xy 171.326336 -381.067589) (xy 171.31983 -381.084786) (xy 171.319444 -381.09398) (xy 171.319444 -381.251206)
			(xy 171.318978 -381.261335) (xy 171.311245 -381.280059) (xy 171.296952 -381.294416) (xy 171.278263 -381.302232)
			(xy 171.268136 -381.302768) (xy 170.551856 -381.302768) (xy 170.541695 -381.302414) (xy 170.522936 -381.294598)
			(xy 170.508613 -381.28018) (xy 170.50092 -381.26137) (xy 170.500548 -381.251206) (xy 170.500548 -381.09398)
			(xy 170.500137 -381.084793) (xy 170.493623 -381.067609) (xy 170.487848 -381.060452) (xy 170.466002 -381.034771)
			(xy 170.42791 -380.97914) (xy 170.396755 -380.919347) (xy 170.372988 -380.856252) (xy 170.35695 -380.790764)
			(xy 170.348871 -380.723827) (xy 170.34887 -380.656403) (xy 167.070824 -380.656403) (xy 167.070831 -380.656462)
			(xy 167.070829 -380.723768) (xy 167.062783 -380.790592) (xy 167.046808 -380.855976) (xy 167.023133 -380.918981)
			(xy 166.992097 -380.978705) (xy 166.954145 -381.034292) (xy 166.932356 -381.059944) (xy 166.926553 -381.067084)
			(xy 166.920043 -381.084279) (xy 166.919656 -381.093472) (xy 166.919656 -381.251206) (xy 166.919171 -381.261365)
			(xy 166.911394 -381.280135) (xy 166.897025 -381.2945) (xy 166.878253 -381.302274) (xy 166.868094 -381.302768)
			(xy 166.151814 -381.302768) (xy 166.141644 -381.302325) (xy 166.122851 -381.294546) (xy 166.108466 -381.280166)
			(xy 166.100679 -381.261376) (xy 166.100252 -381.251206) (xy 166.100252 -381.093472) (xy 166.099844 -381.084285)
			(xy 166.093327 -381.067101) (xy 166.087552 -381.059944) (xy 166.065784 -381.034276) (xy 166.027833 -380.978692)
			(xy 165.996799 -380.918971) (xy 165.973124 -380.855968) (xy 165.957149 -380.790588) (xy 165.949103 -380.723767)
			(xy 165.949102 -380.656463) (xy 162.671063 -380.656463) (xy 162.671061 -380.723828) (xy 162.662983 -380.790768)
			(xy 162.646944 -380.856259) (xy 162.623176 -380.919357) (xy 162.59202 -380.979153) (xy 162.553927 -381.034787)
			(xy 162.53206 -381.060452) (xy 162.526254 -381.06759) (xy 162.519746 -381.084786) (xy 162.51936 -381.09398)
			(xy 162.51936 -381.251206) (xy 162.518878 -381.261333) (xy 162.511148 -381.280054) (xy 162.496861 -381.29441)
			(xy 162.478177 -381.302229) (xy 162.468052 -381.302768) (xy 161.751772 -381.302768) (xy 161.741612 -381.302401)
			(xy 161.722853 -381.29459) (xy 161.708529 -381.280176) (xy 161.700836 -381.261368) (xy 161.700464 -381.251206)
			(xy 161.700464 -381.09398) (xy 161.700049 -381.084794) (xy 161.693537 -381.06761) (xy 161.687764 -381.060452)
			(xy 161.665921 -381.03477) (xy 161.627834 -380.979137) (xy 161.596684 -380.919343) (xy 161.572921 -380.856248)
			(xy 161.556885 -380.790762) (xy 161.548808 -380.723826) (xy 161.548806 -380.656404) (xy 131.871003 -380.656404)
			(xy 131.87101 -380.656461) (xy 131.871008 -380.723769) (xy 131.862961 -380.790593) (xy 131.846985 -380.855977)
			(xy 131.823309 -380.918982) (xy 131.792271 -380.978706) (xy 131.754318 -381.034292) (xy 131.732528 -381.059944)
			(xy 131.726722 -381.067082) (xy 131.720215 -381.084278) (xy 131.719828 -381.093472) (xy 131.719828 -381.251206)
			(xy 131.71944 -381.261382) (xy 131.711647 -381.280184) (xy 131.69725 -381.294569) (xy 131.678443 -381.302348)
			(xy 131.668266 -381.302768) (xy 130.951986 -381.302768) (xy 130.941828 -381.302278) (xy 130.92306 -381.2945)
			(xy 130.908695 -381.280133) (xy 130.90092 -381.261364) (xy 130.900424 -381.251206) (xy 130.900424 -381.093472)
			(xy 130.900022 -381.084284) (xy 130.893502 -381.0671) (xy 130.887724 -381.059944) (xy 130.865956 -381.034276)
			(xy 130.828008 -380.978691) (xy 130.796975 -380.91897) (xy 130.773301 -380.855967) (xy 130.757327 -380.790587)
			(xy 130.749282 -380.723767) (xy 130.74928 -380.656463) (xy 127.471217 -380.656463) (xy 127.471215 -380.723827)
			(xy 127.463138 -380.790766) (xy 127.447101 -380.856256) (xy 127.423336 -380.919354) (xy 127.392185 -380.979151)
			(xy 127.354096 -381.034786) (xy 127.332232 -381.060452) (xy 127.326423 -381.067588) (xy 127.319918 -381.084786)
			(xy 127.319532 -381.09398) (xy 127.319532 -381.251206) (xy 127.319077 -381.261337) (xy 127.311342 -381.280063)
			(xy 127.297046 -381.29442) (xy 127.278352 -381.302234) (xy 127.268224 -381.302768) (xy 126.551944 -381.302768)
			(xy 126.541789 -381.302342) (xy 126.523031 -381.294555) (xy 126.508705 -381.280159) (xy 126.50101 -381.261363)
			(xy 126.500636 -381.251206) (xy 126.500636 -381.09398) (xy 126.500227 -381.084793) (xy 126.493712 -381.067609)
			(xy 126.487936 -381.060452) (xy 126.46609 -381.034771) (xy 126.427999 -380.97914) (xy 126.396845 -380.919346)
			(xy 126.373078 -380.856251) (xy 126.35704 -380.790764) (xy 126.348962 -380.723826) (xy 126.34896 -380.656404)
			(xy 123.070915 -380.656404) (xy 123.070922 -380.656462) (xy 123.07092 -380.723769) (xy 123.062874 -380.790593)
			(xy 123.046898 -380.855976) (xy 123.023223 -380.918982) (xy 122.992186 -380.978706) (xy 122.954234 -381.034292)
			(xy 122.932444 -381.059944) (xy 122.926639 -381.067083) (xy 122.920131 -381.084279) (xy 122.919744 -381.093472)
			(xy 122.919744 -381.251206) (xy 122.919341 -381.26138) (xy 122.91155 -381.280178) (xy 122.897158 -381.294564)
			(xy 122.878356 -381.302345) (xy 122.868182 -381.302768) (xy 122.151902 -381.302768) (xy 122.141745 -381.302265)
			(xy 122.122977 -381.294492) (xy 122.108612 -381.28013) (xy 122.100836 -381.261363) (xy 122.10034 -381.251206)
			(xy 122.10034 -381.093472) (xy 122.099934 -381.084285) (xy 122.093417 -381.067101) (xy 122.08764 -381.059944)
			(xy 122.065872 -381.034276) (xy 122.027923 -380.978691) (xy 121.996888 -380.91897) (xy 121.973215 -380.855968)
			(xy 121.95724 -380.790588) (xy 121.949194 -380.723767) (xy 121.949193 -380.656463) (xy 118.671154 -380.656463)
			(xy 118.671152 -380.723828) (xy 118.663073 -380.790769) (xy 118.647034 -380.85626) (xy 118.623265 -380.919357)
			(xy 118.592109 -380.979154) (xy 118.554015 -381.034788) (xy 118.532148 -381.060452) (xy 118.52634 -381.067589)
			(xy 118.519834 -381.084786) (xy 118.519448 -381.09398) (xy 118.519448 -381.251206) (xy 118.518978 -381.261335)
			(xy 118.511246 -381.280058) (xy 118.496954 -381.294415) (xy 118.478266 -381.302231) (xy 118.46814 -381.302768)
			(xy 117.75186 -381.302768) (xy 117.741699 -381.30241) (xy 117.72294 -381.294596) (xy 117.708617 -381.280179)
			(xy 117.700924 -381.261369) (xy 117.700552 -381.251206) (xy 117.700552 -381.09398) (xy 117.70014 -381.084793)
			(xy 117.693626 -381.06761) (xy 117.687852 -381.060452) (xy 117.666006 -381.034771) (xy 117.627913 -380.97914)
			(xy 117.596759 -380.919347) (xy 117.572991 -380.856252) (xy 117.556953 -380.790764) (xy 117.548874 -380.723827)
			(xy 117.548873 -380.656403) (xy 105.919524 -380.656403) (xy 105.919524 -380.877572) (xy 105.919034 -380.907556)
			(xy 105.911206 -380.967012) (xy 105.895685 -381.024937) (xy 105.872736 -381.080341) (xy 105.842752 -381.132275)
			(xy 105.806246 -381.179851) (xy 105.763841 -381.222256) (xy 105.716265 -381.258762) (xy 105.664331 -381.288746)
			(xy 105.608927 -381.311695) (xy 105.551002 -381.327216) (xy 105.491546 -381.335044) (xy 105.431578 -381.335044)
			(xy 105.372122 -381.327216) (xy 105.314197 -381.311695) (xy 105.258793 -381.288746) (xy 105.206859 -381.258762)
			(xy 105.159283 -381.222256) (xy 105.116878 -381.179851) (xy 105.080372 -381.132275) (xy 105.050388 -381.080341)
			(xy 105.027439 -381.024937) (xy 105.011918 -380.967012) (xy 105.00409 -380.907556) (xy 105.0036 -380.877572)
			(xy 87.838954 -380.877572) (xy 87.823216 -380.919355) (xy 87.792063 -380.979152) (xy 87.753973 -381.034787)
			(xy 87.732108 -381.060452) (xy 87.726308 -381.067595) (xy 87.719795 -381.084787) (xy 87.719408 -381.09398)
			(xy 87.719408 -381.251206) (xy 87.71888 -381.261327) (xy 87.711159 -381.280039) (xy 87.696886 -381.294394)
			(xy 87.678218 -381.302221) (xy 87.6681 -381.302768) (xy 86.95182 -381.302768) (xy 86.941663 -381.302362)
			(xy 86.922905 -381.294567) (xy 86.90858 -381.280165) (xy 86.900885 -381.261365) (xy 86.900512 -381.251206)
			(xy 86.900512 -381.09398) (xy 86.900109 -381.084792) (xy 86.89359 -381.067608) (xy 86.887812 -381.060452)
			(xy 86.865967 -381.034771) (xy 86.827877 -380.979139) (xy 86.796725 -380.919345) (xy 86.772959 -380.85625)
			(xy 86.756922 -380.790763) (xy 86.748844 -380.723826) (xy 86.748842 -380.656404) (xy 83.470797 -380.656404)
			(xy 83.470804 -380.656461) (xy 83.470802 -380.723769) (xy 83.462755 -380.790593) (xy 83.446779 -380.855977)
			(xy 83.423102 -380.918983) (xy 83.392064 -380.978706) (xy 83.35411 -381.034292) (xy 83.33232 -381.059944)
			(xy 83.326525 -381.06709) (xy 83.320009 -381.08428) (xy 83.31962 -381.093472) (xy 83.31962 -381.251206)
			(xy 83.31924 -381.261383) (xy 83.311445 -381.280186) (xy 83.297046 -381.294572) (xy 83.278236 -381.302349)
			(xy 83.268058 -381.302768) (xy 82.551778 -381.302768) (xy 82.54162 -381.302285) (xy 82.522851 -381.294504)
			(xy 82.508487 -381.280136) (xy 82.500712 -381.261365) (xy 82.500216 -381.251206) (xy 82.500216 -381.093472)
			(xy 82.499816 -381.084284) (xy 82.493295 -381.0671) (xy 82.487516 -381.059944) (xy 82.465749 -381.034275)
			(xy 82.427801 -380.978691) (xy 82.396768 -380.918969) (xy 82.373095 -380.855967) (xy 82.357121 -380.790587)
			(xy 82.349076 -380.723767) (xy 82.349074 -380.656464) (xy 79.071011 -380.656464) (xy 79.071009 -380.723827)
			(xy 79.062932 -380.790767) (xy 79.046895 -380.856256) (xy 79.02313 -380.919354) (xy 78.991978 -380.979151)
			(xy 78.953888 -381.034786) (xy 78.932024 -381.060452) (xy 78.926226 -381.067596) (xy 78.919711 -381.084787)
			(xy 78.919324 -381.09398) (xy 78.919324 -381.251206) (xy 78.918877 -381.261337) (xy 78.911141 -381.280066)
			(xy 78.896842 -381.294423) (xy 78.878145 -381.302235) (xy 78.868016 -381.302768) (xy 78.151736 -381.302768)
			(xy 78.14158 -381.302348) (xy 78.122823 -381.294558) (xy 78.108497 -381.28016) (xy 78.100802 -381.261364)
			(xy 78.100428 -381.251206) (xy 78.100428 -381.09398) (xy 78.100021 -381.084793) (xy 78.093505 -381.067609)
			(xy 78.087728 -381.060452) (xy 78.065883 -381.034771) (xy 78.027792 -380.979139) (xy 77.996638 -380.919346)
			(xy 77.972872 -380.856251) (xy 77.956834 -380.790763) (xy 77.948756 -380.723826) (xy 77.948754 -380.656404)
			(xy 74.670709 -380.656404) (xy 74.670716 -380.656462) (xy 74.670714 -380.723769) (xy 74.662667 -380.790593)
			(xy 74.646691 -380.855977) (xy 74.623015 -380.918982) (xy 74.591978 -380.978706) (xy 74.554026 -381.034292)
			(xy 74.532236 -381.059944) (xy 74.52643 -381.067082) (xy 74.519923 -381.084278) (xy 74.519536 -381.093472)
			(xy 74.519536 -381.251206) (xy 74.51914 -381.261381) (xy 74.511349 -381.280181) (xy 74.496954 -381.294567)
			(xy 74.478149 -381.302347) (xy 74.467974 -381.302768) (xy 73.751694 -381.302768) (xy 73.741537 -381.302272)
			(xy 73.722769 -381.294496) (xy 73.708404 -381.280131) (xy 73.700628 -381.261363) (xy 73.700132 -381.251206)
			(xy 73.700132 -381.093472) (xy 73.699728 -381.084284) (xy 73.693209 -381.0671) (xy 73.687432 -381.059944)
			(xy 73.665664 -381.034275) (xy 73.627715 -380.978691) (xy 73.596682 -380.91897) (xy 73.573008 -380.855967)
			(xy 73.557034 -380.790587) (xy 73.548988 -380.723767) (xy 73.548987 -380.656463) (xy 43.87119 -380.656463)
			(xy 43.871188 -380.723828) (xy 43.86311 -380.790767) (xy 43.847073 -380.856258) (xy 43.823306 -380.919355)
			(xy 43.792153 -380.979152) (xy 43.754061 -381.034787) (xy 43.732196 -381.060452) (xy 43.726394 -381.067594)
			(xy 43.719883 -381.084787) (xy 43.719496 -381.09398) (xy 43.719496 -381.251206) (xy 43.718979 -381.261329)
			(xy 43.711256 -381.280043) (xy 43.69698 -381.294398) (xy 43.678308 -381.302223) (xy 43.668188 -381.302768)
			(xy 42.951908 -381.302768) (xy 42.94175 -381.302371) (xy 42.922992 -381.294572) (xy 42.908667 -381.280167)
			(xy 42.900973 -381.261366) (xy 42.9006 -381.251206) (xy 42.9006 -381.09398) (xy 42.9002 -381.084792)
			(xy 42.893679 -381.067607) (xy 42.8879 -381.060452) (xy 42.866056 -381.034771) (xy 42.827966 -380.979138)
			(xy 42.796815 -380.919344) (xy 42.773049 -380.85625) (xy 42.757013 -380.790763) (xy 42.748935 -380.723826)
			(xy 42.748933 -380.656404) (xy 39.470887 -380.656404) (xy 39.470894 -380.656461) (xy 39.470893 -380.723769)
			(xy 39.462846 -380.790594) (xy 39.446869 -380.855978) (xy 39.423192 -380.918983) (xy 39.392153 -380.978707)
			(xy 39.354199 -381.034293) (xy 39.332408 -381.059944) (xy 39.326611 -381.067089) (xy 39.320096 -381.08428)
			(xy 39.319708 -381.093472) (xy 39.319708 -381.251206) (xy 39.319173 -381.261358) (xy 39.311405 -381.280119)
			(xy 39.297052 -381.294482) (xy 39.278298 -381.302265) (xy 39.268146 -381.302768) (xy 38.551866 -381.302768)
			(xy 38.541707 -381.302295) (xy 38.522938 -381.29451) (xy 38.508574 -381.280138) (xy 38.5008 -381.261365)
			(xy 38.500304 -381.251206) (xy 38.500304 -381.093472) (xy 38.499907 -381.084283) (xy 38.493384 -381.067099)
			(xy 38.487604 -381.059944) (xy 38.465837 -381.034275) (xy 38.42789 -380.97869) (xy 38.396858 -380.918969)
			(xy 38.373185 -380.855966) (xy 38.357212 -380.790587) (xy 38.349167 -380.723766) (xy 38.349165 -380.656464)
			(xy 35.071102 -380.656464) (xy 35.0711 -380.723828) (xy 35.063023 -380.790767) (xy 35.046985 -380.856257)
			(xy 35.023219 -380.919355) (xy 34.992067 -380.979151) (xy 34.953977 -381.034787) (xy 34.932112 -381.060452)
			(xy 34.926312 -381.067595) (xy 34.919799 -381.084787) (xy 34.919412 -381.09398) (xy 34.919412 -381.251206)
			(xy 34.91888 -381.261327) (xy 34.91116 -381.280038) (xy 34.896888 -381.294392) (xy 34.878222 -381.30222)
			(xy 34.868104 -381.302768) (xy 34.151824 -381.302768) (xy 34.141667 -381.302358) (xy 34.122909 -381.294565)
			(xy 34.108584 -381.280164) (xy 34.100889 -381.261365) (xy 34.100516 -381.251206) (xy 34.100516 -381.09398)
			(xy 34.100112 -381.084792) (xy 34.093594 -381.067608) (xy 34.087816 -381.060452) (xy 34.065971 -381.034771)
			(xy 34.027881 -380.979139) (xy 33.996728 -380.919345) (xy 33.972962 -380.85625) (xy 33.956925 -380.790763)
			(xy 33.948847 -380.723826) (xy 33.948845 -380.656404) (xy 30.6708 -380.656404) (xy 30.670807 -380.656461)
			(xy 30.670805 -380.723769) (xy 30.662758 -380.790593) (xy 30.646782 -380.855977) (xy 30.623105 -380.918982)
			(xy 30.592068 -380.978706) (xy 30.554114 -381.034292) (xy 30.532324 -381.059944) (xy 30.526529 -381.067091)
			(xy 30.520013 -381.08428) (xy 30.519624 -381.093472) (xy 30.519624 -381.251206) (xy 30.51924 -381.261383)
			(xy 30.511446 -381.280185) (xy 30.497048 -381.294571) (xy 30.478239 -381.302349) (xy 30.468062 -381.302768)
			(xy 29.751782 -381.302768) (xy 29.741624 -381.302282) (xy 29.722855 -381.294502) (xy 29.708491 -381.280135)
			(xy 29.700716 -381.261364) (xy 29.70022 -381.251206) (xy 29.70022 -381.093472) (xy 29.699819 -381.084284)
			(xy 29.693298 -381.0671) (xy 29.68752 -381.059944) (xy 29.665752 -381.034276) (xy 29.627804 -380.978691)
			(xy 29.596771 -380.918969) (xy 29.573098 -380.855967) (xy 29.557124 -380.790587) (xy 29.549079 -380.723767)
			(xy 29.549077 -380.656463) (xy 29.557119 -380.589643) (xy 29.573089 -380.524262) (xy 29.596759 -380.461258)
			(xy 29.627789 -380.401535) (xy 29.665734 -380.345948) (xy 29.68752 -380.320296) (xy 29.693303 -380.313141)
			(xy 29.699825 -380.295958) (xy 29.70022 -380.286768) (xy 29.70022 -379.7935) (xy 29.699806 -379.784313)
			(xy 29.693295 -379.767129) (xy 29.68752 -379.759972) (xy 29.66573 -379.734322) (xy 29.627781 -379.678735)
			(xy 29.596748 -379.619011) (xy 29.573075 -379.556006) (xy 29.557102 -379.490624) (xy 29.549058 -379.423801)
			(xy 28.447 -379.423801) (xy 28.447041 -379.423909) (xy 28.463077 -379.489397) (xy 28.471153 -379.556335)
			(xy 28.471153 -379.623759) (xy 28.463078 -379.690697) (xy 28.447043 -379.756186) (xy 28.423279 -379.819282)
			(xy 28.392128 -379.879078) (xy 28.35404 -379.934713) (xy 28.332176 -379.960378) (xy 28.326361 -379.96751)
			(xy 28.319858 -379.984711) (xy 28.319476 -379.993906) (xy 28.319476 -380.151386) (xy 28.318962 -380.16151)
			(xy 28.311242 -380.180228) (xy 28.296964 -380.194584) (xy 28.278289 -380.202406) (xy 28.268168 -380.202948)
			(xy 27.551888 -380.202948) (xy 27.541739 -380.202489) (xy 27.522996 -380.194699) (xy 27.508674 -380.180314)
			(xy 27.500966 -380.161537) (xy 27.50058 -380.151386) (xy 27.50058 -379.993906) (xy 27.500171 -379.984719)
			(xy 27.493657 -379.967534) (xy 27.48788 -379.960378) (xy 27.466012 -379.934716) (xy 27.427923 -379.879081)
			(xy 27.396771 -379.819285) (xy 27.373007 -379.756187) (xy 27.356972 -379.690698) (xy 27.348896 -379.623759)
			(xy 27.348896 -379.556335) (xy 27.356973 -379.489396) (xy 27.373009 -379.423907) (xy 27.396774 -379.36081)
			(xy 27.427926 -379.301013) (xy 27.466015 -379.245379) (xy 27.48788 -379.219714) (xy 27.493693 -379.21258)
			(xy 27.500199 -379.195381) (xy 27.50058 -379.186186) (xy 27.50058 -378.693934) (xy 27.500158 -378.684748)
			(xy 27.493653 -378.667563) (xy 27.48788 -378.660406) (xy 27.465991 -378.634761) (xy 27.427905 -378.579124)
			(xy 27.396756 -378.519324) (xy 27.372994 -378.456225) (xy 27.356961 -378.390733) (xy 27.348888 -378.323793)
			(xy 1.524 -378.323793) (xy 1.524 -382.223705) (xy 27.348899 -382.223705) (xy 27.3489 -382.15628)
			(xy 27.356976 -382.089342) (xy 27.373012 -382.023853) (xy 27.396777 -381.960755) (xy 27.427928 -381.900959)
			(xy 27.466016 -381.845324) (xy 27.48788 -381.819658) (xy 27.493675 -381.812511) (xy 27.500191 -381.795322)
			(xy 27.50058 -381.78613) (xy 27.50058 -381.628904) (xy 27.501088 -381.618798) (xy 27.508821 -381.600124)
			(xy 27.52311 -381.58583) (xy 27.541782 -381.578091) (xy 27.551888 -381.577596) (xy 28.268168 -381.577596)
			(xy 28.278288 -381.578042) (xy 28.29699 -381.585779) (xy 28.311306 -381.600086) (xy 28.319053 -381.618784)
			(xy 28.319476 -381.628904) (xy 28.319476 -381.78613) (xy 28.319877 -381.795318) (xy 28.326398 -381.812502)
			(xy 28.332176 -381.819658) (xy 28.354031 -381.845331) (xy 28.392122 -381.900964) (xy 28.423274 -381.960759)
			(xy 28.44704 -382.023855) (xy 28.463077 -382.089343) (xy 28.471154 -382.156281) (xy 28.471155 -382.223646)
			(xy 31.749194 -382.223646) (xy 31.749195 -382.156339) (xy 31.757241 -382.089516) (xy 31.773216 -382.024132)
			(xy 31.796891 -381.961127) (xy 31.827927 -381.901404) (xy 31.865879 -381.845818) (xy 31.887668 -381.820166)
			(xy 31.89347 -381.813025) (xy 31.899979 -381.795831) (xy 31.900368 -381.786638) (xy 31.900368 -381.628904)
			(xy 31.900824 -381.618754) (xy 31.908613 -381.600008) (xy 31.922998 -381.585686) (xy 31.941778 -381.57798)
			(xy 31.95193 -381.577596) (xy 32.66821 -381.577596) (xy 32.678332 -381.578117) (xy 32.697045 -381.58584)
			(xy 32.711399 -381.600115) (xy 32.719226 -381.618785) (xy 32.719772 -381.628904) (xy 32.719772 -381.786638)
			(xy 32.72017 -381.795826) (xy 32.726693 -381.81301) (xy 32.732472 -381.820166) (xy 32.75425 -381.845826)
			(xy 32.792198 -381.901412) (xy 32.823231 -381.961134) (xy 32.846904 -382.024138) (xy 32.862877 -382.089519)
			(xy 32.870922 -382.15634) (xy 32.870923 -382.223645) (xy 32.870916 -382.223704) (xy 36.148987 -382.223704)
			(xy 36.148988 -382.156281) (xy 36.157064 -382.089342) (xy 36.1731 -382.023853) (xy 36.196863 -381.960756)
			(xy 36.228013 -381.900959) (xy 36.266101 -381.845324) (xy 36.287964 -381.819658) (xy 36.293769 -381.812519)
			(xy 36.300277 -381.795323) (xy 36.300664 -381.78613) (xy 36.300664 -381.628904) (xy 36.301188 -381.6188)
			(xy 36.308917 -381.600129) (xy 36.323202 -381.585835) (xy 36.341868 -381.578094) (xy 36.351972 -381.577596)
			(xy 37.068252 -381.577596) (xy 37.078371 -381.578055) (xy 37.097073 -381.585787) (xy 37.111388 -381.60009)
			(xy 37.119136 -381.618786) (xy 37.11956 -381.628904) (xy 37.11956 -381.78613) (xy 37.119965 -381.795318)
			(xy 37.126483 -381.812501) (xy 37.13226 -381.819658) (xy 37.154116 -381.845331) (xy 37.192207 -381.900963)
			(xy 37.223361 -381.960758) (xy 37.247127 -382.023854) (xy 37.263164 -382.089343) (xy 37.271242 -382.156281)
			(xy 37.271243 -382.223704) (xy 37.271243 -382.223705) (xy 40.548753 -382.223705) (xy 40.548754 -382.15628)
			(xy 40.556832 -382.08934) (xy 40.57287 -382.02385) (xy 40.596638 -381.960752) (xy 40.627792 -381.900956)
			(xy 40.665886 -381.845322) (xy 40.687752 -381.819658) (xy 40.693555 -381.812518) (xy 40.700065 -381.795323)
			(xy 40.700452 -381.78613) (xy 40.700452 -381.628904) (xy 40.700987 -381.618801) (xy 40.708715 -381.600133)
			(xy 40.722996 -381.585839) (xy 40.741658 -381.578096) (xy 40.75176 -381.577596) (xy 41.46804 -381.577596)
			(xy 41.478151 -381.578052) (xy 41.496829 -381.585802) (xy 41.511122 -381.600108) (xy 41.518856 -381.618793)
			(xy 41.519348 -381.628904) (xy 41.519348 -381.78613) (xy 41.519755 -381.795317) (xy 41.526272 -381.812501)
			(xy 41.532048 -381.819658) (xy 41.553904 -381.84533) (xy 41.591996 -381.900963) (xy 41.62315 -381.960757)
			(xy 41.646917 -382.023853) (xy 41.662955 -382.089342) (xy 41.671033 -382.156281) (xy 41.671034 -382.223645)
			(xy 44.949073 -382.223645) (xy 44.949074 -382.15634) (xy 44.957119 -382.089516) (xy 44.973093 -382.024133)
			(xy 44.996767 -381.961128) (xy 45.027801 -381.901405) (xy 45.065751 -381.845818) (xy 45.08754 -381.820166)
			(xy 45.093339 -381.813022) (xy 45.099851 -381.795831) (xy 45.10024 -381.786638) (xy 45.10024 -381.628904)
			(xy 45.100626 -381.618745) (xy 45.108427 -381.599985) (xy 45.122836 -381.58566) (xy 45.141641 -381.577968)
			(xy 45.151802 -381.577596) (xy 45.868082 -381.577596) (xy 45.878202 -381.57814) (xy 45.896915 -381.585854)
			(xy 45.91127 -381.600122) (xy 45.919098 -381.618787) (xy 45.919644 -381.628904) (xy 45.919644 -381.786638)
			(xy 45.920049 -381.795826) (xy 45.926568 -381.813009) (xy 45.932344 -381.820166) (xy 45.954122 -381.845826)
			(xy 45.992072 -381.901411) (xy 46.023107 -381.961133) (xy 46.046781 -382.024137) (xy 46.062755 -382.089518)
			(xy 46.070801 -382.15634) (xy 46.070801 -382.223645) (xy 46.070794 -382.223705) (xy 71.348808 -382.223705)
			(xy 71.348809 -382.15628) (xy 71.356886 -382.089342) (xy 71.372922 -382.023852) (xy 71.396687 -381.960755)
			(xy 71.427838 -381.900958) (xy 71.465928 -381.845323) (xy 71.487792 -381.819658) (xy 71.493588 -381.812512)
			(xy 71.500103 -381.795322) (xy 71.500492 -381.78613) (xy 71.500492 -381.628904) (xy 71.500919 -381.618783)
			(xy 71.508664 -381.600081) (xy 71.522977 -381.585767) (xy 71.541679 -381.57802) (xy 71.5518 -381.577596)
			(xy 72.26808 -381.577596) (xy 72.278201 -381.578032) (xy 72.296903 -381.585773) (xy 72.311218 -381.600083)
			(xy 72.318965 -381.618783) (xy 72.319388 -381.628904) (xy 72.319388 -381.78613) (xy 72.319786 -381.795318)
			(xy 72.326308 -381.812503) (xy 72.332088 -381.819658) (xy 72.353943 -381.845331) (xy 72.392032 -381.900964)
			(xy 72.423184 -381.960759) (xy 72.446949 -382.023855) (xy 72.462986 -382.089343) (xy 72.471063 -382.156281)
			(xy 72.471064 -382.223646) (xy 75.749104 -382.223646) (xy 75.749104 -382.156339) (xy 75.75715 -382.089515)
			(xy 75.773125 -382.024132) (xy 75.796801 -381.961127) (xy 75.827838 -381.901403) (xy 75.86579 -381.845818)
			(xy 75.88758 -381.820166) (xy 75.893371 -381.813017) (xy 75.89989 -381.795829) (xy 75.90028 -381.786638)
			(xy 75.90028 -381.628904) (xy 75.900725 -381.618753) (xy 75.908515 -381.600004) (xy 75.922904 -381.585681)
			(xy 75.941689 -381.577978) (xy 75.951842 -381.577596) (xy 76.668122 -381.577596) (xy 76.678245 -381.578107)
			(xy 76.696958 -381.585834) (xy 76.711312 -381.600112) (xy 76.719138 -381.618784) (xy 76.719684 -381.628904)
			(xy 76.719684 -381.786638) (xy 76.720079 -381.795827) (xy 76.726604 -381.813011) (xy 76.732384 -381.820166)
			(xy 76.754161 -381.845826) (xy 76.792109 -381.901412) (xy 76.823141 -381.961135) (xy 76.846814 -382.024138)
			(xy 76.862787 -382.089519) (xy 76.870831 -382.156341) (xy 76.870832 -382.223644) (xy 76.870825 -382.223704)
			(xy 80.148896 -382.223704) (xy 80.148897 -382.15628) (xy 80.156973 -382.089342) (xy 80.173009 -382.023853)
			(xy 80.196773 -381.960755) (xy 80.227924 -381.900959) (xy 80.266012 -381.845324) (xy 80.287876 -381.819658)
			(xy 80.29367 -381.812511) (xy 80.300187 -381.795322) (xy 80.300576 -381.78613) (xy 80.300576 -381.628904)
			(xy 80.301088 -381.618798) (xy 80.30882 -381.600125) (xy 80.323108 -381.585831) (xy 80.341779 -381.578092)
			(xy 80.351884 -381.577596) (xy 81.068164 -381.577596) (xy 81.078284 -381.578046) (xy 81.096986 -381.585781)
			(xy 81.111301 -381.600087) (xy 81.119048 -381.618785) (xy 81.119472 -381.628904) (xy 81.119472 -381.78613)
			(xy 81.119874 -381.795318) (xy 81.126394 -381.812502) (xy 81.132172 -381.819658) (xy 81.154027 -381.845331)
			(xy 81.192118 -381.900964) (xy 81.223271 -381.960759) (xy 81.247037 -382.023854) (xy 81.263074 -382.089343)
			(xy 81.271151 -382.156281) (xy 81.271152 -382.223704) (xy 84.548687 -382.223704) (xy 84.548688 -382.156281)
			(xy 84.556764 -382.089342) (xy 84.5728 -382.023853) (xy 84.596563 -381.960756) (xy 84.627713 -381.900959)
			(xy 84.665801 -381.845324) (xy 84.687664 -381.819658) (xy 84.693469 -381.812519) (xy 84.699977 -381.795323)
			(xy 84.700364 -381.78613) (xy 84.700364 -381.628904) (xy 84.700888 -381.6188) (xy 84.708617 -381.600129)
			(xy 84.722902 -381.585835) (xy 84.741568 -381.578094) (xy 84.751672 -381.577596) (xy 85.467952 -381.577596)
			(xy 85.478071 -381.578055) (xy 85.496773 -381.585787) (xy 85.511088 -381.60009) (xy 85.518836 -381.618786)
			(xy 85.51926 -381.628904) (xy 85.51926 -381.78613) (xy 85.519665 -381.795318) (xy 85.526183 -381.812501)
			(xy 85.53196 -381.819658) (xy 85.553816 -381.845331) (xy 85.591907 -381.900963) (xy 85.623061 -381.960758)
			(xy 85.646827 -382.023854) (xy 85.662864 -382.089343) (xy 85.670942 -382.156281) (xy 85.670943 -382.223646)
			(xy 88.948982 -382.223646) (xy 88.948983 -382.156339) (xy 88.957028 -382.089516) (xy 88.973003 -382.024133)
			(xy 88.996677 -381.961128) (xy 89.027712 -381.901404) (xy 89.065663 -381.845818) (xy 89.087452 -381.820166)
			(xy 89.093252 -381.813023) (xy 89.099763 -381.795831) (xy 89.100152 -381.786638) (xy 89.100152 -381.628904)
			(xy 89.100624 -381.618756) (xy 89.108409 -381.600013) (xy 89.12279 -381.585691) (xy 89.141564 -381.577983)
			(xy 89.151714 -381.577596) (xy 89.867994 -381.577596) (xy 89.878115 -381.57813) (xy 89.896828 -381.585848)
			(xy 89.911183 -381.600119) (xy 89.91901 -381.618786) (xy 89.919556 -381.628904) (xy 89.919556 -381.786638)
			(xy 89.919958 -381.795826) (xy 89.926478 -381.81301) (xy 89.932256 -381.820166) (xy 89.954034 -381.845826)
			(xy 89.991983 -381.901411) (xy 90.023017 -381.961134) (xy 90.046691 -382.024137) (xy 90.062665 -382.089519)
			(xy 90.07071 -382.15634) (xy 90.070711 -382.223645) (xy 115.349246 -382.223645) (xy 115.349247 -382.15634)
			(xy 115.357291 -382.089517) (xy 115.373264 -382.024135) (xy 115.396937 -381.96113) (xy 115.427969 -381.901406)
			(xy 115.465917 -381.845819) (xy 115.487704 -381.820166) (xy 115.493498 -381.813019) (xy 115.500014 -381.79583)
			(xy 115.500404 -381.786638) (xy 115.500404 -381.628904) (xy 115.500825 -381.61875) (xy 115.50862 -381.599997)
			(xy 115.523017 -381.585673) (xy 115.54181 -381.577974) (xy 115.551966 -381.577596) (xy 116.268246 -381.577596)
			(xy 116.27837 -381.578088) (xy 116.297084 -381.585822) (xy 116.311437 -381.600106) (xy 116.319262 -381.618782)
			(xy 116.319808 -381.628904) (xy 116.319808 -381.786638) (xy 116.320198 -381.795827) (xy 116.326725 -381.813012)
			(xy 116.332508 -381.820166) (xy 116.354288 -381.845826) (xy 116.39224 -381.90141) (xy 116.423277 -381.961132)
			(xy 116.446952 -382.024135) (xy 116.462928 -382.089517) (xy 116.470973 -382.15634) (xy 116.470974 -382.223645)
			(xy 116.470967 -382.223705) (xy 119.749014 -382.223705) (xy 119.749015 -382.15628) (xy 119.757092 -382.089341)
			(xy 119.773128 -382.023852) (xy 119.796894 -381.960754) (xy 119.828046 -381.900958) (xy 119.866135 -381.845323)
			(xy 119.888 -381.819658) (xy 119.893797 -381.812513) (xy 119.900311 -381.795322) (xy 119.9007 -381.78613)
			(xy 119.9007 -381.628904) (xy 119.901119 -381.618782) (xy 119.908866 -381.600078) (xy 119.923182 -381.585764)
			(xy 119.941886 -381.578019) (xy 119.952008 -381.577596) (xy 120.668288 -381.577596) (xy 120.678409 -381.578026)
			(xy 120.697112 -381.585769) (xy 120.711426 -381.600081) (xy 120.719173 -381.618783) (xy 120.719596 -381.628904)
			(xy 120.719596 -381.78613) (xy 120.719992 -381.795319) (xy 120.726516 -381.812503) (xy 120.732296 -381.819658)
			(xy 120.75415 -381.845331) (xy 120.79224 -381.900965) (xy 120.823391 -381.96076) (xy 120.847156 -382.023855)
			(xy 120.863192 -382.089344) (xy 120.871269 -382.156281) (xy 120.87127 -382.223646) (xy 124.14931 -382.223646)
			(xy 124.14931 -382.156339) (xy 124.157356 -382.089515) (xy 124.173332 -382.024132) (xy 124.197008 -381.961127)
			(xy 124.228045 -381.901403) (xy 124.265998 -381.845818) (xy 124.287788 -381.820166) (xy 124.29358 -381.813018)
			(xy 124.300098 -381.79583) (xy 124.300488 -381.786638) (xy 124.300488 -381.628904) (xy 124.300925 -381.618752)
			(xy 124.308717 -381.600002) (xy 124.323109 -381.585679) (xy 124.341896 -381.577977) (xy 124.35205 -381.577596)
			(xy 125.06833 -381.577596) (xy 125.078453 -381.578101) (xy 125.097167 -381.58583) (xy 125.11152 -381.60011)
			(xy 125.119346 -381.618783) (xy 125.119892 -381.628904) (xy 125.119892 -381.786638) (xy 125.120286 -381.795827)
			(xy 125.126811 -381.813011) (xy 125.132592 -381.820166) (xy 125.154369 -381.845827) (xy 125.192316 -381.901413)
			(xy 125.223348 -381.961135) (xy 125.24702 -382.024139) (xy 125.262993 -382.089519) (xy 125.271037 -382.156341)
			(xy 125.271038 -382.223644) (xy 125.271038 -382.223646) (xy 128.5491 -382.223646) (xy 128.549101 -382.156339)
			(xy 128.557147 -382.089515) (xy 128.573122 -382.024132) (xy 128.596798 -381.961127) (xy 128.627834 -381.901404)
			(xy 128.665787 -381.845818) (xy 128.687576 -381.820166) (xy 128.693367 -381.813016) (xy 128.699886 -381.795829)
			(xy 128.700276 -381.786638) (xy 128.700276 -381.628904) (xy 128.700724 -381.618753) (xy 128.708514 -381.600005)
			(xy 128.722902 -381.585683) (xy 128.741685 -381.577979) (xy 128.751838 -381.577596) (xy 129.468118 -381.577596)
			(xy 129.47824 -381.57811) (xy 129.496954 -381.585836) (xy 129.511308 -381.600113) (xy 129.519134 -381.618784)
			(xy 129.51968 -381.628904) (xy 129.51968 -381.786638) (xy 129.520076 -381.795827) (xy 129.5266 -381.813011)
			(xy 129.53238 -381.820166) (xy 129.554157 -381.845826) (xy 129.592105 -381.901412) (xy 129.623138 -381.961135)
			(xy 129.64681 -382.024138) (xy 129.662784 -382.089519) (xy 129.670828 -382.156341) (xy 129.670829 -382.223644)
			(xy 129.670829 -382.223645) (xy 159.349155 -382.223645) (xy 159.349156 -382.15634) (xy 159.3572 -382.089517)
			(xy 159.373174 -382.024134) (xy 159.396847 -381.96113) (xy 159.42788 -381.901406) (xy 159.465828 -381.845818)
			(xy 159.487616 -381.820166) (xy 159.493411 -381.81302) (xy 159.499926 -381.79583) (xy 159.500316 -381.786638)
			(xy 159.500316 -381.628904) (xy 159.500725 -381.618748) (xy 159.508522 -381.599993) (xy 159.522923 -381.585669)
			(xy 159.54172 -381.577972) (xy 159.551878 -381.577596) (xy 160.268158 -381.577596) (xy 160.278277 -381.57816)
			(xy 160.296988 -381.585866) (xy 160.311345 -381.600128) (xy 160.319173 -381.618789) (xy 160.31972 -381.628904)
			(xy 160.31972 -381.786638) (xy 160.320108 -381.795828) (xy 160.326637 -381.813012) (xy 160.33242 -381.820166)
			(xy 160.354199 -381.845826) (xy 160.392151 -381.90141) (xy 160.423187 -381.961132) (xy 160.446862 -382.024136)
			(xy 160.462837 -382.089518) (xy 160.470882 -382.15634) (xy 160.470883 -382.223645) (xy 160.470876 -382.223705)
			(xy 163.748923 -382.223705) (xy 163.748924 -382.15628) (xy 163.757001 -382.089341) (xy 163.773038 -382.023851)
			(xy 163.796804 -381.960754) (xy 163.827956 -381.900957) (xy 163.866047 -381.845323) (xy 163.887912 -381.819658)
			(xy 163.89371 -381.812514) (xy 163.900224 -381.795323) (xy 163.900612 -381.78613) (xy 163.900612 -381.628904)
			(xy 163.90102 -381.61878) (xy 163.908769 -381.600074) (xy 163.923088 -381.58576) (xy 163.941796 -381.578016)
			(xy 163.95192 -381.577596) (xy 164.6682 -381.577596) (xy 164.678322 -381.578016) (xy 164.697025 -381.585763)
			(xy 164.711339 -381.600079) (xy 164.719085 -381.618782) (xy 164.719508 -381.628904) (xy 164.719508 -381.78613)
			(xy 164.719902 -381.795319) (xy 164.726426 -381.812503) (xy 164.732208 -381.819658) (xy 164.754062 -381.845331)
			(xy 164.79215 -381.900965) (xy 164.823301 -381.96076) (xy 164.847065 -382.023856) (xy 164.863101 -382.089344)
			(xy 164.871178 -382.156281) (xy 164.871179 -382.223645) (xy 168.149243 -382.223645) (xy 168.149244 -382.15634)
			(xy 168.157288 -382.089517) (xy 168.173261 -382.024135) (xy 168.196933 -381.96113) (xy 168.227965 -381.901406)
			(xy 168.265913 -381.845819) (xy 168.2877 -381.820166) (xy 168.293494 -381.813019) (xy 168.30001 -381.79583)
			(xy 168.3004 -381.786638) (xy 168.3004 -381.628904) (xy 168.300825 -381.61875) (xy 168.308619 -381.599998)
			(xy 168.323015 -381.585674) (xy 168.341806 -381.577975) (xy 168.351962 -381.577596) (xy 169.068242 -381.577596)
			(xy 169.078366 -381.578091) (xy 169.09708 -381.585824) (xy 169.111433 -381.600107) (xy 169.119258 -381.618783)
			(xy 169.119804 -381.628904) (xy 169.119804 -381.786638) (xy 169.120195 -381.795827) (xy 169.126722 -381.813012)
			(xy 169.132504 -381.820166) (xy 169.154281 -381.845827) (xy 169.192227 -381.901413) (xy 169.223258 -381.961136)
			(xy 169.24693 -382.024139) (xy 169.262902 -382.08952) (xy 169.270946 -382.156341) (xy 169.270947 -382.223644)
			(xy 169.270947 -382.223646) (xy 172.54901 -382.223646) (xy 172.54901 -382.156339) (xy 172.557056 -382.089515)
			(xy 172.573032 -382.024132) (xy 172.596708 -381.961127) (xy 172.627745 -381.901403) (xy 172.665698 -381.845818)
			(xy 172.687488 -381.820166) (xy 172.69328 -381.813018) (xy 172.699798 -381.79583) (xy 172.700188 -381.786638)
			(xy 172.700188 -381.628904) (xy 172.700625 -381.618752) (xy 172.708417 -381.600002) (xy 172.722809 -381.585679)
			(xy 172.741596 -381.577977) (xy 172.75175 -381.577596) (xy 173.46803 -381.577596) (xy 173.478153 -381.578101)
			(xy 173.496867 -381.58583) (xy 173.51122 -381.60011) (xy 173.519046 -381.618783) (xy 173.519592 -381.628904)
			(xy 173.519592 -381.786638) (xy 173.519986 -381.795827) (xy 173.526511 -381.813011) (xy 173.532292 -381.820166)
			(xy 173.554069 -381.845827) (xy 173.592016 -381.901413) (xy 173.623048 -381.961135) (xy 173.64672 -382.024139)
			(xy 173.662693 -382.089519) (xy 173.670737 -382.156341) (xy 173.670738 -382.223644) (xy 173.662695 -382.290466)
			(xy 173.646725 -382.355847) (xy 173.623054 -382.418851) (xy 173.592024 -382.478574) (xy 173.554078 -382.534161)
			(xy 173.532292 -382.559814) (xy 173.526506 -382.566967) (xy 173.519985 -382.584151) (xy 173.519592 -382.593342)
			(xy 173.519592 -383.086864) (xy 173.520021 -383.096049) (xy 173.526522 -383.113234) (xy 173.532292 -383.120392)
			(xy 173.554094 -383.146032) (xy 173.592041 -383.201621) (xy 173.623072 -383.261346) (xy 173.646507 -383.323727)
			(xy 174.749152 -383.323727) (xy 174.749155 -383.256419) (xy 174.757202 -383.189594) (xy 174.773179 -383.12421)
			(xy 174.796856 -383.061204) (xy 174.827893 -383.001479) (xy 174.865846 -382.945892) (xy 174.887636 -382.92024)
			(xy 174.893445 -382.913104) (xy 174.899951 -382.895906) (xy 174.900336 -382.886712) (xy 174.900336 -382.728724)
			(xy 174.900742 -382.718567) (xy 174.908536 -382.699808) (xy 174.922939 -382.685482) (xy 174.941739 -382.677788)
			(xy 174.951898 -382.677416) (xy 175.668178 -382.677416) (xy 175.6783 -382.677944) (xy 175.697017 -382.68566)
			(xy 175.711373 -382.699933) (xy 175.719197 -382.718605) (xy 175.71974 -382.728724) (xy 175.71974 -382.886712)
			(xy 175.720158 -382.895898) (xy 175.726668 -382.913082) (xy 175.73244 -382.92024) (xy 175.754193 -382.945921)
			(xy 175.792144 -383.001503) (xy 175.82318 -383.061222) (xy 175.846856 -383.124223) (xy 175.862832 -383.189602)
			(xy 175.870879 -383.256422) (xy 175.870883 -383.323724) (xy 175.862842 -383.390545) (xy 175.846872 -383.455925)
			(xy 175.823202 -383.518928) (xy 175.792172 -383.578651) (xy 175.754226 -383.634236) (xy 175.73244 -383.659888)
			(xy 175.726616 -383.667014) (xy 175.720119 -383.684219) (xy 175.71974 -383.693416) (xy 175.71974 -384.186684)
			(xy 175.720171 -384.195869) (xy 175.726672 -384.213053) (xy 175.73244 -384.220212) (xy 175.754264 -384.245835)
			(xy 175.792213 -384.301425) (xy 175.823246 -384.361152) (xy 175.846918 -384.424161) (xy 175.862889 -384.489547)
			(xy 175.87093 -384.556373) (xy 175.870927 -384.623681) (xy 175.862879 -384.690507) (xy 175.846902 -384.755891)
			(xy 175.823224 -384.818897) (xy 175.792185 -384.878622) (xy 175.754231 -384.934208) (xy 175.73244 -384.95986)
			(xy 175.726628 -384.966994) (xy 175.720124 -384.984193) (xy 175.71974 -384.993388) (xy 175.71974 -385.151376)
			(xy 175.71926 -385.161524) (xy 175.71148 -385.180268) (xy 175.697101 -385.194591) (xy 175.678327 -385.202298)
			(xy 175.668178 -385.202684) (xy 174.951898 -385.202684) (xy 174.941774 -385.202176) (xy 174.923058 -385.194452)
			(xy 174.908702 -385.180172) (xy 174.900879 -385.161497) (xy 174.900336 -385.151376) (xy 174.900336 -384.993388)
			(xy 174.899924 -384.984201) (xy 174.893411 -384.967017) (xy 174.887636 -384.95986) (xy 174.865884 -384.934179)
			(xy 174.827934 -384.878596) (xy 174.7969 -384.818877) (xy 174.773225 -384.755876) (xy 174.75725 -384.690497)
			(xy 174.749203 -384.623678) (xy 174.749199 -384.556376) (xy 174.75724 -384.489556) (xy 174.773209 -384.424176)
			(xy 174.796878 -384.361173) (xy 174.827906 -384.30145) (xy 174.865851 -384.245864) (xy 174.887636 -384.220212)
			(xy 174.893457 -384.213084) (xy 174.899956 -384.19588) (xy 174.900336 -384.186684) (xy 174.900336 -383.693416)
			(xy 174.89991 -383.684231) (xy 174.893407 -383.667046) (xy 174.887636 -383.659888) (xy 174.865813 -383.634265)
			(xy 174.827865 -383.578674) (xy 174.796834 -383.518947) (xy 174.773163 -383.455938) (xy 174.757193 -383.390553)
			(xy 174.749152 -383.323727) (xy 173.646507 -383.323727) (xy 173.646742 -383.324352) (xy 173.662713 -383.389736)
			(xy 173.670756 -383.456559) (xy 173.670754 -383.523865) (xy 173.662709 -383.590688) (xy 173.646735 -383.656071)
			(xy 173.623062 -383.719076) (xy 173.592028 -383.7788) (xy 173.55408 -383.834387) (xy 173.532292 -383.86004)
			(xy 173.526495 -383.867185) (xy 173.519981 -383.884376) (xy 173.519592 -383.893568) (xy 173.519592 -384.051556)
			(xy 173.519142 -384.061708) (xy 173.51136 -384.080461) (xy 173.496971 -384.094786) (xy 173.478184 -384.102486)
			(xy 173.46803 -384.102864) (xy 172.75175 -384.102864) (xy 172.741627 -384.102333) (xy 172.722908 -384.094622)
			(xy 172.70855 -384.080349) (xy 172.700728 -384.061676) (xy 172.700188 -384.051556) (xy 172.700188 -383.893568)
			(xy 172.699796 -383.884379) (xy 172.69327 -383.867194) (xy 172.687488 -383.86004) (xy 172.665715 -383.834376)
			(xy 172.627762 -383.778792) (xy 172.596725 -383.719071) (xy 172.57305 -383.656068) (xy 172.557074 -383.590686)
			(xy 172.549028 -383.523864) (xy 172.549026 -383.45656) (xy 172.55707 -383.389737) (xy 172.573042 -383.324355)
			(xy 172.596716 -383.261351) (xy 172.62775 -383.201629) (xy 172.6657 -383.146043) (xy 172.687488 -383.120392)
			(xy 172.693269 -383.113236) (xy 172.699793 -383.096054) (xy 172.700188 -383.086864) (xy 172.700188 -382.593342)
			(xy 172.69976 -382.584157) (xy 172.693259 -382.566972) (xy 172.687488 -382.559814) (xy 172.665689 -382.534171)
			(xy 172.627737 -382.478584) (xy 172.596702 -382.41886) (xy 172.573027 -382.355854) (xy 172.557054 -382.29047)
			(xy 172.54901 -382.223646) (xy 169.270947 -382.223646) (xy 169.262905 -382.290465) (xy 169.246934 -382.355847)
			(xy 169.223264 -382.41885) (xy 169.192235 -382.478574) (xy 169.15429 -382.534161) (xy 169.132504 -382.559814)
			(xy 169.126719 -382.566968) (xy 169.120197 -382.584152) (xy 169.119804 -382.593342) (xy 169.119804 -383.086864)
			(xy 169.120231 -383.096049) (xy 169.126733 -383.113234) (xy 169.132504 -383.120392) (xy 169.154306 -383.146032)
			(xy 169.192252 -383.201621) (xy 169.223282 -383.261347) (xy 169.246739 -383.323787) (xy 170.348832 -383.323787)
			(xy 170.348835 -383.256359) (xy 170.356915 -383.189418) (xy 170.372956 -383.123926) (xy 170.396726 -383.060827)
			(xy 170.427884 -383.001031) (xy 170.46598 -382.945396) (xy 170.487848 -382.919732) (xy 170.493662 -382.912599)
			(xy 170.500165 -382.895399) (xy 170.500548 -382.886204) (xy 170.500548 -382.728724) (xy 170.501103 -382.718623)
			(xy 170.508823 -382.699955) (xy 170.523098 -382.685662) (xy 170.541756 -382.677917) (xy 170.551856 -382.677416)
			(xy 171.268136 -382.677416) (xy 171.278249 -382.677856) (xy 171.296931 -382.685608) (xy 171.311225 -382.699919)
			(xy 171.318956 -382.71861) (xy 171.319444 -382.728724) (xy 171.319444 -382.886204) (xy 171.319865 -382.89539)
			(xy 171.326372 -382.912574) (xy 171.332144 -382.919732) (xy 171.353975 -382.945425) (xy 171.392068 -383.001055)
			(xy 171.423223 -383.060846) (xy 171.446992 -383.12394) (xy 171.463032 -383.189426) (xy 171.471111 -383.256362)
			(xy 171.471115 -383.323784) (xy 171.463041 -383.390721) (xy 171.447008 -383.456209) (xy 171.423246 -383.519304)
			(xy 171.392096 -383.579099) (xy 171.354008 -383.634732) (xy 171.332144 -383.660396) (xy 171.32636 -383.66755)
			(xy 171.319839 -383.684734) (xy 171.319444 -383.693924) (xy 171.319444 -384.186176) (xy 171.319878 -384.19536)
			(xy 171.326376 -384.212544) (xy 171.332144 -384.219704) (xy 171.354045 -384.245339) (xy 171.392137 -384.300977)
			(xy 171.423289 -384.360776) (xy 171.447054 -384.423877) (xy 171.463088 -384.489371) (xy 171.471162 -384.556313)
			(xy 171.471159 -384.623741) (xy 171.463078 -384.690683) (xy 171.447037 -384.756174) (xy 171.423267 -384.819273)
			(xy 171.392109 -384.87907) (xy 171.354012 -384.934704) (xy 171.332144 -384.960368) (xy 171.326329 -384.9675)
			(xy 171.319827 -384.984701) (xy 171.319444 -384.993896) (xy 171.319444 -385.151376) (xy 171.318896 -385.161478)
			(xy 171.311175 -385.180147) (xy 171.296897 -385.194441) (xy 171.278237 -385.202185) (xy 171.268136 -385.202684)
			(xy 170.551856 -385.202684) (xy 170.541742 -385.20225) (xy 170.52306 -385.194495) (xy 170.508766 -385.180183)
			(xy 170.501036 -385.16149) (xy 170.500548 -385.151376) (xy 170.500548 -384.993896) (xy 170.500129 -384.98471)
			(xy 170.49362 -384.967526) (xy 170.487848 -384.960368) (xy 170.466018 -384.934674) (xy 170.427925 -384.879045)
			(xy 170.39677 -384.819253) (xy 170.373001 -384.75616) (xy 170.356962 -384.690674) (xy 170.348883 -384.623738)
			(xy 170.348879 -384.556316) (xy 170.356952 -384.489379) (xy 170.372985 -384.423892) (xy 170.396748 -384.360796)
			(xy 170.427897 -384.301001) (xy 170.465984 -384.245368) (xy 170.487848 -384.219704) (xy 170.493631 -384.21255)
			(xy 170.500153 -384.195366) (xy 170.500548 -384.186176) (xy 170.500548 -383.693924) (xy 170.500116 -383.684739)
			(xy 170.493616 -383.667555) (xy 170.487848 -383.660396) (xy 170.465947 -383.634761) (xy 170.427856 -383.579123)
			(xy 170.396704 -383.519323) (xy 170.37294 -383.456222) (xy 170.356906 -383.390729) (xy 170.348832 -383.323787)
			(xy 169.246739 -383.323787) (xy 169.246952 -383.324353) (xy 169.262922 -383.389736) (xy 169.270965 -383.456559)
			(xy 169.270963 -383.523865) (xy 169.262918 -383.590688) (xy 169.246945 -383.65607) (xy 169.223272 -383.719075)
			(xy 169.192239 -383.7788) (xy 169.154291 -383.834387) (xy 169.132504 -383.86004) (xy 169.126708 -383.867186)
			(xy 169.120193 -383.884376) (xy 169.119804 -383.893568) (xy 169.119804 -384.051556) (xy 169.119342 -384.061707)
			(xy 169.111562 -384.080457) (xy 169.097177 -384.094782) (xy 169.078394 -384.102484) (xy 169.068242 -384.102864)
			(xy 168.351962 -384.102864) (xy 168.341833 -384.102405) (xy 168.323112 -384.094665) (xy 168.308757 -384.080371)
			(xy 168.300939 -384.061682) (xy 168.3004 -384.051556) (xy 168.3004 -383.893568) (xy 168.300005 -383.884379)
			(xy 168.293481 -383.867195) (xy 168.2877 -383.86004) (xy 168.265929 -383.834374) (xy 168.227982 -383.778789)
			(xy 168.196951 -383.719067) (xy 168.173279 -383.656064) (xy 168.157306 -383.590684) (xy 168.149261 -383.523864)
			(xy 168.149259 -383.456561) (xy 168.157301 -383.38974) (xy 168.173272 -383.324359) (xy 168.196941 -383.261355)
			(xy 168.22797 -383.201632) (xy 168.265914 -383.146045) (xy 168.2877 -383.120392) (xy 168.293482 -383.113237)
			(xy 168.300006 -383.096054) (xy 168.3004 -383.086864) (xy 168.3004 -382.593342) (xy 168.29997 -382.584157)
			(xy 168.29347 -382.566972) (xy 168.2877 -382.559814) (xy 168.265904 -382.534169) (xy 168.227958 -382.478581)
			(xy 168.196927 -382.418856) (xy 168.173256 -382.355851) (xy 168.157285 -382.290468) (xy 168.149243 -382.223645)
			(xy 164.871179 -382.223645) (xy 164.871179 -382.223704) (xy 164.863104 -382.290641) (xy 164.84707 -382.35613)
			(xy 164.823307 -382.419226) (xy 164.792158 -382.479022) (xy 164.754071 -382.534657) (xy 164.732208 -382.560322)
			(xy 164.726421 -382.567474) (xy 164.7199 -382.584659) (xy 164.719508 -382.59385) (xy 164.719508 -383.086356)
			(xy 164.719937 -383.095541) (xy 164.726437 -383.112726) (xy 164.732208 -383.119884) (xy 164.754087 -383.145536)
			(xy 164.792175 -383.201173) (xy 164.823325 -383.260971) (xy 164.846959 -383.323727) (xy 165.949064 -383.323727)
			(xy 165.949067 -383.256419) (xy 165.957115 -383.189594) (xy 165.973092 -383.124209) (xy 165.996769 -383.061203)
			(xy 166.027808 -383.001479) (xy 166.065762 -382.945892) (xy 166.087552 -382.92024) (xy 166.093363 -382.913105)
			(xy 166.099868 -382.895907) (xy 166.100252 -382.886712) (xy 166.100252 -382.728724) (xy 166.10074 -382.718577)
			(xy 166.108519 -382.699835) (xy 166.122895 -382.685512) (xy 166.141666 -382.677803) (xy 166.151814 -382.677416)
			(xy 166.868094 -382.677416) (xy 166.878217 -382.677931) (xy 166.896934 -382.685652) (xy 166.911289 -382.699929)
			(xy 166.919113 -382.718603) (xy 166.919656 -382.728724) (xy 166.919656 -382.886712) (xy 166.92007 -382.895899)
			(xy 166.926582 -382.913082) (xy 166.932356 -382.92024) (xy 166.954108 -382.945921) (xy 166.992059 -383.001503)
			(xy 167.023094 -383.061223) (xy 167.046769 -383.124224) (xy 167.062744 -383.189602) (xy 167.070791 -383.256422)
			(xy 167.070795 -383.323724) (xy 167.062754 -383.390544) (xy 167.046785 -383.455925) (xy 167.023116 -383.518928)
			(xy 166.992086 -383.57865) (xy 166.954142 -383.634236) (xy 166.932356 -383.659888) (xy 166.926534 -383.667015)
			(xy 166.920036 -383.68422) (xy 166.919656 -383.693416) (xy 166.919656 -384.186684) (xy 166.920084 -384.195869)
			(xy 166.926586 -384.213053) (xy 166.932356 -384.220212) (xy 166.954179 -384.245835) (xy 166.992127 -384.301425)
			(xy 167.023159 -384.361153) (xy 167.04683 -384.424161) (xy 167.062801 -384.489547) (xy 167.070842 -384.556373)
			(xy 167.070839 -384.623681) (xy 167.062791 -384.690506) (xy 167.046814 -384.75589) (xy 167.023137 -384.818897)
			(xy 166.9921 -384.878621) (xy 166.954146 -384.934208) (xy 166.932356 -384.95986) (xy 166.926546 -384.966995)
			(xy 166.92004 -384.984194) (xy 166.919656 -384.993388) (xy 166.919656 -385.151376) (xy 166.91916 -385.161522)
			(xy 166.911383 -385.180263) (xy 166.89701 -385.194585) (xy 166.878241 -385.202296) (xy 166.868094 -385.202684)
			(xy 166.151814 -385.202684) (xy 166.141691 -385.202163) (xy 166.122975 -385.194444) (xy 166.108619 -385.180169)
			(xy 166.100795 -385.161496) (xy 166.100252 -385.151376) (xy 166.100252 -384.993388) (xy 166.099836 -384.984202)
			(xy 166.093325 -384.967018) (xy 166.087552 -384.95986) (xy 166.065799 -384.934179) (xy 166.027849 -384.878597)
			(xy 165.996813 -384.818877) (xy 165.973138 -384.755877) (xy 165.957162 -384.690498) (xy 165.949115 -384.623678)
			(xy 165.949111 -384.556376) (xy 165.957152 -384.489555) (xy 165.973122 -384.424175) (xy 165.996791 -384.361172)
			(xy 166.027821 -384.30145) (xy 166.065766 -384.245864) (xy 166.087552 -384.220212) (xy 166.093375 -384.213086)
			(xy 166.099872 -384.19588) (xy 166.100252 -384.186684) (xy 166.100252 -383.693416) (xy 166.099823 -383.684231)
			(xy 166.093321 -383.667047) (xy 166.087552 -383.659888) (xy 166.065728 -383.634265) (xy 166.02778 -383.578675)
			(xy 165.996747 -383.518947) (xy 165.973076 -383.455939) (xy 165.957105 -383.390553) (xy 165.949064 -383.323727)
			(xy 164.846959 -383.323727) (xy 164.847088 -383.32407) (xy 164.863122 -383.38956) (xy 164.871196 -383.4565)
			(xy 164.871195 -383.523924) (xy 164.863117 -383.590864) (xy 164.84708 -383.656353) (xy 164.823315 -383.719451)
			(xy 164.792163 -383.779248) (xy 164.754073 -383.834883) (xy 164.732208 -383.860548) (xy 164.726409 -383.867692)
			(xy 164.719896 -383.884883) (xy 164.719508 -383.894076) (xy 164.719508 -384.051556) (xy 164.719048 -384.061675)
			(xy 164.711316 -384.080376) (xy 164.697013 -384.094691) (xy 164.678318 -384.102439) (xy 164.6682 -384.102864)
			(xy 163.95192 -384.102864) (xy 163.941794 -384.102467) (xy 163.923084 -384.094719) (xy 163.908768 -384.080396)
			(xy 163.901028 -384.061682) (xy 163.900612 -384.051556) (xy 163.900612 -383.894076) (xy 163.900211 -383.884888)
			(xy 163.893691 -383.867704) (xy 163.887912 -383.860548) (xy 163.866063 -383.83487) (xy 163.827973 -383.779238)
			(xy 163.796821 -383.719443) (xy 163.773056 -383.656348) (xy 163.757019 -383.59086) (xy 163.748941 -383.523923)
			(xy 163.74894 -383.456501) (xy 163.757014 -383.389563) (xy 163.773049 -383.324075) (xy 163.796811 -383.260979)
			(xy 163.827961 -383.201183) (xy 163.866049 -383.145549) (xy 163.887912 -383.119884) (xy 163.893699 -383.112732)
			(xy 163.900219 -383.095547) (xy 163.900612 -383.086356) (xy 163.900612 -382.59385) (xy 163.900175 -382.584666)
			(xy 163.89368 -382.567481) (xy 163.887912 -382.560322) (xy 163.866038 -382.534665) (xy 163.827949 -382.47903)
			(xy 163.796798 -382.419232) (xy 163.773034 -382.356134) (xy 163.756998 -382.290644) (xy 163.748923 -382.223705)
			(xy 160.470876 -382.223705) (xy 160.46284 -382.290468) (xy 160.446866 -382.35585) (xy 160.423193 -382.418854)
			(xy 160.392159 -382.478577) (xy 160.354208 -382.534162) (xy 160.33242 -382.559814) (xy 160.326637 -382.566969)
			(xy 160.320114 -382.584152) (xy 160.31972 -382.593342) (xy 160.31972 -383.086864) (xy 160.320143 -383.09605)
			(xy 160.326647 -383.113235) (xy 160.33242 -383.120392) (xy 160.354225 -383.146031) (xy 160.392176 -383.201618)
			(xy 160.42321 -383.261343) (xy 160.446672 -383.323786) (xy 161.548769 -383.323786) (xy 161.548772 -383.25636)
			(xy 161.556851 -383.18942) (xy 161.572889 -383.123929) (xy 161.596656 -383.060831) (xy 161.627809 -383.001034)
			(xy 161.665899 -382.945398) (xy 161.687764 -382.919732) (xy 161.69358 -382.912601) (xy 161.700081 -382.895399)
			(xy 161.700464 -382.886204) (xy 161.700464 -382.728724) (xy 161.701004 -382.718621) (xy 161.708727 -382.69995)
			(xy 161.723007 -382.685656) (xy 161.74167 -382.677914) (xy 161.751772 -382.677416) (xy 162.468052 -382.677416)
			(xy 162.478173 -382.677856) (xy 162.496879 -382.685591) (xy 162.511195 -382.699901) (xy 162.51894 -382.718603)
			(xy 162.51936 -382.728724) (xy 162.51936 -382.886204) (xy 162.519777 -382.89539) (xy 162.526287 -382.912574)
			(xy 162.53206 -382.919732) (xy 162.55389 -382.945426) (xy 162.591982 -383.001055) (xy 162.623137 -383.060847)
			(xy 162.646905 -383.12394) (xy 162.662944 -383.189426) (xy 162.671023 -383.256362) (xy 162.671027 -383.323784)
			(xy 162.662954 -383.39072) (xy 162.646921 -383.456208) (xy 162.623159 -383.519303) (xy 162.59201 -383.579098)
			(xy 162.553923 -383.634731) (xy 162.53206 -383.660396) (xy 162.526278 -383.667551) (xy 162.519755 -383.684734)
			(xy 162.51936 -383.693924) (xy 162.51936 -384.186176) (xy 162.51979 -384.195361) (xy 162.526291 -384.212545)
			(xy 162.53206 -384.219704) (xy 162.553961 -384.245339) (xy 162.592051 -384.300977) (xy 162.623202 -384.360777)
			(xy 162.646966 -384.423878) (xy 162.663 -384.489371) (xy 162.671074 -384.556313) (xy 162.671071 -384.623741)
			(xy 162.662991 -384.690682) (xy 162.64695 -384.756174) (xy 162.62318 -384.819272) (xy 162.592023 -384.879069)
			(xy 162.553928 -384.934703) (xy 162.53206 -384.960368) (xy 162.526247 -384.967501) (xy 162.519743 -384.984701)
			(xy 162.51936 -384.993896) (xy 162.51936 -385.151376) (xy 162.518964 -385.161502) (xy 162.511216 -385.180213)
			(xy 162.496893 -385.194529) (xy 162.478178 -385.202268) (xy 162.468052 -385.202684) (xy 161.751772 -385.202684)
			(xy 161.741659 -385.202238) (xy 161.722978 -385.194488) (xy 161.708683 -385.180179) (xy 161.700952 -385.161489)
			(xy 161.700464 -385.151376) (xy 161.700464 -384.993896) (xy 161.700041 -384.98471) (xy 161.693535 -384.967527)
			(xy 161.687764 -384.960368) (xy 161.665937 -384.934673) (xy 161.627849 -384.879042) (xy 161.596699 -384.819249)
			(xy 161.572934 -384.756157) (xy 161.556897 -384.690671) (xy 161.548819 -384.623737) (xy 161.548816 -384.556317)
			(xy 161.556888 -384.489382) (xy 161.572918 -384.423895) (xy 161.596677 -384.3608) (xy 161.627821 -384.301005)
			(xy 161.665903 -384.24537) (xy 161.687764 -384.219704) (xy 161.693549 -384.212551) (xy 161.700069 -384.195366)
			(xy 161.700464 -384.186176) (xy 161.700464 -383.693924) (xy 161.700028 -383.68474) (xy 161.693531 -383.667556)
			(xy 161.687764 -383.660396) (xy 161.665866 -383.634759) (xy 161.627781 -383.57912) (xy 161.596634 -383.519319)
			(xy 161.572873 -383.456219) (xy 161.556841 -383.390727) (xy 161.548769 -383.323786) (xy 160.446672 -383.323786)
			(xy 160.446884 -383.32435) (xy 160.462857 -383.389734) (xy 160.470901 -383.456558) (xy 160.470899 -383.523866)
			(xy 160.462853 -383.59069) (xy 160.446877 -383.656074) (xy 160.423201 -383.719079) (xy 160.392163 -383.778803)
			(xy 160.35421 -383.834388) (xy 160.33242 -383.86004) (xy 160.326626 -383.867187) (xy 160.320109 -383.884376)
			(xy 160.31972 -383.893568) (xy 160.31972 -384.051556) (xy 160.319243 -384.061705) (xy 160.311465 -384.080452)
			(xy 160.297086 -384.094777) (xy 160.278308 -384.102481) (xy 160.268158 -384.102864) (xy 159.551878 -384.102864)
			(xy 159.54175 -384.102392) (xy 159.523029 -384.094657) (xy 159.508674 -384.080367) (xy 159.500855 -384.061681)
			(xy 159.500316 -384.051556) (xy 159.500316 -383.893568) (xy 159.499918 -383.88438) (xy 159.493395 -383.867196)
			(xy 159.487616 -383.86004) (xy 159.465845 -383.834375) (xy 159.427897 -383.77879) (xy 159.396864 -383.719068)
			(xy 159.373191 -383.656065) (xy 159.357218 -383.590684) (xy 159.349173 -383.523864) (xy 159.349172 -383.45656)
			(xy 159.357214 -383.389739) (xy 159.373184 -383.324358) (xy 159.396854 -383.261354) (xy 159.427884 -383.201631)
			(xy 159.46583 -383.146044) (xy 159.487616 -383.120392) (xy 159.4934 -383.113238) (xy 159.499922 -383.096054)
			(xy 159.500316 -383.086864) (xy 159.500316 -382.593342) (xy 159.499882 -382.584157) (xy 159.493384 -382.566973)
			(xy 159.487616 -382.559814) (xy 159.465819 -382.53417) (xy 159.427872 -382.478582) (xy 159.396841 -382.418857)
			(xy 159.373169 -382.355851) (xy 159.357198 -382.290468) (xy 159.349155 -382.223645) (xy 129.670829 -382.223645)
			(xy 129.662786 -382.290466) (xy 129.646815 -382.355847) (xy 129.623144 -382.418851) (xy 129.592113 -382.478575)
			(xy 129.554167 -382.534162) (xy 129.53238 -382.559814) (xy 129.526593 -382.566966) (xy 129.520073 -382.584151)
			(xy 129.51968 -382.593342) (xy 129.51968 -383.086864) (xy 129.520112 -383.096049) (xy 129.526611 -383.113233)
			(xy 129.53238 -383.120392) (xy 129.554183 -383.146031) (xy 129.59213 -383.20162) (xy 129.623162 -383.261346)
			(xy 129.646598 -383.323727) (xy 130.749242 -383.323727) (xy 130.749246 -383.256419) (xy 130.757293 -383.189594)
			(xy 130.77327 -383.12421) (xy 130.796946 -383.061204) (xy 130.827982 -383.00148) (xy 130.865935 -382.945892)
			(xy 130.887724 -382.92024) (xy 130.893531 -382.913103) (xy 130.900039 -382.895906) (xy 130.900424 -382.886712)
			(xy 130.900424 -382.728724) (xy 130.900842 -382.718568) (xy 130.908634 -382.699812) (xy 130.923032 -382.685487)
			(xy 130.941828 -382.67779) (xy 130.951986 -382.677416) (xy 131.668266 -382.677416) (xy 131.678388 -382.677954)
			(xy 131.697103 -382.685666) (xy 131.71146 -382.699937) (xy 131.719284 -382.718606) (xy 131.719828 -382.728724)
			(xy 131.719828 -382.886712) (xy 131.720226 -382.895901) (xy 131.726747 -382.913085) (xy 131.732528 -382.92024)
			(xy 131.754281 -382.945921) (xy 131.792233 -383.001502) (xy 131.82327 -383.061222) (xy 131.846946 -383.124223)
			(xy 131.862923 -383.189602) (xy 131.87097 -383.256422) (xy 131.870973 -383.323724) (xy 131.862932 -383.390545)
			(xy 131.846962 -383.455926) (xy 131.823292 -383.518929) (xy 131.792261 -383.578651) (xy 131.754314 -383.634236)
			(xy 131.732528 -383.659888) (xy 131.726703 -383.667013) (xy 131.720207 -383.684219) (xy 131.719828 -383.693416)
			(xy 131.719828 -384.186684) (xy 131.720239 -384.195871) (xy 131.726751 -384.213056) (xy 131.732528 -384.220212)
			(xy 131.754352 -384.245834) (xy 131.792302 -384.301424) (xy 131.823336 -384.361152) (xy 131.847008 -384.42416)
			(xy 131.86298 -384.489546) (xy 131.871021 -384.556373) (xy 131.871018 -384.623681) (xy 131.86297 -384.690507)
			(xy 131.846992 -384.755892) (xy 131.823314 -384.818898) (xy 131.792274 -384.878622) (xy 131.754319 -384.934208)
			(xy 131.732528 -384.95986) (xy 131.726715 -384.966993) (xy 131.720212 -384.984193) (xy 131.719828 -384.993388)
			(xy 131.719828 -385.151376) (xy 131.719359 -385.161525) (xy 131.711577 -385.180272) (xy 131.697195 -385.194595)
			(xy 131.678417 -385.202301) (xy 131.668266 -385.202684) (xy 130.951986 -385.202684) (xy 130.941861 -385.202185)
			(xy 130.923145 -385.194457) (xy 130.90879 -385.180175) (xy 130.900967 -385.161498) (xy 130.900424 -385.151376)
			(xy 130.900424 -384.993388) (xy 130.900014 -384.984201) (xy 130.8935 -384.967017) (xy 130.887724 -384.95986)
			(xy 130.865972 -384.934178) (xy 130.828023 -384.878596) (xy 130.796989 -384.818876) (xy 130.773315 -384.755876)
			(xy 130.75734 -384.690497) (xy 130.749294 -384.623678) (xy 130.74929 -384.556376) (xy 130.757331 -384.489556)
			(xy 130.773299 -384.424176) (xy 130.796967 -384.361173) (xy 130.827996 -384.301451) (xy 130.865939 -384.245865)
			(xy 130.887724 -384.220212) (xy 130.893543 -384.213083) (xy 130.900044 -384.19588) (xy 130.900424 -384.186684)
			(xy 130.900424 -383.693416) (xy 130.900001 -383.68423) (xy 130.893495 -383.667046) (xy 130.887724 -383.659888)
			(xy 130.865901 -383.634265) (xy 130.827955 -383.578674) (xy 130.796924 -383.518946) (xy 130.773254 -383.455938)
			(xy 130.757284 -383.390552) (xy 130.749242 -383.323727) (xy 129.646598 -383.323727) (xy 129.646833 -383.324352)
			(xy 129.662804 -383.389735) (xy 129.670846 -383.456559) (xy 129.670845 -383.523865) (xy 129.6628 -383.590688)
			(xy 129.646826 -383.656071) (xy 129.623152 -383.719076) (xy 129.592118 -383.778801) (xy 129.554168 -383.834388)
			(xy 129.53238 -383.86004) (xy 129.526582 -383.867184) (xy 129.520069 -383.884375) (xy 129.51968 -383.893568)
			(xy 129.51968 -384.051556) (xy 129.519242 -384.06171) (xy 129.511457 -384.080465) (xy 129.497065 -384.094791)
			(xy 129.478274 -384.102488) (xy 129.468118 -384.102864) (xy 128.751838 -384.102864) (xy 128.741714 -384.102342)
			(xy 128.722995 -384.094628) (xy 128.708637 -384.080352) (xy 128.700816 -384.061677) (xy 128.700276 -384.051556)
			(xy 128.700276 -383.893568) (xy 128.699886 -383.884379) (xy 128.693359 -383.867194) (xy 128.687576 -383.86004)
			(xy 128.665803 -383.834375) (xy 128.627851 -383.778792) (xy 128.596815 -383.71907) (xy 128.57314 -383.656067)
			(xy 128.557165 -383.590686) (xy 128.549119 -383.523864) (xy 128.549117 -383.45656) (xy 128.55716 -383.389738)
			(xy 128.573133 -383.324356) (xy 128.596805 -383.261352) (xy 128.627839 -383.201629) (xy 128.665788 -383.146044)
			(xy 128.687576 -383.120392) (xy 128.693356 -383.113235) (xy 128.699881 -383.096054) (xy 128.700276 -383.086864)
			(xy 128.700276 -382.593342) (xy 128.699851 -382.584156) (xy 128.693348 -382.566971) (xy 128.687576 -382.559814)
			(xy 128.665777 -382.53417) (xy 128.627826 -382.478584) (xy 128.596792 -382.418859) (xy 128.573118 -382.355853)
			(xy 128.557144 -382.29047) (xy 128.5491 -382.223646) (xy 125.271038 -382.223646) (xy 125.262995 -382.290466)
			(xy 125.247025 -382.355847) (xy 125.223354 -382.418851) (xy 125.192324 -382.478574) (xy 125.154378 -382.534161)
			(xy 125.132592 -382.559814) (xy 125.126806 -382.566967) (xy 125.120285 -382.584151) (xy 125.119892 -382.593342)
			(xy 125.119892 -383.086864) (xy 125.120321 -383.096049) (xy 125.126822 -383.113234) (xy 125.132592 -383.120392)
			(xy 125.154394 -383.146032) (xy 125.192341 -383.201621) (xy 125.223372 -383.261346) (xy 125.24683 -383.323787)
			(xy 126.348923 -383.323787) (xy 126.348926 -383.256359) (xy 126.357006 -383.189418) (xy 126.373047 -383.123926)
			(xy 126.396816 -383.060828) (xy 126.427973 -383.001031) (xy 126.466069 -382.945397) (xy 126.487936 -382.919732)
			(xy 126.493749 -382.912598) (xy 126.500253 -382.895399) (xy 126.500636 -382.886204) (xy 126.500636 -382.728724)
			(xy 126.501036 -382.718599) (xy 126.508783 -382.699889) (xy 126.523105 -382.685572) (xy 126.541818 -382.677832)
			(xy 126.551944 -382.677416) (xy 127.268224 -382.677416) (xy 127.278336 -382.677866) (xy 127.297018 -382.685614)
			(xy 127.311313 -382.699922) (xy 127.319044 -382.718611) (xy 127.319532 -382.728724) (xy 127.319532 -382.886204)
			(xy 127.319956 -382.895389) (xy 127.326462 -382.912573) (xy 127.332232 -382.919732) (xy 127.354059 -382.945427)
			(xy 127.392147 -383.001058) (xy 127.423298 -383.06085) (xy 127.447062 -383.123943) (xy 127.463099 -383.189428)
			(xy 127.471178 -383.256363) (xy 127.471181 -383.323783) (xy 127.463109 -383.390718) (xy 127.447078 -383.456205)
			(xy 127.42332 -383.5193) (xy 127.392175 -383.579096) (xy 127.354093 -383.63473) (xy 127.332232 -383.660396)
			(xy 127.326446 -383.667549) (xy 127.319927 -383.684734) (xy 127.319532 -383.693924) (xy 127.319532 -384.186176)
			(xy 127.319969 -384.19536) (xy 127.326466 -384.212544) (xy 127.332232 -384.219704) (xy 127.35413 -384.245341)
			(xy 127.392216 -384.30098) (xy 127.423363 -384.36078) (xy 127.447124 -384.423881) (xy 127.463156 -384.489373)
			(xy 127.471228 -384.556314) (xy 127.471225 -384.62374) (xy 127.463146 -384.69068) (xy 127.447108 -384.756171)
			(xy 127.423341 -384.819269) (xy 127.392188 -384.879066) (xy 127.354097 -384.934702) (xy 127.332232 -384.960368)
			(xy 127.326416 -384.967499) (xy 127.319915 -384.984701) (xy 127.319532 -384.993896) (xy 127.319532 -385.151376)
			(xy 127.318996 -385.161479) (xy 127.311272 -385.180151) (xy 127.296991 -385.194445) (xy 127.278327 -385.202187)
			(xy 127.268224 -385.202684) (xy 126.551944 -385.202684) (xy 126.541822 -385.202247) (xy 126.523117 -385.194511)
			(xy 126.5088 -385.1802) (xy 126.501056 -385.161497) (xy 126.500636 -385.151376) (xy 126.500636 -384.993896)
			(xy 126.50022 -384.98471) (xy 126.49371 -384.967526) (xy 126.487936 -384.960368) (xy 126.466106 -384.934674)
			(xy 126.428014 -384.879045) (xy 126.39686 -384.819253) (xy 126.373092 -384.756159) (xy 126.357053 -384.690673)
			(xy 126.348974 -384.623738) (xy 126.34897 -384.556316) (xy 126.357043 -384.48938) (xy 126.373076 -384.423892)
			(xy 126.396838 -384.360797) (xy 126.427986 -384.301002) (xy 126.466073 -384.245369) (xy 126.487936 -384.219704)
			(xy 126.493718 -384.212549) (xy 126.50024 -384.195366) (xy 126.500636 -384.186176) (xy 126.500636 -383.693924)
			(xy 126.500206 -383.684739) (xy 126.493705 -383.667555) (xy 126.487936 -383.660396) (xy 126.466035 -383.634761)
			(xy 126.427945 -383.579123) (xy 126.396794 -383.519323) (xy 126.373031 -383.456222) (xy 126.356996 -383.390729)
			(xy 126.348923 -383.323787) (xy 125.24683 -383.323787) (xy 125.247042 -383.324352) (xy 125.263013 -383.389736)
			(xy 125.271056 -383.456559) (xy 125.271054 -383.523865) (xy 125.263009 -383.590688) (xy 125.247035 -383.656071)
			(xy 125.223362 -383.719076) (xy 125.192328 -383.7788) (xy 125.15438 -383.834387) (xy 125.132592 -383.86004)
			(xy 125.126795 -383.867185) (xy 125.120281 -383.884376) (xy 125.119892 -383.893568) (xy 125.119892 -384.051556)
			(xy 125.119442 -384.061708) (xy 125.11166 -384.080461) (xy 125.097271 -384.094786) (xy 125.078484 -384.102486)
			(xy 125.06833 -384.102864) (xy 124.35205 -384.102864) (xy 124.341927 -384.102333) (xy 124.323208 -384.094622)
			(xy 124.30885 -384.080349) (xy 124.301028 -384.061676) (xy 124.300488 -384.051556) (xy 124.300488 -383.893568)
			(xy 124.300096 -383.884379) (xy 124.29357 -383.867194) (xy 124.287788 -383.86004) (xy 124.266015 -383.834376)
			(xy 124.228062 -383.778792) (xy 124.197025 -383.719071) (xy 124.17335 -383.656068) (xy 124.157374 -383.590686)
			(xy 124.149328 -383.523864) (xy 124.149326 -383.45656) (xy 124.15737 -383.389737) (xy 124.173342 -383.324355)
			(xy 124.197016 -383.261351) (xy 124.22805 -383.201629) (xy 124.266 -383.146043) (xy 124.287788 -383.120392)
			(xy 124.293569 -383.113236) (xy 124.300093 -383.096054) (xy 124.300488 -383.086864) (xy 124.300488 -382.593342)
			(xy 124.30006 -382.584157) (xy 124.293559 -382.566972) (xy 124.287788 -382.559814) (xy 124.265989 -382.534171)
			(xy 124.228037 -382.478584) (xy 124.197002 -382.41886) (xy 124.173327 -382.355854) (xy 124.157354 -382.29047)
			(xy 124.14931 -382.223646) (xy 120.87127 -382.223646) (xy 120.87127 -382.223704) (xy 120.863195 -382.290642)
			(xy 120.84716 -382.35613) (xy 120.823397 -382.419227) (xy 120.792247 -382.479023) (xy 120.75416 -382.534657)
			(xy 120.732296 -382.560322) (xy 120.726507 -382.567473) (xy 120.719988 -382.584659) (xy 120.719596 -382.59385)
			(xy 120.719596 -383.086356) (xy 120.720028 -383.095541) (xy 120.726527 -383.112725) (xy 120.732296 -383.119884)
			(xy 120.754176 -383.145536) (xy 120.792264 -383.201173) (xy 120.823415 -383.26097) (xy 120.847049 -383.323727)
			(xy 121.949155 -383.323727) (xy 121.949158 -383.256419) (xy 121.957206 -383.189594) (xy 121.973182 -383.12421)
			(xy 121.996859 -383.061204) (xy 122.027897 -383.001479) (xy 122.06585 -382.945892) (xy 122.08764 -382.92024)
			(xy 122.09345 -382.913104) (xy 122.099955 -382.895906) (xy 122.10034 -382.886712) (xy 122.10034 -382.728724)
			(xy 122.100742 -382.718566) (xy 122.108537 -382.699807) (xy 122.122941 -382.685481) (xy 122.141742 -382.677788)
			(xy 122.151902 -382.677416) (xy 122.868182 -382.677416) (xy 122.878305 -382.677941) (xy 122.897021 -382.685658)
			(xy 122.911377 -382.699932) (xy 122.919201 -382.718604) (xy 122.919744 -382.728724) (xy 122.919744 -382.886712)
			(xy 122.920161 -382.895898) (xy 122.926671 -382.913082) (xy 122.932444 -382.92024) (xy 122.954197 -382.945921)
			(xy 122.992148 -383.001503) (xy 123.023183 -383.061222) (xy 123.046859 -383.124223) (xy 123.062835 -383.189602)
			(xy 123.070882 -383.256422) (xy 123.070886 -383.323724) (xy 123.062845 -383.390545) (xy 123.046875 -383.455925)
			(xy 123.023206 -383.518928) (xy 122.992176 -383.57865) (xy 122.95423 -383.634236) (xy 122.932444 -383.659888)
			(xy 122.926621 -383.667014) (xy 122.920124 -383.684219) (xy 122.919744 -383.693416) (xy 122.919744 -384.186684)
			(xy 122.920174 -384.195869) (xy 122.926675 -384.213053) (xy 122.932444 -384.220212) (xy 122.954268 -384.245835)
			(xy 122.992217 -384.301425) (xy 123.023249 -384.361152) (xy 123.046921 -384.424161) (xy 123.062892 -384.489547)
			(xy 123.070933 -384.556373) (xy 123.07093 -384.623681) (xy 123.062882 -384.690507) (xy 123.046905 -384.755891)
			(xy 123.023227 -384.818897) (xy 122.992189 -384.878622) (xy 122.954235 -384.934208) (xy 122.932444 -384.95986)
			(xy 122.926633 -384.966994) (xy 122.920128 -384.984193) (xy 122.919744 -384.993388) (xy 122.919744 -385.151376)
			(xy 122.91926 -385.161523) (xy 122.91148 -385.180267) (xy 122.897103 -385.194589) (xy 122.878331 -385.202298)
			(xy 122.868182 -385.202684) (xy 122.151902 -385.202684) (xy 122.141778 -385.202172) (xy 122.123062 -385.19445)
			(xy 122.108706 -385.180171) (xy 122.100883 -385.161497) (xy 122.10034 -385.151376) (xy 122.10034 -384.993388)
			(xy 122.099927 -384.984201) (xy 122.093414 -384.967017) (xy 122.08764 -384.95986) (xy 122.065888 -384.934179)
			(xy 122.027938 -384.878596) (xy 121.996903 -384.818877) (xy 121.973228 -384.755876) (xy 121.957253 -384.690498)
			(xy 121.949206 -384.623678) (xy 121.949202 -384.556376) (xy 121.957243 -384.489556) (xy 121.973212 -384.424176)
			(xy 121.996881 -384.361173) (xy 122.02791 -384.30145) (xy 122.065855 -384.245864) (xy 122.08764 -384.220212)
			(xy 122.093461 -384.213085) (xy 122.09996 -384.19588) (xy 122.10034 -384.186684) (xy 122.10034 -383.693416)
			(xy 122.099913 -383.684231) (xy 122.09341 -383.667047) (xy 122.08764 -383.659888) (xy 122.065817 -383.634265)
			(xy 122.027869 -383.578674) (xy 121.996837 -383.518947) (xy 121.973166 -383.455939) (xy 121.957196 -383.390553)
			(xy 121.949155 -383.323727) (xy 120.847049 -383.323727) (xy 120.847178 -383.324069) (xy 120.863212 -383.38956)
			(xy 120.871287 -383.4565) (xy 120.871286 -383.523925) (xy 120.863208 -383.590864) (xy 120.847171 -383.656354)
			(xy 120.823405 -383.719452) (xy 120.792252 -383.779248) (xy 120.754161 -383.834883) (xy 120.732296 -383.860548)
			(xy 120.726496 -383.867691) (xy 120.719984 -383.884883) (xy 120.719596 -383.894076) (xy 120.719596 -384.051556)
			(xy 120.719148 -384.061676) (xy 120.711413 -384.080379) (xy 120.697106 -384.094695) (xy 120.678408 -384.102441)
			(xy 120.668288 -384.102864) (xy 119.952008 -384.102864) (xy 119.941882 -384.102477) (xy 119.923171 -384.094724)
			(xy 119.908855 -384.080399) (xy 119.901116 -384.061683) (xy 119.9007 -384.051556) (xy 119.9007 -383.894076)
			(xy 119.900302 -383.884888) (xy 119.89378 -383.867703) (xy 119.888 -383.860548) (xy 119.866152 -383.83487)
			(xy 119.828063 -383.779237) (xy 119.796911 -383.719443) (xy 119.773146 -383.656348) (xy 119.75711 -383.59086)
			(xy 119.749032 -383.523923) (xy 119.749031 -383.456501) (xy 119.757105 -383.389564) (xy 119.773139 -383.324075)
			(xy 119.796901 -383.260979) (xy 119.82805 -383.201184) (xy 119.866137 -383.145549) (xy 119.888 -383.119884)
			(xy 119.893786 -383.112731) (xy 119.900307 -383.095547) (xy 119.9007 -383.086356) (xy 119.9007 -382.59385)
			(xy 119.900266 -382.584665) (xy 119.893769 -382.567481) (xy 119.888 -382.560322) (xy 119.866126 -382.534665)
			(xy 119.828038 -382.479029) (xy 119.796888 -382.419232) (xy 119.773124 -382.356134) (xy 119.757089 -382.290644)
			(xy 119.749014 -382.223705) (xy 116.470967 -382.223705) (xy 116.46293 -382.290468) (xy 116.446957 -382.35585)
			(xy 116.423283 -382.418855) (xy 116.392248 -382.478577) (xy 116.354297 -382.534163) (xy 116.332508 -382.559814)
			(xy 116.326724 -382.566968) (xy 116.320202 -382.584152) (xy 116.319808 -382.593342) (xy 116.319808 -383.086864)
			(xy 116.320234 -383.09605) (xy 116.326736 -383.113234) (xy 116.332508 -383.120392) (xy 116.354313 -383.146031)
			(xy 116.392265 -383.201618) (xy 116.4233 -383.261343) (xy 116.446764 -383.323787) (xy 117.548835 -383.323787)
			(xy 117.548838 -383.256359) (xy 117.556918 -383.189418) (xy 117.572959 -383.123926) (xy 117.59673 -383.060827)
			(xy 117.627888 -383.00103) (xy 117.665984 -382.945396) (xy 117.687852 -382.919732) (xy 117.693666 -382.9126)
			(xy 117.700169 -382.895399) (xy 117.700552 -382.886204) (xy 117.700552 -382.728724) (xy 117.701103 -382.718623)
			(xy 117.708824 -382.699954) (xy 117.7231 -382.68566) (xy 117.741759 -382.677916) (xy 117.75186 -382.677416)
			(xy 118.46814 -382.677416) (xy 118.478253 -382.677853) (xy 118.496935 -382.685607) (xy 118.511229 -382.699918)
			(xy 118.51896 -382.71861) (xy 118.519448 -382.728724) (xy 118.519448 -382.886204) (xy 118.519868 -382.89539)
			(xy 118.526376 -382.912574) (xy 118.532148 -382.919732) (xy 118.553978 -382.945426) (xy 118.592072 -383.001055)
			(xy 118.623227 -383.060847) (xy 118.646995 -383.12394) (xy 118.663035 -383.189426) (xy 118.671114 -383.256362)
			(xy 118.671118 -383.323784) (xy 118.663045 -383.390721) (xy 118.647011 -383.456208) (xy 118.623249 -383.519304)
			(xy 118.592099 -383.579099) (xy 118.554012 -383.634732) (xy 118.532148 -383.660396) (xy 118.526364 -383.66755)
			(xy 118.519843 -383.684734) (xy 118.519448 -383.693924) (xy 118.519448 -384.186176) (xy 118.519881 -384.195361)
			(xy 118.52638 -384.212545) (xy 118.532148 -384.219704) (xy 118.554049 -384.245339) (xy 118.59214 -384.300977)
			(xy 118.623292 -384.360777) (xy 118.647057 -384.423878) (xy 118.663091 -384.489371) (xy 118.671165 -384.556313)
			(xy 118.671162 -384.623741) (xy 118.663082 -384.690682) (xy 118.647041 -384.756174) (xy 118.62327 -384.819273)
			(xy 118.592112 -384.87907) (xy 118.554016 -384.934704) (xy 118.532148 -384.960368) (xy 118.526334 -384.9675)
			(xy 118.519831 -384.984701) (xy 118.519448 -384.993896) (xy 118.519448 -385.151376) (xy 118.518897 -385.161477)
			(xy 118.511176 -385.180146) (xy 118.4969 -385.19444) (xy 118.478241 -385.202184) (xy 118.46814 -385.202684)
			(xy 117.75186 -385.202684) (xy 117.741747 -385.202247) (xy 117.723065 -385.194493) (xy 117.708771 -385.180182)
			(xy 117.70104 -385.16149) (xy 117.700552 -385.151376) (xy 117.700552 -384.993896) (xy 117.700132 -384.98471)
			(xy 117.693624 -384.967526) (xy 117.687852 -384.960368) (xy 117.666022 -384.934674) (xy 117.627928 -384.879045)
			(xy 117.596773 -384.819253) (xy 117.573005 -384.75616) (xy 117.556965 -384.690674) (xy 117.548886 -384.623738)
			(xy 117.548882 -384.556316) (xy 117.556955 -384.489379) (xy 117.572989 -384.423892) (xy 117.596751 -384.360796)
			(xy 117.627901 -384.301001) (xy 117.665988 -384.245368) (xy 117.687852 -384.219704) (xy 117.693636 -384.21255)
			(xy 117.700157 -384.195366) (xy 117.700552 -384.186176) (xy 117.700552 -383.693924) (xy 117.700119 -383.684739)
			(xy 117.69362 -383.667555) (xy 117.687852 -383.660396) (xy 117.665951 -383.634761) (xy 117.62786 -383.579123)
			(xy 117.596708 -383.519323) (xy 117.572943 -383.456222) (xy 117.556909 -383.390729) (xy 117.548835 -383.323787)
			(xy 116.446764 -383.323787) (xy 116.446975 -383.324349) (xy 116.462948 -383.389733) (xy 116.470992 -383.456558)
			(xy 116.47099 -383.523866) (xy 116.462944 -383.59069) (xy 116.446967 -383.656074) (xy 116.423291 -383.719079)
			(xy 116.392252 -383.778803) (xy 116.354298 -383.834389) (xy 116.332508 -383.86004) (xy 116.326713 -383.867186)
			(xy 116.320197 -383.884376) (xy 116.319808 -383.893568) (xy 116.319808 -384.051556) (xy 116.319342 -384.061706)
			(xy 116.311563 -384.080456) (xy 116.297179 -384.094781) (xy 116.278398 -384.102483) (xy 116.268246 -384.102864)
			(xy 115.551966 -384.102864) (xy 115.541838 -384.102401) (xy 115.523116 -384.094663) (xy 115.508761 -384.08037)
			(xy 115.500943 -384.061682) (xy 115.500404 -384.051556) (xy 115.500404 -383.893568) (xy 115.500009 -383.884379)
			(xy 115.493485 -383.867195) (xy 115.487704 -383.86004) (xy 115.465933 -383.834374) (xy 115.427986 -383.778789)
			(xy 115.396954 -383.719067) (xy 115.373282 -383.656064) (xy 115.357309 -383.590684) (xy 115.349264 -383.523864)
			(xy 115.349262 -383.45656) (xy 115.357305 -383.38974) (xy 115.373275 -383.324359) (xy 115.396944 -383.261355)
			(xy 115.427974 -383.201632) (xy 115.465918 -383.146045) (xy 115.487704 -383.120392) (xy 115.493487 -383.113237)
			(xy 115.50001 -383.096054) (xy 115.500404 -383.086864) (xy 115.500404 -382.593342) (xy 115.499973 -382.584157)
			(xy 115.493474 -382.566973) (xy 115.487704 -382.559814) (xy 115.465908 -382.534169) (xy 115.427961 -382.478581)
			(xy 115.39693 -382.418856) (xy 115.37326 -382.355851) (xy 115.357288 -382.290468) (xy 115.349246 -382.223645)
			(xy 90.070711 -382.223645) (xy 90.062667 -382.290467) (xy 90.046695 -382.355848) (xy 90.023023 -382.418852)
			(xy 89.991991 -382.478576) (xy 89.954043 -382.534162) (xy 89.932256 -382.559814) (xy 89.926465 -382.566963)
			(xy 89.919948 -382.584151) (xy 89.919556 -382.593342) (xy 89.919556 -383.086864) (xy 89.919994 -383.096048)
			(xy 89.926489 -383.113232) (xy 89.932256 -383.120392) (xy 89.95406 -383.146031) (xy 89.992008 -383.201619)
			(xy 90.023041 -383.261345) (xy 90.046478 -383.323726) (xy 91.149124 -383.323726) (xy 91.149128 -383.256419)
			(xy 91.157175 -383.189595) (xy 91.17315 -383.124211) (xy 91.196825 -383.061205) (xy 91.227861 -383.001481)
			(xy 91.265811 -382.945893) (xy 91.2876 -382.92024) (xy 91.293405 -382.9131) (xy 91.299914 -382.895906)
			(xy 91.3003 -382.886712) (xy 91.3003 -382.728724) (xy 91.300741 -382.718571) (xy 91.308529 -382.699819)
			(xy 91.32292 -382.685495) (xy 91.341708 -382.677795) (xy 91.351862 -382.677416) (xy 92.068142 -382.677416)
			(xy 92.078268 -382.677891) (xy 92.096986 -382.685629) (xy 92.11134 -382.699918) (xy 92.119162 -382.7186)
			(xy 92.119704 -382.728724) (xy 92.119704 -382.886712) (xy 92.120108 -382.8959) (xy 92.126626 -382.913084)
			(xy 92.132404 -382.92024) (xy 92.154155 -382.945922) (xy 92.192102 -383.001505) (xy 92.223135 -383.061225)
			(xy 92.246808 -383.124225) (xy 92.262782 -383.189604) (xy 92.270828 -383.256422) (xy 92.270831 -383.323724)
			(xy 92.262791 -383.390543) (xy 92.246824 -383.455923) (xy 92.223157 -383.518926) (xy 92.19213 -383.578648)
			(xy 92.154188 -383.634235) (xy 92.132404 -383.659888) (xy 92.126588 -383.66702) (xy 92.120085 -383.68422)
			(xy 92.119704 -383.693416) (xy 92.119704 -384.186684) (xy 92.120121 -384.19587) (xy 92.12663 -384.213055)
			(xy 92.132404 -384.220212) (xy 92.154226 -384.245836) (xy 92.192171 -384.301427) (xy 92.2232 -384.361155)
			(xy 92.246869 -384.424163) (xy 92.262838 -384.489548) (xy 92.270879 -384.556374) (xy 92.270875 -384.623681)
			(xy 92.262828 -384.690505) (xy 92.246853 -384.755889) (xy 92.223178 -384.818894) (xy 92.192143 -384.878619)
			(xy 92.154193 -384.934207) (xy 92.132404 -384.95986) (xy 92.1266 -384.967) (xy 92.12009 -384.984194)
			(xy 92.119704 -384.993388) (xy 92.119704 -385.151376) (xy 92.119259 -385.161528) (xy 92.111472 -385.180279)
			(xy 92.097082 -385.194603) (xy 92.078296 -385.202305) (xy 92.068142 -385.202684) (xy 91.351862 -385.202684)
			(xy 91.341736 -385.202205) (xy 91.323018 -385.194469) (xy 91.308664 -385.180181) (xy 91.300842 -385.1615)
			(xy 91.3003 -385.151376) (xy 91.3003 -384.993388) (xy 91.299895 -384.9842) (xy 91.293378 -384.967016)
			(xy 91.2876 -384.95986) (xy 91.265849 -384.934178) (xy 91.227901 -384.878595) (xy 91.196869 -384.818875)
			(xy 91.173196 -384.755875) (xy 91.157221 -384.690497) (xy 91.149175 -384.623678) (xy 91.149172 -384.556376)
			(xy 91.157212 -384.489557) (xy 91.17318 -384.424177) (xy 91.196847 -384.361174) (xy 91.227874 -384.301451)
			(xy 91.265816 -384.245865) (xy 91.2876 -384.220212) (xy 91.293416 -384.213081) (xy 91.299919 -384.19588)
			(xy 91.3003 -384.186684) (xy 91.3003 -383.693416) (xy 91.299882 -383.68423) (xy 91.293374 -383.667045)
			(xy 91.2876 -383.659888) (xy 91.265778 -383.634264) (xy 91.227833 -383.578673) (xy 91.196803 -383.518945)
			(xy 91.173134 -383.455937) (xy 91.157165 -383.390552) (xy 91.149124 -383.323726) (xy 90.046478 -383.323726)
			(xy 90.046713 -383.324351) (xy 90.062685 -383.389735) (xy 90.070728 -383.456559) (xy 90.070727 -383.523865)
			(xy 90.062681 -383.590689) (xy 90.046706 -383.656072) (xy 90.023031 -383.719077) (xy 89.991996 -383.778801)
			(xy 89.954045 -383.834388) (xy 89.932256 -383.86004) (xy 89.926454 -383.867181) (xy 89.919944 -383.884375)
			(xy 89.919556 -383.893568) (xy 89.919556 -384.051556) (xy 89.919043 -384.0617) (xy 89.911273 -384.080441)
			(xy 89.896905 -384.094764) (xy 89.87814 -384.102475) (xy 89.867994 -384.102864) (xy 89.151714 -384.102864)
			(xy 89.141589 -384.102362) (xy 89.122869 -384.09464) (xy 89.108512 -384.080358) (xy 89.100692 -384.061679)
			(xy 89.100152 -384.051556) (xy 89.100152 -383.893568) (xy 89.099745 -383.884381) (xy 89.093228 -383.867197)
			(xy 89.087452 -383.86004) (xy 89.06568 -383.834375) (xy 89.02773 -383.778791) (xy 88.996695 -383.719069)
			(xy 88.973021 -383.656066) (xy 88.957046 -383.590685) (xy 88.949001 -383.523864) (xy 88.948999 -383.45656)
			(xy 88.957042 -383.389738) (xy 88.973014 -383.324357) (xy 88.996685 -383.261353) (xy 89.027717 -383.20163)
			(xy 89.065665 -383.146044) (xy 89.087452 -383.120392) (xy 89.093241 -383.113242) (xy 89.099759 -383.096055)
			(xy 89.100152 -383.086864) (xy 89.100152 -382.593342) (xy 89.09971 -382.584158) (xy 89.093217 -382.566975)
			(xy 89.087452 -382.559814) (xy 89.065654 -382.53417) (xy 89.027704 -382.478583) (xy 88.996671 -382.418858)
			(xy 88.972998 -382.355853) (xy 88.957025 -382.290469) (xy 88.948982 -382.223646) (xy 85.670943 -382.223646)
			(xy 85.670943 -382.223704) (xy 85.662867 -382.290643) (xy 85.646832 -382.356132) (xy 85.623067 -382.419228)
			(xy 85.591915 -382.479024) (xy 85.553825 -382.534657) (xy 85.53196 -382.560322) (xy 85.526167 -382.567469)
			(xy 85.519651 -382.584658) (xy 85.51926 -382.59385) (xy 85.51926 -383.086356) (xy 85.5197 -383.09554)
			(xy 85.526194 -383.112724) (xy 85.53196 -383.119884) (xy 85.553841 -383.145536) (xy 85.591932 -383.201171)
			(xy 85.623084 -383.260969) (xy 85.646743 -383.323786) (xy 86.748805 -383.323786) (xy 86.748808 -383.25636)
			(xy 86.756888 -383.189419) (xy 86.772927 -383.123927) (xy 86.796696 -383.060829) (xy 86.827852 -383.001032)
			(xy 86.865945 -382.945397) (xy 86.887812 -382.919732) (xy 86.893621 -382.912596) (xy 86.900128 -382.895398)
			(xy 86.900512 -382.886204) (xy 86.900512 -382.728724) (xy 86.900936 -382.718602) (xy 86.908678 -382.699896)
			(xy 86.922993 -382.685581) (xy 86.941698 -382.677837) (xy 86.95182 -382.677416) (xy 87.6681 -382.677416)
			(xy 87.678224 -382.677816) (xy 87.696931 -382.685568) (xy 87.711246 -382.699889) (xy 87.718988 -382.718599)
			(xy 87.719408 -382.728724) (xy 87.719408 -382.886204) (xy 87.719815 -382.895392) (xy 87.726331 -382.912576)
			(xy 87.732108 -382.919732) (xy 87.753936 -382.945427) (xy 87.792026 -383.001057) (xy 87.823177 -383.060849)
			(xy 87.846943 -383.123942) (xy 87.862981 -383.189428) (xy 87.87106 -383.256363) (xy 87.871063 -383.323783)
			(xy 87.862991 -383.390719) (xy 87.846959 -383.456206) (xy 87.8232 -383.519301) (xy 87.792053 -383.579096)
			(xy 87.75397 -383.634731) (xy 87.732108 -383.660396) (xy 87.726332 -383.667556) (xy 87.719805 -383.684735)
			(xy 87.719408 -383.693924) (xy 87.719408 -384.186176) (xy 87.719828 -384.195362) (xy 87.726335 -384.212547)
			(xy 87.732108 -384.219704) (xy 87.754007 -384.24534) (xy 87.792094 -384.300979) (xy 87.823243 -384.360779)
			(xy 87.847005 -384.42388) (xy 87.863037 -384.489373) (xy 87.87111 -384.556314) (xy 87.871107 -384.62374)
			(xy 87.863028 -384.690681) (xy 87.846989 -384.756172) (xy 87.823221 -384.81927) (xy 87.792066 -384.879067)
			(xy 87.753974 -384.934703) (xy 87.732108 -384.960368) (xy 87.726301 -384.967506) (xy 87.719792 -384.984702)
			(xy 87.719408 -384.993896) (xy 87.719408 -385.151376) (xy 87.718965 -385.161496) (xy 87.711226 -385.180198)
			(xy 87.696918 -385.194512) (xy 87.67822 -385.20226) (xy 87.6681 -385.202684) (xy 86.95182 -385.202684)
			(xy 86.941697 -385.202267) (xy 86.922991 -385.194523) (xy 86.908675 -385.180206) (xy 86.900932 -385.161499)
			(xy 86.900512 -385.151376) (xy 86.900512 -384.993896) (xy 86.900101 -384.984709) (xy 86.893587 -384.967525)
			(xy 86.887812 -384.960368) (xy 86.865983 -384.934674) (xy 86.827892 -384.879044) (xy 86.796739 -384.819252)
			(xy 86.772973 -384.756158) (xy 86.756934 -384.690673) (xy 86.748855 -384.623738) (xy 86.748852 -384.556316)
			(xy 86.756925 -384.48938) (xy 86.772957 -384.423893) (xy 86.796717 -384.360798) (xy 86.827865 -384.301003)
			(xy 86.86595 -384.245369) (xy 86.887812 -384.219704) (xy 86.893591 -384.212546) (xy 86.900116 -384.195365)
			(xy 86.900512 -384.186176) (xy 86.900512 -383.693924) (xy 86.900088 -383.684738) (xy 86.893583 -383.667554)
			(xy 86.887812 -383.660396) (xy 86.865912 -383.63476) (xy 86.827824 -383.579122) (xy 86.796674 -383.519322)
			(xy 86.772911 -383.456221) (xy 86.756878 -383.390728) (xy 86.748805 -383.323786) (xy 85.646743 -383.323786)
			(xy 85.646849 -383.324068) (xy 85.662885 -383.389559) (xy 85.67096 -383.456499) (xy 85.670959 -383.523925)
			(xy 85.662881 -383.590865) (xy 85.646842 -383.656355) (xy 85.623074 -383.719453) (xy 85.59192 -383.77925)
			(xy 85.553826 -383.834883) (xy 85.53196 -383.860548) (xy 85.526156 -383.867687) (xy 85.519647 -383.884883)
			(xy 85.51926 -383.894076) (xy 85.51926 -384.051556) (xy 85.518847 -384.061681) (xy 85.511106 -384.080391)
			(xy 85.496787 -384.094708) (xy 85.478077 -384.102448) (xy 85.467952 -384.102864) (xy 84.751672 -384.102864)
			(xy 84.741543 -384.102506) (xy 84.722832 -384.094742) (xy 84.708517 -384.080407) (xy 84.70078 -384.061685)
			(xy 84.700364 -384.051556) (xy 84.700364 -383.894076) (xy 84.699951 -383.884889) (xy 84.693438 -383.867706)
			(xy 84.687664 -383.860548) (xy 84.665817 -383.834869) (xy 84.62773 -383.779236) (xy 84.596581 -383.719441)
			(xy 84.572817 -383.656346) (xy 84.556782 -383.590859) (xy 84.548705 -383.523923) (xy 84.548704 -383.456501)
			(xy 84.556778 -383.389565) (xy 84.57281 -383.324077) (xy 84.596571 -383.260981) (xy 84.627718 -383.201185)
			(xy 84.665802 -383.14555) (xy 84.687664 -383.119884) (xy 84.693458 -383.112737) (xy 84.699972 -383.095548)
			(xy 84.700364 -383.086356) (xy 84.700364 -382.59385) (xy 84.699916 -382.584667) (xy 84.693427 -382.567483)
			(xy 84.687664 -382.560322) (xy 84.665791 -382.534664) (xy 84.627705 -382.479028) (xy 84.596557 -382.41923)
			(xy 84.572795 -382.356132) (xy 84.556761 -382.290643) (xy 84.548687 -382.223704) (xy 81.271152 -382.223704)
			(xy 81.263076 -382.290642) (xy 81.247041 -382.356131) (xy 81.223277 -382.419228) (xy 81.192126 -382.479023)
			(xy 81.154036 -382.534657) (xy 81.132172 -382.560322) (xy 81.12638 -382.56747) (xy 81.119863 -382.584659)
			(xy 81.119472 -382.59385) (xy 81.119472 -383.086356) (xy 81.11991 -383.09554) (xy 81.126405 -383.112724)
			(xy 81.132172 -383.119884) (xy 81.154053 -383.145536) (xy 81.192143 -383.201172) (xy 81.223294 -383.260969)
			(xy 81.246931 -383.323727) (xy 82.349036 -383.323727) (xy 82.34904 -383.256419) (xy 82.357087 -383.189595)
			(xy 82.373063 -383.124211) (xy 82.396739 -383.061205) (xy 82.427775 -383.00148) (xy 82.465727 -382.945892)
			(xy 82.487516 -382.92024) (xy 82.493322 -382.913102) (xy 82.499831 -382.895906) (xy 82.500216 -382.886712)
			(xy 82.500216 -382.728724) (xy 82.500641 -382.718569) (xy 82.508432 -382.699814) (xy 82.522828 -382.68549)
			(xy 82.541621 -382.677792) (xy 82.551778 -382.677416) (xy 83.268058 -382.677416) (xy 83.278179 -382.67796)
			(xy 83.296895 -382.68567) (xy 83.311252 -382.699938) (xy 83.319076 -382.718606) (xy 83.31962 -382.728724)
			(xy 83.31962 -382.886712) (xy 83.32002 -382.8959) (xy 83.32654 -382.913085) (xy 83.33232 -382.92024)
			(xy 83.354074 -382.945921) (xy 83.392026 -383.001502) (xy 83.423063 -383.061221) (xy 83.44674 -383.124222)
			(xy 83.462717 -383.189601) (xy 83.470764 -383.256421) (xy 83.470767 -383.323724) (xy 83.462726 -383.390545)
			(xy 83.446756 -383.455926) (xy 83.423085 -383.518929) (xy 83.392054 -383.578651) (xy 83.354107 -383.634236)
			(xy 83.33232 -383.659888) (xy 83.326506 -383.667021) (xy 83.320001 -383.684221) (xy 83.31962 -383.693416)
			(xy 83.31962 -384.186684) (xy 83.320033 -384.195871) (xy 83.326544 -384.213056) (xy 83.33232 -384.220212)
			(xy 83.354144 -384.245835) (xy 83.392095 -384.301424) (xy 83.423129 -384.361152) (xy 83.446801 -384.42416)
			(xy 83.462773 -384.489546) (xy 83.470815 -384.556373) (xy 83.470812 -384.623681) (xy 83.462763 -384.690507)
			(xy 83.446785 -384.755892) (xy 83.423107 -384.818898) (xy 83.392067 -384.878622) (xy 83.354111 -384.934208)
			(xy 83.33232 -384.95986) (xy 83.326518 -384.967001) (xy 83.320006 -384.984195) (xy 83.31962 -384.993388)
			(xy 83.31962 -385.151376) (xy 83.319159 -385.161526) (xy 83.311375 -385.180274) (xy 83.296991 -385.194598)
			(xy 83.27821 -385.202302) (xy 83.268058 -385.202684) (xy 82.551778 -385.202684) (xy 82.541653 -385.202192)
			(xy 82.522936 -385.194462) (xy 82.508581 -385.180178) (xy 82.500758 -385.161499) (xy 82.500216 -385.151376)
			(xy 82.500216 -384.993388) (xy 82.499808 -384.984201) (xy 82.493293 -384.967016) (xy 82.487516 -384.95986)
			(xy 82.465765 -384.934178) (xy 82.427816 -384.878595) (xy 82.396783 -384.818876) (xy 82.373109 -384.755875)
			(xy 82.357134 -384.690497) (xy 82.349088 -384.623678) (xy 82.349084 -384.556376) (xy 82.357125 -384.489556)
			(xy 82.373093 -384.424177) (xy 82.396761 -384.361174) (xy 82.427788 -384.301451) (xy 82.465731 -384.245865)
			(xy 82.487516 -384.220212) (xy 82.493334 -384.213082) (xy 82.499835 -384.19588) (xy 82.500216 -384.186684)
			(xy 82.500216 -383.693416) (xy 82.499794 -383.68423) (xy 82.493288 -383.667046) (xy 82.487516 -383.659888)
			(xy 82.465694 -383.634265) (xy 82.427747 -383.578674) (xy 82.396717 -383.518946) (xy 82.373047 -383.455938)
			(xy 82.357077 -383.390552) (xy 82.349036 -383.323727) (xy 81.246931 -383.323727) (xy 81.247059 -383.324068)
			(xy 81.263094 -383.389559) (xy 81.271169 -383.456499) (xy 81.271168 -383.523925) (xy 81.26309 -383.590865)
			(xy 81.247052 -383.656355) (xy 81.223285 -383.719453) (xy 81.19213 -383.779249) (xy 81.154038 -383.834883)
			(xy 81.132172 -383.860548) (xy 81.126369 -383.867688) (xy 81.119859 -383.884883) (xy 81.119472 -383.894076)
			(xy 81.119472 -384.051556) (xy 81.119047 -384.061679) (xy 81.111308 -384.080387) (xy 81.096994 -384.094704)
			(xy 81.078287 -384.102446) (xy 81.068164 -384.102864) (xy 80.351884 -384.102864) (xy 80.341756 -384.102496)
			(xy 80.323045 -384.094736) (xy 80.30873 -384.080405) (xy 80.300992 -384.061685) (xy 80.300576 -384.051556)
			(xy 80.300576 -383.894076) (xy 80.300183 -383.884887) (xy 80.293658 -383.867703) (xy 80.287876 -383.860548)
			(xy 80.266029 -383.834869) (xy 80.227941 -383.779236) (xy 80.196791 -383.719442) (xy 80.173027 -383.656347)
			(xy 80.156991 -383.590859) (xy 80.148914 -383.523923) (xy 80.148913 -383.456501) (xy 80.156987 -383.389564)
			(xy 80.17302 -383.324076) (xy 80.196781 -383.26098) (xy 80.227929 -383.201184) (xy 80.266014 -383.14555)
			(xy 80.287876 -383.119884) (xy 80.293659 -383.112729) (xy 80.300183 -383.095546) (xy 80.300576 -383.086356)
			(xy 80.300576 -382.59385) (xy 80.300147 -382.584665) (xy 80.293647 -382.56748) (xy 80.287876 -382.560322)
			(xy 80.266003 -382.534664) (xy 80.227916 -382.479028) (xy 80.196767 -382.419231) (xy 80.173005 -382.356133)
			(xy 80.156971 -382.290643) (xy 80.148896 -382.223704) (xy 76.870825 -382.223704) (xy 76.862789 -382.290466)
			(xy 76.846818 -382.355847) (xy 76.823147 -382.418851) (xy 76.792117 -382.478575) (xy 76.75417 -382.534162)
			(xy 76.732384 -382.559814) (xy 76.726597 -382.566966) (xy 76.720077 -382.584151) (xy 76.719684 -382.593342)
			(xy 76.719684 -383.086864) (xy 76.720115 -383.096049) (xy 76.726615 -383.113233) (xy 76.732384 -383.120392)
			(xy 76.754187 -383.146031) (xy 76.792134 -383.20162) (xy 76.823165 -383.261346) (xy 76.846624 -383.323787)
			(xy 77.948717 -383.323787) (xy 77.94872 -383.256359) (xy 77.9568 -383.189418) (xy 77.97284 -383.123927)
			(xy 77.99661 -383.060828) (xy 78.027766 -383.001031) (xy 78.065861 -382.945397) (xy 78.087728 -382.919732)
			(xy 78.09354 -382.912598) (xy 78.100045 -382.895399) (xy 78.100428 -382.886204) (xy 78.100428 -382.728724)
			(xy 78.100836 -382.7186) (xy 78.108582 -382.699891) (xy 78.122901 -382.685575) (xy 78.141611 -382.677834)
			(xy 78.151736 -382.677416) (xy 78.868016 -382.677416) (xy 78.878142 -382.677803) (xy 78.896849 -382.685559)
			(xy 78.911163 -382.699885) (xy 78.918905 -382.718598) (xy 78.919324 -382.728724) (xy 78.919324 -382.886204)
			(xy 78.919727 -382.895392) (xy 78.926245 -382.912577) (xy 78.932024 -382.919732) (xy 78.953852 -382.945427)
			(xy 78.99194 -383.001058) (xy 79.023091 -383.06085) (xy 79.046856 -383.123943) (xy 79.062893 -383.189428)
			(xy 79.070972 -383.256363) (xy 79.070975 -383.323783) (xy 79.062903 -383.390719) (xy 79.046872 -383.456205)
			(xy 79.023113 -383.519301) (xy 78.991968 -383.579096) (xy 78.953885 -383.63473) (xy 78.932024 -383.660396)
			(xy 78.926249 -383.667557) (xy 78.919721 -383.684735) (xy 78.919324 -383.693924) (xy 78.919324 -384.186176)
			(xy 78.91974 -384.195363) (xy 78.926249 -384.212547) (xy 78.932024 -384.219704) (xy 78.953922 -384.24534)
			(xy 78.992009 -384.30098) (xy 79.023156 -384.36078) (xy 79.046917 -384.423881) (xy 79.06295 -384.489373)
			(xy 79.071022 -384.556314) (xy 79.071019 -384.62374) (xy 79.06294 -384.69068) (xy 79.046901 -384.756171)
			(xy 79.023134 -384.819269) (xy 78.991981 -384.879067) (xy 78.953889 -384.934702) (xy 78.932024 -384.960368)
			(xy 78.926219 -384.967507) (xy 78.919709 -384.984702) (xy 78.919324 -384.993896) (xy 78.919324 -385.151376)
			(xy 78.918865 -385.161494) (xy 78.911129 -385.180193) (xy 78.896826 -385.194507) (xy 78.878134 -385.202257)
			(xy 78.868016 -385.202684) (xy 78.151736 -385.202684) (xy 78.141614 -385.202254) (xy 78.122908 -385.194515)
			(xy 78.108592 -385.180202) (xy 78.100848 -385.161498) (xy 78.100428 -385.151376) (xy 78.100428 -384.993896)
			(xy 78.100014 -384.984709) (xy 78.093502 -384.967525) (xy 78.087728 -384.960368) (xy 78.065898 -384.934674)
			(xy 78.027807 -384.879044) (xy 77.996653 -384.819252) (xy 77.972886 -384.756159) (xy 77.956847 -384.690673)
			(xy 77.948768 -384.623738) (xy 77.948764 -384.556316) (xy 77.956837 -384.48938) (xy 77.972869 -384.423893)
			(xy 77.996631 -384.360797) (xy 78.027779 -384.301002) (xy 78.065865 -384.245369) (xy 78.087728 -384.219704)
			(xy 78.093509 -384.212548) (xy 78.100032 -384.195366) (xy 78.100428 -384.186176) (xy 78.100428 -383.693924)
			(xy 78.1 -383.684739) (xy 78.093498 -383.667555) (xy 78.087728 -383.660396) (xy 78.065828 -383.63476)
			(xy 78.027738 -383.579122) (xy 77.996587 -383.519322) (xy 77.972824 -383.456221) (xy 77.95679 -383.390728)
			(xy 77.948717 -383.323787) (xy 76.846624 -383.323787) (xy 76.846836 -383.324352) (xy 76.862807 -383.389735)
			(xy 76.870849 -383.456559) (xy 76.870848 -383.523865) (xy 76.862803 -383.590688) (xy 76.846829 -383.656071)
			(xy 76.823155 -383.719076) (xy 76.792121 -383.7788) (xy 76.754172 -383.834388) (xy 76.732384 -383.86004)
			(xy 76.726586 -383.867184) (xy 76.720073 -383.884376) (xy 76.719684 -383.893568) (xy 76.719684 -384.051556)
			(xy 76.719242 -384.061709) (xy 76.711458 -384.080464) (xy 76.697067 -384.094789) (xy 76.678277 -384.102488)
			(xy 76.668122 -384.102864) (xy 75.951842 -384.102864) (xy 75.941718 -384.102339) (xy 75.922999 -384.094626)
			(xy 75.908642 -384.080351) (xy 75.90082 -384.061677) (xy 75.90028 -384.051556) (xy 75.90028 -383.893568)
			(xy 75.89989 -383.884379) (xy 75.893363 -383.867194) (xy 75.88758 -383.86004) (xy 75.865807 -383.834375)
			(xy 75.827855 -383.778792) (xy 75.796819 -383.71907) (xy 75.773143 -383.656067) (xy 75.757168 -383.590686)
			(xy 75.749122 -383.523864) (xy 75.74912 -383.45656) (xy 75.757164 -383.389738) (xy 75.773136 -383.324356)
			(xy 75.796809 -383.261352) (xy 75.827842 -383.201629) (xy 75.865792 -383.146044) (xy 75.88758 -383.120392)
			(xy 75.89336 -383.113235) (xy 75.899885 -383.096054) (xy 75.90028 -383.086864) (xy 75.90028 -382.593342)
			(xy 75.899854 -382.584156) (xy 75.893352 -382.566972) (xy 75.88758 -382.559814) (xy 75.865781 -382.53417)
			(xy 75.82783 -382.478584) (xy 75.796795 -382.418859) (xy 75.773121 -382.355854) (xy 75.757147 -382.29047)
			(xy 75.749104 -382.223646) (xy 72.471064 -382.223646) (xy 72.471064 -382.223704) (xy 72.462989 -382.290642)
			(xy 72.446954 -382.356131) (xy 72.42319 -382.419227) (xy 72.39204 -382.479023) (xy 72.353952 -382.534657)
			(xy 72.332088 -382.560322) (xy 72.326298 -382.567472) (xy 72.31978 -382.584659) (xy 72.319388 -382.59385)
			(xy 72.319388 -383.086356) (xy 72.319822 -383.095541) (xy 72.326319 -383.112725) (xy 72.332088 -383.119884)
			(xy 72.353968 -383.145536) (xy 72.392057 -383.201172) (xy 72.423208 -383.26097) (xy 72.446843 -383.323727)
			(xy 73.548949 -383.323727) (xy 73.548952 -383.256419) (xy 73.556999 -383.189594) (xy 73.572976 -383.12421)
			(xy 73.596652 -383.061204) (xy 73.62769 -383.001479) (xy 73.665642 -382.945892) (xy 73.687432 -382.92024)
			(xy 73.693241 -382.913103) (xy 73.699747 -382.895906) (xy 73.700132 -382.886712) (xy 73.700132 -382.728724)
			(xy 73.700542 -382.718567) (xy 73.708335 -382.699809) (xy 73.722736 -382.685484) (xy 73.741535 -382.677789)
			(xy 73.751694 -382.677416) (xy 74.467974 -382.677416) (xy 74.478096 -382.677947) (xy 74.496812 -382.685662)
			(xy 74.511169 -382.699934) (xy 74.518993 -382.718605) (xy 74.519536 -382.728724) (xy 74.519536 -382.886712)
			(xy 74.519955 -382.895898) (xy 74.526464 -382.913082) (xy 74.532236 -382.92024) (xy 74.553989 -382.945921)
			(xy 74.591941 -383.001503) (xy 74.622977 -383.061222) (xy 74.646653 -383.124223) (xy 74.662629 -383.189602)
			(xy 74.670676 -383.256422) (xy 74.670679 -383.323724) (xy 74.662639 -383.390545) (xy 74.646669 -383.455925)
			(xy 74.622999 -383.518928) (xy 74.591968 -383.578651) (xy 74.554022 -383.634236) (xy 74.532236 -383.659888)
			(xy 74.526412 -383.667013) (xy 74.519915 -383.684219) (xy 74.519536 -383.693416) (xy 74.519536 -384.186684)
			(xy 74.519968 -384.195869) (xy 74.526468 -384.213052) (xy 74.532236 -384.220212) (xy 74.55406 -384.245835)
			(xy 74.592009 -384.301425) (xy 74.623043 -384.361152) (xy 74.646714 -384.424161) (xy 74.662686 -384.489547)
			(xy 74.670727 -384.556373) (xy 74.670724 -384.623681) (xy 74.662676 -384.690507) (xy 74.646698 -384.755891)
			(xy 74.623021 -384.818897) (xy 74.591982 -384.878622) (xy 74.554027 -384.934208) (xy 74.532236 -384.95986)
			(xy 74.526424 -384.966994) (xy 74.51992 -384.984193) (xy 74.519536 -384.993388) (xy 74.519536 -385.151376)
			(xy 74.51906 -385.161524) (xy 74.511279 -385.180269) (xy 74.496899 -385.194592) (xy 74.478124 -385.202299)
			(xy 74.467974 -385.202684) (xy 73.751694 -385.202684) (xy 73.74157 -385.202179) (xy 73.722853 -385.194454)
			(xy 73.708498 -385.180173) (xy 73.700675 -385.161497) (xy 73.700132 -385.151376) (xy 73.700132 -384.993388)
			(xy 73.699721 -384.984201) (xy 73.693207 -384.967017) (xy 73.687432 -384.95986) (xy 73.66568 -384.934178)
			(xy 73.627731 -384.878596) (xy 73.596696 -384.818877) (xy 73.573022 -384.755876) (xy 73.557047 -384.690497)
			(xy 73.549 -384.623678) (xy 73.548996 -384.556376) (xy 73.557037 -384.489556) (xy 73.573006 -384.424176)
			(xy 73.596674 -384.361173) (xy 73.627703 -384.30145) (xy 73.665647 -384.245864) (xy 73.687432 -384.220212)
			(xy 73.693253 -384.213084) (xy 73.699752 -384.19588) (xy 73.700132 -384.186684) (xy 73.700132 -383.693416)
			(xy 73.699707 -383.684231) (xy 73.693203 -383.667046) (xy 73.687432 -383.659888) (xy 73.665609 -383.634265)
			(xy 73.627662 -383.578674) (xy 73.59663 -383.518946) (xy 73.57296 -383.455938) (xy 73.55699 -383.390553)
			(xy 73.548949 -383.323727) (xy 72.446843 -383.323727) (xy 72.446972 -383.324069) (xy 72.463006 -383.38956)
			(xy 72.471081 -383.456499) (xy 72.47108 -383.523925) (xy 72.463002 -383.590864) (xy 72.446964 -383.656354)
			(xy 72.423198 -383.719452) (xy 72.392045 -383.779248) (xy 72.353953 -383.834883) (xy 72.332088 -383.860548)
			(xy 72.326287 -383.86769) (xy 72.319775 -383.884883) (xy 72.319388 -383.894076) (xy 72.319388 -384.051556)
			(xy 72.318948 -384.061677) (xy 72.311212 -384.080382) (xy 72.296902 -384.094698) (xy 72.278201 -384.102443)
			(xy 72.26808 -384.102864) (xy 71.5518 -384.102864) (xy 71.541673 -384.102483) (xy 71.522963 -384.094728)
			(xy 71.508647 -384.0804) (xy 71.500908 -384.061683) (xy 71.500492 -384.051556) (xy 71.500492 -383.894076)
			(xy 71.500095 -383.884887) (xy 71.493572 -383.867703) (xy 71.487792 -383.860548) (xy 71.465944 -383.83487)
			(xy 71.427855 -383.779237) (xy 71.396704 -383.719442) (xy 71.37294 -383.656347) (xy 71.356903 -383.59086)
			(xy 71.348826 -383.523923) (xy 71.348825 -383.456501) (xy 71.356899 -383.389564) (xy 71.372933 -383.324076)
			(xy 71.396695 -383.26098) (xy 71.427843 -383.201184) (xy 71.465929 -383.145549) (xy 71.487792 -383.119884)
			(xy 71.493577 -383.11273) (xy 71.500099 -383.095546) (xy 71.500492 -383.086356) (xy 71.500492 -382.59385)
			(xy 71.50006 -382.584665) (xy 71.493562 -382.56748) (xy 71.487792 -382.560322) (xy 71.465918 -382.534665)
			(xy 71.427831 -382.479029) (xy 71.396681 -382.419231) (xy 71.372918 -382.356134) (xy 71.356883 -382.290644)
			(xy 71.348808 -382.223705) (xy 46.070794 -382.223705) (xy 46.062758 -382.290467) (xy 46.046786 -382.355849)
			(xy 46.023113 -382.418853) (xy 45.99208 -382.478576) (xy 45.954131 -382.534162) (xy 45.932344 -382.559814)
			(xy 45.926552 -382.566962) (xy 45.920036 -382.584151) (xy 45.919644 -382.593342) (xy 45.919644 -383.086864)
			(xy 45.920084 -383.096048) (xy 45.926578 -383.113232) (xy 45.932344 -383.120392) (xy 45.954148 -383.146031)
			(xy 45.992098 -383.201619) (xy 46.023131 -383.261344) (xy 46.04657 -383.323727) (xy 47.149191 -383.323727)
			(xy 47.149195 -383.256419) (xy 47.157243 -383.189593) (xy 47.173221 -383.124208) (xy 47.1969 -383.061202)
			(xy 47.22794 -383.001477) (xy 47.265897 -382.945892) (xy 47.287688 -382.92024) (xy 47.293491 -382.913099)
			(xy 47.300002 -382.895905) (xy 47.300388 -382.886712) (xy 47.300388 -382.728724) (xy 47.300841 -382.718573)
			(xy 47.308626 -382.699823) (xy 47.323013 -382.685499) (xy 47.341797 -382.677797) (xy 47.35195 -382.677416)
			(xy 48.06823 -382.677416) (xy 48.078356 -382.677901) (xy 48.097073 -382.685634) (xy 48.111427 -382.699921)
			(xy 48.11925 -382.718601) (xy 48.119792 -382.728724) (xy 48.119792 -382.886712) (xy 48.120198 -382.8959)
			(xy 48.126715 -382.913084) (xy 48.132492 -382.92024) (xy 48.154243 -382.945922) (xy 48.192191 -383.001505)
			(xy 48.223224 -383.061224) (xy 48.246898 -383.124225) (xy 48.262872 -383.189603) (xy 48.270919 -383.256422)
			(xy 48.270922 -383.323724) (xy 48.262882 -383.390543) (xy 48.246914 -383.455923) (xy 48.223247 -383.518926)
			(xy 48.192219 -383.578649) (xy 48.154277 -383.634236) (xy 48.132492 -383.659888) (xy 48.126675 -383.667018)
			(xy 48.120173 -383.68422) (xy 48.119792 -383.693416) (xy 48.119792 -384.186684) (xy 48.120212 -384.19587)
			(xy 48.126719 -384.213054) (xy 48.132492 -384.220212) (xy 48.154314 -384.245835) (xy 48.19226 -384.301427)
			(xy 48.22329 -384.361155) (xy 48.246959 -384.424163) (xy 48.262929 -384.489548) (xy 48.27097 -384.556373)
			(xy 48.270966 -384.623681) (xy 48.262919 -384.690505) (xy 48.246943 -384.755889) (xy 48.223268 -384.818895)
			(xy 48.192232 -384.87862) (xy 48.154281 -384.934207) (xy 48.132492 -384.95986) (xy 48.126687 -384.966999)
			(xy 48.120177 -384.984194) (xy 48.119792 -384.993388) (xy 48.119792 -385.151376) (xy 48.119359 -385.16153)
			(xy 48.11157 -385.180283) (xy 48.097176 -385.194608) (xy 48.078386 -385.202307) (xy 48.06823 -385.202684)
			(xy 47.35195 -385.202684) (xy 47.341829 -385.202133) (xy 47.323114 -385.194426) (xy 47.308757 -385.18016)
			(xy 47.300932 -385.161493) (xy 47.300388 -385.151376) (xy 47.300388 -384.993388) (xy 47.299986 -384.9842)
			(xy 47.293467 -384.967016) (xy 47.287688 -384.95986) (xy 47.265934 -384.934179) (xy 47.227981 -384.878598)
			(xy 47.196944 -384.818879) (xy 47.173267 -384.755878) (xy 47.15729 -384.690499) (xy 47.149242 -384.623679)
			(xy 47.149239 -384.556376) (xy 47.15728 -384.489554) (xy 47.173251 -384.424174) (xy 47.196921 -384.361171)
			(xy 47.227953 -384.301448) (xy 47.265901 -384.245863) (xy 47.287688 -384.220212) (xy 47.293503 -384.21308)
			(xy 47.300007 -384.195879) (xy 47.300388 -384.186684) (xy 47.300388 -383.693416) (xy 47.299973 -383.684229)
			(xy 47.293463 -383.667045) (xy 47.287688 -383.659888) (xy 47.265863 -383.634266) (xy 47.227913 -383.578676)
			(xy 47.196878 -383.518949) (xy 47.173205 -383.45594) (xy 47.157233 -383.390554) (xy 47.149191 -383.323727)
			(xy 46.04657 -383.323727) (xy 46.046804 -383.32435) (xy 46.062776 -383.389734) (xy 46.070819 -383.456559)
			(xy 46.070818 -383.523865) (xy 46.062772 -383.590689) (xy 46.046797 -383.656073) (xy 46.023121 -383.719078)
			(xy 45.992085 -383.778802) (xy 45.954133 -383.834388) (xy 45.932344 -383.86004) (xy 45.926541 -383.86718)
			(xy 45.920032 -383.884375) (xy 45.919644 -383.893568) (xy 45.919644 -384.051556) (xy 45.919143 -384.061702)
			(xy 45.91137 -384.080445) (xy 45.896998 -384.094768) (xy 45.878229 -384.102477) (xy 45.868082 -384.102864)
			(xy 45.151802 -384.102864) (xy 45.141676 -384.102372) (xy 45.122956 -384.094645) (xy 45.108599 -384.080361)
			(xy 45.100779 -384.06168) (xy 45.10024 -384.051556) (xy 45.10024 -383.893568) (xy 45.099836 -383.88438)
			(xy 45.093317 -383.867197) (xy 45.08754 -383.86004) (xy 45.065768 -383.834375) (xy 45.027819 -383.77879)
			(xy 44.996785 -383.719068) (xy 44.973111 -383.656066) (xy 44.957137 -383.590685) (xy 44.949092 -383.523864)
			(xy 44.94909 -383.45656) (xy 44.957133 -383.389739) (xy 44.973104 -383.324357) (xy 44.996775 -383.261354)
			(xy 45.027806 -383.20163) (xy 45.065753 -383.146044) (xy 45.08754 -383.120392) (xy 45.093328 -383.113241)
			(xy 45.099847 -383.096055) (xy 45.10024 -383.086864) (xy 45.10024 -382.593342) (xy 45.0998 -382.584158)
			(xy 45.093306 -382.566974) (xy 45.08754 -382.559814) (xy 45.065742 -382.53417) (xy 45.027794 -382.478582)
			(xy 44.996761 -382.418858) (xy 44.973088 -382.355852) (xy 44.957116 -382.290469) (xy 44.949073 -382.223645)
			(xy 41.671034 -382.223645) (xy 41.671034 -382.223704) (xy 41.662958 -382.290643) (xy 41.646922 -382.356132)
			(xy 41.623157 -382.419229) (xy 41.592004 -382.479024) (xy 41.553913 -382.534658) (xy 41.532048 -382.560322)
			(xy 41.526253 -382.567468) (xy 41.519739 -382.584658) (xy 41.519348 -382.59385) (xy 41.519348 -383.086356)
			(xy 41.519791 -383.095539) (xy 41.526283 -383.112723) (xy 41.532048 -383.119884) (xy 41.55393 -383.145535)
			(xy 41.592021 -383.201171) (xy 41.623174 -383.260968) (xy 41.646834 -383.323786) (xy 42.748896 -383.323786)
			(xy 42.748899 -383.25636) (xy 42.756978 -383.189419) (xy 42.773018 -383.123928) (xy 42.796786 -383.06083)
			(xy 42.827941 -383.001032) (xy 42.866034 -382.945397) (xy 42.8879 -382.919732) (xy 42.893708 -382.912595)
			(xy 42.900216 -382.895398) (xy 42.9006 -382.886204) (xy 42.9006 -382.728724) (xy 42.901035 -382.718603)
			(xy 42.908776 -382.6999) (xy 42.923086 -382.685585) (xy 42.941787 -382.677839) (xy 42.951908 -382.677416)
			(xy 43.668188 -382.677416) (xy 43.678312 -382.677826) (xy 43.697018 -382.685573) (xy 43.711333 -382.699892)
			(xy 43.719076 -382.7186) (xy 43.719496 -382.728724) (xy 43.719496 -382.886204) (xy 43.719905 -382.895391)
			(xy 43.72642 -382.912575) (xy 43.732196 -382.919732) (xy 43.754025 -382.945426) (xy 43.792115 -383.001057)
			(xy 43.823267 -383.060849) (xy 43.847034 -383.123942) (xy 43.863072 -383.189427) (xy 43.871151 -383.256363)
			(xy 43.871154 -383.323783) (xy 43.863081 -383.390719) (xy 43.84705 -383.456206) (xy 43.823289 -383.519302)
			(xy 43.792143 -383.579097) (xy 43.754058 -383.634731) (xy 43.732196 -383.660396) (xy 43.726418 -383.667554)
			(xy 43.719892 -383.684735) (xy 43.719496 -383.693924) (xy 43.719496 -384.186176) (xy 43.719919 -384.195362)
			(xy 43.726424 -384.212546) (xy 43.732196 -384.219704) (xy 43.754095 -384.24534) (xy 43.792183 -384.300979)
			(xy 43.823333 -384.360779) (xy 43.847095 -384.42388) (xy 43.863128 -384.489372) (xy 43.871201 -384.556314)
			(xy 43.871198 -384.62374) (xy 43.863118 -384.690681) (xy 43.847079 -384.756172) (xy 43.823311 -384.819271)
			(xy 43.792156 -384.879068) (xy 43.754062 -384.934703) (xy 43.732196 -384.960368) (xy 43.726388 -384.967505)
			(xy 43.71988 -384.984702) (xy 43.719496 -384.993896) (xy 43.719496 -385.151376) (xy 43.719064 -385.161497)
			(xy 43.711323 -385.180201) (xy 43.697011 -385.194517) (xy 43.678309 -385.202262) (xy 43.668188 -385.202684)
			(xy 42.951908 -385.202684) (xy 42.941784 -385.202277) (xy 42.923078 -385.194529) (xy 42.908762 -385.180209)
			(xy 42.90102 -385.1615) (xy 42.9006 -385.151376) (xy 42.9006 -384.993896) (xy 42.900192 -384.984709)
			(xy 42.893677 -384.967524) (xy 42.8879 -384.960368) (xy 42.866071 -384.934674) (xy 42.827982 -384.879043)
			(xy 42.796829 -384.819251) (xy 42.773063 -384.756158) (xy 42.757025 -384.690672) (xy 42.748946 -384.623737)
			(xy 42.748943 -384.556317) (xy 42.757015 -384.489381) (xy 42.773047 -384.423894) (xy 42.796807 -384.360798)
			(xy 42.827954 -384.301003) (xy 42.866038 -384.245369) (xy 42.8879 -384.219704) (xy 42.893677 -384.212545)
			(xy 42.900204 -384.195365) (xy 42.9006 -384.186176) (xy 42.9006 -383.693924) (xy 42.900178 -383.684738)
			(xy 42.893673 -383.667554) (xy 42.8879 -383.660396) (xy 42.866001 -383.63476) (xy 42.827913 -383.579121)
			(xy 42.796764 -383.519321) (xy 42.773002 -383.45622) (xy 42.756969 -383.390728) (xy 42.748896 -383.323786)
			(xy 41.646834 -383.323786) (xy 41.64694 -383.324067) (xy 41.662976 -383.389558) (xy 41.671051 -383.456499)
			(xy 41.67105 -383.523925) (xy 41.662971 -383.590865) (xy 41.646933 -383.656356) (xy 41.623164 -383.719454)
			(xy 41.592009 -383.77925) (xy 41.553915 -383.834884) (xy 41.532048 -383.860548) (xy 41.526242 -383.867686)
			(xy 41.519734 -383.884882) (xy 41.519348 -383.894076) (xy 41.519348 -384.051556) (xy 41.518849 -384.06167)
			(xy 41.511124 -384.080363) (xy 41.496834 -384.094677) (xy 41.478153 -384.102432) (xy 41.46804 -384.102864)
			(xy 40.75176 -384.102864) (xy 40.74163 -384.102516) (xy 40.722919 -384.094748) (xy 40.708605 -384.08041)
			(xy 40.700868 -384.061686) (xy 40.700452 -384.051556) (xy 40.700452 -383.894076) (xy 40.700042 -383.884889)
			(xy 40.693527 -383.867705) (xy 40.687752 -383.860548) (xy 40.665902 -383.834871) (xy 40.627809 -383.779239)
			(xy 40.596655 -383.719445) (xy 40.572888 -383.65635) (xy 40.556849 -383.590862) (xy 40.548772 -383.523924)
			(xy 40.54877 -383.4565) (xy 40.556845 -383.389562) (xy 40.572881 -383.324073) (xy 40.596645 -383.260977)
			(xy 40.627797 -383.201182) (xy 40.665887 -383.145548) (xy 40.687752 -383.119884) (xy 40.693544 -383.112736)
			(xy 40.70006 -383.095547) (xy 40.700452 -383.086356) (xy 40.700452 -382.59385) (xy 40.700006 -382.584667)
			(xy 40.693516 -382.567483) (xy 40.687752 -382.560322) (xy 40.665876 -382.534666) (xy 40.627785 -382.479031)
			(xy 40.596631 -382.419234) (xy 40.572865 -382.356136) (xy 40.556829 -382.290645) (xy 40.548753 -382.223705)
			(xy 37.271243 -382.223705) (xy 37.263167 -382.290643) (xy 37.247132 -382.356132) (xy 37.223367 -382.419228)
			(xy 37.192215 -382.479024) (xy 37.154125 -382.534657) (xy 37.13226 -382.560322) (xy 37.126467 -382.567469)
			(xy 37.119951 -382.584658) (xy 37.11956 -382.59385) (xy 37.11956 -383.086356) (xy 37.12 -383.09554)
			(xy 37.126494 -383.112724) (xy 37.13226 -383.119884) (xy 37.154141 -383.145536) (xy 37.192232 -383.201171)
			(xy 37.223384 -383.260969) (xy 37.247021 -383.323727) (xy 38.349127 -383.323727) (xy 38.349131 -383.256419)
			(xy 38.357178 -383.189595) (xy 38.373154 -383.124211) (xy 38.396829 -383.061205) (xy 38.427864 -383.00148)
			(xy 38.465815 -382.945893) (xy 38.487604 -382.92024) (xy 38.493409 -382.913101) (xy 38.499919 -382.895906)
			(xy 38.500304 -382.886712) (xy 38.500304 -382.728724) (xy 38.500741 -382.718571) (xy 38.50853 -382.699818)
			(xy 38.522922 -382.685494) (xy 38.541711 -382.677794) (xy 38.551866 -382.677416) (xy 39.268146 -382.677416)
			(xy 39.278273 -382.677888) (xy 39.29699 -382.685627) (xy 39.311344 -382.699917) (xy 39.319166 -382.7186)
			(xy 39.319708 -382.728724) (xy 39.319708 -382.886712) (xy 39.320111 -382.8959) (xy 39.326629 -382.913084)
			(xy 39.332408 -382.92024) (xy 39.354162 -382.945921) (xy 39.392115 -383.001502) (xy 39.423153 -383.061221)
			(xy 39.44683 -383.124222) (xy 39.462807 -383.189601) (xy 39.470855 -383.256421) (xy 39.470858 -383.323725)
			(xy 39.462817 -383.390546) (xy 39.446846 -383.455926) (xy 39.423175 -383.51893) (xy 39.392143 -383.578652)
			(xy 39.354195 -383.634237) (xy 39.332408 -383.659888) (xy 39.326592 -383.66702) (xy 39.320089 -383.684221)
			(xy 39.319708 -383.693416) (xy 39.319708 -384.186684) (xy 39.320124 -384.195871) (xy 39.326633 -384.213055)
			(xy 39.332408 -384.220212) (xy 39.354233 -384.245834) (xy 39.392184 -384.301424) (xy 39.423219 -384.361151)
			(xy 39.446892 -384.42416) (xy 39.462864 -384.489546) (xy 39.470906 -384.556373) (xy 39.470902 -384.623682)
			(xy 39.462854 -384.690507) (xy 39.446876 -384.755892) (xy 39.423196 -384.818898) (xy 39.392156 -384.878623)
			(xy 39.354199 -384.934209) (xy 39.332408 -384.95986) (xy 39.326604 -384.967) (xy 39.320094 -384.984195)
			(xy 39.319708 -384.993388) (xy 39.319708 -385.151376) (xy 39.319259 -385.161528) (xy 39.311473 -385.180278)
			(xy 39.297085 -385.194602) (xy 39.278299 -385.202304) (xy 39.268146 -385.202684) (xy 38.551866 -385.202684)
			(xy 38.54174 -385.202202) (xy 38.523023 -385.194468) (xy 38.508668 -385.18018) (xy 38.500846 -385.1615)
			(xy 38.500304 -385.151376) (xy 38.500304 -384.993388) (xy 38.499899 -384.9842) (xy 38.493381 -384.967016)
			(xy 38.487604 -384.95986) (xy 38.465853 -384.934178) (xy 38.427905 -384.878595) (xy 38.396872 -384.818875)
			(xy 38.373199 -384.755875) (xy 38.357224 -384.690497) (xy 38.349178 -384.623678) (xy 38.349175 -384.556376)
			(xy 38.357215 -384.489557) (xy 38.373183 -384.424177) (xy 38.39685 -384.361174) (xy 38.427877 -384.301451)
			(xy 38.465819 -384.245865) (xy 38.487604 -384.220212) (xy 38.493421 -384.213081) (xy 38.499923 -384.19588)
			(xy 38.500304 -384.186684) (xy 38.500304 -383.693416) (xy 38.499885 -383.68423) (xy 38.493377 -383.667045)
			(xy 38.487604 -383.659888) (xy 38.465782 -383.634264) (xy 38.427837 -383.578673) (xy 38.396807 -383.518945)
			(xy 38.373138 -383.455937) (xy 38.357168 -383.390552) (xy 38.349127 -383.323727) (xy 37.247021 -383.323727)
			(xy 37.247149 -383.324068) (xy 37.263185 -383.389559) (xy 37.27126 -383.456499) (xy 37.271259 -383.523925)
			(xy 37.263181 -383.590865) (xy 37.247142 -383.656355) (xy 37.223374 -383.719453) (xy 37.19222 -383.77925)
			(xy 37.154126 -383.834883) (xy 37.13226 -383.860548) (xy 37.126456 -383.867687) (xy 37.119947 -383.884883)
			(xy 37.11956 -383.894076) (xy 37.11956 -384.051556) (xy 37.119147 -384.061681) (xy 37.111406 -384.080391)
			(xy 37.097087 -384.094708) (xy 37.078377 -384.102448) (xy 37.068252 -384.102864) (xy 36.351972 -384.102864)
			(xy 36.341843 -384.102506) (xy 36.323132 -384.094742) (xy 36.308817 -384.080407) (xy 36.30108 -384.061685)
			(xy 36.300664 -384.051556) (xy 36.300664 -383.894076) (xy 36.300251 -383.884889) (xy 36.293738 -383.867706)
			(xy 36.287964 -383.860548) (xy 36.266117 -383.834869) (xy 36.22803 -383.779236) (xy 36.196881 -383.719441)
			(xy 36.173117 -383.656346) (xy 36.157082 -383.590859) (xy 36.149005 -383.523923) (xy 36.149004 -383.456501)
			(xy 36.157078 -383.389565) (xy 36.17311 -383.324077) (xy 36.196871 -383.260981) (xy 36.228018 -383.201185)
			(xy 36.266102 -383.14555) (xy 36.287964 -383.119884) (xy 36.293758 -383.112737) (xy 36.300272 -383.095548)
			(xy 36.300664 -383.086356) (xy 36.300664 -382.59385) (xy 36.300216 -382.584667) (xy 36.293727 -382.567483)
			(xy 36.287964 -382.560322) (xy 36.266091 -382.534664) (xy 36.228005 -382.479028) (xy 36.196857 -382.41923)
			(xy 36.173095 -382.356132) (xy 36.157061 -382.290643) (xy 36.148987 -382.223704) (xy 32.870916 -382.223704)
			(xy 32.86288 -382.290466) (xy 32.846909 -382.355848) (xy 32.823237 -382.418852) (xy 32.792206 -382.478575)
			(xy 32.754259 -382.534162) (xy 32.732472 -382.559814) (xy 32.726683 -382.566965) (xy 32.720165 -382.584151)
			(xy 32.719772 -382.593342) (xy 32.719772 -383.086864) (xy 32.720206 -383.096049) (xy 32.726704 -383.113233)
			(xy 32.732472 -383.120392) (xy 32.754275 -383.146031) (xy 32.792223 -383.20162) (xy 32.823255 -383.261345)
			(xy 32.846714 -383.323786) (xy 33.948808 -383.323786) (xy 33.948811 -383.25636) (xy 33.956891 -383.189419)
			(xy 33.972931 -383.123927) (xy 33.996699 -383.060829) (xy 34.027855 -383.001032) (xy 34.065949 -382.945397)
			(xy 34.087816 -382.919732) (xy 34.093626 -382.912596) (xy 34.100132 -382.895398) (xy 34.100516 -382.886204)
			(xy 34.100516 -382.728724) (xy 34.100936 -382.718601) (xy 34.108679 -382.699895) (xy 34.122995 -382.685579)
			(xy 34.141701 -382.677836) (xy 34.151824 -382.677416) (xy 34.868104 -382.677416) (xy 34.878229 -382.677813)
			(xy 34.896935 -382.685566) (xy 34.91125 -382.699888) (xy 34.918992 -382.718599) (xy 34.919412 -382.728724)
			(xy 34.919412 -382.886204) (xy 34.919818 -382.895392) (xy 34.926334 -382.912576) (xy 34.932112 -382.919732)
			(xy 34.95394 -382.945427) (xy 34.992029 -383.001057) (xy 35.023181 -383.060849) (xy 35.046946 -383.123942)
			(xy 35.062984 -383.189428) (xy 35.071063 -383.256363) (xy 35.071066 -383.323783) (xy 35.062994 -383.390719)
			(xy 35.046962 -383.456206) (xy 35.023203 -383.519301) (xy 34.992057 -383.579096) (xy 34.953973 -383.634731)
			(xy 34.932112 -383.660396) (xy 34.926336 -383.667556) (xy 34.919809 -383.684735) (xy 34.919412 -383.693924)
			(xy 34.919412 -384.186176) (xy 34.919831 -384.195362) (xy 34.926338 -384.212547) (xy 34.932112 -384.219704)
			(xy 34.954011 -384.24534) (xy 34.992098 -384.300979) (xy 35.023246 -384.36078) (xy 35.047008 -384.42388)
			(xy 35.06304 -384.489373) (xy 35.071113 -384.556314) (xy 35.07111 -384.62374) (xy 35.063031 -384.690681)
			(xy 35.046992 -384.756172) (xy 35.023224 -384.81927) (xy 34.99207 -384.879067) (xy 34.953978 -384.934703)
			(xy 34.932112 -384.960368) (xy 34.926305 -384.967506) (xy 34.919796 -384.984702) (xy 34.919412 -384.993896)
			(xy 34.919412 -385.151376) (xy 34.918965 -385.161495) (xy 34.911227 -385.180196) (xy 34.89692 -385.194511)
			(xy 34.878223 -385.202259) (xy 34.868104 -385.202684) (xy 34.151824 -385.202684) (xy 34.141701 -385.202264)
			(xy 34.122995 -385.194521) (xy 34.108679 -385.180205) (xy 34.100936 -385.161499) (xy 34.100516 -385.151376)
			(xy 34.100516 -384.993896) (xy 34.100104 -384.984709) (xy 34.093591 -384.967525) (xy 34.087816 -384.960368)
			(xy 34.065987 -384.934674) (xy 34.027896 -384.879044) (xy 33.996743 -384.819252) (xy 33.972976 -384.756159)
			(xy 33.956937 -384.690673) (xy 33.948858 -384.623738) (xy 33.948855 -384.556316) (xy 33.956928 -384.48938)
			(xy 33.97296 -384.423893) (xy 33.996721 -384.360798) (xy 34.027868 -384.301003) (xy 34.065954 -384.245369)
			(xy 34.087816 -384.219704) (xy 34.093595 -384.212547) (xy 34.10012 -384.195365) (xy 34.100516 -384.186176)
			(xy 34.100516 -383.693924) (xy 34.100091 -383.684739) (xy 34.093587 -383.667554) (xy 34.087816 -383.660396)
			(xy 34.065916 -383.63476) (xy 34.027827 -383.579122) (xy 33.996677 -383.519322) (xy 33.972915 -383.456221)
			(xy 33.956881 -383.390728) (xy 33.948808 -383.323786) (xy 32.846714 -383.323786) (xy 32.846926 -383.324351)
			(xy 32.862898 -383.389735) (xy 32.87094 -383.456559) (xy 32.870939 -383.523865) (xy 32.862893 -383.590689)
			(xy 32.846919 -383.656072) (xy 32.823245 -383.719077) (xy 32.79221 -383.778801) (xy 32.75426 -383.834388)
			(xy 32.732472 -383.86004) (xy 32.726672 -383.867183) (xy 32.72016 -383.884375) (xy 32.719772 -383.893568)
			(xy 32.719772 -384.051556) (xy 32.719342 -384.061711) (xy 32.711555 -384.080468) (xy 32.697161 -384.094793)
			(xy 32.678367 -384.10249) (xy 32.66821 -384.102864) (xy 31.95193 -384.102864) (xy 31.941806 -384.102349)
			(xy 31.923086 -384.094632) (xy 31.908729 -384.080354) (xy 31.900908 -384.061678) (xy 31.900368 -384.051556)
			(xy 31.900368 -383.893568) (xy 31.899958 -383.884381) (xy 31.893443 -383.867197) (xy 31.887668 -383.86004)
			(xy 31.865895 -383.834375) (xy 31.827944 -383.778791) (xy 31.796908 -383.71907) (xy 31.773234 -383.656067)
			(xy 31.757259 -383.590686) (xy 31.749213 -383.523864) (xy 31.749211 -383.45656) (xy 31.757254 -383.389738)
			(xy 31.773226 -383.324356) (xy 31.796899 -383.261352) (xy 31.827932 -383.201629) (xy 31.86588 -383.146044)
			(xy 31.887668 -383.120392) (xy 31.893459 -383.113243) (xy 31.899975 -383.096055) (xy 31.900368 -383.086864)
			(xy 31.900368 -382.593342) (xy 31.899923 -382.584159) (xy 31.893432 -382.566975) (xy 31.887668 -382.559814)
			(xy 31.86587 -382.53417) (xy 31.827919 -382.478583) (xy 31.796885 -382.418859) (xy 31.773211 -382.355853)
			(xy 31.757238 -382.29047) (xy 31.749194 -382.223646) (xy 28.471155 -382.223646) (xy 28.471155 -382.223704)
			(xy 28.463079 -382.290642) (xy 28.447044 -382.356131) (xy 28.42328 -382.419228) (xy 28.392129 -382.479023)
			(xy 28.35404 -382.534657) (xy 28.332176 -382.560322) (xy 28.326385 -382.567471) (xy 28.319868 -382.584659)
			(xy 28.319476 -382.59385) (xy 28.319476 -383.086356) (xy 28.319913 -383.09554) (xy 28.326409 -383.112725)
			(xy 28.332176 -383.119884) (xy 28.354057 -383.145536) (xy 28.392146 -383.201172) (xy 28.423298 -383.26097)
			(xy 28.446934 -383.323727) (xy 29.549039 -383.323727) (xy 29.549043 -383.256419) (xy 29.55709 -383.189594)
			(xy 29.573066 -383.12421) (xy 29.596742 -383.061205) (xy 29.627779 -383.00148) (xy 29.665731 -382.945892)
			(xy 29.68752 -382.92024) (xy 29.693327 -382.913102) (xy 29.699835 -382.895906) (xy 29.70022 -382.886712)
			(xy 29.70022 -382.728724) (xy 29.700641 -382.718569) (xy 29.708433 -382.699813) (xy 29.72283 -382.685488)
			(xy 29.741625 -382.677791) (xy 29.751782 -382.677416) (xy 30.468062 -382.677416) (xy 30.478183 -382.677957)
			(xy 30.496899 -382.685668) (xy 30.511256 -382.699938) (xy 30.51908 -382.718606) (xy 30.519624 -382.728724)
			(xy 30.519624 -382.886712) (xy 30.520023 -382.8959) (xy 30.526544 -382.913085) (xy 30.532324 -382.92024)
			(xy 30.554077 -382.945921) (xy 30.59203 -383.001502) (xy 30.623067 -383.061222) (xy 30.646743 -383.124222)
			(xy 30.66272 -383.189601) (xy 30.670767 -383.256421) (xy 30.67077 -383.323724) (xy 30.662729 -383.390545)
			(xy 30.646759 -383.455926) (xy 30.623089 -383.518929) (xy 30.592058 -383.578651) (xy 30.554111 -383.634236)
			(xy 30.532324 -383.659888) (xy 30.52651 -383.667021) (xy 30.520005 -383.684221) (xy 30.519624 -383.693416)
			(xy 30.519624 -384.186684) (xy 30.520036 -384.195871) (xy 30.526548 -384.213056) (xy 30.532324 -384.220212)
			(xy 30.554149 -384.245834) (xy 30.592099 -384.301424) (xy 30.623132 -384.361152) (xy 30.646805 -384.42416)
			(xy 30.662776 -384.489546) (xy 30.670818 -384.556373) (xy 30.670815 -384.623681) (xy 30.662767 -384.690507)
			(xy 30.646789 -384.755892) (xy 30.62311 -384.818898) (xy 30.592071 -384.878622) (xy 30.554115 -384.934209)
			(xy 30.532324 -384.95986) (xy 30.526522 -384.967002) (xy 30.52001 -384.984195) (xy 30.519624 -384.993388)
			(xy 30.519624 -385.151376) (xy 30.519159 -385.161526) (xy 30.511376 -385.180273) (xy 30.496993 -385.194596)
			(xy 30.478213 -385.202301) (xy 30.468062 -385.202684) (xy 29.751782 -385.202684) (xy 29.741657 -385.202189)
			(xy 29.72294 -385.19446) (xy 29.708585 -385.180177) (xy 29.700762 -385.161498) (xy 29.70022 -385.151376)
			(xy 29.70022 -384.993388) (xy 29.699811 -384.984201) (xy 29.693296 -384.967017) (xy 29.68752 -384.95986)
			(xy 29.665769 -384.934178) (xy 29.62782 -384.878596) (xy 29.596786 -384.818876) (xy 29.573112 -384.755875)
			(xy 29.557137 -384.690497) (xy 29.549091 -384.623678) (xy 29.549087 -384.556376) (xy 29.557128 -384.489556)
			(xy 29.573096 -384.424176) (xy 29.596764 -384.361174) (xy 29.627792 -384.301451) (xy 29.665735 -384.245865)
			(xy 29.68752 -384.220212) (xy 29.693339 -384.213083) (xy 29.69984 -384.19588) (xy 29.70022 -384.186684)
			(xy 29.70022 -383.693416) (xy 29.699797 -383.68423) (xy 29.693292 -383.667046) (xy 29.68752 -383.659888)
			(xy 29.665697 -383.634265) (xy 29.627751 -383.578674) (xy 29.59672 -383.518946) (xy 29.57305 -383.455938)
			(xy 29.55708 -383.390552) (xy 29.549039 -383.323727) (xy 28.446934 -383.323727) (xy 28.447062 -383.324068)
			(xy 28.463097 -383.389559) (xy 28.471172 -383.456499) (xy 28.471171 -383.523925) (xy 28.463093 -383.590865)
			(xy 28.447055 -383.656355) (xy 28.423288 -383.719452) (xy 28.392134 -383.779249) (xy 28.354042 -383.834883)
			(xy 28.332176 -383.860548) (xy 28.326374 -383.867689) (xy 28.319863 -383.884883) (xy 28.319476 -383.894076)
			(xy 28.319476 -384.051556) (xy 28.319047 -384.061679) (xy 28.311309 -384.080386) (xy 28.296996 -384.094702)
			(xy 28.27829 -384.102445) (xy 28.268168 -384.102864) (xy 27.551888 -384.102864) (xy 27.54176 -384.102493)
			(xy 27.523049 -384.094734) (xy 27.508734 -384.080404) (xy 27.500996 -384.061684) (xy 27.50058 -384.051556)
			(xy 27.50058 -383.894076) (xy 27.500186 -383.884887) (xy 27.493661 -383.867703) (xy 27.48788 -383.860548)
			(xy 27.466032 -383.834869) (xy 27.427945 -383.779236) (xy 27.396794 -383.719442) (xy 27.37303 -383.656347)
			(xy 27.356994 -383.59086) (xy 27.348917 -383.523923) (xy 27.348916 -383.456501) (xy 27.35699 -383.389564)
			(xy 27.373023 -383.324076) (xy 27.396784 -383.26098) (xy 27.427932 -383.201184) (xy 27.466018 -383.14555)
			(xy 27.48788 -383.119884) (xy 27.493664 -383.112729) (xy 27.500187 -383.095546) (xy 27.50058 -383.086356)
			(xy 27.50058 -382.59385) (xy 27.50015 -382.584665) (xy 27.49365 -382.56748) (xy 27.48788 -382.560322)
			(xy 27.466007 -382.534665) (xy 27.42792 -382.479028) (xy 27.396771 -382.419231) (xy 27.373008 -382.356133)
			(xy 27.356974 -382.290643) (xy 27.348899 -382.223705) (xy 1.524 -382.223705) (xy 1.524 -385.583938)
			(xy 100.447856 -385.583938) (xy 100.447856 -384.720338) (xy 100.448346 -384.690354) (xy 100.456174 -384.630898)
			(xy 100.471695 -384.572973) (xy 100.494644 -384.517569) (xy 100.524628 -384.465635) (xy 100.561134 -384.418059)
			(xy 100.603539 -384.375654) (xy 100.651115 -384.339148) (xy 100.703049 -384.309164) (xy 100.758453 -384.286215)
			(xy 100.816378 -384.270694) (xy 100.875834 -384.262866) (xy 100.935802 -384.262866) (xy 100.995258 -384.270694)
			(xy 101.053183 -384.286215) (xy 101.108587 -384.309164) (xy 101.160521 -384.339148) (xy 101.208097 -384.375654)
			(xy 101.250502 -384.418059) (xy 101.287008 -384.465635) (xy 101.316992 -384.517569) (xy 101.339941 -384.572973)
			(xy 101.355462 -384.630898) (xy 101.36329 -384.690354) (xy 101.36378 -384.720338) (xy 101.36378 -385.319283)
			(xy 104.635826 -385.319283) (xy 104.635826 -385.259317) (xy 104.643653 -385.199864) (xy 104.659172 -385.141942)
			(xy 104.682119 -385.08654) (xy 104.7121 -385.034608) (xy 104.748603 -384.987032) (xy 104.791004 -384.944628)
			(xy 104.838576 -384.908121) (xy 104.890506 -384.878136) (xy 104.945906 -384.855184) (xy 105.003827 -384.83966)
			(xy 105.063279 -384.831828) (xy 105.093262 -384.831336) (xy 105.956862 -384.831336) (xy 105.986849 -384.831807)
			(xy 106.046311 -384.83963) (xy 106.104243 -384.855149) (xy 106.159653 -384.878097) (xy 106.211594 -384.908081)
			(xy 106.259176 -384.944589) (xy 106.301586 -384.986995) (xy 106.338098 -385.034574) (xy 106.368087 -385.086513)
			(xy 106.391039 -385.141921) (xy 106.406562 -385.199852) (xy 106.414391 -385.259313) (xy 106.414391 -385.319287)
			(xy 106.406562 -385.378748) (xy 106.391039 -385.436679) (xy 106.368087 -385.492087) (xy 106.338098 -385.544026)
			(xy 106.301586 -385.591605) (xy 106.259176 -385.634011) (xy 106.211594 -385.670519) (xy 106.159653 -385.700503)
			(xy 106.104243 -385.723451) (xy 106.046311 -385.73897) (xy 105.986849 -385.746793) (xy 105.956862 -385.74726)
			(xy 105.093262 -385.74726) (xy 105.063279 -385.746772) (xy 105.003827 -385.73894) (xy 104.945906 -385.723416)
			(xy 104.890506 -385.700464) (xy 104.838576 -385.670479) (xy 104.791004 -385.633972) (xy 104.748603 -385.591568)
			(xy 104.7121 -385.543992) (xy 104.682119 -385.49206) (xy 104.659172 -385.436658) (xy 104.643653 -385.378736)
			(xy 104.635826 -385.319283) (xy 101.36378 -385.319283) (xy 101.36378 -385.583938) (xy 101.36329 -385.613922)
			(xy 101.355462 -385.673378) (xy 101.339941 -385.731303) (xy 101.316992 -385.786707) (xy 101.287008 -385.838641)
			(xy 101.250502 -385.886217) (xy 101.208097 -385.928622) (xy 101.160521 -385.965128) (xy 101.108587 -385.995112)
			(xy 101.053183 -386.018061) (xy 100.995258 -386.033582) (xy 100.935802 -386.04141) (xy 100.875834 -386.04141)
			(xy 100.816378 -386.033582) (xy 100.758453 -386.018061) (xy 100.703049 -385.995112) (xy 100.651115 -385.965128)
			(xy 100.603539 -385.928622) (xy 100.561134 -385.886217) (xy 100.524628 -385.838641) (xy 100.494644 -385.786707)
			(xy 100.471695 -385.731303) (xy 100.456174 -385.673378) (xy 100.448346 -385.613922) (xy 100.447856 -385.583938)
			(xy 1.524 -385.583938) (xy 1.524 -387.121908) (xy 1.52439 -387.132027) (xy 1.53214 -387.150718) (xy 1.546542 -387.164931)
			(xy 1.55575 -387.169152) (xy 1.642872 -387.204458) (xy 1.647438 -387.206216) (xy 1.657031 -387.20814)
			(xy 1.661922 -387.208268) (xy 1.698498 -387.192774) (xy 1.72014 -387.171139) (xy 1.768171 -387.133222)
			(xy 1.820826 -387.102041) (xy 1.877165 -387.078154) (xy 1.936184 -387.061985) (xy 1.996831 -387.053823)
			(xy 2.027428 -387.053328) (xy 2.057385 -387.053817) (xy 2.116788 -387.061635) (xy 2.174662 -387.077136)
			(xy 2.230019 -387.100056) (xy 2.281912 -387.130004) (xy 2.329454 -387.166466) (xy 2.371832 -387.20882)
			(xy 2.408322 -387.256341) (xy 2.438299 -387.308217) (xy 2.46125 -387.363561) (xy 2.476785 -387.421427)
			(xy 2.484636 -387.480825) (xy 2.485136 -387.510782) (xy 2.485136 -388.37489) (xy 2.484647 -388.404864)
			(xy 2.476825 -388.464299) (xy 2.461315 -388.522205) (xy 2.438381 -388.577593) (xy 2.408417 -388.629515)
			(xy 2.371935 -388.677083) (xy 2.329557 -388.719484) (xy 2.28201 -388.755994) (xy 2.230105 -388.785987)
			(xy 2.17473 -388.808951) (xy 2.116832 -388.824494) (xy 2.057402 -388.83235) (xy 2.027428 -388.832852)
			(xy 1.996831 -388.832343) (xy 1.936181 -388.824192) (xy 1.877159 -388.80803) (xy 1.820818 -388.784147)
			(xy 1.768161 -388.752969) (xy 1.720129 -388.715051) (xy 1.698498 -388.693406) (xy 1.661922 -388.677912)
			(xy 1.657032 -388.678051) (xy 1.647441 -388.679974) (xy 1.642872 -388.681722) (xy 1.55575 -388.717028)
			(xy 1.546556 -388.721247) (xy 1.53222 -388.735496) (xy 1.524469 -388.754165) (xy 1.524 -388.764272)
			(xy 1.524 -393.100052) (xy 194.140844 -393.100052) (xy 194.144848 -392.894864) (xy 194.156855 -392.689988)
			(xy 194.176846 -392.485737) (xy 194.204791 -392.282422) (xy 194.240647 -392.080351) (xy 194.284361 -391.879833)
			(xy 194.335864 -391.681174) (xy 194.395079 -391.484675) (xy 194.461915 -391.290636) (xy 194.536271 -391.099353)
			(xy 194.618034 -390.911116) (xy 194.707079 -390.726213) (xy 194.80327 -390.544925) (xy 194.906461 -390.367528)
			(xy 195.016495 -390.194291) (xy 195.133204 -390.02548) (xy 195.25641 -389.861351) (xy 195.385927 -389.702154)
			(xy 195.521556 -389.548132) (xy 195.663091 -389.399518) (xy 195.810316 -389.25654) (xy 195.963008 -389.119415)
			(xy 196.120934 -388.988351) (xy 196.283853 -388.863549) (xy 196.451518 -388.745199) (xy 196.623672 -388.63348)
			(xy 196.800054 -388.528563) (xy 196.980395 -388.430608) (xy 197.164421 -388.339764) (xy 197.351851 -388.256168)
			(xy 197.5424 -388.179949) (xy 197.735777 -388.111223) (xy 197.931689 -388.050094) (xy 198.129836 -387.996655)
			(xy 198.329918 -387.950988) (xy 198.531629 -387.913161) (xy 198.734662 -387.883234) (xy 198.938709 -387.861251)
			(xy 199.143458 -387.847246) (xy 199.348597 -387.84124) (xy 199.553814 -387.843242) (xy 199.758797 -387.85325)
			(xy 199.963234 -387.871247) (xy 200.166812 -387.897207) (xy 200.369223 -387.93109) (xy 200.570157 -387.972845)
			(xy 200.76931 -388.022408) (xy 200.966377 -388.079703) (xy 201.161059 -388.144643) (xy 201.353059 -388.217129)
			(xy 201.542084 -388.297052) (xy 201.727847 -388.384288) (xy 201.910065 -388.478706) (xy 202.088461 -388.580161)
			(xy 202.262762 -388.6885) (xy 202.432704 -388.803556) (xy 202.598027 -388.925156) (xy 202.75848 -389.053113)
			(xy 202.913819 -389.187232) (xy 203.063806 -389.327311) (xy 203.208214 -389.473135) (xy 203.346822 -389.624481)
			(xy 203.47942 -389.781121) (xy 203.605806 -389.942815) (xy 203.725786 -390.109317) (xy 203.839179 -390.280373)
			(xy 203.945812 -390.455723) (xy 204.045522 -390.6351) (xy 204.138158 -390.81823) (xy 204.223578 -391.004836)
			(xy 204.301652 -391.194632) (xy 204.372262 -391.38733) (xy 204.435299 -391.582636) (xy 204.490669 -391.780252)
			(xy 204.538286 -391.979879) (xy 204.578078 -392.181211) (xy 204.609985 -392.383943) (xy 204.633958 -392.587765)
			(xy 204.64996 -392.792368) (xy 204.657967 -392.997438) (xy 204.658468 -393.100052) (xy 204.657967 -393.202666)
			(xy 204.64996 -393.407736) (xy 204.633958 -393.612339) (xy 204.609985 -393.816161) (xy 204.578078 -394.018893)
			(xy 204.538286 -394.220225) (xy 204.490669 -394.419852) (xy 204.435299 -394.617468) (xy 204.372262 -394.812774)
			(xy 204.301652 -395.005472) (xy 204.223578 -395.195268) (xy 204.138158 -395.381874) (xy 204.045522 -395.565004)
			(xy 203.945812 -395.744381) (xy 203.839179 -395.919731) (xy 203.725786 -396.090787) (xy 203.605806 -396.257289)
			(xy 203.47942 -396.418983) (xy 203.346822 -396.575623) (xy 203.208214 -396.726969) (xy 203.063806 -396.872793)
			(xy 202.913819 -397.012872) (xy 202.75848 -397.146991) (xy 202.598027 -397.274948) (xy 202.432704 -397.396548)
			(xy 202.262762 -397.511604) (xy 202.088461 -397.619943) (xy 201.910065 -397.721398) (xy 201.727847 -397.815816)
			(xy 201.542084 -397.903052) (xy 201.353059 -397.982975) (xy 201.161059 -398.055461) (xy 200.966377 -398.120401)
			(xy 200.76931 -398.177696) (xy 200.570157 -398.227259) (xy 200.369223 -398.269014) (xy 200.166812 -398.302897)
			(xy 199.963234 -398.328857) (xy 199.758797 -398.346854) (xy 199.553814 -398.356862) (xy 199.348597 -398.358864)
			(xy 199.143458 -398.352858) (xy 198.938709 -398.338853) (xy 198.734662 -398.31687) (xy 198.531629 -398.286943)
			(xy 198.329918 -398.249116) (xy 198.129836 -398.203449) (xy 197.931689 -398.15001) (xy 197.735777 -398.088881)
			(xy 197.5424 -398.020155) (xy 197.351851 -397.943936) (xy 197.164421 -397.86034) (xy 196.980395 -397.769496)
			(xy 196.800054 -397.671541) (xy 196.623672 -397.566624) (xy 196.451518 -397.454905) (xy 196.283853 -397.336555)
			(xy 196.120934 -397.211753) (xy 195.963008 -397.080689) (xy 195.810316 -396.943564) (xy 195.663091 -396.800586)
			(xy 195.521556 -396.651972) (xy 195.385927 -396.49795) (xy 195.25641 -396.338753) (xy 195.133204 -396.174624)
			(xy 195.016495 -396.005813) (xy 194.906461 -395.832576) (xy 194.80327 -395.655179) (xy 194.707079 -395.473891)
			(xy 194.618034 -395.288988) (xy 194.536271 -395.100751) (xy 194.461915 -394.909468) (xy 194.395079 -394.715429)
			(xy 194.335864 -394.51893) (xy 194.284361 -394.320271) (xy 194.240647 -394.119753) (xy 194.204791 -393.917682)
			(xy 194.176846 -393.714367) (xy 194.156855 -393.510116) (xy 194.144848 -393.30524) (xy 194.140844 -393.100052)
			(xy 1.524 -393.100052) (xy 1.524 -398.100042) (xy 2.59945 -398.100042) (xy 2.603399 -397.95679) (xy 2.615233 -397.813972)
			(xy 2.634917 -397.672024) (xy 2.66239 -397.531375) (xy 2.69757 -397.392454) (xy 2.740349 -397.255681)
			(xy 2.790598 -397.121473) (xy 2.848163 -396.990236) (xy 2.912871 -396.86237) (xy 2.984524 -396.738263)
			(xy 3.062906 -396.618291) (xy 3.147777 -396.50282) (xy 3.238881 -396.392199) (xy 3.33594 -396.286765)
			(xy 3.438659 -396.186838) (xy 3.546728 -396.092721) (xy 3.659817 -396.0047) (xy 3.777583 -395.923042)
			(xy 3.899669 -395.847997) (xy 4.025703 -395.77979) (xy 4.155304 -395.71863) (xy 4.288077 -395.664703)
			(xy 4.423619 -395.618171) (xy 4.561518 -395.579177) (xy 4.701356 -395.547838) (xy 4.842709 -395.524251)
			(xy 4.985146 -395.508486) (xy 5.128235 -395.500591) (xy 5.199888 -395.500098) (xy 6.800088 -395.500098)
			(xy 6.871742 -395.500579) (xy 7.014831 -395.508473) (xy 7.157269 -395.524238) (xy 7.298622 -395.547826)
			(xy 7.438461 -395.579164) (xy 7.576361 -395.618158) (xy 7.711903 -395.66469) (xy 7.844677 -395.718618)
			(xy 7.974278 -395.779778) (xy 8.100313 -395.847985) (xy 8.222399 -395.923031) (xy 8.340166 -396.004689)
			(xy 8.453256 -396.09271) (xy 8.561325 -396.186827) (xy 8.664045 -396.286755) (xy 8.761105 -396.392189)
			(xy 8.852209 -396.502811) (xy 8.93708 -396.618283) (xy 9.015462 -396.738255) (xy 9.087116 -396.862363)
			(xy 9.151824 -396.990229) (xy 9.20939 -397.121466) (xy 9.259639 -397.255675) (xy 9.302418 -397.392449)
			(xy 9.337598 -397.531371) (xy 9.365072 -397.67202) (xy 9.384756 -397.813969) (xy 9.385578 -397.823885)
			(xy 27.348879 -397.823885) (xy 27.348883 -397.756458) (xy 27.356962 -397.689518) (xy 27.373001 -397.624027)
			(xy 27.396769 -397.560929) (xy 27.427923 -397.501131) (xy 27.466014 -397.445496) (xy 27.48788 -397.41983)
			(xy 27.493686 -397.412692) (xy 27.500196 -397.395496) (xy 27.50058 -397.386302) (xy 27.50058 -396.89405)
			(xy 27.50015 -396.884865) (xy 27.49365 -396.86768) (xy 27.48788 -396.860522) (xy 27.466007 -396.834865)
			(xy 27.42792 -396.779228) (xy 27.396771 -396.719431) (xy 27.373008 -396.656333) (xy 27.356974 -396.590843)
			(xy 27.348899 -396.523905) (xy 27.3489 -396.45648) (xy 27.356976 -396.389542) (xy 27.373012 -396.324053)
			(xy 27.396777 -396.260955) (xy 27.427928 -396.201159) (xy 27.466016 -396.145524) (xy 27.48788 -396.119858)
			(xy 27.493675 -396.112711) (xy 27.500191 -396.095522) (xy 27.50058 -396.08633) (xy 27.50058 -395.92885)
			(xy 27.501069 -395.918722) (xy 27.508787 -395.899994) (xy 27.523074 -395.885635) (xy 27.541762 -395.877821)
			(xy 27.551888 -395.877288) (xy 28.268168 -395.877288) (xy 28.278319 -395.877747) (xy 28.297068 -395.88553)
			(xy 28.311392 -395.899915) (xy 28.319095 -395.918698) (xy 28.319476 -395.92885) (xy 28.319476 -396.08633)
			(xy 28.319877 -396.095518) (xy 28.326398 -396.112702) (xy 28.332176 -396.119858) (xy 28.354031 -396.145531)
			(xy 28.392122 -396.201164) (xy 28.423274 -396.260959) (xy 28.44704 -396.324055) (xy 28.463077 -396.389543)
			(xy 28.471154 -396.456481) (xy 28.471155 -396.523904) (xy 28.463079 -396.590842) (xy 28.447044 -396.656331)
			(xy 28.42328 -396.719428) (xy 28.392129 -396.779223) (xy 28.35404 -396.834857) (xy 28.332176 -396.860522)
			(xy 28.326385 -396.867671) (xy 28.319868 -396.884859) (xy 28.319476 -396.89405) (xy 28.319476 -397.386302)
			(xy 28.31989 -397.395489) (xy 28.326402 -397.412673) (xy 28.332176 -397.41983) (xy 28.354003 -397.445526)
			(xy 28.392095 -397.501155) (xy 28.420857 -397.556356) (xy 29.549071 -397.556356) (xy 29.557114 -397.489534)
			(xy 29.573085 -397.424153) (xy 29.596756 -397.361149) (xy 29.627787 -397.301425) (xy 29.665733 -397.245838)
			(xy 29.68752 -397.220186) (xy 29.693307 -397.213034) (xy 29.699827 -397.195849) (xy 29.70022 -397.186658)
			(xy 29.70022 -397.028924) (xy 29.700641 -397.018769) (xy 29.708433 -397.000013) (xy 29.72283 -396.985688)
			(xy 29.741625 -396.977991) (xy 29.751782 -396.977616) (xy 30.468062 -396.977616) (xy 30.478183 -396.978157)
			(xy 30.496899 -396.985868) (xy 30.511256 -397.000138) (xy 30.51908 -397.018806) (xy 30.519624 -397.028924)
			(xy 30.519624 -397.186658) (xy 30.520049 -397.195844) (xy 30.526552 -397.213029) (xy 30.532324 -397.220186)
			(xy 30.554123 -397.24583) (xy 30.592074 -397.301416) (xy 30.623108 -397.361141) (xy 30.646782 -397.424147)
			(xy 30.662756 -397.48953) (xy 30.6708 -397.556354) (xy 30.670799 -397.623661) (xy 30.662753 -397.690485)
			(xy 30.646778 -397.755868) (xy 30.623102 -397.818873) (xy 30.620528 -397.823826) (xy 31.749174 -397.823826)
			(xy 31.749178 -397.756517) (xy 31.757226 -397.689691) (xy 31.773204 -397.624307) (xy 31.796882 -397.5613)
			(xy 31.827922 -397.501576) (xy 31.865877 -397.44599) (xy 31.887668 -397.420338) (xy 31.893482 -397.413205)
			(xy 31.899984 -397.396005) (xy 31.900368 -397.38681) (xy 31.900368 -396.893542) (xy 31.899923 -396.884359)
			(xy 31.893432 -396.867175) (xy 31.887668 -396.860014) (xy 31.86587 -396.83437) (xy 31.827919 -396.778783)
			(xy 31.796885 -396.719059) (xy 31.773211 -396.656053) (xy 31.757238 -396.59067) (xy 31.749194 -396.523846)
			(xy 31.749195 -396.456539) (xy 31.757241 -396.389716) (xy 31.773216 -396.324332) (xy 31.796891 -396.261327)
			(xy 31.827927 -396.201604) (xy 31.865879 -396.146018) (xy 31.887668 -396.120366) (xy 31.89347 -396.113225)
			(xy 31.899979 -396.096031) (xy 31.900368 -396.086838) (xy 31.900368 -395.92885) (xy 31.900805 -395.918678)
			(xy 31.90858 -395.899879) (xy 31.922962 -395.885491) (xy 31.941758 -395.877709) (xy 31.95193 -395.877288)
			(xy 32.66821 -395.877288) (xy 32.678388 -395.877657) (xy 32.697193 -395.885455) (xy 32.711579 -395.899858)
			(xy 32.719355 -395.918671) (xy 32.719772 -395.92885) (xy 32.719772 -396.086838) (xy 32.72017 -396.096026)
			(xy 32.726693 -396.11321) (xy 32.732472 -396.120366) (xy 32.75425 -396.146026) (xy 32.792198 -396.201612)
			(xy 32.823231 -396.261334) (xy 32.846904 -396.324338) (xy 32.862877 -396.389719) (xy 32.870922 -396.45654)
			(xy 32.870923 -396.523845) (xy 32.86288 -396.590666) (xy 32.846909 -396.656048) (xy 32.823237 -396.719052)
			(xy 32.792206 -396.778775) (xy 32.754259 -396.834362) (xy 32.732472 -396.860014) (xy 32.726683 -396.867165)
			(xy 32.720165 -396.884351) (xy 32.719772 -396.893542) (xy 32.719772 -397.38681) (xy 32.720183 -397.395997)
			(xy 32.726697 -397.413181) (xy 32.732472 -397.420338) (xy 32.754222 -397.446021) (xy 32.792171 -397.501603)
			(xy 32.820593 -397.556296) (xy 33.948839 -397.556296) (xy 33.956914 -397.489358) (xy 33.972949 -397.423869)
			(xy 33.996713 -397.360773) (xy 34.027863 -397.300977) (xy 34.065952 -397.245343) (xy 34.087816 -397.219678)
			(xy 34.093606 -397.212528) (xy 34.100124 -397.195341) (xy 34.100516 -397.18615) (xy 34.100516 -397.028924)
			(xy 34.100936 -397.018801) (xy 34.108679 -397.000095) (xy 34.122995 -396.985779) (xy 34.141701 -396.978036)
			(xy 34.151824 -396.977616) (xy 34.868104 -396.977616) (xy 34.878229 -396.978013) (xy 34.896935 -396.985766)
			(xy 34.91125 -397.000088) (xy 34.918992 -397.018799) (xy 34.919412 -397.028924) (xy 34.919412 -397.18615)
			(xy 34.919843 -397.195335) (xy 34.926342 -397.21252) (xy 34.932112 -397.219678) (xy 34.953985 -397.245335)
			(xy 34.992073 -397.300971) (xy 35.023223 -397.360769) (xy 35.046986 -397.423867) (xy 35.06302 -397.489356)
			(xy 35.071095 -397.556295) (xy 35.071094 -397.62372) (xy 35.063017 -397.690658) (xy 35.046981 -397.756148)
			(xy 35.023216 -397.819245) (xy 35.020799 -397.823884) (xy 36.148967 -397.823884) (xy 36.148971 -397.756458)
			(xy 36.15705 -397.689518) (xy 36.173088 -397.624028) (xy 36.196855 -397.560929) (xy 36.228008 -397.501132)
			(xy 36.266099 -397.445496) (xy 36.287964 -397.41983) (xy 36.293781 -397.412699) (xy 36.300282 -397.395497)
			(xy 36.300664 -397.386302) (xy 36.300664 -396.89405) (xy 36.300216 -396.884867) (xy 36.293727 -396.867683)
			(xy 36.287964 -396.860522) (xy 36.266091 -396.834864) (xy 36.228005 -396.779228) (xy 36.196857 -396.71943)
			(xy 36.173095 -396.656332) (xy 36.157061 -396.590843) (xy 36.148987 -396.523904) (xy 36.148988 -396.456481)
			(xy 36.157064 -396.389542) (xy 36.1731 -396.324053) (xy 36.196863 -396.260956) (xy 36.228013 -396.201159)
			(xy 36.266101 -396.145524) (xy 36.287964 -396.119858) (xy 36.293769 -396.112719) (xy 36.300277 -396.095523)
			(xy 36.300664 -396.08633) (xy 36.300664 -395.92885) (xy 36.301168 -395.918724) (xy 36.308884 -395.899999)
			(xy 36.323166 -395.88564) (xy 36.341848 -395.877823) (xy 36.351972 -395.877288) (xy 37.068252 -395.877288)
			(xy 37.078402 -395.877761) (xy 37.097151 -395.885538) (xy 37.111475 -395.899919) (xy 37.119179 -395.918699)
			(xy 37.11956 -395.92885) (xy 37.11956 -396.08633) (xy 37.119965 -396.095518) (xy 37.126483 -396.112701)
			(xy 37.13226 -396.119858) (xy 37.154116 -396.145531) (xy 37.192207 -396.201163) (xy 37.223361 -396.260958)
			(xy 37.247127 -396.324054) (xy 37.263164 -396.389543) (xy 37.271242 -396.456481) (xy 37.271243 -396.523904)
			(xy 37.263167 -396.590843) (xy 37.247132 -396.656332) (xy 37.223367 -396.719428) (xy 37.192215 -396.779224)
			(xy 37.154125 -396.834857) (xy 37.13226 -396.860522) (xy 37.126467 -396.867669) (xy 37.119951 -396.884858)
			(xy 37.11956 -396.89405) (xy 37.11956 -397.386302) (xy 37.119978 -397.395488) (xy 37.126487 -397.412672)
			(xy 37.13226 -397.41983) (xy 37.154088 -397.445525) (xy 37.192181 -397.501155) (xy 37.220943 -397.556356)
			(xy 38.349159 -397.556356) (xy 38.357201 -397.489534) (xy 38.373172 -397.424153) (xy 38.396842 -397.361149)
			(xy 38.427873 -397.301426) (xy 38.465818 -397.245839) (xy 38.487604 -397.220186) (xy 38.493389 -397.213033)
			(xy 38.499911 -397.195848) (xy 38.500304 -397.186658) (xy 38.500304 -397.028924) (xy 38.500741 -397.018771)
			(xy 38.50853 -397.000018) (xy 38.522922 -396.985694) (xy 38.541711 -396.977994) (xy 38.551866 -396.977616)
			(xy 39.268146 -396.977616) (xy 39.278273 -396.978088) (xy 39.29699 -396.985827) (xy 39.311344 -397.000117)
			(xy 39.319166 -397.0188) (xy 39.319708 -397.028924) (xy 39.319708 -397.186658) (xy 39.320136 -397.195843)
			(xy 39.326637 -397.213028) (xy 39.332408 -397.220186) (xy 39.354207 -397.245829) (xy 39.392159 -397.301416)
			(xy 39.423195 -397.36114) (xy 39.446869 -397.424146) (xy 39.462843 -397.48953) (xy 39.470887 -397.556354)
			(xy 39.470887 -397.623661) (xy 39.462841 -397.690485) (xy 39.446865 -397.755869) (xy 39.423189 -397.818874)
			(xy 39.420585 -397.823885) (xy 40.548734 -397.823885) (xy 40.548737 -397.756458) (xy 40.556817 -397.689516)
			(xy 40.572859 -397.624024) (xy 40.596629 -397.560925) (xy 40.627787 -397.501128) (xy 40.665884 -397.445494)
			(xy 40.687752 -397.41983) (xy 40.693567 -397.412698) (xy 40.700069 -397.395497) (xy 40.700452 -397.386302)
			(xy 40.700452 -396.89405) (xy 40.700006 -396.884867) (xy 40.693516 -396.867683) (xy 40.687752 -396.860522)
			(xy 40.665876 -396.834866) (xy 40.627785 -396.779231) (xy 40.596631 -396.719434) (xy 40.572865 -396.656336)
			(xy 40.556829 -396.590845) (xy 40.548753 -396.523905) (xy 40.548754 -396.45648) (xy 40.556832 -396.38954)
			(xy 40.57287 -396.32405) (xy 40.596638 -396.260952) (xy 40.627792 -396.201156) (xy 40.665886 -396.145522)
			(xy 40.687752 -396.119858) (xy 40.693555 -396.112718) (xy 40.700065 -396.095523) (xy 40.700452 -396.08633)
			(xy 40.700452 -395.92885) (xy 40.700968 -395.918725) (xy 40.708682 -395.900003) (xy 40.722959 -395.885644)
			(xy 40.741638 -395.877825) (xy 40.75176 -395.877288) (xy 41.46804 -395.877288) (xy 41.478195 -395.877689)
			(xy 41.496946 -395.885495) (xy 41.511268 -395.899898) (xy 41.518968 -395.918693) (xy 41.519348 -395.92885)
			(xy 41.519348 -396.08633) (xy 41.519755 -396.095517) (xy 41.526272 -396.112701) (xy 41.532048 -396.119858)
			(xy 41.553904 -396.14553) (xy 41.591996 -396.201163) (xy 41.62315 -396.260957) (xy 41.646917 -396.324053)
			(xy 41.662955 -396.389542) (xy 41.671033 -396.456481) (xy 41.671034 -396.523904) (xy 41.662958 -396.590843)
			(xy 41.646922 -396.656332) (xy 41.623157 -396.719429) (xy 41.592004 -396.779224) (xy 41.553913 -396.834858)
			(xy 41.532048 -396.860522) (xy 41.526253 -396.867668) (xy 41.519739 -396.884858) (xy 41.519348 -396.89405)
			(xy 41.519348 -397.386302) (xy 41.519769 -397.395488) (xy 41.526276 -397.412672) (xy 41.532048 -397.41983)
			(xy 41.553876 -397.445525) (xy 41.59197 -397.501154) (xy 41.620702 -397.556296) (xy 42.748927 -397.556296)
			(xy 42.757002 -397.489358) (xy 42.773037 -397.42387) (xy 42.7968 -397.360774) (xy 42.827949 -397.300978)
			(xy 42.866037 -397.245343) (xy 42.8879 -397.219678) (xy 42.893688 -397.212527) (xy 42.900208 -397.195341)
			(xy 42.9006 -397.18615) (xy 42.9006 -397.028924) (xy 42.901035 -397.018803) (xy 42.908776 -397.0001)
			(xy 42.923086 -396.985785) (xy 42.941787 -396.978039) (xy 42.951908 -396.977616) (xy 43.668188 -396.977616)
			(xy 43.678312 -396.978026) (xy 43.697018 -396.985773) (xy 43.711333 -397.000092) (xy 43.719076 -397.0188)
			(xy 43.719496 -397.028924) (xy 43.719496 -397.18615) (xy 43.719931 -397.195335) (xy 43.726427 -397.212519)
			(xy 43.732196 -397.219678) (xy 43.75407 -397.245335) (xy 43.792159 -397.300971) (xy 43.823309 -397.360768)
			(xy 43.847073 -397.423866) (xy 43.863108 -397.489356) (xy 43.871183 -397.556295) (xy 43.871182 -397.62372)
			(xy 43.863105 -397.690659) (xy 43.847068 -397.756148) (xy 43.823303 -397.819246) (xy 43.820917 -397.823825)
			(xy 44.949053 -397.823825) (xy 44.949057 -397.756517) (xy 44.957105 -397.689692) (xy 44.973082 -397.624308)
			(xy 44.996759 -397.561302) (xy 45.027796 -397.501577) (xy 45.06575 -397.44599) (xy 45.08754 -397.420338)
			(xy 45.09335 -397.413203) (xy 45.099856 -397.396004) (xy 45.10024 -397.38681) (xy 45.10024 -396.893542)
			(xy 45.0998 -396.884358) (xy 45.093306 -396.867174) (xy 45.08754 -396.860014) (xy 45.065742 -396.83437)
			(xy 45.027794 -396.778782) (xy 44.996761 -396.719058) (xy 44.973088 -396.656052) (xy 44.957116 -396.590669)
			(xy 44.949073 -396.523845) (xy 44.949074 -396.45654) (xy 44.957119 -396.389716) (xy 44.973093 -396.324333)
			(xy 44.996767 -396.261328) (xy 45.027801 -396.201605) (xy 45.065751 -396.146018) (xy 45.08754 -396.120366)
			(xy 45.093339 -396.113222) (xy 45.099851 -396.096031) (xy 45.10024 -396.086838) (xy 45.10024 -395.92885)
			(xy 45.100705 -395.918681) (xy 45.108474 -395.899887) (xy 45.122847 -395.885501) (xy 45.141634 -395.877714)
			(xy 45.151802 -395.877288) (xy 45.868082 -395.877288) (xy 45.878259 -395.87768) (xy 45.897063 -395.885468)
			(xy 45.91145 -395.899864) (xy 45.919227 -395.918673) (xy 45.919644 -395.92885) (xy 45.919644 -396.086838)
			(xy 45.920049 -396.096026) (xy 45.926568 -396.113209) (xy 45.932344 -396.120366) (xy 45.954122 -396.146026)
			(xy 45.992072 -396.201611) (xy 46.023107 -396.261333) (xy 46.046781 -396.324337) (xy 46.062755 -396.389718)
			(xy 46.070801 -396.45654) (xy 46.070801 -396.523845) (xy 46.062758 -396.590667) (xy 46.046786 -396.656049)
			(xy 46.023113 -396.719053) (xy 45.99208 -396.778776) (xy 45.954131 -396.834362) (xy 45.932344 -396.860014)
			(xy 45.926552 -396.867162) (xy 45.920036 -396.884351) (xy 45.919644 -396.893542) (xy 45.919644 -397.38681)
			(xy 45.920062 -397.395996) (xy 45.926572 -397.41318) (xy 45.932344 -397.420338) (xy 45.954095 -397.446021)
			(xy 45.992046 -397.501602) (xy 46.020501 -397.556355) (xy 47.149223 -397.556355) (xy 47.157267 -397.489532)
			(xy 47.17324 -397.42415) (xy 47.196914 -397.361146) (xy 47.227949 -397.301423) (xy 47.265899 -397.245837)
			(xy 47.287688 -397.220186) (xy 47.293472 -397.213032) (xy 47.299994 -397.195848) (xy 47.300388 -397.186658)
			(xy 47.300388 -397.028924) (xy 47.300841 -397.018773) (xy 47.308626 -397.000023) (xy 47.323013 -396.985699)
			(xy 47.341797 -396.977997) (xy 47.35195 -396.977616) (xy 48.06823 -396.977616) (xy 48.078356 -396.978101)
			(xy 48.097073 -396.985834) (xy 48.111427 -397.000121) (xy 48.11925 -397.018801) (xy 48.119792 -397.028924)
			(xy 48.119792 -397.186658) (xy 48.120224 -397.195843) (xy 48.126723 -397.213027) (xy 48.132492 -397.220186)
			(xy 48.154289 -397.24583) (xy 48.192235 -397.301419) (xy 48.223266 -397.361144) (xy 48.246937 -397.424149)
			(xy 48.262908 -397.489532) (xy 48.270951 -397.556355) (xy 48.27095 -397.62366) (xy 48.262906 -397.690483)
			(xy 48.246933 -397.755865) (xy 48.22326 -397.81887) (xy 48.192227 -397.878594) (xy 48.154279 -397.934181)
			(xy 48.132492 -397.959834) (xy 48.126698 -397.966981) (xy 48.120182 -397.98417) (xy 48.119792 -397.993362)
			(xy 48.119792 -398.486884) (xy 48.120212 -398.49607) (xy 48.126719 -398.513254) (xy 48.132492 -398.520412)
			(xy 48.154314 -398.546035) (xy 48.19226 -398.601627) (xy 48.22329 -398.661355) (xy 48.246959 -398.724363)
			(xy 48.262929 -398.789748) (xy 48.27097 -398.856573) (xy 48.270966 -398.923881) (xy 48.262919 -398.990705)
			(xy 48.246943 -399.056089) (xy 48.223268 -399.119095) (xy 48.192232 -399.17882) (xy 48.154281 -399.234407)
			(xy 48.132492 -399.26006) (xy 48.126687 -399.267199) (xy 48.120177 -399.284394) (xy 48.119792 -399.293588)
			(xy 48.119792 -399.451576) (xy 48.119359 -399.46173) (xy 48.11157 -399.480483) (xy 48.097176 -399.494808)
			(xy 48.078386 -399.502507) (xy 48.06823 -399.502884) (xy 47.35195 -399.502884) (xy 47.341829 -399.502333)
			(xy 47.323114 -399.494626) (xy 47.308757 -399.48036) (xy 47.300932 -399.461693) (xy 47.300388 -399.451576)
			(xy 47.300388 -399.293588) (xy 47.299986 -399.2844) (xy 47.293467 -399.267216) (xy 47.287688 -399.26006)
			(xy 47.265934 -399.234379) (xy 47.227981 -399.178798) (xy 47.196944 -399.119079) (xy 47.173267 -399.056078)
			(xy 47.15729 -398.990699) (xy 47.149242 -398.923879) (xy 47.149239 -398.856576) (xy 47.15728 -398.789754)
			(xy 47.173251 -398.724374) (xy 47.196921 -398.661371) (xy 47.227953 -398.601648) (xy 47.265901 -398.546063)
			(xy 47.287688 -398.520412) (xy 47.293503 -398.51328) (xy 47.300007 -398.496079) (xy 47.300388 -398.486884)
			(xy 47.300388 -397.993362) (xy 47.299999 -397.984172) (xy 47.293471 -397.966988) (xy 47.287688 -397.959834)
			(xy 47.265909 -397.934174) (xy 47.227956 -397.87859) (xy 47.19692 -397.818868) (xy 47.173244 -397.755864)
			(xy 47.157269 -397.690483) (xy 47.149224 -397.62366) (xy 47.149223 -397.556355) (xy 46.020501 -397.556355)
			(xy 46.023082 -397.561322) (xy 46.046757 -397.624322) (xy 46.062733 -397.689701) (xy 46.070781 -397.75652)
			(xy 46.070784 -397.823823) (xy 46.062744 -397.890643) (xy 46.046774 -397.956023) (xy 46.023105 -398.019026)
			(xy 45.992075 -398.078748) (xy 45.95413 -398.134334) (xy 45.932344 -398.159986) (xy 45.926522 -398.167113)
			(xy 45.920024 -398.184318) (xy 45.919644 -398.193514) (xy 45.919644 -398.351502) (xy 45.919237 -398.361676)
			(xy 45.911448 -398.380474) (xy 45.897057 -398.39486) (xy 45.878256 -398.402641) (xy 45.868082 -398.403064)
			(xy 45.151802 -398.403064) (xy 45.141645 -398.402565) (xy 45.122876 -398.394792) (xy 45.108511 -398.380427)
			(xy 45.100736 -398.361659) (xy 45.10024 -398.351502) (xy 45.10024 -398.193514) (xy 45.099814 -398.184329)
			(xy 45.093311 -398.167145) (xy 45.08754 -398.159986) (xy 45.065715 -398.134365) (xy 45.027767 -398.078774)
			(xy 44.996735 -398.019046) (xy 44.973065 -397.956037) (xy 44.957094 -397.890651) (xy 44.949053 -397.823825)
			(xy 43.820917 -397.823825) (xy 43.792151 -397.879042) (xy 43.754061 -397.934677) (xy 43.732196 -397.960342)
			(xy 43.726399 -397.967487) (xy 43.719885 -397.984678) (xy 43.719496 -397.99387) (xy 43.719496 -398.486376)
			(xy 43.719919 -398.495562) (xy 43.726424 -398.512746) (xy 43.732196 -398.519904) (xy 43.754095 -398.54554)
			(xy 43.792183 -398.601179) (xy 43.823333 -398.660979) (xy 43.847095 -398.72408) (xy 43.863128 -398.789572)
			(xy 43.871201 -398.856514) (xy 43.871198 -398.92394) (xy 43.863118 -398.990881) (xy 43.847079 -399.056372)
			(xy 43.823311 -399.119471) (xy 43.792156 -399.179268) (xy 43.754062 -399.234903) (xy 43.732196 -399.260568)
			(xy 43.726388 -399.267705) (xy 43.71988 -399.284902) (xy 43.719496 -399.294096) (xy 43.719496 -399.451576)
			(xy 43.719064 -399.461697) (xy 43.711323 -399.480401) (xy 43.697011 -399.494717) (xy 43.678309 -399.502462)
			(xy 43.668188 -399.502884) (xy 42.951908 -399.502884) (xy 42.941784 -399.502477) (xy 42.923078 -399.494729)
			(xy 42.908762 -399.480409) (xy 42.90102 -399.4617) (xy 42.9006 -399.451576) (xy 42.9006 -399.294096)
			(xy 42.900192 -399.284909) (xy 42.893677 -399.267724) (xy 42.8879 -399.260568) (xy 42.866071 -399.234874)
			(xy 42.827982 -399.179243) (xy 42.796829 -399.119451) (xy 42.773063 -399.056358) (xy 42.757025 -398.990872)
			(xy 42.748946 -398.923937) (xy 42.748943 -398.856517) (xy 42.757015 -398.789581) (xy 42.773047 -398.724094)
			(xy 42.796807 -398.660998) (xy 42.827954 -398.601203) (xy 42.866038 -398.545569) (xy 42.8879 -398.519904)
			(xy 42.893677 -398.512745) (xy 42.900204 -398.495565) (xy 42.9006 -398.486376) (xy 42.9006 -397.99387)
			(xy 42.900204 -397.984681) (xy 42.893681 -397.967497) (xy 42.8879 -397.960342) (xy 42.866046 -397.934669)
			(xy 42.827957 -397.879035) (xy 42.796806 -397.81924) (xy 42.773041 -397.756144) (xy 42.757005 -397.690656)
			(xy 42.748928 -397.623719) (xy 42.748927 -397.556296) (xy 41.620702 -397.556296) (xy 41.623125 -397.560946)
			(xy 41.646894 -397.624039) (xy 41.662933 -397.689525) (xy 41.671013 -397.756461) (xy 41.671016 -397.823882)
			(xy 41.662944 -397.890819) (xy 41.646911 -397.956307) (xy 41.623148 -398.019402) (xy 41.591999 -398.079197)
			(xy 41.553912 -398.13483) (xy 41.532048 -398.160494) (xy 41.526265 -398.167649) (xy 41.519744 -398.184832)
			(xy 41.519348 -398.194022) (xy 41.519348 -398.351502) (xy 41.518875 -398.36163) (xy 41.511144 -398.380354)
			(xy 41.496853 -398.39471) (xy 41.478166 -398.402527) (xy 41.46804 -398.403064) (xy 40.75176 -398.403064)
			(xy 40.741599 -398.40271) (xy 40.722839 -398.394895) (xy 40.708515 -398.380477) (xy 40.700824 -398.361666)
			(xy 40.700452 -398.351502) (xy 40.700452 -398.194022) (xy 40.70002 -398.184837) (xy 40.69352 -398.167653)
			(xy 40.687752 -398.160494) (xy 40.665849 -398.13486) (xy 40.627758 -398.079223) (xy 40.596606 -398.019423)
			(xy 40.572842 -397.956321) (xy 40.556807 -397.890828) (xy 40.548734 -397.823885) (xy 39.420585 -397.823885)
			(xy 39.392151 -397.878597) (xy 39.354198 -397.934183) (xy 39.332408 -397.959834) (xy 39.326615 -397.966982)
			(xy 39.320098 -397.98417) (xy 39.319708 -397.993362) (xy 39.319708 -398.486884) (xy 39.320124 -398.496071)
			(xy 39.326633 -398.513255) (xy 39.332408 -398.520412) (xy 39.354233 -398.546034) (xy 39.392184 -398.601624)
			(xy 39.423219 -398.661351) (xy 39.446892 -398.72436) (xy 39.462864 -398.789746) (xy 39.470906 -398.856573)
			(xy 39.470902 -398.923882) (xy 39.462854 -398.990707) (xy 39.446876 -399.056092) (xy 39.423196 -399.119098)
			(xy 39.392156 -399.178823) (xy 39.354199 -399.234409) (xy 39.332408 -399.26006) (xy 39.326604 -399.2672)
			(xy 39.320094 -399.284395) (xy 39.319708 -399.293588) (xy 39.319708 -399.451576) (xy 39.319259 -399.461728)
			(xy 39.311473 -399.480478) (xy 39.297085 -399.494802) (xy 39.278299 -399.502504) (xy 39.268146 -399.502884)
			(xy 38.551866 -399.502884) (xy 38.54174 -399.502402) (xy 38.523023 -399.494668) (xy 38.508668 -399.48038)
			(xy 38.500846 -399.4617) (xy 38.500304 -399.451576) (xy 38.500304 -399.293588) (xy 38.499899 -399.2844)
			(xy 38.493381 -399.267216) (xy 38.487604 -399.26006) (xy 38.465853 -399.234378) (xy 38.427905 -399.178795)
			(xy 38.396872 -399.119075) (xy 38.373199 -399.056075) (xy 38.357224 -398.990697) (xy 38.349178 -398.923878)
			(xy 38.349175 -398.856576) (xy 38.357215 -398.789757) (xy 38.373183 -398.724377) (xy 38.39685 -398.661374)
			(xy 38.427877 -398.601651) (xy 38.465819 -398.546065) (xy 38.487604 -398.520412) (xy 38.493421 -398.513281)
			(xy 38.499923 -398.49608) (xy 38.500304 -398.486884) (xy 38.500304 -397.993362) (xy 38.499911 -397.984173)
			(xy 38.493385 -397.966989) (xy 38.487604 -397.959834) (xy 38.465827 -397.934173) (xy 38.42788 -397.878587)
			(xy 38.396849 -397.818865) (xy 38.373177 -397.755861) (xy 38.357204 -397.69048) (xy 38.34916 -397.623659)
			(xy 38.349159 -397.556356) (xy 37.220943 -397.556356) (xy 37.223335 -397.560946) (xy 37.247103 -397.624039)
			(xy 37.263142 -397.689525) (xy 37.271222 -397.756461) (xy 37.271225 -397.823882) (xy 37.263153 -397.890819)
			(xy 37.24712 -397.956306) (xy 37.223358 -398.019402) (xy 37.19221 -398.079196) (xy 37.154123 -398.134829)
			(xy 37.13226 -398.160494) (xy 37.126478 -398.16765) (xy 37.119956 -398.184832) (xy 37.11956 -398.194022)
			(xy 37.11956 -398.351502) (xy 37.119075 -398.361629) (xy 37.111347 -398.38035) (xy 37.09706 -398.394706)
			(xy 37.078376 -398.402525) (xy 37.068252 -398.403064) (xy 36.351972 -398.403064) (xy 36.341812 -398.402701)
			(xy 36.323052 -398.394889) (xy 36.308728 -398.380474) (xy 36.301036 -398.361665) (xy 36.300664 -398.351502)
			(xy 36.300664 -398.194022) (xy 36.300229 -398.184838) (xy 36.293731 -398.167654) (xy 36.287964 -398.160494)
			(xy 36.266064 -398.134859) (xy 36.227979 -398.079219) (xy 36.196832 -398.019419) (xy 36.173071 -397.956318)
			(xy 36.15704 -397.890825) (xy 36.148967 -397.823884) (xy 35.020799 -397.823884) (xy 34.992065 -397.879042)
			(xy 34.953976 -397.934677) (xy 34.932112 -397.960342) (xy 34.926316 -397.967488) (xy 34.919801 -397.984678)
			(xy 34.919412 -397.99387) (xy 34.919412 -398.486376) (xy 34.919831 -398.495562) (xy 34.926338 -398.512747)
			(xy 34.932112 -398.519904) (xy 34.954011 -398.54554) (xy 34.992098 -398.601179) (xy 35.023246 -398.66098)
			(xy 35.047008 -398.72408) (xy 35.06304 -398.789573) (xy 35.071113 -398.856514) (xy 35.07111 -398.92394)
			(xy 35.063031 -398.990881) (xy 35.046992 -399.056372) (xy 35.023224 -399.11947) (xy 34.99207 -399.179267)
			(xy 34.953978 -399.234903) (xy 34.932112 -399.260568) (xy 34.926305 -399.267706) (xy 34.919796 -399.284902)
			(xy 34.919412 -399.294096) (xy 34.919412 -399.451576) (xy 34.918965 -399.461695) (xy 34.911227 -399.480396)
			(xy 34.89692 -399.494711) (xy 34.878223 -399.502459) (xy 34.868104 -399.502884) (xy 34.151824 -399.502884)
			(xy 34.141701 -399.502464) (xy 34.122995 -399.494721) (xy 34.108679 -399.480405) (xy 34.100936 -399.461699)
			(xy 34.100516 -399.451576) (xy 34.100516 -399.294096) (xy 34.100104 -399.284909) (xy 34.093591 -399.267725)
			(xy 34.087816 -399.260568) (xy 34.065987 -399.234874) (xy 34.027896 -399.179244) (xy 33.996743 -399.119452)
			(xy 33.972976 -399.056359) (xy 33.956937 -398.990873) (xy 33.948858 -398.923938) (xy 33.948855 -398.856516)
			(xy 33.956928 -398.78958) (xy 33.97296 -398.724093) (xy 33.996721 -398.660998) (xy 34.027868 -398.601203)
			(xy 34.065954 -398.545569) (xy 34.087816 -398.519904) (xy 34.093595 -398.512747) (xy 34.10012 -398.495565)
			(xy 34.100516 -398.486376) (xy 34.100516 -397.99387) (xy 34.100117 -397.984682) (xy 34.093595 -397.967498)
			(xy 34.087816 -397.960342) (xy 34.065961 -397.934669) (xy 34.027871 -397.879036) (xy 33.996719 -397.819241)
			(xy 33.972954 -397.756145) (xy 33.956917 -397.690657) (xy 33.94884 -397.623719) (xy 33.948839 -397.556296)
			(xy 32.820593 -397.556296) (xy 32.823205 -397.561323) (xy 32.84688 -397.624323) (xy 32.862855 -397.689702)
			(xy 32.870902 -397.756521) (xy 32.870905 -397.823822) (xy 32.862865 -397.890642) (xy 32.846897 -397.956022)
			(xy 32.823229 -398.019025) (xy 32.7922 -398.078747) (xy 32.754257 -398.134334) (xy 32.732472 -398.159986)
			(xy 32.726653 -398.167115) (xy 32.720152 -398.184318) (xy 32.719772 -398.193514) (xy 32.719772 -398.351502)
			(xy 32.719268 -398.361659) (xy 32.711495 -398.380426) (xy 32.697133 -398.394791) (xy 32.678367 -398.402567)
			(xy 32.66821 -398.403064) (xy 31.95193 -398.403064) (xy 31.941761 -398.402611) (xy 31.922967 -398.394837)
			(xy 31.908581 -398.38046) (xy 31.900795 -398.361671) (xy 31.900368 -398.351502) (xy 31.900368 -398.193514)
			(xy 31.899936 -398.184329) (xy 31.893436 -398.167146) (xy 31.887668 -398.159986) (xy 31.865842 -398.134365)
			(xy 31.827892 -398.078775) (xy 31.796859 -398.019047) (xy 31.773187 -397.956039) (xy 31.757216 -397.890652)
			(xy 31.749174 -397.823826) (xy 30.620528 -397.823826) (xy 30.592066 -397.878596) (xy 30.554113 -397.934182)
			(xy 30.532324 -397.959834) (xy 30.526533 -397.966984) (xy 30.520014 -397.984171) (xy 30.519624 -397.993362)
			(xy 30.519624 -398.486884) (xy 30.520036 -398.496071) (xy 30.526548 -398.513256) (xy 30.532324 -398.520412)
			(xy 30.554149 -398.546034) (xy 30.592099 -398.601624) (xy 30.623132 -398.661352) (xy 30.646805 -398.72436)
			(xy 30.662776 -398.789746) (xy 30.670818 -398.856573) (xy 30.670815 -398.923881) (xy 30.662767 -398.990707)
			(xy 30.646789 -399.056092) (xy 30.62311 -399.119098) (xy 30.592071 -399.178822) (xy 30.554115 -399.234409)
			(xy 30.532324 -399.26006) (xy 30.526522 -399.267202) (xy 30.52001 -399.284395) (xy 30.519624 -399.293588)
			(xy 30.519624 -399.451576) (xy 30.519159 -399.461726) (xy 30.511376 -399.480473) (xy 30.496993 -399.494796)
			(xy 30.478213 -399.502501) (xy 30.468062 -399.502884) (xy 29.751782 -399.502884) (xy 29.741657 -399.502389)
			(xy 29.72294 -399.49466) (xy 29.708585 -399.480377) (xy 29.700762 -399.461698) (xy 29.70022 -399.451576)
			(xy 29.70022 -399.293588) (xy 29.699811 -399.284401) (xy 29.693296 -399.267217) (xy 29.68752 -399.26006)
			(xy 29.665769 -399.234378) (xy 29.62782 -399.178796) (xy 29.596786 -399.119076) (xy 29.573112 -399.056075)
			(xy 29.557137 -398.990697) (xy 29.549091 -398.923878) (xy 29.549087 -398.856576) (xy 29.557128 -398.789756)
			(xy 29.573096 -398.724376) (xy 29.596764 -398.661374) (xy 29.627792 -398.601651) (xy 29.665735 -398.546065)
			(xy 29.68752 -398.520412) (xy 29.693339 -398.513283) (xy 29.69984 -398.49608) (xy 29.70022 -398.486884)
			(xy 29.70022 -397.993362) (xy 29.699824 -397.984173) (xy 29.6933 -397.966989) (xy 29.68752 -397.959834)
			(xy 29.665743 -397.934174) (xy 29.627795 -397.878588) (xy 29.596762 -397.818865) (xy 29.57309 -397.755862)
			(xy 29.557116 -397.690481) (xy 29.549072 -397.623659) (xy 29.549071 -397.556356) (xy 28.420857 -397.556356)
			(xy 28.423249 -397.560947) (xy 28.447016 -397.62404) (xy 28.463055 -397.689526) (xy 28.471134 -397.756461)
			(xy 28.471138 -397.823882) (xy 28.463065 -397.890818) (xy 28.447033 -397.956305) (xy 28.423272 -398.019401)
			(xy 28.392124 -398.079196) (xy 28.354039 -398.134829) (xy 28.332176 -398.160494) (xy 28.326397 -398.167651)
			(xy 28.319873 -398.184833) (xy 28.319476 -398.194022) (xy 28.319476 -398.351502) (xy 28.318975 -398.361627)
			(xy 28.31125 -398.380345) (xy 28.296968 -398.394701) (xy 28.27829 -398.402523) (xy 28.268168 -398.403064)
			(xy 27.551888 -398.403064) (xy 27.541729 -398.402688) (xy 27.522969 -398.394881) (xy 27.508645 -398.38047)
			(xy 27.500952 -398.361664) (xy 27.50058 -398.351502) (xy 27.50058 -398.194022) (xy 27.500164 -398.184835)
			(xy 27.493655 -398.167651) (xy 27.48788 -398.160494) (xy 27.465979 -398.134859) (xy 27.427893 -398.07922)
			(xy 27.396745 -398.019419) (xy 27.372984 -397.956318) (xy 27.356952 -397.890826) (xy 27.348879 -397.823885)
			(xy 9.385578 -397.823885) (xy 9.39659 -397.956787) (xy 9.400539 -398.10004) (xy 9.39659 -398.243293)
			(xy 9.384756 -398.386111) (xy 9.365072 -398.52806) (xy 9.337598 -398.668709) (xy 9.302418 -398.807631)
			(xy 9.259639 -398.944405) (xy 9.20939 -399.078614) (xy 9.151824 -399.209851) (xy 9.087116 -399.337717)
			(xy 9.015462 -399.461825) (xy 8.93708 -399.581797) (xy 8.852209 -399.697269) (xy 8.761105 -399.807891)
			(xy 8.664045 -399.913325) (xy 8.561325 -400.013253) (xy 8.453256 -400.10737) (xy 8.340166 -400.195391)
			(xy 8.222399 -400.277049) (xy 8.100313 -400.352095) (xy 7.974278 -400.420302) (xy 7.844677 -400.481462)
			(xy 7.711903 -400.53539) (xy 7.576361 -400.581922) (xy 7.438461 -400.620916) (xy 7.298622 -400.652254)
			(xy 7.157269 -400.675842) (xy 7.014831 -400.691607) (xy 6.871742 -400.699501) (xy 6.800088 -400.699986)
			(xy 5.199888 -400.699986) (xy 5.128235 -400.699493) (xy 4.985146 -400.691598) (xy 4.842709 -400.675833)
			(xy 4.701356 -400.652246) (xy 4.561518 -400.620907) (xy 4.423619 -400.581913) (xy 4.288077 -400.535381)
			(xy 4.155304 -400.481454) (xy 4.025703 -400.420294) (xy 3.899669 -400.352087) (xy 3.777583 -400.277042)
			(xy 3.659817 -400.195384) (xy 3.546728 -400.107363) (xy 3.438659 -400.013246) (xy 3.33594 -399.913319)
			(xy 3.238881 -399.807885) (xy 3.147777 -399.697264) (xy 3.062906 -399.581793) (xy 2.984524 -399.461821)
			(xy 2.912871 -399.337714) (xy 2.848163 -399.209848) (xy 2.790598 -399.078611) (xy 2.740349 -398.944403)
			(xy 2.69757 -398.80763) (xy 2.66239 -398.668709) (xy 2.634917 -398.52806) (xy 2.615233 -398.386112)
			(xy 2.603399 -398.243294) (xy 2.59945 -398.100042) (xy 1.524 -398.100042) (xy 1.524 -401.723796)
			(xy 27.348891 -401.723796) (xy 27.348893 -401.656371) (xy 27.35697 -401.589432) (xy 27.373007 -401.523942)
			(xy 27.396773 -401.460844) (xy 27.427925 -401.401047) (xy 27.466015 -401.345412) (xy 27.48788 -401.319746)
			(xy 27.49368 -401.312603) (xy 27.500193 -401.295411) (xy 27.50058 -401.286218) (xy 27.50058 -400.793966)
			(xy 27.500191 -400.784777) (xy 27.493663 -400.767592) (xy 27.48788 -400.760438) (xy 27.466023 -400.734768)
			(xy 27.427935 -400.679133) (xy 27.396785 -400.619338) (xy 27.373022 -400.556241) (xy 27.356986 -400.490753)
			(xy 27.34891 -400.423816) (xy 27.34891 -400.356393) (xy 27.356985 -400.289456) (xy 27.373019 -400.223967)
			(xy 27.396782 -400.160871) (xy 27.42793 -400.101074) (xy 27.466017 -400.04544) (xy 27.48788 -400.019774)
			(xy 27.493668 -400.012622) (xy 27.500188 -399.995437) (xy 27.50058 -399.986246) (xy 27.50058 -399.828766)
			(xy 27.501 -399.818632) (xy 27.508746 -399.799903) (xy 27.523053 -399.785546) (xy 27.541756 -399.777735)
			(xy 27.551888 -399.777204) (xy 28.268168 -399.777204) (xy 28.278321 -399.777648) (xy 28.297073 -399.785433)
			(xy 28.311398 -399.799824) (xy 28.319098 -399.818612) (xy 28.319476 -399.828766) (xy 28.319476 -399.986246)
			(xy 28.319918 -399.99543) (xy 28.32641 -400.012614) (xy 28.332176 -400.019774) (xy 28.354047 -400.045434)
			(xy 28.392137 -400.101069) (xy 28.423289 -400.160865) (xy 28.447053 -400.223963) (xy 28.463089 -400.289453)
			(xy 28.471165 -400.356392) (xy 28.471165 -400.423817) (xy 28.463088 -400.490756) (xy 28.447051 -400.556246)
			(xy 28.423285 -400.619343) (xy 28.392132 -400.679139) (xy 28.354041 -400.734773) (xy 28.332176 -400.760438)
			(xy 28.326378 -400.767582) (xy 28.319865 -400.784774) (xy 28.319476 -400.793966) (xy 28.319476 -401.286218)
			(xy 28.319883 -401.295405) (xy 28.326399 -401.31259) (xy 28.332176 -401.319746) (xy 28.354019 -401.345429)
			(xy 28.39211 -401.40106) (xy 28.423263 -401.460854) (xy 28.446989 -401.523838) (xy 29.549051 -401.523838)
			(xy 29.549053 -401.456532) (xy 29.557098 -401.389708) (xy 29.573073 -401.324325) (xy 29.596747 -401.26132)
			(xy 29.627782 -401.201596) (xy 29.665732 -401.146008) (xy 29.68752 -401.120356) (xy 29.69332 -401.113213)
			(xy 29.699832 -401.096021) (xy 29.70022 -401.086828) (xy 29.70022 -400.92884) (xy 29.700655 -400.918686)
			(xy 29.708441 -400.899931) (xy 29.722834 -400.885605) (xy 29.741626 -400.877908) (xy 29.751782 -400.877532)
			(xy 30.468062 -400.877532) (xy 30.478185 -400.878058) (xy 30.496904 -400.885771) (xy 30.511261 -400.900046)
			(xy 30.519083 -400.91872) (xy 30.519624 -400.92884) (xy 30.519624 -401.086828) (xy 30.520015 -401.096017)
			(xy 30.526542 -401.113202) (xy 30.532324 -401.120356) (xy 30.554093 -401.146024) (xy 30.592045 -401.201607)
			(xy 30.623081 -401.261328) (xy 30.646757 -401.324331) (xy 30.662732 -401.389711) (xy 30.670778 -401.456533)
			(xy 30.67078 -401.523837) (xy 30.662738 -401.590659) (xy 30.646766 -401.65604) (xy 30.623093 -401.719044)
			(xy 30.620654 -401.723737) (xy 31.749186 -401.723737) (xy 31.749188 -401.65643) (xy 31.757235 -401.589605)
			(xy 31.773211 -401.524221) (xy 31.796887 -401.461216) (xy 31.827925 -401.401492) (xy 31.865878 -401.345906)
			(xy 31.887668 -401.320254) (xy 31.893475 -401.313116) (xy 31.899981 -401.29592) (xy 31.900368 -401.286726)
			(xy 31.900368 -400.793458) (xy 31.899963 -400.784271) (xy 31.893444 -400.767087) (xy 31.887668 -400.75993)
			(xy 31.865885 -400.734273) (xy 31.827935 -400.678688) (xy 31.796899 -400.618966) (xy 31.773225 -400.555962)
			(xy 31.757251 -400.49058) (xy 31.749206 -400.423757) (xy 31.749205 -400.356452) (xy 31.757249 -400.289629)
			(xy 31.773222 -400.224247) (xy 31.796896 -400.161243) (xy 31.82793 -400.10152) (xy 31.86588 -400.045934)
			(xy 31.887668 -400.020282) (xy 31.893463 -400.013136) (xy 31.899977 -399.995946) (xy 31.900368 -399.986754)
			(xy 31.900368 -399.828766) (xy 31.900806 -399.818602) (xy 31.908597 -399.799827) (xy 31.92298 -399.785462)
			(xy 31.941766 -399.777694) (xy 31.95193 -399.777204) (xy 32.66821 -399.777204) (xy 32.678364 -399.777725)
			(xy 32.697127 -399.785496) (xy 32.711491 -399.799853) (xy 32.719271 -399.818612) (xy 32.719772 -399.828766)
			(xy 32.719772 -399.986754) (xy 32.720211 -399.995938) (xy 32.726705 -400.013122) (xy 32.732472 -400.020282)
			(xy 32.754265 -400.045929) (xy 32.792213 -400.101517) (xy 32.823246 -400.161241) (xy 32.846918 -400.224246)
			(xy 32.86289 -400.289629) (xy 32.870933 -400.356452) (xy 32.870933 -400.423757) (xy 32.862888 -400.49058)
			(xy 32.846915 -400.555962) (xy 32.823242 -400.618967) (xy 32.792209 -400.678691) (xy 32.75426 -400.734278)
			(xy 32.732472 -400.75993) (xy 32.726677 -400.767076) (xy 32.720162 -400.784266) (xy 32.719772 -400.793458)
			(xy 32.719772 -401.286726) (xy 32.720176 -401.295914) (xy 32.726695 -401.313098) (xy 32.732472 -401.320254)
			(xy 32.754237 -401.345924) (xy 32.792186 -401.401508) (xy 32.82322 -401.46123) (xy 32.846893 -401.524232)
			(xy 32.862868 -401.589612) (xy 32.870913 -401.656432) (xy 32.870915 -401.723735) (xy 32.862873 -401.790556)
			(xy 32.846903 -401.855937) (xy 32.823233 -401.91894) (xy 32.792203 -401.978663) (xy 32.754258 -402.03425)
			(xy 32.732472 -402.059902) (xy 32.726688 -402.067056) (xy 32.720167 -402.08424) (xy 32.719772 -402.09343)
			(xy 32.719772 -402.251418) (xy 32.719282 -402.261576) (xy 32.711503 -402.280343) (xy 32.697137 -402.294708)
			(xy 32.678368 -402.302483) (xy 32.66821 -402.30298) (xy 31.95193 -402.30298) (xy 31.941763 -402.302512)
			(xy 31.922972 -402.29474) (xy 31.908587 -402.280368) (xy 31.900798 -402.261585) (xy 31.900368 -402.251418)
			(xy 31.900368 -402.09343) (xy 31.899928 -402.084246) (xy 31.893434 -402.067062) (xy 31.887668 -402.059902)
			(xy 31.865858 -402.034268) (xy 31.827908 -401.97868) (xy 31.796874 -401.918954) (xy 31.773201 -401.855947)
			(xy 31.757229 -401.790562) (xy 31.749186 -401.723737) (xy 30.620654 -401.723737) (xy 30.59206 -401.778767)
			(xy 30.554112 -401.834352) (xy 30.532324 -401.860004) (xy 30.526546 -401.867163) (xy 30.520019 -401.884343)
			(xy 30.519624 -401.893532) (xy 30.519624 -402.3868) (xy 30.520029 -402.395988) (xy 30.526546 -402.413172)
			(xy 30.532324 -402.420328) (xy 30.554114 -402.445978) (xy 30.592063 -402.501565) (xy 30.623097 -402.561289)
			(xy 30.64677 -402.624293) (xy 30.662743 -402.689676) (xy 30.670787 -402.756499) (xy 30.670787 -402.823804)
			(xy 30.670778 -402.823878) (xy 33.948799 -402.823878) (xy 33.948804 -402.75645) (xy 33.956885 -402.689508)
			(xy 33.972926 -402.624016) (xy 33.996696 -402.560917) (xy 34.027853 -402.50112) (xy 34.065949 -402.445485)
			(xy 34.087816 -402.41982) (xy 34.093631 -402.412688) (xy 34.100134 -402.395487) (xy 34.100516 -402.386292)
			(xy 34.100516 -401.89404) (xy 34.100083 -401.884855) (xy 34.093585 -401.867671) (xy 34.087816 -401.860512)
			(xy 34.065932 -401.834863) (xy 34.027843 -401.779227) (xy 33.996692 -401.719428) (xy 33.972928 -401.656329)
			(xy 33.956894 -401.590838) (xy 33.948819 -401.523898) (xy 33.948821 -401.456472) (xy 33.956899 -401.389532)
			(xy 33.972937 -401.324042) (xy 33.996704 -401.260944) (xy 34.027858 -401.201147) (xy 34.06595 -401.145513)
			(xy 34.087816 -401.119848) (xy 34.093619 -401.112707) (xy 34.100129 -401.095513) (xy 34.100516 -401.08632)
			(xy 34.100516 -400.92884) (xy 34.100949 -400.918718) (xy 34.108687 -400.900012) (xy 34.122999 -400.885696)
			(xy 34.141702 -400.877952) (xy 34.151824 -400.877532) (xy 34.868104 -400.877532) (xy 34.878231 -400.877914)
			(xy 34.89694 -400.885669) (xy 34.911256 -400.899997) (xy 34.918995 -400.918713) (xy 34.919412 -400.92884)
			(xy 34.919412 -401.08632) (xy 34.91981 -401.095509) (xy 34.926332 -401.112693) (xy 34.932112 -401.119848)
			(xy 34.953956 -401.14553) (xy 34.992044 -401.201162) (xy 35.023195 -401.260956) (xy 35.04696 -401.324051)
			(xy 35.062997 -401.389538) (xy 35.071074 -401.456474) (xy 35.071076 -401.523896) (xy 35.063002 -401.590833)
			(xy 35.046969 -401.65632) (xy 35.023208 -401.719416) (xy 35.020926 -401.723796) (xy 36.148978 -401.723796)
			(xy 36.14898 -401.656371) (xy 36.157058 -401.589432) (xy 36.173095 -401.523942) (xy 36.19686 -401.460845)
			(xy 36.228011 -401.401047) (xy 36.2661 -401.345412) (xy 36.287964 -401.319746) (xy 36.293774 -401.312611)
			(xy 36.300279 -401.295412) (xy 36.300664 -401.286218) (xy 36.300664 -400.793966) (xy 36.300256 -400.784779)
			(xy 36.293739 -400.767595) (xy 36.287964 -400.760438) (xy 36.266107 -400.734767) (xy 36.228021 -400.679133)
			(xy 36.196872 -400.619337) (xy 36.173109 -400.556241) (xy 36.157074 -400.490753) (xy 36.148998 -400.423816)
			(xy 36.148998 -400.356393) (xy 36.157072 -400.289456) (xy 36.173106 -400.223968) (xy 36.196868 -400.160871)
			(xy 36.228016 -400.101075) (xy 36.266102 -400.04544) (xy 36.287964 -400.019774) (xy 36.293762 -400.01263)
			(xy 36.300274 -399.995438) (xy 36.300664 -399.986246) (xy 36.300664 -399.828766) (xy 36.301099 -399.818634)
			(xy 36.308843 -399.799908) (xy 36.323145 -399.785552) (xy 36.341842 -399.777738) (xy 36.351972 -399.777204)
			(xy 37.068252 -399.777204) (xy 37.078404 -399.777661) (xy 37.097156 -399.785442) (xy 37.111481 -399.799828)
			(xy 37.119181 -399.818613) (xy 37.11956 -399.828766) (xy 37.11956 -399.986246) (xy 37.120005 -399.995429)
			(xy 37.126496 -400.012613) (xy 37.13226 -400.019774) (xy 37.154131 -400.045434) (xy 37.192222 -400.101068)
			(xy 37.223375 -400.160865) (xy 37.247141 -400.223962) (xy 37.263177 -400.289453) (xy 37.271253 -400.356392)
			(xy 37.271252 -400.423817) (xy 37.263175 -400.490756) (xy 37.247138 -400.556246) (xy 37.223371 -400.619344)
			(xy 37.192218 -400.67914) (xy 37.154126 -400.734773) (xy 37.13226 -400.760438) (xy 37.12646 -400.76758)
			(xy 37.119948 -400.784773) (xy 37.11956 -400.793966) (xy 37.11956 -401.286218) (xy 37.11997 -401.295405)
			(xy 37.126485 -401.312589) (xy 37.13226 -401.319746) (xy 37.154104 -401.345428) (xy 37.192196 -401.40106)
			(xy 37.22335 -401.460853) (xy 37.247117 -401.523948) (xy 37.263155 -401.589435) (xy 37.271233 -401.656372)
			(xy 37.271235 -401.723795) (xy 37.263161 -401.790732) (xy 37.247127 -401.856221) (xy 37.223363 -401.919317)
			(xy 37.192213 -401.979112) (xy 37.154124 -402.034745) (xy 37.13226 -402.06041) (xy 37.126472 -402.067561)
			(xy 37.119953 -402.084747) (xy 37.11956 -402.093938) (xy 37.11956 -402.251418) (xy 37.119088 -402.261546)
			(xy 37.111355 -402.280268) (xy 37.097064 -402.294623) (xy 37.078378 -402.302442) (xy 37.068252 -402.30298)
			(xy 36.351972 -402.30298) (xy 36.341814 -402.302601) (xy 36.323057 -402.294792) (xy 36.308734 -402.280383)
			(xy 36.301038 -402.261579) (xy 36.300664 -402.251418) (xy 36.300664 -402.093938) (xy 36.300221 -402.084755)
			(xy 36.293729 -402.067571) (xy 36.287964 -402.06041) (xy 36.26608 -402.034762) (xy 36.227994 -401.979124)
			(xy 36.196846 -401.919325) (xy 36.173085 -401.856226) (xy 36.157052 -401.790735) (xy 36.148978 -401.723796)
			(xy 35.020926 -401.723796) (xy 34.99206 -401.779212) (xy 34.953974 -401.834847) (xy 34.932112 -401.860512)
			(xy 34.926329 -401.867667) (xy 34.919806 -401.88485) (xy 34.919412 -401.89404) (xy 34.919412 -402.386292)
			(xy 34.919823 -402.395479) (xy 34.926336 -402.412664) (xy 34.932112 -402.41982) (xy 34.953928 -402.445524)
			(xy 34.992018 -402.501154) (xy 35.02317 -402.560944) (xy 35.046936 -402.624036) (xy 35.062975 -402.68952)
			(xy 35.071054 -402.756454) (xy 35.071059 -402.823818) (xy 38.349119 -402.823818) (xy 38.349123 -402.75651)
			(xy 38.357172 -402.689685) (xy 38.373149 -402.6243) (xy 38.396825 -402.561294) (xy 38.427862 -402.501569)
			(xy 38.465814 -402.445981) (xy 38.487604 -402.420328) (xy 38.493414 -402.413192) (xy 38.499921 -402.395995)
			(xy 38.500304 -402.3868) (xy 38.500304 -401.893532) (xy 38.499878 -401.884347) (xy 38.493375 -401.867162)
			(xy 38.487604 -401.860004) (xy 38.465798 -401.834368) (xy 38.427852 -401.778778) (xy 38.396821 -401.719052)
			(xy 38.373151 -401.656045) (xy 38.357181 -401.590662) (xy 38.349139 -401.523838) (xy 38.34914 -401.456532)
			(xy 38.357186 -401.389709) (xy 38.37316 -401.324326) (xy 38.396834 -401.261321) (xy 38.427867 -401.201596)
			(xy 38.465816 -401.146009) (xy 38.487604 -401.120356) (xy 38.493402 -401.113212) (xy 38.499916 -401.096021)
			(xy 38.500304 -401.086828) (xy 38.500304 -400.92884) (xy 38.500755 -400.918688) (xy 38.508538 -400.899936)
			(xy 38.522926 -400.885611) (xy 38.541712 -400.87791) (xy 38.551866 -400.877532) (xy 39.268146 -400.877532)
			(xy 39.278275 -400.877989) (xy 39.296995 -400.88573) (xy 39.31135 -400.900025) (xy 39.319169 -400.918714)
			(xy 39.319708 -400.92884) (xy 39.319708 -401.086828) (xy 39.320103 -401.096017) (xy 39.326627 -401.113201)
			(xy 39.332408 -401.120356) (xy 39.354178 -401.146024) (xy 39.392131 -401.201607) (xy 39.423168 -401.261328)
			(xy 39.446844 -401.32433) (xy 39.46282 -401.389711) (xy 39.470866 -401.456533) (xy 39.470868 -401.523837)
			(xy 39.462825 -401.590659) (xy 39.446853 -401.656041) (xy 39.42318 -401.719045) (xy 39.420711 -401.723797)
			(xy 40.548745 -401.723797) (xy 40.548747 -401.65637) (xy 40.556826 -401.58943) (xy 40.572865 -401.523939)
			(xy 40.596634 -401.460841) (xy 40.62779 -401.401044) (xy 40.665885 -401.34541) (xy 40.687752 -401.319746)
			(xy 40.69356 -401.312609) (xy 40.700067 -401.295412) (xy 40.700452 -401.286218) (xy 40.700452 -400.793966)
			(xy 40.700046 -400.784779) (xy 40.693528 -400.767595) (xy 40.687752 -400.760438) (xy 40.665892 -400.734769)
			(xy 40.6278 -400.679136) (xy 40.596646 -400.619341) (xy 40.572879 -400.556244) (xy 40.556842 -400.490755)
			(xy 40.548764 -400.423817) (xy 40.548764 -400.356392) (xy 40.55684 -400.289454) (xy 40.572876 -400.223964)
			(xy 40.596642 -400.160867) (xy 40.627795 -400.101072) (xy 40.665887 -400.045438) (xy 40.687752 -400.019774)
			(xy 40.693549 -400.012629) (xy 40.700062 -399.995438) (xy 40.700452 -399.986246) (xy 40.700452 -399.828766)
			(xy 40.700899 -399.818636) (xy 40.70864 -399.799911) (xy 40.722939 -399.785556) (xy 40.741632 -399.77774)
			(xy 40.75176 -399.777204) (xy 41.46804 -399.777204) (xy 41.478197 -399.777589) (xy 41.496951 -399.785399)
			(xy 41.511273 -399.799806) (xy 41.518971 -399.818606) (xy 41.519348 -399.828766) (xy 41.519348 -399.986246)
			(xy 41.519796 -399.995429) (xy 41.526285 -400.012613) (xy 41.532048 -400.019774) (xy 41.55392 -400.045433)
			(xy 41.592012 -400.101068) (xy 41.623165 -400.160864) (xy 41.646931 -400.223962) (xy 41.662968 -400.289452)
			(xy 41.671044 -400.356392) (xy 41.671043 -400.423817) (xy 41.662966 -400.490757) (xy 41.646928 -400.556247)
			(xy 41.623161 -400.619344) (xy 41.592007 -400.67914) (xy 41.553914 -400.734774) (xy 41.532048 -400.760438)
			(xy 41.526246 -400.767579) (xy 41.519736 -400.784773) (xy 41.519348 -400.793966) (xy 41.519348 -401.286218)
			(xy 41.519761 -401.295405) (xy 41.526274 -401.312588) (xy 41.532048 -401.319746) (xy 41.553892 -401.345428)
			(xy 41.591985 -401.401059) (xy 41.62314 -401.460852) (xy 41.646907 -401.523947) (xy 41.662946 -401.589435)
			(xy 41.671024 -401.656372) (xy 41.671026 -401.723795) (xy 41.662952 -401.790733) (xy 41.646917 -401.856221)
			(xy 41.623153 -401.919317) (xy 41.592002 -401.979113) (xy 41.553912 -402.034746) (xy 41.532048 -402.06041)
			(xy 41.526258 -402.06756) (xy 41.519741 -402.084747) (xy 41.519348 -402.093938) (xy 41.519348 -402.251418)
			(xy 41.518888 -402.261547) (xy 41.511152 -402.280271) (xy 41.496858 -402.294627) (xy 41.478167 -402.302444)
			(xy 41.46804 -402.30298) (xy 40.75176 -402.30298) (xy 40.741601 -402.302611) (xy 40.722844 -402.294798)
			(xy 40.708521 -402.280385) (xy 40.700826 -402.26158) (xy 40.700452 -402.251418) (xy 40.700452 -402.093938)
			(xy 40.700012 -402.084754) (xy 40.693518 -402.06757) (xy 40.687752 -402.06041) (xy 40.665865 -402.034763)
			(xy 40.627773 -401.979127) (xy 40.59662 -401.919329) (xy 40.572855 -401.85623) (xy 40.55682 -401.790738)
			(xy 40.548745 -401.723797) (xy 39.420711 -401.723797) (xy 39.392146 -401.778768) (xy 39.354196 -401.834353)
			(xy 39.332408 -401.860004) (xy 39.326628 -401.867161) (xy 39.320103 -401.884342) (xy 39.319708 -401.893532)
			(xy 39.319708 -402.3868) (xy 39.320116 -402.395987) (xy 39.326631 -402.413172) (xy 39.332408 -402.420328)
			(xy 39.35415 -402.446018) (xy 39.392104 -402.501598) (xy 39.423142 -402.561316) (xy 39.44682 -402.624315)
			(xy 39.462798 -402.689694) (xy 39.470847 -402.756513) (xy 39.470851 -402.823815) (xy 39.470843 -402.823878)
			(xy 42.748887 -402.823878) (xy 42.748892 -402.75645) (xy 42.756972 -402.689509) (xy 42.773013 -402.624017)
			(xy 42.796782 -402.560918) (xy 42.827939 -402.501121) (xy 42.866033 -402.445485) (xy 42.8879 -402.41982)
			(xy 42.893713 -402.412686) (xy 42.900218 -402.395487) (xy 42.9006 -402.386292) (xy 42.9006 -401.89404)
			(xy 42.900171 -401.884855) (xy 42.89367 -401.86767) (xy 42.8879 -401.860512) (xy 42.866016 -401.834863)
			(xy 42.827928 -401.779226) (xy 42.796778 -401.719428) (xy 42.773015 -401.656329) (xy 42.756981 -401.590838)
			(xy 42.748907 -401.523898) (xy 42.748909 -401.456472) (xy 42.756987 -401.389533) (xy 42.773024 -401.324043)
			(xy 42.796791 -401.260945) (xy 42.827944 -401.201148) (xy 42.866035 -401.145513) (xy 42.8879 -401.119848)
			(xy 42.893701 -401.112706) (xy 42.900213 -401.095513) (xy 42.9006 -401.08632) (xy 42.9006 -400.92884)
			(xy 42.901049 -400.91872) (xy 42.908784 -400.900017) (xy 42.923091 -400.885702) (xy 42.941788 -400.877955)
			(xy 42.951908 -400.877532) (xy 43.668188 -400.877532) (xy 43.678314 -400.877927) (xy 43.697023 -400.885677)
			(xy 43.711339 -400.9) (xy 43.719079 -400.918714) (xy 43.719496 -400.92884) (xy 43.719496 -401.08632)
			(xy 43.719897 -401.095508) (xy 43.726417 -401.112692) (xy 43.732196 -401.119848) (xy 43.75404 -401.145529)
			(xy 43.79213 -401.201162) (xy 43.823282 -401.260955) (xy 43.847047 -401.32405) (xy 43.863084 -401.389537)
			(xy 43.871162 -401.456474) (xy 43.871164 -401.523896) (xy 43.86309 -401.590833) (xy 43.847056 -401.656321)
			(xy 43.823294 -401.719417) (xy 43.821044 -401.723737) (xy 44.949064 -401.723737) (xy 44.949066 -401.65643)
			(xy 44.957113 -401.589606) (xy 44.973088 -401.524222) (xy 44.996763 -401.461217) (xy 45.027799 -401.401493)
			(xy 45.065751 -401.345906) (xy 45.08754 -401.320254) (xy 45.093344 -401.313114) (xy 45.099853 -401.295919)
			(xy 45.10024 -401.286726) (xy 45.10024 -400.793458) (xy 45.099841 -400.78427) (xy 45.093319 -400.767086)
			(xy 45.08754 -400.75993) (xy 45.065758 -400.734273) (xy 45.027809 -400.678687) (xy 44.996776 -400.618964)
			(xy 44.973103 -400.55596) (xy 44.957129 -400.490579) (xy 44.949085 -400.423757) (xy 44.949084 -400.356452)
			(xy 44.957128 -400.28963) (xy 44.9731 -400.224248) (xy 44.996772 -400.161244) (xy 45.027805 -400.101521)
			(xy 45.065753 -400.045934) (xy 45.08754 -400.020282) (xy 45.093332 -400.013134) (xy 45.099848 -399.995945)
			(xy 45.10024 -399.986754) (xy 45.10024 -399.828766) (xy 45.100706 -399.818606) (xy 45.108492 -399.799835)
			(xy 45.122866 -399.785471) (xy 45.141641 -399.777698) (xy 45.151802 -399.777204) (xy 45.868082 -399.777204)
			(xy 45.878234 -399.777747) (xy 45.896997 -399.785509) (xy 45.911361 -399.79986) (xy 45.919143 -399.818614)
			(xy 45.919644 -399.828766) (xy 45.919644 -399.986754) (xy 45.920089 -399.995937) (xy 45.92658 -400.013121)
			(xy 45.932344 -400.020282) (xy 45.954138 -400.045929) (xy 45.992088 -400.101516) (xy 46.023122 -400.16124)
			(xy 46.046795 -400.224245) (xy 46.062768 -400.289628) (xy 46.070812 -400.356452) (xy 46.070811 -400.423757)
			(xy 46.062766 -400.490581) (xy 46.046792 -400.555963) (xy 46.023118 -400.618968) (xy 45.992083 -400.678692)
			(xy 45.954132 -400.734278) (xy 45.932344 -400.75993) (xy 45.926545 -400.767073) (xy 45.920033 -400.784266)
			(xy 45.919644 -400.793458) (xy 45.919644 -401.286726) (xy 45.920054 -401.295913) (xy 45.926569 -401.313097)
			(xy 45.932344 -401.320254) (xy 45.95411 -401.345924) (xy 45.992061 -401.401507) (xy 46.023096 -401.461228)
			(xy 46.046771 -401.524231) (xy 46.062746 -401.589611) (xy 46.070792 -401.656432) (xy 46.070794 -401.723735)
			(xy 46.062752 -401.790557) (xy 46.046781 -401.855938) (xy 46.02311 -401.918941) (xy 45.992078 -401.978664)
			(xy 45.954131 -402.03425) (xy 45.932344 -402.059902) (xy 45.926557 -402.067054) (xy 45.920038 -402.084239)
			(xy 45.919644 -402.09343) (xy 45.919644 -402.251418) (xy 45.919181 -402.261579) (xy 45.911397 -402.280352)
			(xy 45.897022 -402.294718) (xy 45.878244 -402.302488) (xy 45.868082 -402.30298) (xy 45.151802 -402.30298)
			(xy 45.141647 -402.302465) (xy 45.122881 -402.294695) (xy 45.108516 -402.280336) (xy 45.100739 -402.261573)
			(xy 45.10024 -402.251418) (xy 45.10024 -402.09343) (xy 45.099806 -402.084246) (xy 45.093308 -402.067061)
			(xy 45.08754 -402.059902) (xy 45.06573 -402.034268) (xy 45.027782 -401.978679) (xy 44.99675 -401.918953)
			(xy 44.973078 -401.855946) (xy 44.957107 -401.790561) (xy 44.949064 -401.723737) (xy 43.821044 -401.723737)
			(xy 43.792146 -401.779213) (xy 43.754059 -401.834847) (xy 43.732196 -401.860512) (xy 43.726411 -401.867666)
			(xy 43.71989 -401.88485) (xy 43.719496 -401.89404) (xy 43.719496 -402.386292) (xy 43.719911 -402.395479)
			(xy 43.726421 -402.412663) (xy 43.732196 -402.41982) (xy 43.754013 -402.445524) (xy 43.792103 -402.501153)
			(xy 43.823256 -402.560944) (xy 43.847023 -402.624036) (xy 43.863062 -402.68952) (xy 43.871142 -402.756454)
			(xy 43.871146 -402.823874) (xy 43.863075 -402.890809) (xy 43.847045 -402.956295) (xy 43.823286 -403.01939)
			(xy 43.792141 -403.079185) (xy 43.754057 -403.134819) (xy 43.732196 -403.160484) (xy 43.726381 -403.167616)
			(xy 43.719877 -403.184817) (xy 43.719496 -403.194012) (xy 43.719496 -403.351492) (xy 43.719077 -403.361614)
			(xy 43.711331 -403.380319) (xy 43.697015 -403.394633) (xy 43.67831 -403.402378) (xy 43.668188 -403.4028)
			(xy 42.951908 -403.4028) (xy 42.941786 -403.402377) (xy 42.923083 -403.394632) (xy 42.908768 -403.380317)
			(xy 42.901023 -403.361614) (xy 42.9006 -403.351492) (xy 42.9006 -403.194012) (xy 42.900184 -403.184825)
			(xy 42.893674 -403.167641) (xy 42.8879 -403.160484) (xy 42.865989 -403.134858) (xy 42.827902 -403.079218)
			(xy 42.796753 -403.019416) (xy 42.772992 -402.956314) (xy 42.756959 -402.89082) (xy 42.748887 -402.823878)
			(xy 39.470843 -402.823878) (xy 39.462811 -402.890635) (xy 39.446841 -402.956016) (xy 39.423172 -403.019018)
			(xy 39.392141 -403.07874) (xy 39.354194 -403.134325) (xy 39.332408 -403.159976) (xy 39.326598 -403.167111)
			(xy 39.320091 -403.184309) (xy 39.319708 -403.193504) (xy 39.319708 -403.351492) (xy 39.319272 -403.361645)
			(xy 39.311481 -403.380395) (xy 39.297088 -403.394719) (xy 39.278301 -403.40242) (xy 39.268146 -403.4028)
			(xy 38.551866 -403.4028) (xy 38.541742 -403.402303) (xy 38.523028 -403.394571) (xy 38.508674 -403.380289)
			(xy 38.500849 -403.361613) (xy 38.500304 -403.351492) (xy 38.500304 -403.193504) (xy 38.499891 -403.184317)
			(xy 38.493379 -403.167133) (xy 38.487604 -403.159976) (xy 38.46577 -403.134362) (xy 38.427825 -403.078769)
			(xy 38.396796 -403.01904) (xy 38.373127 -402.956031) (xy 38.357159 -402.890644) (xy 38.349119 -402.823818)
			(xy 35.071059 -402.823818) (xy 35.071059 -402.823874) (xy 35.062988 -402.890809) (xy 35.046958 -402.956295)
			(xy 35.023199 -403.01939) (xy 34.992055 -403.079185) (xy 34.953973 -403.134819) (xy 34.932112 -403.160484)
			(xy 34.926299 -403.167617) (xy 34.919794 -403.184817) (xy 34.919412 -403.194012) (xy 34.919412 -403.351492)
			(xy 34.918978 -403.361612) (xy 34.911234 -403.380314) (xy 34.896924 -403.394628) (xy 34.878224 -403.402375)
			(xy 34.868104 -403.4028) (xy 34.151824 -403.4028) (xy 34.141703 -403.402365) (xy 34.123 -403.394624)
			(xy 34.108685 -403.380314) (xy 34.100939 -403.361613) (xy 34.100516 -403.351492) (xy 34.100516 -403.194012)
			(xy 34.100096 -403.184826) (xy 34.093589 -403.167642) (xy 34.087816 -403.160484) (xy 34.065904 -403.134858)
			(xy 34.027816 -403.079218) (xy 33.996666 -403.019417) (xy 33.972904 -402.956315) (xy 33.956872 -402.890821)
			(xy 33.948799 -402.823878) (xy 30.670778 -402.823878) (xy 30.662742 -402.890627) (xy 30.646769 -402.956009)
			(xy 30.623096 -403.019014) (xy 30.592062 -403.078738) (xy 30.554112 -403.134324) (xy 30.532324 -403.159976)
			(xy 30.526515 -403.167113) (xy 30.520007 -403.18431) (xy 30.519624 -403.193504) (xy 30.519624 -403.351492)
			(xy 30.519172 -403.361643) (xy 30.511384 -403.38039) (xy 30.496997 -403.394713) (xy 30.478214 -403.402417)
			(xy 30.468062 -403.4028) (xy 29.751782 -403.4028) (xy 29.741659 -403.40229) (xy 29.722945 -403.394563)
			(xy 29.708591 -403.380285) (xy 29.700765 -403.361612) (xy 29.70022 -403.351492) (xy 29.70022 -403.193504)
			(xy 29.699804 -403.184318) (xy 29.693294 -403.167133) (xy 29.68752 -403.159976) (xy 29.665734 -403.134322)
			(xy 29.627785 -403.078736) (xy 29.596752 -403.019013) (xy 29.573079 -402.956008) (xy 29.557106 -402.890626)
			(xy 29.549061 -402.823804) (xy 29.549061 -402.756499) (xy 29.557105 -402.689677) (xy 29.573078 -402.624294)
			(xy 29.59675 -402.56129) (xy 29.627784 -402.501566) (xy 29.665732 -402.44598) (xy 29.68752 -402.420328)
			(xy 29.693332 -402.413194) (xy 29.699837 -402.395995) (xy 29.70022 -402.3868) (xy 29.70022 -401.893532)
			(xy 29.69979 -401.884347) (xy 29.69329 -401.867163) (xy 29.68752 -401.860004) (xy 29.665713 -401.834368)
			(xy 29.627766 -401.778779) (xy 29.596735 -401.719053) (xy 29.573064 -401.656046) (xy 29.557093 -401.590662)
			(xy 29.549051 -401.523838) (xy 28.446989 -401.523838) (xy 28.44703 -401.523948) (xy 28.463067 -401.589436)
			(xy 28.471145 -401.656372) (xy 28.471147 -401.723795) (xy 28.463073 -401.790732) (xy 28.447039 -401.85622)
			(xy 28.423277 -401.919316) (xy 28.392127 -401.979111) (xy 28.354039 -402.034745) (xy 28.332176 -402.06041)
			(xy 28.32639 -402.067562) (xy 28.31987 -402.084748) (xy 28.319476 -402.093938) (xy 28.319476 -402.251418)
			(xy 28.318989 -402.261544) (xy 28.311258 -402.280263) (xy 28.296972 -402.294618) (xy 28.278291 -402.302439)
			(xy 28.268168 -402.30298) (xy 27.551888 -402.30298) (xy 27.541731 -402.302588) (xy 27.522974 -402.294785)
			(xy 27.50865 -402.280379) (xy 27.500954 -402.261578) (xy 27.50058 -402.251418) (xy 27.50058 -402.093938)
			(xy 27.500156 -402.084752) (xy 27.493653 -402.067567) (xy 27.48788 -402.06041) (xy 27.465995 -402.034762)
			(xy 27.427908 -401.979125) (xy 27.39676 -401.919326) (xy 27.372998 -401.856227) (xy 27.356964 -401.790736)
			(xy 27.348891 -401.723796) (xy 1.524 -401.723796) (xy 1.524 -404.502366) (xy 1.524459 -404.513094)
			(xy 1.533205 -404.532683) (xy 1.549214 -404.546963) (xy 1.559306 -404.550626) (xy 1.66751 -404.58517)
			(xy 1.698752 -404.574756) (xy 1.708404 -404.56104) (xy 1.769258 -404.475991) (xy 1.896821 -404.310242)
			(xy 2.030874 -404.149697) (xy 2.171205 -403.994609) (xy 2.317592 -403.845223) (xy 2.469804 -403.701777)
			(xy 2.627599 -403.564498) (xy 2.790728 -403.433601) (xy 2.958933 -403.309295) (xy 3.131949 -403.191776)
			(xy 3.3095 -403.081229) (xy 3.491307 -402.977831) (xy 3.677082 -402.881743) (xy 3.866531 -402.793119)
			(xy 4.059354 -402.712099) (xy 4.255247 -402.63881) (xy 4.453898 -402.573369) (xy 4.654995 -402.515878)
			(xy 4.858219 -402.46643) (xy 5.063249 -402.425102) (xy 5.269759 -402.39196) (xy 5.477425 -402.367056)
			(xy 5.685916 -402.350429) (xy 5.894903 -402.342106) (xy 5.99948 -402.341588) (xy 5.999988 -402.341588)
			(xy 6.101963 -402.342082) (xy 6.30576 -402.349991) (xy 6.509097 -402.365795) (xy 6.711669 -402.389472)
			(xy 6.913169 -402.420987) (xy 7.113297 -402.46029) (xy 7.31175 -402.507324) (xy 7.50823 -402.562018)
			(xy 7.702441 -402.62429) (xy 7.894092 -402.694045) (xy 8.082893 -402.771179) (xy 8.268562 -402.855576)
			(xy 8.450819 -402.947108) (xy 8.629389 -403.045639) (xy 8.804005 -403.15102) (xy 8.974403 -403.263093)
			(xy 9.140327 -403.381689) (xy 9.301528 -403.506629) (xy 9.457763 -403.637725) (xy 9.608797 -403.774782)
			(xy 9.754403 -403.917591) (xy 9.894363 -404.065939) (xy 10.028464 -404.219603) (xy 10.156507 -404.378351)
			(xy 10.278298 -404.541944) (xy 10.393653 -404.710137) (xy 10.502401 -404.882676) (xy 10.604376 -405.059302)
			(xy 10.699426 -405.23975) (xy 10.787407 -405.423747) (xy 10.868188 -405.611018) (xy 10.873087 -405.623707)
			(xy 27.348902 -405.623707) (xy 27.348902 -405.556284) (xy 27.356979 -405.489345) (xy 27.373014 -405.423856)
			(xy 27.396778 -405.360759) (xy 27.427928 -405.300963) (xy 27.466016 -405.245328) (xy 27.48788 -405.219662)
			(xy 27.493673 -405.212514) (xy 27.50019 -405.195326) (xy 27.50058 -405.186134) (xy 27.50058 -404.693882)
			(xy 27.500183 -404.684693) (xy 27.493661 -404.667509) (xy 27.48788 -404.660354) (xy 27.466038 -404.634671)
			(xy 27.42795 -404.579038) (xy 27.3968 -404.519244) (xy 27.373035 -404.45615) (xy 27.356999 -404.390663)
			(xy 27.348922 -404.323727) (xy 27.34892 -404.256306) (xy 27.356993 -404.189369) (xy 27.373025 -404.123882)
			(xy 27.396786 -404.060786) (xy 27.427933 -404.00099) (xy 27.466018 -403.945356) (xy 27.48788 -403.91969)
			(xy 27.493661 -403.912534) (xy 27.500186 -403.895352) (xy 27.50058 -403.886162) (xy 27.50058 -403.728682)
			(xy 27.501013 -403.718549) (xy 27.508754 -403.69982) (xy 27.523057 -403.685463) (xy 27.541757 -403.677651)
			(xy 27.551888 -403.67712) (xy 28.268168 -403.67712) (xy 28.278323 -403.677548) (xy 28.297078 -403.685337)
			(xy 28.311404 -403.699732) (xy 28.319101 -403.718525) (xy 28.319476 -403.728682) (xy 28.319476 -403.886162)
			(xy 28.31991 -403.895347) (xy 28.326408 -403.912531) (xy 28.332176 -403.91969) (xy 28.354062 -403.945337)
			(xy 28.392152 -404.000974) (xy 28.423303 -404.060772) (xy 28.447067 -404.123871) (xy 28.463102 -404.189363)
			(xy 28.471176 -404.256304) (xy 28.471174 -404.323729) (xy 28.463096 -404.39067) (xy 28.447057 -404.45616)
			(xy 28.42329 -404.519258) (xy 28.392135 -404.579055) (xy 28.354042 -404.634689) (xy 28.332176 -404.660354)
			(xy 28.326371 -404.667493) (xy 28.319862 -404.684688) (xy 28.319476 -404.693882) (xy 28.319476 -405.186134)
			(xy 28.319875 -405.195322) (xy 28.326397 -405.212506) (xy 28.332176 -405.219662) (xy 28.354035 -405.245332)
			(xy 28.392125 -405.300965) (xy 28.423278 -405.36076) (xy 28.447043 -405.423857) (xy 28.46308 -405.489345)
			(xy 28.471157 -405.556284) (xy 28.471157 -405.623707) (xy 28.463081 -405.690646) (xy 28.447046 -405.756135)
			(xy 28.423281 -405.819231) (xy 28.39213 -405.879027) (xy 28.35404 -405.934661) (xy 28.332176 -405.960326)
			(xy 28.326383 -405.967474) (xy 28.319867 -405.984662) (xy 28.319476 -405.993854) (xy 28.319476 -406.151334)
			(xy 28.319002 -406.161461) (xy 28.311266 -406.18018) (xy 28.296976 -406.194534) (xy 28.278293 -406.202355)
			(xy 28.268168 -406.202896) (xy 27.551888 -406.202896) (xy 27.541733 -406.202488) (xy 27.522979 -406.194688)
			(xy 27.508656 -406.180287) (xy 27.500957 -406.161492) (xy 27.50058 -406.151334) (xy 27.50058 -405.993854)
			(xy 27.500148 -405.984669) (xy 27.49365 -405.967484) (xy 27.48788 -405.960326) (xy 27.466011 -405.934665)
			(xy 27.427924 -405.87903) (xy 27.396774 -405.819233) (xy 27.373011 -405.756135) (xy 27.356977 -405.690646)
			(xy 27.348902 -405.623707) (xy 10.873087 -405.623707) (xy 10.941646 -405.80128) (xy 11.007672 -405.994247)
			(xy 11.066165 -406.189629) (xy 11.117039 -406.387133) (xy 11.160216 -406.58646) (xy 11.18442 -406.72373)
			(xy 29.549042 -406.72373) (xy 29.549045 -406.656422) (xy 29.557092 -406.589598) (xy 29.573068 -406.524214)
			(xy 29.596744 -406.461208) (xy 29.627779 -406.401484) (xy 29.665731 -406.345896) (xy 29.68752 -406.320244)
			(xy 29.693325 -406.313105) (xy 29.699834 -406.29591) (xy 29.70022 -406.286716) (xy 29.70022 -405.793448)
			(xy 29.699782 -405.784264) (xy 29.693287 -405.767079) (xy 29.68752 -405.75992) (xy 29.665729 -405.734271)
			(xy 29.627781 -405.678684) (xy 29.596749 -405.618959) (xy 29.573078 -405.555955) (xy 29.557105 -405.490572)
			(xy 29.549062 -405.423749) (xy 29.549062 -405.356444) (xy 29.557107 -405.289622) (xy 29.573079 -405.22424)
			(xy 29.596752 -405.161235) (xy 29.627784 -405.101511) (xy 29.665733 -405.045924) (xy 29.68752 -405.020272)
			(xy 29.693313 -405.013125) (xy 29.699829 -404.995936) (xy 29.70022 -404.986744) (xy 29.70022 -404.828756)
			(xy 29.700586 -404.818597) (xy 29.7084 -404.799839) (xy 29.722814 -404.785517) (xy 29.74162 -404.777822)
			(xy 29.751782 -404.777448) (xy 30.468062 -404.777448) (xy 30.478187 -404.777958) (xy 30.496909 -404.785675)
			(xy 30.511267 -404.799954) (xy 30.519086 -404.818634) (xy 30.519624 -404.828756) (xy 30.519624 -404.986744)
			(xy 30.520008 -404.995934) (xy 30.526539 -405.013118) (xy 30.532324 -405.020272) (xy 30.554109 -405.045927)
			(xy 30.59206 -405.101512) (xy 30.623096 -405.161235) (xy 30.64677 -405.224239) (xy 30.662745 -405.289621)
			(xy 30.67079 -405.356444) (xy 30.67079 -405.42375) (xy 30.662746 -405.490573) (xy 30.646772 -405.555955)
			(xy 30.623098 -405.61896) (xy 30.620661 -405.623649) (xy 31.749197 -405.623649) (xy 31.749198 -405.556342)
			(xy 31.757243 -405.489519) (xy 31.773217 -405.424136) (xy 31.796892 -405.361131) (xy 31.827928 -405.301408)
			(xy 31.865879 -405.245822) (xy 31.887668 -405.22017) (xy 31.893468 -405.213028) (xy 31.899979 -405.195835)
			(xy 31.900368 -405.186642) (xy 31.900368 -404.693374) (xy 31.899955 -404.684187) (xy 31.893441 -404.667004)
			(xy 31.887668 -404.659846) (xy 31.865901 -404.634176) (xy 31.82795 -404.578593) (xy 31.796914 -404.518872)
			(xy 31.773239 -404.45587) (xy 31.757263 -404.39049) (xy 31.749217 -404.323668) (xy 31.749215 -404.256365)
			(xy 31.757257 -404.189543) (xy 31.773229 -404.124162) (xy 31.7969 -404.061158) (xy 31.827933 -404.001435)
			(xy 31.865881 -403.94585) (xy 31.887668 -403.920198) (xy 31.893456 -403.913047) (xy 31.899974 -403.895861)
			(xy 31.900368 -403.88667) (xy 31.900368 -403.728682) (xy 31.90075 -403.718506) (xy 31.908547 -403.699705)
			(xy 31.922945 -403.68532) (xy 31.941753 -403.677541) (xy 31.95193 -403.67712) (xy 32.66821 -403.67712)
			(xy 32.678366 -403.677625) (xy 32.697132 -403.685399) (xy 32.711496 -403.699761) (xy 32.719273 -403.718526)
			(xy 32.719772 -403.728682) (xy 32.719772 -403.88667) (xy 32.720203 -403.895855) (xy 32.726703 -403.913039)
			(xy 32.732472 -403.920198) (xy 32.754281 -403.945832) (xy 32.792229 -404.001422) (xy 32.82326 -404.061148)
			(xy 32.846931 -404.124155) (xy 32.862902 -404.189539) (xy 32.870945 -404.256363) (xy 32.870943 -404.32367)
			(xy 32.862897 -404.390494) (xy 32.846922 -404.455877) (xy 32.823247 -404.518882) (xy 32.792212 -404.578607)
			(xy 32.754261 -404.634194) (xy 32.732472 -404.659846) (xy 32.72667 -404.666987) (xy 32.720159 -404.684181)
			(xy 32.719772 -404.693374) (xy 32.719772 -405.186642) (xy 32.720168 -405.195831) (xy 32.726692 -405.213014)
			(xy 32.732472 -405.22017) (xy 32.754254 -405.245827) (xy 32.792202 -405.301413) (xy 32.823235 -405.361136)
			(xy 32.846907 -405.42414) (xy 32.862881 -405.489521) (xy 32.870925 -405.556343) (xy 32.870926 -405.623648)
			(xy 32.862882 -405.69047) (xy 32.84691 -405.755851) (xy 32.823239 -405.818856) (xy 32.792207 -405.878579)
			(xy 32.754259 -405.934166) (xy 32.732472 -405.959818) (xy 32.726682 -405.966967) (xy 32.720164 -405.984155)
			(xy 32.719772 -405.993346) (xy 32.719772 -406.151334) (xy 32.719295 -406.161493) (xy 32.711511 -406.180261)
			(xy 32.697141 -406.194624) (xy 32.678369 -406.202399) (xy 32.66821 -406.202896) (xy 31.95193 -406.202896)
			(xy 31.941778 -406.202343) (xy 31.923016 -406.194585) (xy 31.908651 -406.180237) (xy 31.900869 -406.161485)
			(xy 31.900368 -406.151334) (xy 31.900368 -405.993346) (xy 31.899921 -405.984163) (xy 31.893431 -405.966979)
			(xy 31.887668 -405.959818) (xy 31.865874 -405.934171) (xy 31.827923 -405.878584) (xy 31.796888 -405.81886)
			(xy 31.773215 -405.755855) (xy 31.757241 -405.690472) (xy 31.749197 -405.623649) (xy 30.620661 -405.623649)
			(xy 30.592063 -405.678683) (xy 30.554113 -405.734268) (xy 30.532324 -405.75992) (xy 30.526539 -405.767074)
			(xy 30.520017 -405.784258) (xy 30.519624 -405.793448) (xy 30.519624 -406.286716) (xy 30.520021 -406.295905)
			(xy 30.526543 -406.313089) (xy 30.532324 -406.320244) (xy 30.554081 -406.345922) (xy 30.592034 -406.401503)
			(xy 30.62307 -406.461223) (xy 30.646746 -406.524224) (xy 30.662723 -406.589604) (xy 30.67077 -406.656424)
			(xy 30.670773 -406.723728) (xy 30.670766 -406.723789) (xy 33.948811 -406.723789) (xy 33.948814 -406.656363)
			(xy 33.956893 -406.589422) (xy 33.972932 -406.523931) (xy 33.996701 -406.460833) (xy 34.027856 -406.401036)
			(xy 34.06595 -406.345401) (xy 34.087816 -406.319736) (xy 34.093624 -406.312599) (xy 34.100131 -406.295402)
			(xy 34.100516 -406.286208) (xy 34.100516 -405.793956) (xy 34.100123 -405.784767) (xy 34.093597 -405.767583)
			(xy 34.087816 -405.760428) (xy 34.065948 -405.734766) (xy 34.027858 -405.679132) (xy 33.996706 -405.619335)
			(xy 33.972942 -405.556238) (xy 33.956906 -405.490748) (xy 33.94883 -405.423809) (xy 33.948831 -405.356385)
			(xy 33.956907 -405.289446) (xy 33.972944 -405.223957) (xy 33.996709 -405.160859) (xy 34.027861 -405.101063)
			(xy 34.065951 -405.045429) (xy 34.087816 -405.019764) (xy 34.093612 -405.012619) (xy 34.100127 -404.995428)
			(xy 34.100516 -404.986236) (xy 34.100516 -404.828756) (xy 34.10095 -404.818642) (xy 34.108705 -404.79996)
			(xy 34.123017 -404.785666) (xy 34.14171 -404.777936) (xy 34.151824 -404.777448) (xy 34.868104 -404.777448)
			(xy 34.878207 -404.777981) (xy 34.896875 -404.78571) (xy 34.911168 -404.799992) (xy 34.918911 -404.818654)
			(xy 34.919412 -404.828756) (xy 34.919412 -404.986236) (xy 34.919802 -404.995425) (xy 34.926329 -405.01261)
			(xy 34.932112 -405.019764) (xy 34.953972 -405.045433) (xy 34.99206 -405.101067) (xy 35.02321 -405.160863)
			(xy 35.046974 -405.223959) (xy 35.063009 -405.289448) (xy 35.071085 -405.356385) (xy 35.071085 -405.423809)
			(xy 35.06301 -405.490746) (xy 35.046976 -405.556235) (xy 35.023212 -405.619332) (xy 35.020933 -405.623707)
			(xy 36.14899 -405.623707) (xy 36.14899 -405.556284) (xy 36.157066 -405.489346) (xy 36.173101 -405.423857)
			(xy 36.196864 -405.36076) (xy 36.228014 -405.300963) (xy 36.266101 -405.245328) (xy 36.287964 -405.219662)
			(xy 36.293767 -405.212522) (xy 36.300276 -405.195327) (xy 36.300664 -405.186134) (xy 36.300664 -404.693882)
			(xy 36.300248 -404.684696) (xy 36.293737 -404.667512) (xy 36.287964 -404.660354) (xy 36.266123 -404.63467)
			(xy 36.228036 -404.579038) (xy 36.196886 -404.519244) (xy 36.173122 -404.456149) (xy 36.157087 -404.390663)
			(xy 36.149009 -404.323727) (xy 36.149007 -404.256306) (xy 36.157081 -404.18937) (xy 36.173113 -404.123882)
			(xy 36.196873 -404.060787) (xy 36.228019 -404.000991) (xy 36.266103 -403.945356) (xy 36.287964 -403.91969)
			(xy 36.293755 -403.912541) (xy 36.300271 -403.895353) (xy 36.300664 -403.886162) (xy 36.300664 -403.728682)
			(xy 36.301112 -403.718551) (xy 36.30885 -403.699825) (xy 36.323149 -403.685468) (xy 36.341843 -403.677654)
			(xy 36.351972 -403.67712) (xy 37.068252 -403.67712) (xy 37.078405 -403.677561) (xy 37.097161 -403.685345)
			(xy 37.111486 -403.699736) (xy 37.119184 -403.718527) (xy 37.11956 -403.728682) (xy 37.11956 -403.886162)
			(xy 37.119998 -403.895346) (xy 37.126493 -403.91253) (xy 37.13226 -403.91969) (xy 37.154147 -403.945337)
			(xy 37.192238 -404.000973) (xy 37.22339 -404.060771) (xy 37.247154 -404.123871) (xy 37.26319 -404.189362)
			(xy 37.271264 -404.256303) (xy 37.271262 -404.32373) (xy 37.263184 -404.39067) (xy 37.247145 -404.456161)
			(xy 37.223376 -404.519259) (xy 37.192221 -404.579055) (xy 37.154127 -404.634689) (xy 37.13226 -404.660354)
			(xy 37.126453 -404.667492) (xy 37.119946 -404.684688) (xy 37.11956 -404.693882) (xy 37.11956 -405.186134)
			(xy 37.119963 -405.195322) (xy 37.126483 -405.212506) (xy 37.13226 -405.219662) (xy 37.154119 -405.245331)
			(xy 37.192211 -405.300964) (xy 37.223364 -405.36076) (xy 37.24713 -405.423856) (xy 37.263168 -405.489345)
			(xy 37.271245 -405.556284) (xy 37.271245 -405.623707) (xy 37.263169 -405.690646) (xy 37.247133 -405.756135)
			(xy 37.223368 -405.819232) (xy 37.192216 -405.879028) (xy 37.154125 -405.934661) (xy 37.13226 -405.960326)
			(xy 37.126465 -405.967472) (xy 37.11995 -405.984662) (xy 37.11956 -405.993854) (xy 37.11956 -406.151334)
			(xy 37.119101 -406.161463) (xy 37.111362 -406.180185) (xy 37.097068 -406.19454) (xy 37.078379 -406.202358)
			(xy 37.068252 -406.202896) (xy 36.351972 -406.202896) (xy 36.341816 -406.202501) (xy 36.323062 -406.194696)
			(xy 36.308739 -406.180291) (xy 36.301041 -406.161493) (xy 36.300664 -406.151334) (xy 36.300664 -405.993854)
			(xy 36.300214 -405.984671) (xy 36.293726 -405.967487) (xy 36.287964 -405.960326) (xy 36.266095 -405.934665)
			(xy 36.228009 -405.879029) (xy 36.196861 -405.819232) (xy 36.173099 -405.756135) (xy 36.157065 -405.690645)
			(xy 36.14899 -405.623707) (xy 35.020933 -405.623707) (xy 34.992063 -405.679128) (xy 34.953975 -405.734763)
			(xy 34.932112 -405.760428) (xy 34.926322 -405.767578) (xy 34.919803 -405.784765) (xy 34.919412 -405.793956)
			(xy 34.919412 -406.286208) (xy 34.919816 -406.295396) (xy 34.926334 -406.31258) (xy 34.932112 -406.319736)
			(xy 34.953944 -406.345427) (xy 34.992033 -406.401058) (xy 35.023184 -406.460851) (xy 35.04695 -406.523945)
			(xy 35.062987 -406.58943) (xy 35.071065 -406.656366) (xy 35.071068 -406.723729) (xy 38.34913 -406.723729)
			(xy 38.349133 -406.656422) (xy 38.35718 -406.589598) (xy 38.373155 -406.524215) (xy 38.39683 -406.461209)
			(xy 38.427865 -406.401484) (xy 38.465815 -406.345897) (xy 38.487604 -406.320244) (xy 38.493407 -406.313104)
			(xy 38.499918 -406.295909) (xy 38.500304 -406.286716) (xy 38.500304 -405.793448) (xy 38.49987 -405.784263)
			(xy 38.493373 -405.767079) (xy 38.487604 -405.75992) (xy 38.465813 -405.734271) (xy 38.427867 -405.678683)
			(xy 38.396836 -405.618959) (xy 38.373165 -405.555954) (xy 38.357193 -405.490572) (xy 38.34915 -405.423749)
			(xy 38.34915 -405.356445) (xy 38.357194 -405.289622) (xy 38.373167 -405.22424) (xy 38.396838 -405.161236)
			(xy 38.42787 -405.101512) (xy 38.465817 -405.045925) (xy 38.487604 -405.020272) (xy 38.493395 -405.013123)
			(xy 38.499913 -404.995935) (xy 38.500304 -404.986744) (xy 38.500304 -404.828756) (xy 38.500686 -404.818599)
			(xy 38.508497 -404.799844) (xy 38.522905 -404.785523) (xy 38.541706 -404.777825) (xy 38.551866 -404.777448)
			(xy 39.268146 -404.777448) (xy 39.278277 -404.777889) (xy 39.297 -404.785634) (xy 39.311355 -404.799934)
			(xy 39.319171 -404.818627) (xy 39.319708 -404.828756) (xy 39.319708 -404.986744) (xy 39.320095 -404.995934)
			(xy 39.326624 -405.013118) (xy 39.332408 -405.020272) (xy 39.354193 -405.045927) (xy 39.392146 -405.101512)
			(xy 39.423182 -405.161234) (xy 39.446858 -405.224239) (xy 39.462832 -405.289621) (xy 39.470878 -405.356444)
			(xy 39.470878 -405.42375) (xy 39.462833 -405.490573) (xy 39.446859 -405.555956) (xy 39.423185 -405.61896)
			(xy 39.420718 -405.623708) (xy 40.548756 -405.623708) (xy 40.548757 -405.556283) (xy 40.556834 -405.489343)
			(xy 40.572872 -405.423853) (xy 40.596639 -405.360756) (xy 40.627793 -405.30096) (xy 40.665886 -405.245326)
			(xy 40.687752 -405.219662) (xy 40.693554 -405.212521) (xy 40.700064 -405.195327) (xy 40.700452 -405.186134)
			(xy 40.700452 -404.693882) (xy 40.700039 -404.684695) (xy 40.693526 -404.667512) (xy 40.687752 -404.660354)
			(xy 40.665908 -404.634672) (xy 40.627815 -404.579041) (xy 40.59666 -404.519248) (xy 40.572893 -404.456153)
			(xy 40.556854 -404.390665) (xy 40.548776 -404.323728) (xy 40.548774 -404.256305) (xy 40.556848 -404.189367)
			(xy 40.572883 -404.123879) (xy 40.596647 -404.060783) (xy 40.627798 -404.000987) (xy 40.665888 -403.945354)
			(xy 40.687752 -403.91969) (xy 40.693542 -403.91254) (xy 40.700059 -403.895353) (xy 40.700452 -403.886162)
			(xy 40.700452 -403.728682) (xy 40.700912 -403.718553) (xy 40.708648 -403.699829) (xy 40.722942 -403.685473)
			(xy 40.741633 -403.677656) (xy 40.75176 -403.67712) (xy 41.46804 -403.67712) (xy 41.478199 -403.677489)
			(xy 41.496956 -403.685302) (xy 41.511279 -403.699715) (xy 41.518974 -403.71852) (xy 41.519348 -403.728682)
			(xy 41.519348 -403.886162) (xy 41.519788 -403.895346) (xy 41.526282 -403.91253) (xy 41.532048 -403.91969)
			(xy 41.553935 -403.945337) (xy 41.592027 -404.000973) (xy 41.62318 -404.060771) (xy 41.646945 -404.12387)
			(xy 41.66298 -404.189362) (xy 41.671055 -404.256303) (xy 41.671053 -404.32373) (xy 41.662974 -404.39067)
			(xy 41.646935 -404.456161) (xy 41.623166 -404.519259) (xy 41.59201 -404.579056) (xy 41.553915 -404.63469)
			(xy 41.532048 -404.660354) (xy 41.52624 -404.667491) (xy 41.519733 -404.684688) (xy 41.519348 -404.693882)
			(xy 41.519348 -405.186134) (xy 41.519754 -405.195321) (xy 41.526272 -405.212505) (xy 41.532048 -405.219662)
			(xy 41.553908 -405.245331) (xy 41.592 -405.300964) (xy 41.623154 -405.360759) (xy 41.646921 -405.423856)
			(xy 41.662958 -405.489345) (xy 41.671036 -405.556283) (xy 41.671036 -405.623708) (xy 41.66296 -405.690646)
			(xy 41.646924 -405.756136) (xy 41.623158 -405.819233) (xy 41.592005 -405.879028) (xy 41.553913 -405.934662)
			(xy 41.532048 -405.960326) (xy 41.526251 -405.967471) (xy 41.519738 -405.984662) (xy 41.519348 -405.993854)
			(xy 41.519348 -406.151334) (xy 41.518901 -406.161464) (xy 41.51116 -406.180189) (xy 41.496861 -406.194544)
			(xy 41.478168 -406.20236) (xy 41.46804 -406.202896) (xy 40.75176 -406.202896) (xy 40.741603 -406.202511)
			(xy 40.722849 -406.194701) (xy 40.708527 -406.180294) (xy 40.700829 -406.161494) (xy 40.700452 -406.151334)
			(xy 40.700452 -405.993854) (xy 40.700004 -405.984671) (xy 40.693515 -405.967487) (xy 40.687752 -405.960326)
			(xy 40.66588 -405.934667) (xy 40.627788 -405.879032) (xy 40.596635 -405.819236) (xy 40.572869 -405.756138)
			(xy 40.556832 -405.690648) (xy 40.548756 -405.623708) (xy 39.420718 -405.623708) (xy 39.392149 -405.678683)
			(xy 39.354197 -405.734269) (xy 39.332408 -405.75992) (xy 39.326621 -405.767072) (xy 39.3201 -405.784257)
			(xy 39.319708 -405.793448) (xy 39.319708 -406.286716) (xy 39.320109 -406.295904) (xy 39.326629 -406.313088)
			(xy 39.332408 -406.320244) (xy 39.354166 -406.345921) (xy 39.392119 -406.401503) (xy 39.423157 -406.461222)
			(xy 39.446834 -406.524224) (xy 39.46281 -406.589604) (xy 39.470858 -406.656424) (xy 39.470861 -406.723728)
			(xy 39.470854 -406.723789) (xy 42.748899 -406.723789) (xy 42.748901 -406.656363) (xy 42.756981 -406.589422)
			(xy 42.773019 -406.523932) (xy 42.796787 -406.460833) (xy 42.827942 -406.401036) (xy 42.866034 -406.345401)
			(xy 42.8879 -406.319736) (xy 42.893706 -406.312598) (xy 42.900215 -406.295402) (xy 42.9006 -406.286208)
			(xy 42.9006 -405.793956) (xy 42.900211 -405.784767) (xy 42.893683 -405.767582) (xy 42.8879 -405.760428)
			(xy 42.866032 -405.734766) (xy 42.827944 -405.679131) (xy 42.796793 -405.619334) (xy 42.773029 -405.556237)
			(xy 42.756994 -405.490748) (xy 42.748918 -405.423809) (xy 42.748919 -405.356385) (xy 42.756995 -405.289446)
			(xy 42.773031 -405.223957) (xy 42.796795 -405.16086) (xy 42.827947 -405.101064) (xy 42.866036 -405.045429)
			(xy 42.8879 -405.019764) (xy 42.893694 -405.012617) (xy 42.90021 -404.995428) (xy 42.9006 -404.986236)
			(xy 42.9006 -404.828756) (xy 42.901049 -404.818644) (xy 42.908801 -404.799965) (xy 42.923109 -404.785672)
			(xy 42.941796 -404.777939) (xy 42.951908 -404.777448) (xy 43.668188 -404.777448) (xy 43.67829 -404.777994)
			(xy 43.696958 -404.785718) (xy 43.711251 -404.799995) (xy 43.718995 -404.818655) (xy 43.719496 -404.828756)
			(xy 43.719496 -404.986236) (xy 43.71989 -404.995425) (xy 43.726415 -405.012609) (xy 43.732196 -405.019764)
			(xy 43.754056 -405.045432) (xy 43.792145 -405.101066) (xy 43.823296 -405.160862) (xy 43.847061 -405.223959)
			(xy 43.863097 -405.289447) (xy 43.871173 -405.356385) (xy 43.871173 -405.423809) (xy 43.863098 -405.490747)
			(xy 43.847063 -405.556236) (xy 43.823299 -405.619332) (xy 43.792148 -405.679128) (xy 43.75406 -405.734763)
			(xy 43.732196 -405.760428) (xy 43.726405 -405.767577) (xy 43.719887 -405.784765) (xy 43.719496 -405.793956)
			(xy 43.719496 -406.286208) (xy 43.719903 -406.295395) (xy 43.726419 -406.31258) (xy 43.732196 -406.319736)
			(xy 43.754029 -406.345427) (xy 43.792119 -406.401058) (xy 43.823271 -406.46085) (xy 43.847037 -406.523944)
			(xy 43.863075 -406.58943) (xy 43.871153 -406.656365) (xy 43.871156 -406.72373) (xy 47.149194 -406.72373)
			(xy 47.149197 -406.656422) (xy 47.157245 -406.589596) (xy 47.173223 -406.524212) (xy 47.196901 -406.461206)
			(xy 47.227941 -406.401481) (xy 47.265897 -406.345896) (xy 47.287688 -406.320244) (xy 47.293489 -406.313102)
			(xy 47.300002 -406.295909) (xy 47.300388 -406.286716) (xy 47.300388 -405.793448) (xy 47.299958 -405.784263)
			(xy 47.293458 -405.767078) (xy 47.287688 -405.75992) (xy 47.265895 -405.734272) (xy 47.227943 -405.678686)
			(xy 47.196907 -405.618962) (xy 47.173232 -405.555957) (xy 47.157258 -405.490574) (xy 47.149214 -405.42375)
			(xy 47.149214 -405.356444) (xy 47.157259 -405.28962) (xy 47.173234 -405.224237) (xy 47.19691 -405.161232)
			(xy 47.227946 -405.101509) (xy 47.265899 -405.045924) (xy 47.287688 -405.020272) (xy 47.293478 -405.013122)
			(xy 47.299997 -404.995935) (xy 47.300388 -404.986744) (xy 47.300388 -404.828756) (xy 47.300785 -404.818601)
			(xy 47.308593 -404.79985) (xy 47.322997 -404.785528) (xy 47.341792 -404.777828) (xy 47.35195 -404.777448)
			(xy 48.06823 -404.777448) (xy 48.07836 -404.777902) (xy 48.097083 -404.785641) (xy 48.111439 -404.799937)
			(xy 48.119255 -404.818629) (xy 48.119792 -404.828756) (xy 48.119792 -404.986744) (xy 48.120183 -404.995933)
			(xy 48.12671 -405.013117) (xy 48.132492 -405.020272) (xy 48.154275 -405.045928) (xy 48.192222 -405.101514)
			(xy 48.223254 -405.161238) (xy 48.246925 -405.224242) (xy 48.262897 -405.289623) (xy 48.270941 -405.356445)
			(xy 48.270942 -405.423749) (xy 48.262899 -405.490571) (xy 48.246927 -405.555952) (xy 48.223256 -405.618957)
			(xy 48.192225 -405.67868) (xy 48.154279 -405.734267) (xy 48.132492 -405.75992) (xy 48.126704 -405.767071)
			(xy 48.120184 -405.784257) (xy 48.119792 -405.793448) (xy 48.119792 -406.286716) (xy 48.120196 -406.295904)
			(xy 48.126714 -406.313088) (xy 48.132492 -406.320244) (xy 48.154247 -406.345922) (xy 48.192195 -406.401506)
			(xy 48.223228 -406.461226) (xy 48.246901 -406.524227) (xy 48.262876 -406.589606) (xy 48.270922 -406.656425)
			(xy 48.270925 -406.723727) (xy 48.262884 -406.790547) (xy 48.246916 -406.855927) (xy 48.223248 -406.91893)
			(xy 48.19222 -406.978653) (xy 48.154277 -407.034239) (xy 48.132492 -407.059892) (xy 48.126715 -407.067051)
			(xy 48.120189 -407.084231) (xy 48.119792 -407.09342) (xy 48.119792 -407.251408) (xy 48.119385 -407.261564)
			(xy 48.111585 -407.280318) (xy 48.097184 -407.294641) (xy 48.078388 -407.302339) (xy 48.06823 -407.302716)
			(xy 47.35195 -407.302716) (xy 47.341821 -407.302231) (xy 47.323093 -407.294512) (xy 47.308733 -407.280224)
			(xy 47.30092 -407.261534) (xy 47.300388 -407.251408) (xy 47.300388 -407.09342) (xy 47.299971 -407.084233)
			(xy 47.293462 -407.067049) (xy 47.287688 -407.059892) (xy 47.265867 -407.034266) (xy 47.227916 -406.978677)
			(xy 47.196882 -406.91895) (xy 47.173209 -406.855942) (xy 47.157236 -406.790556) (xy 47.149194 -406.72373)
			(xy 43.871156 -406.72373) (xy 43.871156 -406.723787) (xy 43.863084 -406.790723) (xy 43.847051 -406.85621)
			(xy 43.823291 -406.919306) (xy 43.792143 -406.979101) (xy 43.754058 -407.034735) (xy 43.732196 -407.0604)
			(xy 43.726416 -407.067557) (xy 43.719892 -407.084739) (xy 43.719496 -407.093928) (xy 43.719496 -407.251408)
			(xy 43.71909 -407.261531) (xy 43.711339 -407.280236) (xy 43.697019 -407.29455) (xy 43.678312 -407.302294)
			(xy 43.668188 -407.302716) (xy 42.951908 -407.302716) (xy 42.941802 -407.302209) (xy 42.923127 -407.294477)
			(xy 42.908832 -407.280187) (xy 42.901094 -407.261514) (xy 42.9006 -407.251408) (xy 42.9006 -407.093928)
			(xy 42.900176 -407.084742) (xy 42.893672 -407.067558) (xy 42.8879 -407.0604) (xy 42.866005 -407.034761)
			(xy 42.827917 -406.979122) (xy 42.796768 -406.919323) (xy 42.773005 -406.856222) (xy 42.756972 -406.79073)
			(xy 42.748899 -406.723789) (xy 39.470854 -406.723789) (xy 39.462819 -406.790549) (xy 39.446848 -406.85593)
			(xy 39.423176 -406.918933) (xy 39.392144 -406.978656) (xy 39.354195 -407.034241) (xy 39.332408 -407.059892)
			(xy 39.326633 -407.067053) (xy 39.320105 -407.084231) (xy 39.319708 -407.09342) (xy 39.319708 -407.251408)
			(xy 39.319285 -407.261562) (xy 39.311488 -407.280313) (xy 39.297092 -407.294635) (xy 39.278302 -407.302336)
			(xy 39.268146 -407.302716) (xy 38.551866 -407.302716) (xy 38.541732 -407.3023) (xy 38.523001 -407.294553)
			(xy 38.508645 -407.280245) (xy 38.500835 -407.261541) (xy 38.500304 -407.251408) (xy 38.500304 -407.09342)
			(xy 38.499883 -407.084234) (xy 38.493377 -407.06705) (xy 38.487604 -407.059892) (xy 38.465786 -407.034265)
			(xy 38.42784 -406.978674) (xy 38.39681 -406.918947) (xy 38.373141 -406.855939) (xy 38.357171 -406.790554)
			(xy 38.34913 -406.723729) (xy 35.071068 -406.723729) (xy 35.071068 -406.723786) (xy 35.062996 -406.790722)
			(xy 35.046964 -406.856209) (xy 35.023204 -406.919305) (xy 34.992058 -406.9791) (xy 34.953974 -407.034735)
			(xy 34.932112 -407.0604) (xy 34.926334 -407.067559) (xy 34.919808 -407.084739) (xy 34.919412 -407.093928)
			(xy 34.919412 -407.251408) (xy 34.918922 -407.261516) (xy 34.911184 -407.280192) (xy 34.896888 -407.294486)
			(xy 34.878212 -407.302222) (xy 34.868104 -407.302716) (xy 34.151824 -407.302716) (xy 34.141705 -407.302265)
			(xy 34.123005 -407.294528) (xy 34.10869 -407.280222) (xy 34.100941 -407.261527) (xy 34.100516 -407.251408)
			(xy 34.100516 -407.093928) (xy 34.100089 -407.084743) (xy 34.093586 -407.067558) (xy 34.087816 -407.0604)
			(xy 34.06592 -407.034761) (xy 34.027831 -406.979123) (xy 33.996681 -406.919323) (xy 33.972918 -406.856223)
			(xy 33.956884 -406.790731) (xy 33.948811 -406.723789) (xy 30.670766 -406.723789) (xy 30.662731 -406.790549)
			(xy 30.646761 -406.855929) (xy 30.62309 -406.918933) (xy 30.592058 -406.978655) (xy 30.554111 -407.03424)
			(xy 30.532324 -407.059892) (xy 30.526551 -407.067054) (xy 30.520022 -407.084232) (xy 30.519624 -407.09342)
			(xy 30.519624 -407.251408) (xy 30.519185 -407.26156) (xy 30.511392 -407.280307) (xy 30.497001 -407.29463)
			(xy 30.478216 -407.302333) (xy 30.468062 -407.302716) (xy 29.751782 -407.302716) (xy 29.741649 -407.302287)
			(xy 29.722919 -407.294545) (xy 29.708561 -407.280241) (xy 29.700751 -407.261539) (xy 29.70022 -407.251408)
			(xy 29.70022 -407.09342) (xy 29.699796 -407.084234) (xy 29.693291 -407.06705) (xy 29.68752 -407.059892)
			(xy 29.665701 -407.034265) (xy 29.627755 -406.978675) (xy 29.596724 -406.918948) (xy 29.573054 -406.85594)
			(xy 29.557084 -406.790555) (xy 29.549042 -406.72373) (xy 11.18442 -406.72373) (xy 11.195631 -406.787312)
			(xy 11.223232 -406.989386) (xy 11.242977 -407.192379) (xy 11.254836 -407.395984) (xy 11.258791 -407.599896)
			(xy 11.254836 -407.803808) (xy 11.242977 -408.007413) (xy 11.223232 -408.210406) (xy 11.195631 -408.41248)
			(xy 11.160216 -408.613332) (xy 11.117039 -408.812659) (xy 11.066165 -409.010163) (xy 11.007672 -409.205545)
			(xy 10.941646 -409.398512) (xy 10.893241 -409.523886) (xy 27.348881 -409.523886) (xy 27.348884 -409.45646)
			(xy 27.356963 -409.38952) (xy 27.373002 -409.324029) (xy 27.396769 -409.26093) (xy 27.427923 -409.201133)
			(xy 27.466015 -409.145498) (xy 27.48788 -409.119832) (xy 27.493686 -409.112693) (xy 27.500196 -409.095498)
			(xy 27.50058 -409.086304) (xy 27.50058 -408.594052) (xy 27.500149 -408.584867) (xy 27.49365 -408.567682)
			(xy 27.48788 -408.560524) (xy 27.466009 -408.534865) (xy 27.427922 -408.479229) (xy 27.396772 -408.419432)
			(xy 27.37301 -408.356334) (xy 27.356975 -408.290845) (xy 27.3489 -408.223906) (xy 27.348901 -408.156482)
			(xy 27.356977 -408.089544) (xy 27.373013 -408.024054) (xy 27.396777 -407.960957) (xy 27.427928 -407.901161)
			(xy 27.466016 -407.845526) (xy 27.48788 -407.81986) (xy 27.493674 -407.812713) (xy 27.500191 -407.795524)
			(xy 27.50058 -407.786332) (xy 27.50058 -407.628852) (xy 27.501045 -407.618743) (xy 27.508795 -407.600067)
			(xy 27.523098 -407.585775) (xy 27.541778 -407.578038) (xy 27.551888 -407.577544) (xy 28.268168 -407.577544)
			(xy 28.278268 -407.57811) (xy 28.296935 -407.585826) (xy 28.311229 -407.600098) (xy 28.318975 -407.618753)
			(xy 28.319476 -407.628852) (xy 28.319476 -407.786332) (xy 28.319876 -407.79552) (xy 28.326397 -407.812704)
			(xy 28.332176 -407.81986) (xy 28.354033 -407.845531) (xy 28.392123 -407.901164) (xy 28.423276 -407.96096)
			(xy 28.447042 -408.024056) (xy 28.463078 -408.089544) (xy 28.471155 -408.156482) (xy 28.471156 -408.223906)
			(xy 28.46308 -408.290844) (xy 28.447045 -408.356333) (xy 28.423281 -408.419429) (xy 28.39213 -408.479225)
			(xy 28.35404 -408.534859) (xy 28.332176 -408.560524) (xy 28.326384 -408.567672) (xy 28.319867 -408.584861)
			(xy 28.319476 -408.594052) (xy 28.319476 -409.086304) (xy 28.319889 -409.095491) (xy 28.326401 -409.112675)
			(xy 28.332176 -409.119832) (xy 28.354005 -409.145526) (xy 28.392097 -409.201156) (xy 28.42325 -409.260948)
			(xy 28.447018 -409.324041) (xy 28.463056 -409.389527) (xy 28.471135 -409.456462) (xy 28.471139 -409.523884)
			(xy 28.463066 -409.59082) (xy 28.447034 -409.656307) (xy 28.423273 -409.719403) (xy 28.392125 -409.779198)
			(xy 28.354039 -409.834831) (xy 28.332176 -409.860496) (xy 28.326396 -409.867653) (xy 28.319872 -409.884835)
			(xy 28.319476 -409.894024) (xy 28.319476 -410.051504) (xy 28.319087 -410.06163) (xy 28.311333 -410.080338)
			(xy 28.297008 -410.094653) (xy 28.278294 -410.102394) (xy 28.268168 -410.102812) (xy 27.551888 -410.102812)
			(xy 27.54178 -410.102325) (xy 27.523104 -410.094585) (xy 27.50881 -410.080289) (xy 27.501074 -410.061612)
			(xy 27.50058 -410.051504) (xy 27.50058 -409.894024) (xy 27.500163 -409.884837) (xy 27.493655 -409.867653)
			(xy 27.48788 -409.860496) (xy 27.465981 -409.83486) (xy 27.427895 -409.77922) (xy 27.396747 -409.71942)
			(xy 27.372986 -409.656319) (xy 27.356953 -409.590827) (xy 27.348881 -409.523886) (xy 10.893241 -409.523886)
			(xy 10.868188 -409.588774) (xy 10.787407 -409.776045) (xy 10.699426 -409.960042) (xy 10.604376 -410.14049)
			(xy 10.502401 -410.317116) (xy 10.393653 -410.489655) (xy 10.301759 -410.623641) (xy 29.549054 -410.623641)
			(xy 29.549055 -410.556335) (xy 29.5571 -410.489512) (xy 29.573074 -410.424129) (xy 29.596748 -410.361124)
			(xy 29.627782 -410.301399) (xy 29.665732 -410.245812) (xy 29.68752 -410.22016) (xy 29.693318 -410.213016)
			(xy 29.699831 -410.195825) (xy 29.70022 -410.186632) (xy 29.70022 -409.693364) (xy 29.699823 -409.684176)
			(xy 29.6933 -409.666992) (xy 29.68752 -409.659836) (xy 29.665745 -409.634174) (xy 29.627797 -409.578588)
			(xy 29.596764 -409.518866) (xy 29.573091 -409.455863) (xy 29.557118 -409.390482) (xy 29.549073 -409.323661)
			(xy 29.549072 -409.256357) (xy 29.557115 -409.189536) (xy 29.573086 -409.124154) (xy 29.596757 -409.06115)
			(xy 29.627787 -409.001427) (xy 29.665734 -408.94584) (xy 29.68752 -408.920188) (xy 29.693306 -408.913036)
			(xy 29.699827 -408.895851) (xy 29.70022 -408.88666) (xy 29.70022 -408.728672) (xy 29.700599 -408.718514)
			(xy 29.708408 -408.699757) (xy 29.722817 -408.685434) (xy 29.741621 -408.677738) (xy 29.751782 -408.677364)
			(xy 30.468062 -408.677364) (xy 30.478189 -408.677859) (xy 30.496914 -408.685578) (xy 30.511272 -408.699863)
			(xy 30.519089 -408.718547) (xy 30.519624 -408.728672) (xy 30.519624 -408.88666) (xy 30.520048 -408.895846)
			(xy 30.526551 -408.913031) (xy 30.532324 -408.920188) (xy 30.554125 -408.94583) (xy 30.592075 -409.001417)
			(xy 30.62311 -409.061142) (xy 30.646784 -409.124148) (xy 30.662757 -409.189531) (xy 30.670801 -409.256356)
			(xy 30.6708 -409.323662) (xy 30.662754 -409.390486) (xy 30.646779 -409.45587) (xy 30.623103 -409.518875)
			(xy 30.62053 -409.523827) (xy 31.749176 -409.523827) (xy 31.749179 -409.456519) (xy 31.757227 -409.389693)
			(xy 31.773205 -409.324309) (xy 31.796883 -409.261302) (xy 31.827922 -409.201578) (xy 31.865877 -409.145992)
			(xy 31.887668 -409.12034) (xy 31.893481 -409.113207) (xy 31.899984 -409.096007) (xy 31.900368 -409.086812)
			(xy 31.900368 -408.593544) (xy 31.899922 -408.584361) (xy 31.893432 -408.567177) (xy 31.887668 -408.560016)
			(xy 31.865872 -408.534371) (xy 31.827921 -408.478784) (xy 31.796887 -408.41906) (xy 31.773213 -408.356054)
			(xy 31.75724 -408.290671) (xy 31.749196 -408.223847) (xy 31.749197 -408.156541) (xy 31.757242 -408.089717)
			(xy 31.773217 -408.024334) (xy 31.796892 -407.961329) (xy 31.827927 -407.901606) (xy 31.865879 -407.84602)
			(xy 31.887668 -407.820368) (xy 31.893469 -407.813226) (xy 31.899979 -407.796033) (xy 31.900368 -407.78684)
			(xy 31.900368 -407.628852) (xy 31.900782 -407.618699) (xy 31.908587 -407.599952) (xy 31.922985 -407.585631)
			(xy 31.941775 -407.577927) (xy 31.95193 -407.577544) (xy 32.66821 -407.577544) (xy 32.678338 -407.578019)
			(xy 32.69706 -407.58575) (xy 32.711416 -407.60004) (xy 32.719234 -407.618727) (xy 32.719772 -407.628852)
			(xy 32.719772 -407.78684) (xy 32.720169 -407.796028) (xy 32.726693 -407.813212) (xy 32.732472 -407.820368)
			(xy 32.754252 -407.846027) (xy 32.7922 -407.901612) (xy 32.823233 -407.961335) (xy 32.846906 -408.024339)
			(xy 32.862879 -408.08972) (xy 32.870924 -408.156542) (xy 32.870924 -408.223846) (xy 32.862881 -408.290668)
			(xy 32.846909 -408.35605) (xy 32.823238 -408.419054) (xy 32.792206 -408.478777) (xy 32.754259 -408.534364)
			(xy 32.732472 -408.560016) (xy 32.726682 -408.567166) (xy 32.720164 -408.584353) (xy 32.719772 -408.593544)
			(xy 32.719772 -409.086812) (xy 32.720183 -409.095999) (xy 32.726697 -409.113183) (xy 32.732472 -409.12034)
			(xy 32.754224 -409.146022) (xy 32.792173 -409.201604) (xy 32.823207 -409.261324) (xy 32.846881 -409.324324)
			(xy 32.862857 -409.389703) (xy 32.870903 -409.456522) (xy 32.870907 -409.523824) (xy 32.862866 -409.590644)
			(xy 32.846897 -409.656024) (xy 32.823229 -409.719027) (xy 32.792201 -409.778749) (xy 32.754257 -409.834336)
			(xy 32.732472 -409.859988) (xy 32.726652 -409.867116) (xy 32.720152 -409.88432) (xy 32.719772 -409.893516)
			(xy 32.719772 -410.051504) (xy 32.719381 -410.061662) (xy 32.711579 -410.08042) (xy 32.697172 -410.094744)
			(xy 32.67837 -410.102438) (xy 32.66821 -410.102812) (xy 31.95193 -410.102812) (xy 31.941812 -410.102251)
			(xy 31.923101 -410.094542) (xy 31.908745 -410.080279) (xy 31.900916 -410.061619) (xy 31.900368 -410.051504)
			(xy 31.900368 -409.893516) (xy 31.899935 -409.884332) (xy 31.893436 -409.867148) (xy 31.887668 -409.859988)
			(xy 31.865844 -409.834366) (xy 31.827894 -409.778775) (xy 31.796861 -409.719048) (xy 31.773189 -409.65604)
			(xy 31.757217 -409.590654) (xy 31.749176 -409.523827) (xy 30.62053 -409.523827) (xy 30.592066 -409.578598)
			(xy 30.554113 -409.634184) (xy 30.532324 -409.659836) (xy 30.526532 -409.666985) (xy 30.520014 -409.684172)
			(xy 30.519624 -409.693364) (xy 30.519624 -410.186632) (xy 30.520014 -410.195821) (xy 30.526541 -410.213006)
			(xy 30.532324 -410.22016) (xy 30.554097 -410.245825) (xy 30.592049 -410.301408) (xy 30.623085 -410.36113)
			(xy 30.64676 -410.424133) (xy 30.662735 -410.489514) (xy 30.670781 -410.556336) (xy 30.670783 -410.62364)
			(xy 30.670776 -410.623701) (xy 33.948822 -410.623701) (xy 33.948823 -410.556275) (xy 33.956901 -410.489336)
			(xy 33.972939 -410.423846) (xy 33.996705 -410.360748) (xy 34.027859 -410.300951) (xy 34.065951 -410.245317)
			(xy 34.087816 -410.219652) (xy 34.093617 -410.21251) (xy 34.100129 -410.195317) (xy 34.100516 -410.186124)
			(xy 34.100516 -409.693872) (xy 34.100116 -409.684684) (xy 34.093595 -409.6675) (xy 34.087816 -409.660344)
			(xy 34.065963 -409.634669) (xy 34.027873 -409.579037) (xy 33.996721 -409.519242) (xy 33.972955 -409.456146)
			(xy 33.956919 -409.390658) (xy 33.948842 -409.323721) (xy 33.948841 -409.256297) (xy 33.956915 -409.18936)
			(xy 33.97295 -409.123871) (xy 33.996714 -409.060775) (xy 34.027864 -409.000979) (xy 34.065952 -408.945345)
			(xy 34.087816 -408.91968) (xy 34.093605 -408.91253) (xy 34.100124 -408.895343) (xy 34.100516 -408.886152)
			(xy 34.100516 -408.728672) (xy 34.100962 -408.718559) (xy 34.108712 -408.699878) (xy 34.123021 -408.685583)
			(xy 34.141711 -408.677852) (xy 34.151824 -408.677364) (xy 34.868104 -408.677364) (xy 34.878209 -408.677881)
			(xy 34.89688 -408.685613) (xy 34.911173 -408.6999) (xy 34.918914 -408.718568) (xy 34.919412 -408.728672)
			(xy 34.919412 -408.886152) (xy 34.919842 -408.895337) (xy 34.926342 -408.912522) (xy 34.932112 -408.91968)
			(xy 34.953987 -408.945336) (xy 34.992075 -409.000972) (xy 35.023224 -409.06077) (xy 35.046987 -409.123868)
			(xy 35.063022 -409.189358) (xy 35.071096 -409.256297) (xy 35.071095 -409.323721) (xy 35.063018 -409.39066)
			(xy 35.046982 -409.45615) (xy 35.023217 -409.519247) (xy 35.0208 -409.523886) (xy 36.148969 -409.523886)
			(xy 36.148972 -409.45646) (xy 36.157051 -409.38952) (xy 36.173089 -409.324029) (xy 36.196856 -409.260931)
			(xy 36.228009 -409.201134) (xy 36.266099 -409.145498) (xy 36.287964 -409.119832) (xy 36.29378 -409.112701)
			(xy 36.300281 -409.095499) (xy 36.300664 -409.086304) (xy 36.300664 -408.594052) (xy 36.300215 -408.584869)
			(xy 36.293727 -408.567685) (xy 36.287964 -408.560524) (xy 36.266093 -408.534865) (xy 36.228007 -408.479228)
			(xy 36.196859 -408.419431) (xy 36.173097 -408.356334) (xy 36.157063 -408.290844) (xy 36.148988 -408.223906)
			(xy 36.148989 -408.156482) (xy 36.157065 -408.089544) (xy 36.1731 -408.024055) (xy 36.196864 -407.960958)
			(xy 36.228014 -407.901161) (xy 36.266101 -407.845526) (xy 36.287964 -407.81986) (xy 36.293768 -407.81272)
			(xy 36.300276 -407.795525) (xy 36.300664 -407.786332) (xy 36.300664 -407.628852) (xy 36.301145 -407.618745)
			(xy 36.308892 -407.600072) (xy 36.323189 -407.585781) (xy 36.341864 -407.578041) (xy 36.351972 -407.577544)
			(xy 37.068252 -407.577544) (xy 37.078351 -407.578123) (xy 37.097017 -407.585835) (xy 37.111312 -407.600102)
			(xy 37.119058 -407.618754) (xy 37.11956 -407.628852) (xy 37.11956 -407.786332) (xy 37.119964 -407.79552)
			(xy 37.126483 -407.812703) (xy 37.13226 -407.81986) (xy 37.154118 -407.845531) (xy 37.192209 -407.901164)
			(xy 37.223362 -407.960959) (xy 37.247129 -408.024055) (xy 37.263166 -408.089544) (xy 37.271243 -408.156482)
			(xy 37.271244 -408.223906) (xy 37.263168 -408.290844) (xy 37.247132 -408.356333) (xy 37.223367 -408.41943)
			(xy 37.192215 -408.479226) (xy 37.154125 -408.534859) (xy 37.13226 -408.560524) (xy 37.126466 -408.567671)
			(xy 37.119951 -408.58486) (xy 37.11956 -408.594052) (xy 37.11956 -409.086304) (xy 37.119977 -409.09549)
			(xy 37.126487 -409.112674) (xy 37.13226 -409.119832) (xy 37.15409 -409.145526) (xy 37.192182 -409.201155)
			(xy 37.223337 -409.260947) (xy 37.247105 -409.32404) (xy 37.263144 -409.389526) (xy 37.271223 -409.456462)
			(xy 37.271227 -409.523884) (xy 37.263154 -409.59082) (xy 37.247121 -409.656308) (xy 37.223359 -409.719403)
			(xy 37.19221 -409.779198) (xy 37.154123 -409.834831) (xy 37.13226 -409.860496) (xy 37.126478 -409.867651)
			(xy 37.119955 -409.884834) (xy 37.11956 -409.894024) (xy 37.11956 -410.051504) (xy 37.119186 -410.061632)
			(xy 37.111429 -410.080343) (xy 37.097099 -410.094659) (xy 37.07838 -410.102396) (xy 37.068252 -410.102812)
			(xy 36.351972 -410.102812) (xy 36.341863 -410.102338) (xy 36.323186 -410.094594) (xy 36.308893 -410.080293)
			(xy 36.301157 -410.061613) (xy 36.300664 -410.051504) (xy 36.300664 -409.894024) (xy 36.300228 -409.88484)
			(xy 36.293731 -409.867656) (xy 36.287964 -409.860496) (xy 36.266066 -409.834859) (xy 36.227981 -409.77922)
			(xy 36.196834 -409.719419) (xy 36.173073 -409.656319) (xy 36.157041 -409.590827) (xy 36.148969 -409.523886)
			(xy 35.0208 -409.523886) (xy 34.992066 -409.579044) (xy 34.953976 -409.634679) (xy 34.932112 -409.660344)
			(xy 34.926316 -409.667489) (xy 34.9198 -409.68468) (xy 34.919412 -409.693872) (xy 34.919412 -410.186124)
			(xy 34.919808 -410.195313) (xy 34.926331 -410.212497) (xy 34.932112 -410.219652) (xy 34.95396 -410.24533)
			(xy 34.992048 -410.300963) (xy 35.023199 -410.360758) (xy 35.046964 -410.423853) (xy 35.063 -410.48934)
			(xy 35.071077 -410.556277) (xy 35.071078 -410.623641) (xy 38.349141 -410.623641) (xy 38.349143 -410.556335)
			(xy 38.357188 -410.489512) (xy 38.373162 -410.424129) (xy 38.396835 -410.361124) (xy 38.427868 -410.3014)
			(xy 38.465816 -410.245813) (xy 38.487604 -410.22016) (xy 38.493401 -410.213015) (xy 38.499915 -410.195824)
			(xy 38.500304 -410.186632) (xy 38.500304 -409.693364) (xy 38.49991 -409.684175) (xy 38.493385 -409.666991)
			(xy 38.487604 -409.659836) (xy 38.465829 -409.634174) (xy 38.427882 -409.578588) (xy 38.39685 -409.518865)
			(xy 38.373178 -409.455862) (xy 38.357206 -409.390482) (xy 38.349161 -409.323661) (xy 38.34916 -409.256357)
			(xy 38.357202 -409.189536) (xy 38.373173 -409.124155) (xy 38.396843 -409.061151) (xy 38.427873 -409.001428)
			(xy 38.465818 -408.945841) (xy 38.487604 -408.920188) (xy 38.493389 -408.913034) (xy 38.49991 -408.89585)
			(xy 38.500304 -408.88666) (xy 38.500304 -408.728672) (xy 38.500699 -408.718516) (xy 38.508504 -408.699762)
			(xy 38.522909 -408.685439) (xy 38.541707 -408.677741) (xy 38.551866 -408.677364) (xy 39.268146 -408.677364)
			(xy 39.278279 -408.67779) (xy 39.297005 -408.685537) (xy 39.311361 -408.699842) (xy 39.319174 -408.718541)
			(xy 39.319708 -408.728672) (xy 39.319708 -408.88666) (xy 39.320136 -408.895845) (xy 39.326637 -408.91303)
			(xy 39.332408 -408.920188) (xy 39.354209 -408.94583) (xy 39.392161 -409.001416) (xy 39.423197 -409.061141)
			(xy 39.446871 -409.124147) (xy 39.462845 -409.189531) (xy 39.470889 -409.256356) (xy 39.470888 -409.323663)
			(xy 39.462842 -409.390487) (xy 39.446866 -409.45587) (xy 39.423189 -409.518876) (xy 39.420585 -409.523887)
			(xy 40.548735 -409.523887) (xy 40.548738 -409.456459) (xy 40.556818 -409.389518) (xy 40.572859 -409.324026)
			(xy 40.59663 -409.260927) (xy 40.627788 -409.20113) (xy 40.665884 -409.145496) (xy 40.687752 -409.119832)
			(xy 40.693566 -409.1127) (xy 40.700069 -409.095499) (xy 40.700452 -409.086304) (xy 40.700452 -408.594052)
			(xy 40.700005 -408.584869) (xy 40.693516 -408.567685) (xy 40.687752 -408.560524) (xy 40.665878 -408.534866)
			(xy 40.627786 -408.479232) (xy 40.596633 -408.419435) (xy 40.572867 -408.356337) (xy 40.556831 -408.290847)
			(xy 40.548755 -408.223907) (xy 40.548755 -408.156481) (xy 40.556833 -408.089542) (xy 40.572871 -408.024051)
			(xy 40.596638 -407.960954) (xy 40.627793 -407.901158) (xy 40.665886 -407.845524) (xy 40.687752 -407.81986)
			(xy 40.693554 -407.812719) (xy 40.700064 -407.795525) (xy 40.700452 -407.786332) (xy 40.700452 -407.628852)
			(xy 40.700945 -407.618746) (xy 40.708689 -407.600076) (xy 40.722983 -407.585785) (xy 40.741654 -407.578043)
			(xy 40.75176 -407.577544) (xy 41.46804 -407.577544) (xy 41.478144 -407.578051) (xy 41.496813 -407.585791)
			(xy 41.511104 -407.600081) (xy 41.518847 -407.618748) (xy 41.519348 -407.628852) (xy 41.519348 -407.786332)
			(xy 41.519755 -407.795519) (xy 41.526272 -407.812703) (xy 41.532048 -407.81986) (xy 41.553906 -407.845531)
			(xy 41.591998 -407.901163) (xy 41.623152 -407.960958) (xy 41.646919 -408.024055) (xy 41.662957 -408.089543)
			(xy 41.671034 -408.156482) (xy 41.671035 -408.223906) (xy 41.662959 -408.290845) (xy 41.646923 -408.356334)
			(xy 41.623157 -408.419431) (xy 41.592004 -408.479226) (xy 41.553913 -408.53486) (xy 41.532048 -408.560524)
			(xy 41.526252 -408.56767) (xy 41.519739 -408.58486) (xy 41.519348 -408.594052) (xy 41.519348 -409.086304)
			(xy 41.519768 -409.09549) (xy 41.526276 -409.112674) (xy 41.532048 -409.119832) (xy 41.553878 -409.145526)
			(xy 41.591972 -409.201155) (xy 41.623127 -409.260947) (xy 41.646895 -409.32404) (xy 41.662935 -409.389526)
			(xy 41.671014 -409.456462) (xy 41.671018 -409.523884) (xy 41.662945 -409.590821) (xy 41.646911 -409.656308)
			(xy 41.623149 -409.719404) (xy 41.591999 -409.779199) (xy 41.553912 -409.834832) (xy 41.532048 -409.860496)
			(xy 41.526264 -409.86765) (xy 41.519743 -409.884834) (xy 41.519348 -409.894024) (xy 41.519348 -410.051504)
			(xy 41.518819 -410.061607) (xy 41.511089 -410.080276) (xy 41.496806 -410.094569) (xy 41.478143 -410.102312)
			(xy 41.46804 -410.102812) (xy 40.75176 -410.102812) (xy 40.74165 -410.102348) (xy 40.722973 -410.094599)
			(xy 40.70868 -410.080296) (xy 40.700945 -410.061614) (xy 40.700452 -410.051504) (xy 40.700452 -409.894024)
			(xy 40.700019 -409.884839) (xy 40.69352 -409.867655) (xy 40.687752 -409.860496) (xy 40.665851 -409.834861)
			(xy 40.62776 -409.779223) (xy 40.596608 -409.719423) (xy 40.572843 -409.656322) (xy 40.556809 -409.590829)
			(xy 40.548735 -409.523887) (xy 39.420585 -409.523887) (xy 39.392152 -409.578599) (xy 39.354198 -409.634185)
			(xy 39.332408 -409.659836) (xy 39.326615 -409.666984) (xy 39.320098 -409.684172) (xy 39.319708 -409.693364)
			(xy 39.319708 -410.186632) (xy 39.320101 -410.195821) (xy 39.326626 -410.213005) (xy 39.332408 -410.22016)
			(xy 39.354182 -410.245824) (xy 39.392134 -410.301408) (xy 39.423171 -410.361129) (xy 39.446847 -410.424132)
			(xy 39.462823 -410.489513) (xy 39.470869 -410.556336) (xy 39.470871 -410.62364) (xy 39.470864 -410.6237)
			(xy 42.74891 -410.6237) (xy 42.748911 -410.556276) (xy 42.756989 -410.489336) (xy 42.773026 -410.423846)
			(xy 42.796792 -410.360749) (xy 42.827944 -410.300952) (xy 42.866035 -410.245317) (xy 42.8879 -410.219652)
			(xy 42.893699 -410.212509) (xy 42.900212 -410.195317) (xy 42.9006 -410.186124) (xy 42.9006 -409.693872)
			(xy 42.900204 -409.684683) (xy 42.89368 -409.667499) (xy 42.8879 -409.660344) (xy 42.866048 -409.634669)
			(xy 42.827959 -409.579036) (xy 42.796808 -409.519241) (xy 42.773043 -409.456145) (xy 42.757006 -409.390658)
			(xy 42.74893 -409.32372) (xy 42.748928 -409.256298) (xy 42.757003 -409.18936) (xy 42.773037 -409.123872)
			(xy 42.7968 -409.060775) (xy 42.827949 -409.00098) (xy 42.866037 -408.945345) (xy 42.8879 -408.91968)
			(xy 42.893688 -408.912528) (xy 42.900208 -408.895343) (xy 42.9006 -408.886152) (xy 42.9006 -408.728672)
			(xy 42.901062 -408.718561) (xy 42.908809 -408.699883) (xy 42.923113 -408.685589) (xy 42.941797 -408.677855)
			(xy 42.951908 -408.677364) (xy 43.668188 -408.677364) (xy 43.678292 -408.677894) (xy 43.696963 -408.685621)
			(xy 43.711257 -408.699904) (xy 43.718998 -408.718569) (xy 43.719496 -408.728672) (xy 43.719496 -408.886152)
			(xy 43.71993 -408.895337) (xy 43.726427 -408.912521) (xy 43.732196 -408.91968) (xy 43.754072 -408.945335)
			(xy 43.792161 -409.000971) (xy 43.823311 -409.060769) (xy 43.847075 -409.123867) (xy 43.863109 -409.189357)
			(xy 43.871184 -409.256297) (xy 43.871183 -409.323721) (xy 43.863106 -409.390661) (xy 43.847069 -409.45615)
			(xy 43.823304 -409.519248) (xy 43.792151 -409.579044) (xy 43.754061 -409.634679) (xy 43.732196 -409.660344)
			(xy 43.726398 -409.667488) (xy 43.719884 -409.684679) (xy 43.719496 -409.693872) (xy 43.719496 -410.186124)
			(xy 43.719895 -410.195312) (xy 43.726417 -410.212497) (xy 43.732196 -410.219652) (xy 43.754044 -410.24533)
			(xy 43.792134 -410.300963) (xy 43.823285 -410.360757) (xy 43.847051 -410.423852) (xy 43.863087 -410.48934)
			(xy 43.871165 -410.556277) (xy 43.871166 -410.623642) (xy 47.149205 -410.623642) (xy 47.149207 -410.556334)
			(xy 47.157253 -410.48951) (xy 47.173229 -410.424126) (xy 47.196906 -410.361121) (xy 47.227944 -410.301397)
			(xy 47.265898 -410.245812) (xy 47.287688 -410.22016) (xy 47.293483 -410.213013) (xy 47.299999 -410.195824)
			(xy 47.300388 -410.186632) (xy 47.300388 -409.693364) (xy 47.299998 -409.684175) (xy 47.293471 -409.66699)
			(xy 47.287688 -409.659836) (xy 47.265911 -409.634175) (xy 47.227958 -409.578591) (xy 47.196922 -409.518869)
			(xy 47.173246 -409.455866) (xy 47.157271 -409.390484) (xy 47.149225 -409.323662) (xy 47.149224 -409.256357)
			(xy 47.157268 -409.189534) (xy 47.173241 -409.124152) (xy 47.196914 -409.061148) (xy 47.227949 -409.001425)
			(xy 47.2659 -408.945839) (xy 47.287688 -408.920188) (xy 47.293471 -408.913033) (xy 47.299994 -408.89585)
			(xy 47.300388 -408.88666) (xy 47.300388 -408.728672) (xy 47.300798 -408.718518) (xy 47.308601 -408.699767)
			(xy 47.323001 -408.685445) (xy 47.341793 -408.677744) (xy 47.35195 -408.677364) (xy 48.06823 -408.677364)
			(xy 48.078362 -408.677803) (xy 48.097088 -408.685545) (xy 48.111444 -408.699846) (xy 48.119258 -408.718542)
			(xy 48.119792 -408.728672) (xy 48.119792 -408.88666) (xy 48.120223 -408.895845) (xy 48.126722 -408.913029)
			(xy 48.132492 -408.920188) (xy 48.154291 -408.945831) (xy 48.192237 -409.001419) (xy 48.223268 -409.061145)
			(xy 48.246939 -409.12415) (xy 48.26291 -409.189533) (xy 48.270953 -409.256356) (xy 48.270952 -409.323662)
			(xy 48.262907 -409.390485) (xy 48.246933 -409.455867) (xy 48.223261 -409.518872) (xy 48.192228 -409.578596)
			(xy 48.15428 -409.634183) (xy 48.132492 -409.659836) (xy 48.126697 -409.666982) (xy 48.120182 -409.684172)
			(xy 48.119792 -409.693364) (xy 48.119792 -410.186632) (xy 48.120188 -410.195821) (xy 48.126712 -410.213005)
			(xy 48.132492 -410.22016) (xy 48.154263 -410.245825) (xy 48.19221 -410.301411) (xy 48.223243 -410.361133)
			(xy 48.246915 -410.424135) (xy 48.262888 -410.489516) (xy 48.270933 -410.556336) (xy 48.270934 -410.62364)
			(xy 48.262892 -410.690461) (xy 48.246922 -410.755842) (xy 48.223252 -410.818845) (xy 48.192223 -410.878569)
			(xy 48.154278 -410.934155) (xy 48.132492 -410.959808) (xy 48.126709 -410.966963) (xy 48.120186 -410.984146)
			(xy 48.119792 -410.993336) (xy 48.119792 -411.151324) (xy 48.119398 -411.161481) (xy 48.111593 -411.180235)
			(xy 48.097188 -411.194558) (xy 48.078389 -411.202255) (xy 48.06823 -411.202632) (xy 47.35195 -411.202632)
			(xy 47.341823 -411.202132) (xy 47.323098 -411.194415) (xy 47.308739 -411.180132) (xy 47.300923 -411.161448)
			(xy 47.300388 -411.151324) (xy 47.300388 -410.993336) (xy 47.299963 -410.98415) (xy 47.29346 -410.966966)
			(xy 47.287688 -410.959808) (xy 47.265883 -410.934169) (xy 47.227932 -410.878582) (xy 47.196896 -410.818857)
			(xy 47.173222 -410.755851) (xy 47.157249 -410.690466) (xy 47.149205 -410.623642) (xy 43.871166 -410.623642)
			(xy 43.871166 -410.623699) (xy 43.863092 -410.690636) (xy 43.847058 -410.756125) (xy 43.823295 -410.819221)
			(xy 43.792146 -410.879017) (xy 43.754059 -410.934651) (xy 43.732196 -410.960316) (xy 43.72641 -410.967468)
			(xy 43.719889 -410.984653) (xy 43.719496 -410.993844) (xy 43.719496 -411.151324) (xy 43.719035 -411.161435)
			(xy 43.711288 -411.180114) (xy 43.696984 -411.194408) (xy 43.678299 -411.202142) (xy 43.668188 -411.202632)
			(xy 42.951908 -411.202632) (xy 42.941804 -411.202109) (xy 42.923132 -411.19438) (xy 42.908838 -411.180095)
			(xy 42.901097 -411.161428) (xy 42.9006 -411.151324) (xy 42.9006 -410.993844) (xy 42.900169 -410.984659)
			(xy 42.89367 -410.967474) (xy 42.8879 -410.960316) (xy 42.86602 -410.934664) (xy 42.827932 -410.879027)
			(xy 42.796782 -410.819229) (xy 42.773019 -410.756131) (xy 42.756984 -410.69064) (xy 42.74891 -410.6237)
			(xy 39.470864 -410.6237) (xy 39.462827 -410.690463) (xy 39.446854 -410.755845) (xy 39.423181 -410.818849)
			(xy 39.392147 -410.878572) (xy 39.354196 -410.934157) (xy 39.332408 -410.959808) (xy 39.326626 -410.966964)
			(xy 39.320103 -410.984146) (xy 39.319708 -410.993336) (xy 39.319708 -411.151324) (xy 39.319298 -411.161479)
			(xy 39.311496 -411.18023) (xy 39.297096 -411.194552) (xy 39.278303 -411.202253) (xy 39.268146 -411.202632)
			(xy 38.551866 -411.202632) (xy 38.541734 -411.202201) (xy 38.523006 -411.194456) (xy 38.50865 -411.180153)
			(xy 38.500837 -411.161454) (xy 38.500304 -411.151324) (xy 38.500304 -410.993336) (xy 38.499876 -410.984151)
			(xy 38.493375 -410.966966) (xy 38.487604 -410.959808) (xy 38.465802 -410.934168) (xy 38.427856 -410.878579)
			(xy 38.396825 -410.818854) (xy 38.373155 -410.755848) (xy 38.357184 -410.690464) (xy 38.349141 -410.623641)
			(xy 35.071078 -410.623641) (xy 35.071078 -410.623699) (xy 35.063004 -410.690636) (xy 35.046971 -410.756124)
			(xy 35.023209 -410.81922) (xy 34.992061 -410.879016) (xy 34.953975 -410.934651) (xy 34.932112 -410.960316)
			(xy 34.926328 -410.96747) (xy 34.919805 -410.984654) (xy 34.919412 -410.993844) (xy 34.919412 -411.151324)
			(xy 34.918935 -411.161433) (xy 34.911192 -411.180109) (xy 34.896893 -411.194403) (xy 34.878213 -411.202139)
			(xy 34.868104 -411.202632) (xy 34.151824 -411.202632) (xy 34.141721 -411.202096) (xy 34.123049 -411.194372)
			(xy 34.108755 -411.180091) (xy 34.101013 -411.161427) (xy 34.100516 -411.151324) (xy 34.100516 -410.993844)
			(xy 34.100081 -410.98466) (xy 34.093584 -410.967475) (xy 34.087816 -410.960316) (xy 34.065936 -410.934664)
			(xy 34.027846 -410.879028) (xy 33.996696 -410.81923) (xy 33.972932 -410.756131) (xy 33.956897 -410.690641)
			(xy 33.948822 -410.623701) (xy 30.670776 -410.623701) (xy 30.66274 -410.690462) (xy 30.646767 -410.755844)
			(xy 30.623095 -410.818848) (xy 30.592061 -410.878571) (xy 30.554112 -410.934156) (xy 30.532324 -410.959808)
			(xy 30.526544 -410.966965) (xy 30.520019 -410.984146) (xy 30.519624 -410.993336) (xy 30.519624 -411.151324)
			(xy 30.519199 -411.161477) (xy 30.5114 -411.180225) (xy 30.497005 -411.194547) (xy 30.478217 -411.20225)
			(xy 30.468062 -411.202632) (xy 29.751782 -411.202632) (xy 29.741651 -411.202188) (xy 29.722924 -411.194449)
			(xy 29.708567 -411.180149) (xy 29.700753 -411.161453) (xy 29.70022 -411.151324) (xy 29.70022 -410.993336)
			(xy 29.699788 -410.984151) (xy 29.693289 -410.966967) (xy 29.68752 -410.959808) (xy 29.665717 -410.934169)
			(xy 29.62777 -410.87858) (xy 29.596738 -410.818854) (xy 29.573067 -410.755848) (xy 29.557096 -410.690465)
			(xy 29.549054 -410.623641) (xy 10.301759 -410.623641) (xy 10.278298 -410.657848) (xy 10.156507 -410.821441)
			(xy 10.028464 -410.980189) (xy 9.894363 -411.133853) (xy 9.754403 -411.282201) (xy 9.608797 -411.42501)
			(xy 9.457763 -411.562067) (xy 9.301528 -411.693163) (xy 9.140327 -411.818103) (xy 8.974403 -411.936699)
			(xy 8.804005 -412.048772) (xy 8.629389 -412.154153) (xy 8.450819 -412.252684) (xy 8.268562 -412.344216)
			(xy 8.082893 -412.428613) (xy 7.894092 -412.505747) (xy 7.702441 -412.575502) (xy 7.50823 -412.637774)
			(xy 7.31175 -412.692468) (xy 7.113297 -412.739502) (xy 6.913169 -412.778805) (xy 6.711669 -412.81032)
			(xy 6.509097 -412.833997) (xy 6.30576 -412.849801) (xy 6.101963 -412.85771) (xy 5.999988 -412.858204)
			(xy 5.99948 -412.858204) (xy 5.894904 -412.857685) (xy 5.685917 -412.849357) (xy 5.477427 -412.832726)
			(xy 5.269763 -412.807817) (xy 5.063254 -412.774672) (xy 4.858226 -412.733341) (xy 4.655003 -412.68389)
			(xy 4.453908 -412.626398) (xy 4.255257 -412.560955) (xy 4.059366 -412.487665) (xy 3.866544 -412.406644)
			(xy 3.677096 -412.31802) (xy 3.491322 -412.221933) (xy 3.309516 -412.118536) (xy 3.131964 -412.00799)
			(xy 2.958949 -411.890473) (xy 2.790743 -411.766169) (xy 2.627613 -411.635274) (xy 2.469816 -411.497997)
			(xy 2.317603 -411.354554) (xy 2.171214 -411.205172) (xy 2.030881 -411.050088) (xy 1.896825 -410.889546)
			(xy 1.769258 -410.7238) (xy 1.708404 -410.638752) (xy 1.698752 -410.625036) (xy 1.66751 -410.614622)
			(xy 1.559306 -410.649166) (xy 1.549303 -410.652979) (xy 1.533375 -410.667242) (xy 1.5246 -410.686739)
			(xy 1.524 -410.697426) (xy 1.524 -416.589972) (xy 1.52451 -416.621137) (xy 1.532646 -416.682934)
			(xy 1.548778 -416.74314) (xy 1.572631 -416.800725) (xy 1.603796 -416.854705) (xy 1.64174 -416.904155)
			(xy 1.685814 -416.948229) (xy 1.735263 -416.986173) (xy 1.789243 -417.017338) (xy 1.846828 -417.041191)
			(xy 1.907034 -417.057324) (xy 1.968831 -417.06546) (xy 1.999996 -417.065968)
		)
		(stroke
			(width 0)
			(type solid)
		)
		(fill yes)
		(layer "In2.Cu")
		(net "P12V_AUX")
	)
	(gr_line
		(start 0.066802 -368.68354)
		(end 0.178054 -368.794792)
		(stroke
			(width 0.508)
			(type default)
		)
		(layer "In2.Cu")
	)
	(gr_line
		(start 0.066802 -368.322352)
		(end 0.066802 -368.68354)
		(stroke
			(width 0.508)
			(type default)
		)
		(layer "In2.Cu")
	)
	(gr_line
		(start 0.122174 -368.26698)
		(end 0.066802 -368.322352)
		(stroke
			(width 0.508)
			(type default)
		)
		(layer "In2.Cu")
	)
	(gr_line
		(start 0.122174 -368.26698)
		(end 203.986892 -368.26698)
		(stroke
			(width 0.635)
			(type default)
		)
		(layer "In2.Cu")
	)
	(gr_line
		(start 0.178054 -368.794792)
		(end 0.539242 -368.433604)
		(stroke
			(width 0.508)
			(type default)
		)
		(layer "In2.Cu")
	)
	(gr_line
		(start 0.289306 -367.961164)
		(end 0.011176 -367.961164)
		(stroke
			(width 0.508)
			(type default)
		)
		(layer "In2.Cu")
	)
	(gr_line
		(start 0.35306 -58.234834)
		(end 13.130276 -58.234834)
		(stroke
			(width 0.635)
			(type default)
		)
		(layer "In2.Cu")
	)
	(gr_line
		(start 0.539242 -368.433604)
		(end 0.539242 -368.2111)
		(stroke
			(width 0.508)
			(type default)
		)
		(layer "In2.Cu")
	)
	(gr_line
		(start 0.539242 -368.2111)
		(end 0.289306 -367.961164)
		(stroke
			(width 0.508)
			(type default)
		)
		(layer "In2.Cu")
	)
	(gr_arc
		(start 0.585724 -245.074186)
		(mid 0.152244 -245.723085)
		(end 0 -246.488458)
		(stroke
			(width 3.048)
			(type default)
		)
		(layer "In2.Cu")
	)
	(gr_line
		(start 0.585724 -245.074186)
		(end 3.214116 -242.445794)
		(stroke
			(width 3.048)
			(type default)
		)
		(layer "In2.Cu")
	)
	(gr_arc
		(start 1.999996 0)
		(mid 0.585785 -0.585785)
		(end 0 -1.999996)
		(stroke
			(width 3.048)
			(type default)
		)
		(layer "In2.Cu")
	)
	(gr_line
		(start 1.999996 0)
		(end 5.964936 0)
		(stroke
			(width 3.048)
			(type default)
		)
		(layer "In2.Cu")
	)
	(gr_arc
		(start 3.214116 -242.445794)
		(mid 3.647762 -241.796936)
		(end 3.800094 -241.031522)
		(stroke
			(width 3.048)
			(type default)
		)
		(layer "In2.Cu")
	)
	(gr_line
		(start 3.214116 -86.174326)
		(end 0.585724 -83.54568)
		(stroke
			(width 3.048)
			(type default)
		)
		(layer "In2.Cu")
	)
	(gr_circle
		(center 3.499866 -311.410096)
		(end 5.607812 -311.410096)
		(stroke
			(width 0.2)
			(type default)
		)
		(fill no)
		(layer "In2.Cu")
	)
	(gr_line
		(start 3.800094 -241.031522)
		(end 3.800094 -87.588344)
		(stroke
			(width 3.048)
			(type default)
		)
		(layer "In2.Cu")
	)
	(gr_arc
		(start 3.800094 -87.588344)
		(mid 3.647755 -86.823047)
		(end 3.214116 -86.174326)
		(stroke
			(width 3.048)
			(type default)
		)
		(layer "In2.Cu")
	)
	(gr_line
		(start 5.199888 -400.699986)
		(end 6.800088 -400.699986)
		(stroke
			(width 0.2)
			(type default)
		)
		(layer "In2.Cu")
	)
	(gr_arc
		(start 5.199888 -395.500098)
		(mid 2.599944 -398.100042)
		(end 5.199888 -400.699986)
		(stroke
			(width 0.2)
			(type default)
		)
		(layer "In2.Cu")
	)
	(gr_circle
		(center 5.999988 -407.599896)
		(end 11.174984 -407.599896)
		(stroke
			(width 0.2)
			(type default)
		)
		(fill no)
		(layer "In2.Cu")
	)
	(gr_arc
		(start 6.800088 -400.699986)
		(mid 9.400032 -398.100042)
		(end 6.800088 -395.500098)
		(stroke
			(width 0.2)
			(type default)
		)
		(layer "In2.Cu")
	)
	(gr_line
		(start 6.800088 -395.500098)
		(end 5.199888 -395.500098)
		(stroke
			(width 0.2)
			(type default)
		)
		(layer "In2.Cu")
	)
	(gr_arc
		(start 7.964932 -11.850116)
		(mid 8.257825 -12.557221)
		(end 8.96493 -12.850114)
		(stroke
			(width 3.048)
			(type default)
		)
		(layer "In2.Cu")
	)
	(gr_arc
		(start 7.964932 -1.999996)
		(mid 7.379145 -0.585789)
		(end 5.964936 0)
		(stroke
			(width 3.048)
			(type default)
		)
		(layer "In2.Cu")
	)
	(gr_line
		(start 7.964932 -1.999996)
		(end 7.964932 -11.850116)
		(stroke
			(width 3.048)
			(type default)
		)
		(layer "In2.Cu")
	)
	(gr_line
		(start 8.96493 -12.850114)
		(end 16.964914 -12.850114)
		(stroke
			(width 3.048)
			(type default)
		)
		(layer "In2.Cu")
	)
	(gr_line
		(start 13.130276 -58.234834)
		(end 13.15593 -58.260488)
		(stroke
			(width 0.635)
			(type default)
		)
		(layer "In2.Cu")
	)
	(gr_line
		(start 13.15593 -58.260488)
		(end 13.902182 -57.514236)
		(stroke
			(width 0.635)
			(type default)
		)
		(layer "In2.Cu")
	)
	(gr_line
		(start 13.902182 -57.514236)
		(end 13.902182 -50.415698)
		(stroke
			(width 0.635)
			(type default)
		)
		(layer "In2.Cu")
	)
	(gr_line
		(start 13.902182 -50.415698)
		(end 14.24813 -50.06975)
		(stroke
			(width 0.635)
			(type default)
		)
		(layer "In2.Cu")
	)
	(gr_line
		(start 14.24813 -50.06975)
		(end 467.422738 -50.06975)
		(stroke
			(width 0.635)
			(type default)
		)
		(layer "In2.Cu")
	)
	(gr_circle
		(center 15.80007 -194.360038)
		(end 20.975066 -194.360038)
		(stroke
			(width 0.2)
			(type default)
		)
		(fill no)
		(layer "In2.Cu")
	)
	(gr_arc
		(start 16.964914 -12.850114)
		(mid 17.672019 -12.557221)
		(end 17.964912 -11.850116)
		(stroke
			(width 3.048)
			(type default)
		)
		(layer "In2.Cu")
	)
	(gr_line
		(start 17.964912 -11.850116)
		(end 17.964912 -1.999996)
		(stroke
			(width 3.048)
			(type default)
		)
		(layer "In2.Cu")
	)
	(gr_circle
		(center 18.800064 -84.699856)
		(end 23.97506 -84.699856)
		(stroke
			(width 0.2)
			(type default)
		)
		(fill no)
		(layer "In2.Cu")
	)
	(gr_arc
		(start 19.964908 0)
		(mid 18.550691 -0.585782)
		(end 17.964912 -1.999996)
		(stroke
			(width 3.048)
			(type default)
		)
		(layer "In2.Cu")
	)
	(gr_line
		(start 19.964908 0)
		(end 31.964884 0)
		(stroke
			(width 3.048)
			(type default)
		)
		(layer "In2.Cu")
	)
	(gr_circle
		(center 20.14982 -301.410116)
		(end 22.257766 -301.410116)
		(stroke
			(width 0.2)
			(type default)
		)
		(fill no)
		(layer "In2.Cu")
	)
	(gr_circle
		(center 25.964896 -17.999964)
		(end 31.139892 -17.999964)
		(stroke
			(width 0.2)
			(type default)
		)
		(fill no)
		(layer "In2.Cu")
	)
	(gr_circle
		(center 29.649928 -320.900044)
		(end 34.285936 -320.900044)
		(stroke
			(width 0.2)
			(type default)
		)
		(fill no)
		(layer "In2.Cu")
	)
	(gr_circle
		(center 29.649928 -270.89989)
		(end 34.285936 -270.89989)
		(stroke
			(width 0.2)
			(type default)
		)
		(fill no)
		(layer "In2.Cu")
	)
	(gr_arc
		(start 33.96488 -11.850116)
		(mid 34.257773 -12.557221)
		(end 34.964878 -12.850114)
		(stroke
			(width 3.048)
			(type default)
		)
		(layer "In2.Cu")
	)
	(gr_arc
		(start 33.96488 -1.999996)
		(mid 33.379092 -0.585794)
		(end 31.964884 0)
		(stroke
			(width 3.048)
			(type default)
		)
		(layer "In2.Cu")
	)
	(gr_line
		(start 33.96488 -1.999996)
		(end 33.96488 -11.850116)
		(stroke
			(width 3.048)
			(type default)
		)
		(layer "In2.Cu")
	)
	(gr_line
		(start 34.964878 -12.850114)
		(end 42.965116 -12.850114)
		(stroke
			(width 3.048)
			(type default)
		)
		(layer "In2.Cu")
	)
	(gr_line
		(start 36.374578 -337.617562)
		(end 36.931854 -338.174838)
		(stroke
			(width 0.635)
			(type default)
		)
		(layer "In2.Cu")
	)
	(gr_line
		(start 36.374578 -286.87522)
		(end 36.374578 -337.617562)
		(stroke
			(width 0.635)
			(type default)
		)
		(layer "In2.Cu")
	)
	(gr_line
		(start 36.374578 -272.53819)
		(end 36.374578 -286.87522)
		(stroke
			(width 0.635)
			(type default)
		)
		(layer "In2.Cu")
	)
	(gr_line
		(start 36.403788 -286.180022)
		(end 36.417504 -286.180022)
		(stroke
			(width 0.508)
			(type default)
		)
		(layer "In2.Cu")
	)
	(gr_line
		(start 36.403788 -285.940246)
		(end 36.403788 -286.180022)
		(stroke
			(width 0.508)
			(type default)
		)
		(layer "In2.Cu")
	)
	(gr_line
		(start 36.417504 -286.180022)
		(end 36.640008 -285.957518)
		(stroke
			(width 0.508)
			(type default)
		)
		(layer "In2.Cu")
	)
	(gr_line
		(start 36.441888 -285.902146)
		(end 36.403788 -285.940246)
		(stroke
			(width 0.508)
			(type default)
		)
		(layer "In2.Cu")
	)
	(gr_line
		(start 36.464494 -285.924752)
		(end 36.441888 -285.902146)
		(stroke
			(width 0.508)
			(type default)
		)
		(layer "In2.Cu")
	)
	(gr_line
		(start 36.640008 -285.957518)
		(end 36.640008 -285.891478)
		(stroke
			(width 0.508)
			(type default)
		)
		(layer "In2.Cu")
	)
	(gr_line
		(start 36.640008 -285.891478)
		(end 36.449 -285.70047)
		(stroke
			(width 0.508)
			(type default)
		)
		(layer "In2.Cu")
	)
	(gr_line
		(start 36.922964 -271.989804)
		(end 36.374578 -272.53819)
		(stroke
			(width 0.635)
			(type default)
		)
		(layer "In2.Cu")
	)
	(gr_line
		(start 36.922964 -271.989804)
		(end 130.785616 -271.989804)
		(stroke
			(width 0.635)
			(type default)
		)
		(layer "In2.Cu")
	)
	(gr_line
		(start 36.931854 -338.174838)
		(end 197.785482 -338.174838)
		(stroke
			(width 0.635)
			(type default)
		)
		(layer "In2.Cu")
	)
	(gr_arc
		(start 42.965116 -12.850114)
		(mid 43.672221 -12.557221)
		(end 43.965114 -11.850116)
		(stroke
			(width 3.048)
			(type default)
		)
		(layer "In2.Cu")
	)
	(gr_line
		(start 43.965114 -11.850116)
		(end 43.965114 -1.999996)
		(stroke
			(width 3.048)
			(type default)
		)
		(layer "In2.Cu")
	)
	(gr_arc
		(start 45.96511 0)
		(mid 44.550891 -0.585781)
		(end 43.965114 -1.999996)
		(stroke
			(width 3.048)
			(type default)
		)
		(layer "In2.Cu")
	)
	(gr_line
		(start 45.96511 0)
		(end 57.965086 0)
		(stroke
			(width 3.048)
			(type default)
		)
		(layer "In2.Cu")
	)
	(gr_arc
		(start 59.965082 -11.850116)
		(mid 60.257975 -12.557221)
		(end 60.96508 -12.850114)
		(stroke
			(width 3.048)
			(type default)
		)
		(layer "In2.Cu")
	)
	(gr_arc
		(start 59.965082 -1.999996)
		(mid 59.379294 -0.585793)
		(end 57.965086 0)
		(stroke
			(width 3.048)
			(type default)
		)
		(layer "In2.Cu")
	)
	(gr_line
		(start 59.965082 -1.999996)
		(end 59.965082 -11.850116)
		(stroke
			(width 3.048)
			(type default)
		)
		(layer "In2.Cu")
	)
	(gr_line
		(start 60.96508 -12.850114)
		(end 68.965064 -12.850114)
		(stroke
			(width 3.048)
			(type default)
		)
		(layer "In2.Cu")
	)
	(gr_arc
		(start 68.965064 -12.850114)
		(mid 69.672169 -12.557221)
		(end 69.965062 -11.850116)
		(stroke
			(width 3.048)
			(type default)
		)
		(layer "In2.Cu")
	)
	(gr_line
		(start 69.965062 -11.850116)
		(end 69.965062 -1.999996)
		(stroke
			(width 3.048)
			(type default)
		)
		(layer "In2.Cu")
	)
	(gr_arc
		(start 71.965058 0)
		(mid 70.550873 -0.5858)
		(end 69.965062 -1.999996)
		(stroke
			(width 3.048)
			(type default)
		)
		(layer "In2.Cu")
	)
	(gr_line
		(start 71.965058 0)
		(end 83.965034 0)
		(stroke
			(width 3.048)
			(type default)
		)
		(layer "In2.Cu")
	)
	(gr_arc
		(start 85.96503 -11.850116)
		(mid 86.257923 -12.557221)
		(end 86.965028 -12.850114)
		(stroke
			(width 3.048)
			(type default)
		)
		(layer "In2.Cu")
	)
	(gr_arc
		(start 85.96503 -1.999996)
		(mid 85.379245 -0.585776)
		(end 83.965034 0)
		(stroke
			(width 3.048)
			(type default)
		)
		(layer "In2.Cu")
	)
	(gr_line
		(start 85.96503 -1.999996)
		(end 85.96503 -11.850116)
		(stroke
			(width 3.048)
			(type default)
		)
		(layer "In2.Cu")
	)
	(gr_line
		(start 86.965028 -12.850114)
		(end 94.965012 -12.850114)
		(stroke
			(width 3.048)
			(type default)
		)
		(layer "In2.Cu")
	)
	(gr_circle
		(center 89.650062 -320.900044)
		(end 94.28607 -320.900044)
		(stroke
			(width 0.2)
			(type default)
		)
		(fill no)
		(layer "In2.Cu")
	)
	(gr_circle
		(center 89.650062 -270.89989)
		(end 94.28607 -270.89989)
		(stroke
			(width 0.2)
			(type default)
		)
		(fill no)
		(layer "In2.Cu")
	)
	(gr_arc
		(start 94.965012 -12.850114)
		(mid 95.672117 -12.557221)
		(end 95.96501 -11.850116)
		(stroke
			(width 3.048)
			(type default)
		)
		(layer "In2.Cu")
	)
	(gr_line
		(start 95.96501 -11.850116)
		(end 95.96501 -1.999996)
		(stroke
			(width 3.048)
			(type default)
		)
		(layer "In2.Cu")
	)
	(gr_arc
		(start 97.965006 0)
		(mid 96.55079 -0.585783)
		(end 95.96501 -1.999996)
		(stroke
			(width 3.048)
			(type default)
		)
		(layer "In2.Cu")
	)
	(gr_line
		(start 97.965006 0)
		(end 122.065034 0)
		(stroke
			(width 3.048)
			(type default)
		)
		(layer "In2.Cu")
	)
	(gr_circle
		(center 99.149916 -289.820096)
		(end 101.257862 -289.820096)
		(stroke
			(width 0.2)
			(type default)
		)
		(fill no)
		(layer "In2.Cu")
	)
	(gr_line
		(start 99.914964 -285.924752)
		(end 36.464494 -285.924752)
		(stroke
			(width 0.508)
			(type default)
		)
		(layer "In2.Cu")
	)
	(gr_line
		(start 100.25253 -293.562786)
		(end 100.25253 -285.587186)
		(stroke
			(width 0.508)
			(type default)
		)
		(layer "In2.Cu")
	)
	(gr_line
		(start 100.25253 -285.587186)
		(end 99.914964 -285.924752)
		(stroke
			(width 0.508)
			(type default)
		)
		(layer "In2.Cu")
	)
	(gr_line
		(start 100.25253 -285.587186)
		(end 100.25253 -279.197562)
		(stroke
			(width 0.508)
			(type default)
		)
		(layer "In2.Cu")
	)
	(gr_line
		(start 100.25253 -279.197562)
		(end 101.0031 -278.446992)
		(stroke
			(width 0.508)
			(type default)
		)
		(layer "In2.Cu")
	)
	(gr_line
		(start 100.863908 -294.174164)
		(end 100.25253 -293.562786)
		(stroke
			(width 0.508)
			(type default)
		)
		(layer "In2.Cu")
	)
	(gr_line
		(start 101.0031 -278.446992)
		(end 134.85241 -278.446992)
		(stroke
			(width 0.508)
			(type default)
		)
		(layer "In2.Cu")
	)
	(gr_circle
		(center 104.009952 -407.599896)
		(end 109.184948 -407.599896)
		(stroke
			(width 0.2)
			(type default)
		)
		(fill no)
		(layer "In2.Cu")
	)
	(gr_circle
		(center 110.01502 -17.999964)
		(end 115.190016 -17.999964)
		(stroke
			(width 0.2)
			(type default)
		)
		(fill no)
		(layer "In2.Cu")
	)
	(gr_line
		(start 116.954808 -294.174164)
		(end 100.863908 -294.174164)
		(stroke
			(width 0.508)
			(type default)
		)
		(layer "In2.Cu")
	)
	(gr_line
		(start 117.4115 -294.250872)
		(end 117.675406 -294.514778)
		(stroke
			(width 0.508)
			(type default)
		)
		(layer "In2.Cu")
	)
	(gr_line
		(start 117.47373 -338.150454)
		(end 117.47373 -338.029804)
		(stroke
			(width 0.508)
			(type default)
		)
		(layer "In2.Cu")
	)
	(gr_line
		(start 117.47373 -338.029804)
		(end 117.763544 -337.73999)
		(stroke
			(width 0.508)
			(type default)
		)
		(layer "In2.Cu")
	)
	(gr_line
		(start 117.64264 -338.150454)
		(end 117.47373 -338.150454)
		(stroke
			(width 0.508)
			(type default)
		)
		(layer "In2.Cu")
	)
	(gr_line
		(start 117.675406 -294.514778)
		(end 117.75186 -294.514778)
		(stroke
			(width 0.508)
			(type default)
		)
		(layer "In2.Cu")
	)
	(gr_circle
		(center 117.700044 -194.360038)
		(end 122.87504 -194.360038)
		(stroke
			(width 0.2)
			(type default)
		)
		(fill no)
		(layer "In2.Cu")
	)
	(gr_circle
		(center 117.700298 -72.700134)
		(end 122.875294 -72.700134)
		(stroke
			(width 0.2)
			(type default)
		)
		(fill no)
		(layer "In2.Cu")
	)
	(gr_line
		(start 117.730778 -338.062316)
		(end 117.64264 -338.150454)
		(stroke
			(width 0.508)
			(type default)
		)
		(layer "In2.Cu")
	)
	(gr_line
		(start 117.730778 -294.29964)
		(end 117.730778 -338.062316)
		(stroke
			(width 0.508)
			(type default)
		)
		(layer "In2.Cu")
	)
	(gr_line
		(start 117.738144 -294.58412)
		(end 117.738144 -294.292274)
		(stroke
			(width 0.508)
			(type default)
		)
		(layer "In2.Cu")
	)
	(gr_line
		(start 117.738144 -294.292274)
		(end 117.730778 -294.29964)
		(stroke
			(width 0.508)
			(type default)
		)
		(layer "In2.Cu")
	)
	(gr_line
		(start 117.75186 -294.514778)
		(end 117.75186 -294.49395)
		(stroke
			(width 0.508)
			(type default)
		)
		(layer "In2.Cu")
	)
	(gr_line
		(start 117.75186 -294.49395)
		(end 118.036848 -294.208962)
		(stroke
			(width 0.508)
			(type default)
		)
		(layer "In2.Cu")
	)
	(gr_line
		(start 117.763544 -337.73999)
		(end 118.029228 -338.005674)
		(stroke
			(width 0.508)
			(type default)
		)
		(layer "In2.Cu")
	)
	(gr_line
		(start 118.029228 -338.005674)
		(end 118.029228 -338.053934)
		(stroke
			(width 0.508)
			(type default)
		)
		(layer "In2.Cu")
	)
	(gr_line
		(start 118.036848 -294.285416)
		(end 117.738144 -294.58412)
		(stroke
			(width 0.508)
			(type default)
		)
		(layer "In2.Cu")
	)
	(gr_line
		(start 118.036848 -294.208962)
		(end 118.036848 -294.285416)
		(stroke
			(width 0.508)
			(type default)
		)
		(layer "In2.Cu")
	)
	(gr_arc
		(start 124.06503 -11.850116)
		(mid 124.357923 -12.557221)
		(end 125.065028 -12.850114)
		(stroke
			(width 3.048)
			(type default)
		)
		(layer "In2.Cu")
	)
	(gr_arc
		(start 124.06503 -1.999996)
		(mid 123.479245 -0.585776)
		(end 122.065034 0)
		(stroke
			(width 3.048)
			(type default)
		)
		(layer "In2.Cu")
	)
	(gr_line
		(start 124.06503 -1.999996)
		(end 124.06503 -11.850116)
		(stroke
			(width 3.048)
			(type default)
		)
		(layer "In2.Cu")
	)
	(gr_line
		(start 125.065028 -12.850114)
		(end 133.065012 -12.850114)
		(stroke
			(width 3.048)
			(type default)
		)
		(layer "In2.Cu")
	)
	(gr_line
		(start 130.785616 -271.989804)
		(end 132.554726 -270.220694)
		(stroke
			(width 0.635)
			(type default)
		)
		(layer "In2.Cu")
	)
	(gr_line
		(start 132.554726 -270.220694)
		(end 140.895832 -270.220694)
		(stroke
			(width 0.635)
			(type default)
		)
		(layer "In2.Cu")
	)
	(gr_arc
		(start 133.065012 -12.850114)
		(mid 133.772117 -12.557221)
		(end 134.06501 -11.850116)
		(stroke
			(width 3.048)
			(type default)
		)
		(layer "In2.Cu")
	)
	(gr_line
		(start 134.06501 -11.850116)
		(end 134.06501 -1.999996)
		(stroke
			(width 3.048)
			(type default)
		)
		(layer "In2.Cu")
	)
	(gr_line
		(start 134.85241 -278.446992)
		(end 135.489188 -279.08377)
		(stroke
			(width 0.508)
			(type default)
		)
		(layer "In2.Cu")
	)
	(gr_line
		(start 134.933436 -294.174164)
		(end 116.954808 -294.174164)
		(stroke
			(width 0.508)
			(type default)
		)
		(layer "In2.Cu")
	)
	(gr_line
		(start 135.489188 -293.618412)
		(end 134.933436 -294.174164)
		(stroke
			(width 0.508)
			(type default)
		)
		(layer "In2.Cu")
	)
	(gr_line
		(start 135.489188 -279.08377)
		(end 135.489188 -293.618412)
		(stroke
			(width 0.508)
			(type default)
		)
		(layer "In2.Cu")
	)
	(gr_line
		(start 135.489442 -286.086804)
		(end 135.76046 -286.357822)
		(stroke
			(width 0.508)
			(type default)
		)
		(layer "In2.Cu")
	)
	(gr_line
		(start 135.558784 -286.621728)
		(end 135.780526 -286.399986)
		(stroke
			(width 0.508)
			(type default)
		)
		(layer "In2.Cu")
	)
	(gr_line
		(start 135.56615 -286.621728)
		(end 135.558784 -286.621728)
		(stroke
			(width 0.508)
			(type default)
		)
		(layer "In2.Cu")
	)
	(gr_line
		(start 135.76046 -286.427418)
		(end 135.56615 -286.621728)
		(stroke
			(width 0.508)
			(type default)
		)
		(layer "In2.Cu")
	)
	(gr_line
		(start 135.76046 -286.357822)
		(end 135.76046 -286.427418)
		(stroke
			(width 0.508)
			(type default)
		)
		(layer "In2.Cu")
	)
	(gr_line
		(start 135.780526 -286.399986)
		(end 198.685912 -286.399986)
		(stroke
			(width 0.508)
			(type default)
		)
		(layer "In2.Cu")
	)
	(gr_arc
		(start 136.065006 0)
		(mid 134.65079 -0.585783)
		(end 134.06501 -1.999996)
		(stroke
			(width 3.048)
			(type default)
		)
		(layer "In2.Cu")
	)
	(gr_line
		(start 136.065006 0)
		(end 148.064982 0)
		(stroke
			(width 3.048)
			(type default)
		)
		(layer "In2.Cu")
	)
	(gr_circle
		(center 136.250172 -276.010116)
		(end 138.358118 -276.010116)
		(stroke
			(width 0.2)
			(type default)
		)
		(fill no)
		(layer "In2.Cu")
	)
	(gr_line
		(start 140.895832 -270.220694)
		(end 142.484602 -271.809464)
		(stroke
			(width 0.635)
			(type default)
		)
		(layer "In2.Cu")
	)
	(gr_line
		(start 142.484602 -271.989804)
		(end 198.205344 -271.989804)
		(stroke
			(width 0.635)
			(type default)
		)
		(layer "In2.Cu")
	)
	(gr_line
		(start 142.484602 -271.809464)
		(end 142.484602 -271.989804)
		(stroke
			(width 0.635)
			(type default)
		)
		(layer "In2.Cu")
	)
	(gr_circle
		(center 145.750026 -320.900044)
		(end 150.386034 -320.900044)
		(stroke
			(width 0.2)
			(type default)
		)
		(fill no)
		(layer "In2.Cu")
	)
	(gr_circle
		(center 145.750026 -270.89989)
		(end 150.386034 -270.89989)
		(stroke
			(width 0.2)
			(type default)
		)
		(fill no)
		(layer "In2.Cu")
	)
	(gr_arc
		(start 150.064978 -11.850116)
		(mid 150.357871 -12.557221)
		(end 151.064976 -12.850114)
		(stroke
			(width 3.048)
			(type default)
		)
		(layer "In2.Cu")
	)
	(gr_arc
		(start 150.064978 -1.999996)
		(mid 149.47919 -0.585794)
		(end 148.064982 0)
		(stroke
			(width 3.048)
			(type default)
		)
		(layer "In2.Cu")
	)
	(gr_line
		(start 150.064978 -1.999996)
		(end 150.064978 -11.850116)
		(stroke
			(width 3.048)
			(type default)
		)
		(layer "In2.Cu")
	)
	(gr_line
		(start 151.064976 -12.850114)
		(end 159.06496 -12.850114)
		(stroke
			(width 3.048)
			(type default)
		)
		(layer "In2.Cu")
	)
	(gr_arc
		(start 159.06496 -12.850114)
		(mid 159.772065 -12.557221)
		(end 160.064958 -11.850116)
		(stroke
			(width 3.048)
			(type default)
		)
		(layer "In2.Cu")
	)
	(gr_line
		(start 160.064958 -11.850116)
		(end 160.064958 -1.999996)
		(stroke
			(width 3.048)
			(type default)
		)
		(layer "In2.Cu")
	)
	(gr_arc
		(start 162.064954 0)
		(mid 160.650772 -0.585801)
		(end 160.064958 -1.999996)
		(stroke
			(width 3.048)
			(type default)
		)
		(layer "In2.Cu")
	)
	(gr_line
		(start 162.064954 0)
		(end 174.06493 0)
		(stroke
			(width 3.048)
			(type default)
		)
		(layer "In2.Cu")
	)
	(gr_circle
		(center 168.064942 -4.99999)
		(end 173.239938 -4.99999)
		(stroke
			(width 0.2)
			(type default)
		)
		(fill no)
		(layer "In2.Cu")
	)
	(gr_arc
		(start 176.064926 -11.850116)
		(mid 176.357819 -12.557221)
		(end 177.064924 -12.850114)
		(stroke
			(width 3.048)
			(type default)
		)
		(layer "In2.Cu")
	)
	(gr_arc
		(start 176.064926 -1.999996)
		(mid 175.479141 -0.585777)
		(end 174.06493 0)
		(stroke
			(width 3.048)
			(type default)
		)
		(layer "In2.Cu")
	)
	(gr_line
		(start 176.064926 -1.999996)
		(end 176.064926 -11.850116)
		(stroke
			(width 3.048)
			(type default)
		)
		(layer "In2.Cu")
	)
	(gr_line
		(start 177.064924 -12.850114)
		(end 185.064908 -12.850114)
		(stroke
			(width 3.048)
			(type default)
		)
		(layer "In2.Cu")
	)
	(gr_arc
		(start 185.064908 -12.850114)
		(mid 185.772013 -12.557221)
		(end 186.064906 -11.850116)
		(stroke
			(width 3.048)
			(type default)
		)
		(layer "In2.Cu")
	)
	(gr_line
		(start 186.064906 -11.850116)
		(end 186.064906 -1.999996)
		(stroke
			(width 3.048)
			(type default)
		)
		(layer "In2.Cu")
	)
	(gr_arc
		(start 188.064902 0)
		(mid 186.650689 -0.585784)
		(end 186.064906 -1.999996)
		(stroke
			(width 3.048)
			(type default)
		)
		(layer "In2.Cu")
	)
	(gr_line
		(start 188.064902 0)
		(end 200.064878 0)
		(stroke
			(width 3.048)
			(type default)
		)
		(layer "In2.Cu")
	)
	(gr_circle
		(center 195.699888 -378.70003)
		(end 200.874884 -378.70003)
		(stroke
			(width 0.2)
			(type default)
		)
		(fill no)
		(layer "In2.Cu")
	)
	(gr_line
		(start 197.785482 -338.174838)
		(end 199.025256 -336.935064)
		(stroke
			(width 0.635)
			(type default)
		)
		(layer "In2.Cu")
	)
	(gr_line
		(start 198.21525 -271.99971)
		(end 198.205344 -271.989804)
		(stroke
			(width 0.635)
			(type default)
		)
		(layer "In2.Cu")
	)
	(gr_line
		(start 198.340472 -271.99971)
		(end 198.21525 -271.99971)
		(stroke
			(width 0.635)
			(type default)
		)
		(layer "In2.Cu")
	)
	(gr_line
		(start 198.685912 -286.399986)
		(end 199.019414 -286.733488)
		(stroke
			(width 0.508)
			(type default)
		)
		(layer "In2.Cu")
	)
	(gr_line
		(start 198.70674 -286.38627)
		(end 198.70674 -286.337502)
		(stroke
			(width 0.508)
			(type default)
		)
		(layer "In2.Cu")
	)
	(gr_line
		(start 198.70674 -286.337502)
		(end 198.984616 -286.059626)
		(stroke
			(width 0.508)
			(type default)
		)
		(layer "In2.Cu")
	)
	(gr_line
		(start 198.984616 -286.059626)
		(end 198.998586 -286.059626)
		(stroke
			(width 0.508)
			(type default)
		)
		(layer "In2.Cu")
	)
	(gr_line
		(start 199.019414 -286.733488)
		(end 199.019414 -286.698944)
		(stroke
			(width 0.508)
			(type default)
		)
		(layer "In2.Cu")
	)
	(gr_line
		(start 199.019414 -286.698944)
		(end 198.70674 -286.38627)
		(stroke
			(width 0.508)
			(type default)
		)
		(layer "In2.Cu")
	)
	(gr_line
		(start 199.025002 -318.224662)
		(end 199.025002 -272.68424)
		(stroke
			(width 0.635)
			(type default)
		)
		(layer "In2.Cu")
	)
	(gr_line
		(start 199.025002 -272.68424)
		(end 198.340472 -271.99971)
		(stroke
			(width 0.635)
			(type default)
		)
		(layer "In2.Cu")
	)
	(gr_line
		(start 199.025256 -336.935064)
		(end 199.025256 -326.572118)
		(stroke
			(width 0.635)
			(type default)
		)
		(layer "In2.Cu")
	)
	(gr_line
		(start 199.025256 -326.572118)
		(end 199.025256 -318.224916)
		(stroke
			(width 0.635)
			(type default)
		)
		(layer "In2.Cu")
	)
	(gr_line
		(start 199.025256 -318.224916)
		(end 199.025002 -318.224662)
		(stroke
			(width 0.635)
			(type default)
		)
		(layer "In2.Cu")
	)
	(gr_circle
		(center 199.399906 -393.100052)
		(end 204.574902 -393.100052)
		(stroke
			(width 0.2)
			(type default)
		)
		(fill no)
		(layer "In2.Cu")
	)
	(gr_line
		(start 200.481184 -418.589968)
		(end 1.999996 -418.589968)
		(stroke
			(width 3.048)
			(type default)
		)
		(layer "In2.Cu")
	)
	(gr_arc
		(start 200.481184 -418.589968)
		(mid 201.291806 -418.418339)
		(end 201.963274 -417.93287)
		(stroke
			(width 3.048)
			(type default)
		)
		(layer "In2.Cu")
	)
	(gr_arc
		(start 202.064874 -11.850116)
		(mid 202.357841 -12.557401)
		(end 203.065126 -12.850114)
		(stroke
			(width 3.048)
			(type default)
		)
		(layer "In2.Cu")
	)
	(gr_arc
		(start 202.064874 -1.999996)
		(mid 201.479086 -0.585796)
		(end 200.064878 0)
		(stroke
			(width 3.048)
			(type default)
		)
		(layer "In2.Cu")
	)
	(gr_line
		(start 202.064874 -1.999996)
		(end 202.064874 -11.850116)
		(stroke
			(width 3.048)
			(type default)
		)
		(layer "In2.Cu")
	)
	(gr_line
		(start 203.065126 -12.850114)
		(end 211.06511 -12.850114)
		(stroke
			(width 3.048)
			(type default)
		)
		(layer "In2.Cu")
	)
	(gr_arc
		(start 203.445364 -417.275772)
		(mid 202.634751 -417.447411)
		(end 201.963274 -417.93287)
		(stroke
			(width 3.048)
			(type default)
		)
		(layer "In2.Cu")
	)
	(gr_line
		(start 203.984098 -368.267996)
		(end 204.295756 -367.956338)
		(stroke
			(width 0.635)
			(type default)
		)
		(layer "In2.Cu")
	)
	(gr_line
		(start 203.986892 -368.26698)
		(end 204.29855 -368.578638)
		(stroke
			(width 0.635)
			(type default)
		)
		(layer "In2.Cu")
	)
	(gr_line
		(start 204.690218 -419.12413)
		(end 204.88275 -418.931598)
		(stroke
			(width 0.508)
			(type default)
		)
		(layer "In2.Cu")
	)
	(gr_circle
		(center 205.749906 -320.900044)
		(end 210.385914 -320.900044)
		(stroke
			(width 0.2)
			(type default)
		)
		(fill no)
		(layer "In2.Cu")
	)
	(gr_circle
		(center 205.749906 -270.89989)
		(end 210.385914 -270.89989)
		(stroke
			(width 0.2)
			(type default)
		)
		(fill no)
		(layer "In2.Cu")
	)
	(gr_circle
		(center 208.300066 -98.700082)
		(end 213.475062 -98.700082)
		(stroke
			(width 0.2)
			(type default)
		)
		(fill no)
		(layer "In2.Cu")
	)
	(gr_arc
		(start 211.06511 -12.850114)
		(mid 211.772215 -12.557221)
		(end 212.065108 -11.850116)
		(stroke
			(width 3.048)
			(type default)
		)
		(layer "In2.Cu")
	)
	(gr_line
		(start 212.065108 -11.850116)
		(end 212.065108 -1.999996)
		(stroke
			(width 3.048)
			(type default)
		)
		(layer "In2.Cu")
	)
	(gr_arc
		(start 214.065104 0)
		(mid 212.650889 -0.585784)
		(end 212.065108 -1.999996)
		(stroke
			(width 3.048)
			(type default)
		)
		(layer "In2.Cu")
	)
	(gr_line
		(start 214.065104 0)
		(end 238.164878 0)
		(stroke
			(width 3.048)
			(type default)
		)
		(layer "In2.Cu")
	)
	(gr_circle
		(center 216.990168 -311.179972)
		(end 219.098114 -311.179972)
		(stroke
			(width 0.2)
			(type default)
		)
		(fill no)
		(layer "In2.Cu")
	)
	(gr_circle
		(center 226.115118 -4.99999)
		(end 231.290114 -4.99999)
		(stroke
			(width 0.2)
			(type default)
		)
		(fill no)
		(layer "In2.Cu")
	)
	(gr_circle
		(center 233.800142 -194.359784)
		(end 238.975138 -194.359784)
		(stroke
			(width 0.2)
			(type default)
		)
		(fill no)
		(layer "In2.Cu")
	)
	(gr_arc
		(start 240.164874 -11.850116)
		(mid 240.457841 -12.557401)
		(end 241.165126 -12.850114)
		(stroke
			(width 3.048)
			(type default)
		)
		(layer "In2.Cu")
	)
	(gr_arc
		(start 240.164874 -1.999996)
		(mid 239.579086 -0.585796)
		(end 238.164878 0)
		(stroke
			(width 3.048)
			(type default)
		)
		(layer "In2.Cu")
	)
	(gr_line
		(start 240.164874 -1.999996)
		(end 240.164874 -11.850116)
		(stroke
			(width 3.048)
			(type default)
		)
		(layer "In2.Cu")
	)
	(gr_line
		(start 241.165126 -12.850114)
		(end 249.16511 -12.850114)
		(stroke
			(width 3.048)
			(type default)
		)
		(layer "In2.Cu")
	)
	(gr_arc
		(start 249.16511 -12.850114)
		(mid 249.872215 -12.557221)
		(end 250.165108 -11.850116)
		(stroke
			(width 3.048)
			(type default)
		)
		(layer "In2.Cu")
	)
	(gr_line
		(start 250.165108 -11.850116)
		(end 250.165108 -1.999996)
		(stroke
			(width 3.048)
			(type default)
		)
		(layer "In2.Cu")
	)
	(gr_arc
		(start 252.165104 0)
		(mid 250.750889 -0.585784)
		(end 250.165108 -1.999996)
		(stroke
			(width 3.048)
			(type default)
		)
		(layer "In2.Cu")
	)
	(gr_line
		(start 252.165104 0)
		(end 264.16508 0)
		(stroke
			(width 3.048)
			(type default)
		)
		(layer "In2.Cu")
	)
	(gr_circle
		(center 252.350016 -297.369992)
		(end 254.457962 -297.369992)
		(stroke
			(width 0.2)
			(type default)
		)
		(fill no)
		(layer "In2.Cu")
	)
	(gr_circle
		(center 259.299964 -98.700082)
		(end 264.47496 -98.700082)
		(stroke
			(width 0.2)
			(type default)
		)
		(fill no)
		(layer "In2.Cu")
	)
	(gr_circle
		(center 261.850124 -320.900044)
		(end 266.486132 -320.900044)
		(stroke
			(width 0.2)
			(type default)
		)
		(fill no)
		(layer "In2.Cu")
	)
	(gr_circle
		(center 261.850124 -270.89989)
		(end 266.486132 -270.89989)
		(stroke
			(width 0.2)
			(type default)
		)
		(fill no)
		(layer "In2.Cu")
	)
	(gr_arc
		(start 266.165076 -11.850116)
		(mid 266.457969 -12.557221)
		(end 267.165074 -12.850114)
		(stroke
			(width 3.048)
			(type default)
		)
		(layer "In2.Cu")
	)
	(gr_arc
		(start 266.165076 -1.999996)
		(mid 265.579288 -0.585795)
		(end 264.16508 0)
		(stroke
			(width 3.048)
			(type default)
		)
		(layer "In2.Cu")
	)
	(gr_line
		(start 266.165076 -1.999996)
		(end 266.165076 -11.850116)
		(stroke
			(width 3.048)
			(type default)
		)
		(layer "In2.Cu")
	)
	(gr_line
		(start 266.176506 -368.740436)
		(end 266.63269 -368.284252)
		(stroke
			(width 0.635)
			(type default)
		)
		(layer "In2.Cu")
	)
	(gr_line
		(start 266.893802 -368.179604)
		(end 265.631168 -368.179604)
		(stroke
			(width 0.635)
			(type default)
		)
		(layer "In2.Cu")
	)
	(gr_line
		(start 267.165074 -12.850114)
		(end 275.165058 -12.850114)
		(stroke
			(width 3.048)
			(type default)
		)
		(layer "In2.Cu")
	)
	(gr_line
		(start 267.890244 -367.183162)
		(end 266.893802 -368.179604)
		(stroke
			(width 0.635)
			(type default)
		)
		(layer "In2.Cu")
	)
	(gr_circle
		(center 268.19987 -393.099798)
		(end 273.374866 -393.099798)
		(stroke
			(width 0.2)
			(type default)
		)
		(fill no)
		(layer "In2.Cu")
	)
	(gr_line
		(start 268.57452 -326.62114)
		(end 268.57452 -286.87522)
		(stroke
			(width 0.635)
			(type default)
		)
		(layer "In2.Cu")
	)
	(gr_line
		(start 268.57452 -272.53819)
		(end 268.57452 -286.87522)
		(stroke
			(width 0.635)
			(type default)
		)
		(layer "In2.Cu")
	)
	(gr_line
		(start 268.574774 -337.617562)
		(end 269.13205 -338.174838)
		(stroke
			(width 0.635)
			(type default)
		)
		(layer "In2.Cu")
	)
	(gr_line
		(start 268.574774 -286.87522)
		(end 268.574774 -337.617562)
		(stroke
			(width 0.635)
			(type default)
		)
		(layer "In2.Cu")
	)
	(gr_line
		(start 268.60373 -286.180022)
		(end 268.617446 -286.180022)
		(stroke
			(width 0.508)
			(type default)
		)
		(layer "In2.Cu")
	)
	(gr_line
		(start 268.60373 -285.940246)
		(end 268.60373 -286.180022)
		(stroke
			(width 0.508)
			(type default)
		)
		(layer "In2.Cu")
	)
	(gr_line
		(start 268.617446 -286.180022)
		(end 268.83995 -285.957518)
		(stroke
			(width 0.508)
			(type default)
		)
		(layer "In2.Cu")
	)
	(gr_line
		(start 268.64183 -285.902146)
		(end 268.60373 -285.940246)
		(stroke
			(width 0.508)
			(type default)
		)
		(layer "In2.Cu")
	)
	(gr_line
		(start 268.664436 -285.924752)
		(end 268.64183 -285.902146)
		(stroke
			(width 0.508)
			(type default)
		)
		(layer "In2.Cu")
	)
	(gr_line
		(start 268.83995 -285.957518)
		(end 268.83995 -285.891478)
		(stroke
			(width 0.508)
			(type default)
		)
		(layer "In2.Cu")
	)
	(gr_line
		(start 268.83995 -285.891478)
		(end 268.648942 -285.70047)
		(stroke
			(width 0.508)
			(type default)
		)
		(layer "In2.Cu")
	)
	(gr_line
		(start 269.122906 -271.989804)
		(end 268.57452 -272.53819)
		(stroke
			(width 0.635)
			(type default)
		)
		(layer "In2.Cu")
	)
	(gr_line
		(start 269.122906 -271.989804)
		(end 361.8484 -271.989804)
		(stroke
			(width 0.635)
			(type default)
		)
		(layer "In2.Cu")
	)
	(gr_line
		(start 269.12316 -271.989804)
		(end 361.8484 -271.989804)
		(stroke
			(width 0.635)
			(type default)
		)
		(layer "In2.Cu")
	)
	(gr_line
		(start 269.12316 -271.989804)
		(end 362.985812 -271.989804)
		(stroke
			(width 0.635)
			(type default)
		)
		(layer "In2.Cu")
	)
	(gr_line
		(start 269.13205 -338.174838)
		(end 429.985678 -338.174838)
		(stroke
			(width 0.635)
			(type default)
		)
		(layer "In2.Cu")
	)
	(gr_line
		(start 271.794478 -417.275772)
		(end 203.445364 -417.275772)
		(stroke
			(width 3.048)
			(type default)
		)
		(layer "In2.Cu")
	)
	(gr_circle
		(center 271.899888 -378.70003)
		(end 277.074884 -378.70003)
		(stroke
			(width 0.2)
			(type default)
		)
		(fill no)
		(layer "In2.Cu")
	)
	(gr_arc
		(start 273.276568 -417.93287)
		(mid 272.605089 -417.447415)
		(end 271.794478 -417.275772)
		(stroke
			(width 3.048)
			(type default)
		)
		(layer "In2.Cu")
	)
	(gr_arc
		(start 273.276568 -417.93287)
		(mid 273.948042 -418.418346)
		(end 274.758658 -418.589968)
		(stroke
			(width 3.048)
			(type default)
		)
		(layer "In2.Cu")
	)
	(gr_arc
		(start 275.165058 -12.850114)
		(mid 275.872163 -12.557221)
		(end 276.165056 -11.850116)
		(stroke
			(width 3.048)
			(type default)
		)
		(layer "In2.Cu")
	)
	(gr_line
		(start 276.165056 -11.850116)
		(end 276.165056 -1.999996)
		(stroke
			(width 3.048)
			(type default)
		)
		(layer "In2.Cu")
	)
	(gr_arc
		(start 278.165052 0)
		(mid 276.750871 -0.585802)
		(end 276.165056 -1.999996)
		(stroke
			(width 3.048)
			(type default)
		)
		(layer "In2.Cu")
	)
	(gr_line
		(start 278.165052 0)
		(end 290.165028 0)
		(stroke
			(width 3.048)
			(type default)
		)
		(layer "In2.Cu")
	)
	(gr_circle
		(center 284.16504 -4.99999)
		(end 289.340036 -4.99999)
		(stroke
			(width 0.2)
			(type default)
		)
		(fill no)
		(layer "In2.Cu")
	)
	(gr_arc
		(start 292.165024 -11.850116)
		(mid 292.457917 -12.557221)
		(end 293.165022 -12.850114)
		(stroke
			(width 3.048)
			(type default)
		)
		(layer "In2.Cu")
	)
	(gr_arc
		(start 292.165024 -1.999996)
		(mid 291.579239 -0.585778)
		(end 290.165028 0)
		(stroke
			(width 3.048)
			(type default)
		)
		(layer "In2.Cu")
	)
	(gr_line
		(start 292.165024 -1.999996)
		(end 292.165024 -11.850116)
		(stroke
			(width 3.048)
			(type default)
		)
		(layer "In2.Cu")
	)
	(gr_line
		(start 293.165022 -12.850114)
		(end 301.165006 -12.850114)
		(stroke
			(width 3.048)
			(type default)
		)
		(layer "In2.Cu")
	)
	(gr_arc
		(start 301.165006 -12.850114)
		(mid 301.872111 -12.557221)
		(end 302.165004 -11.850116)
		(stroke
			(width 3.048)
			(type default)
		)
		(layer "In2.Cu")
	)
	(gr_line
		(start 302.165004 -11.850116)
		(end 302.165004 -1.999996)
		(stroke
			(width 3.048)
			(type default)
		)
		(layer "In2.Cu")
	)
	(gr_arc
		(start 304.165 0)
		(mid 302.750788 -0.585785)
		(end 302.165004 -1.999996)
		(stroke
			(width 3.048)
			(type default)
		)
		(layer "In2.Cu")
	)
	(gr_line
		(start 304.165 0)
		(end 316.164976 0)
		(stroke
			(width 3.048)
			(type default)
		)
		(layer "In2.Cu")
	)
	(gr_arc
		(start 318.164972 -11.850116)
		(mid 318.457865 -12.557221)
		(end 319.16497 -12.850114)
		(stroke
			(width 3.048)
			(type default)
		)
		(layer "In2.Cu")
	)
	(gr_arc
		(start 318.164972 -1.999996)
		(mid 317.579184 -0.585796)
		(end 316.164976 0)
		(stroke
			(width 3.048)
			(type default)
		)
		(layer "In2.Cu")
	)
	(gr_line
		(start 318.164972 -1.999996)
		(end 318.164972 -11.850116)
		(stroke
			(width 3.048)
			(type default)
		)
		(layer "In2.Cu")
	)
	(gr_line
		(start 319.16497 -12.850114)
		(end 327.164954 -12.850114)
		(stroke
			(width 3.048)
			(type default)
		)
		(layer "In2.Cu")
	)
	(gr_circle
		(center 321.850004 -320.900044)
		(end 326.486012 -320.900044)
		(stroke
			(width 0.2)
			(type default)
		)
		(fill no)
		(layer "In2.Cu")
	)
	(gr_circle
		(center 321.850004 -270.89989)
		(end 326.486012 -270.89989)
		(stroke
			(width 0.2)
			(type default)
		)
		(fill no)
		(layer "In2.Cu")
	)
	(gr_arc
		(start 327.164954 -12.850114)
		(mid 327.872059 -12.557221)
		(end 328.164952 -11.850116)
		(stroke
			(width 3.048)
			(type default)
		)
		(layer "In2.Cu")
	)
	(gr_line
		(start 328.164952 -11.850116)
		(end 328.164952 -1.999996)
		(stroke
			(width 3.048)
			(type default)
		)
		(layer "In2.Cu")
	)
	(gr_arc
		(start 330.164948 0)
		(mid 328.750705 -0.585768)
		(end 328.164952 -1.999996)
		(stroke
			(width 3.048)
			(type default)
		)
		(layer "In2.Cu")
	)
	(gr_line
		(start 330.164948 0)
		(end 354.264976 0)
		(stroke
			(width 3.048)
			(type default)
		)
		(layer "In2.Cu")
	)
	(gr_circle
		(center 331.350112 -289.820096)
		(end 333.458058 -289.820096)
		(stroke
			(width 0.2)
			(type default)
		)
		(fill no)
		(layer "In2.Cu")
	)
	(gr_line
		(start 332.114906 -285.924752)
		(end 268.664436 -285.924752)
		(stroke
			(width 0.508)
			(type default)
		)
		(layer "In2.Cu")
	)
	(gr_line
		(start 332.452472 -293.562786)
		(end 332.452472 -285.587186)
		(stroke
			(width 0.508)
			(type default)
		)
		(layer "In2.Cu")
	)
	(gr_line
		(start 332.452472 -285.587186)
		(end 332.114906 -285.924752)
		(stroke
			(width 0.508)
			(type default)
		)
		(layer "In2.Cu")
	)
	(gr_line
		(start 332.452472 -285.587186)
		(end 332.452472 -279.197562)
		(stroke
			(width 0.508)
			(type default)
		)
		(layer "In2.Cu")
	)
	(gr_line
		(start 332.452472 -279.197562)
		(end 333.203042 -278.446992)
		(stroke
			(width 0.508)
			(type default)
		)
		(layer "In2.Cu")
	)
	(gr_line
		(start 333.06385 -294.174164)
		(end 332.452472 -293.562786)
		(stroke
			(width 0.508)
			(type default)
		)
		(layer "In2.Cu")
	)
	(gr_line
		(start 333.203042 -278.446992)
		(end 367.052352 -278.446992)
		(stroke
			(width 0.508)
			(type default)
		)
		(layer "In2.Cu")
	)
	(gr_circle
		(center 342.214962 -17.999964)
		(end 347.389958 -17.999964)
		(stroke
			(width 0.2)
			(type default)
		)
		(fill no)
		(layer "In2.Cu")
	)
	(gr_line
		(start 349.15475 -294.174164)
		(end 333.06385 -294.174164)
		(stroke
			(width 0.508)
			(type default)
		)
		(layer "In2.Cu")
	)
	(gr_line
		(start 349.611696 -294.250872)
		(end 349.875602 -294.514778)
		(stroke
			(width 0.508)
			(type default)
		)
		(layer "In2.Cu")
	)
	(gr_line
		(start 349.673926 -338.150454)
		(end 349.673926 -338.029804)
		(stroke
			(width 0.508)
			(type default)
		)
		(layer "In2.Cu")
	)
	(gr_line
		(start 349.673926 -338.029804)
		(end 349.96374 -337.73999)
		(stroke
			(width 0.508)
			(type default)
		)
		(layer "In2.Cu")
	)
	(gr_line
		(start 349.842836 -338.150454)
		(end 349.673926 -338.150454)
		(stroke
			(width 0.508)
			(type default)
		)
		(layer "In2.Cu")
	)
	(gr_line
		(start 349.875348 -294.514778)
		(end 349.611442 -294.250872)
		(stroke
			(width 0.508)
			(type default)
		)
		(layer "In2.Cu")
	)
	(gr_line
		(start 349.875602 -294.514778)
		(end 349.952056 -294.514778)
		(stroke
			(width 0.508)
			(type default)
		)
		(layer "In2.Cu")
	)
	(gr_circle
		(center 349.899986 -194.360038)
		(end 355.074982 -194.360038)
		(stroke
			(width 0.2)
			(type default)
		)
		(fill no)
		(layer "In2.Cu")
	)
	(gr_circle
		(center 349.899986 -72.69988)
		(end 355.074982 -72.69988)
		(stroke
			(width 0.2)
			(type default)
		)
		(fill no)
		(layer "In2.Cu")
	)
	(gr_line
		(start 349.93072 -326.550528)
		(end 349.93072 -294.29964)
		(stroke
			(width 0.508)
			(type default)
		)
		(layer "In2.Cu")
	)
	(gr_line
		(start 349.93072 -294.29964)
		(end 349.938086 -294.292274)
		(stroke
			(width 0.508)
			(type default)
		)
		(layer "In2.Cu")
	)
	(gr_line
		(start 349.930974 -338.062316)
		(end 349.842836 -338.150454)
		(stroke
			(width 0.508)
			(type default)
		)
		(layer "In2.Cu")
	)
	(gr_line
		(start 349.930974 -294.29964)
		(end 349.930974 -338.062316)
		(stroke
			(width 0.508)
			(type default)
		)
		(layer "In2.Cu")
	)
	(gr_line
		(start 349.938086 -294.58412)
		(end 350.23679 -294.285416)
		(stroke
			(width 0.508)
			(type default)
		)
		(layer "In2.Cu")
	)
	(gr_line
		(start 349.938086 -294.292274)
		(end 349.938086 -294.58412)
		(stroke
			(width 0.508)
			(type default)
		)
		(layer "In2.Cu")
	)
	(gr_line
		(start 349.93834 -294.58412)
		(end 349.93834 -294.292274)
		(stroke
			(width 0.508)
			(type default)
		)
		(layer "In2.Cu")
	)
	(gr_line
		(start 349.93834 -294.292274)
		(end 349.930974 -294.29964)
		(stroke
			(width 0.508)
			(type default)
		)
		(layer "In2.Cu")
	)
	(gr_line
		(start 349.951802 -294.514778)
		(end 349.875348 -294.514778)
		(stroke
			(width 0.508)
			(type default)
		)
		(layer "In2.Cu")
	)
	(gr_line
		(start 349.951802 -294.49395)
		(end 349.951802 -294.514778)
		(stroke
			(width 0.508)
			(type default)
		)
		(layer "In2.Cu")
	)
	(gr_line
		(start 349.952056 -294.514778)
		(end 349.952056 -294.49395)
		(stroke
			(width 0.508)
			(type default)
		)
		(layer "In2.Cu")
	)
	(gr_line
		(start 349.952056 -294.49395)
		(end 350.237044 -294.208962)
		(stroke
			(width 0.508)
			(type default)
		)
		(layer "In2.Cu")
	)
	(gr_line
		(start 349.96374 -337.73999)
		(end 350.229424 -338.005674)
		(stroke
			(width 0.508)
			(type default)
		)
		(layer "In2.Cu")
	)
	(gr_line
		(start 350.229424 -338.005674)
		(end 350.229424 -338.053934)
		(stroke
			(width 0.508)
			(type default)
		)
		(layer "In2.Cu")
	)
	(gr_line
		(start 350.23679 -294.285416)
		(end 350.23679 -294.208962)
		(stroke
			(width 0.508)
			(type default)
		)
		(layer "In2.Cu")
	)
	(gr_line
		(start 350.23679 -294.208962)
		(end 349.951802 -294.49395)
		(stroke
			(width 0.508)
			(type default)
		)
		(layer "In2.Cu")
	)
	(gr_line
		(start 350.237044 -294.285416)
		(end 349.93834 -294.58412)
		(stroke
			(width 0.508)
			(type default)
		)
		(layer "In2.Cu")
	)
	(gr_line
		(start 350.237044 -294.208962)
		(end 350.237044 -294.285416)
		(stroke
			(width 0.508)
			(type default)
		)
		(layer "In2.Cu")
	)
	(gr_arc
		(start 356.264972 -11.850116)
		(mid 356.557865 -12.557221)
		(end 357.26497 -12.850114)
		(stroke
			(width 3.048)
			(type default)
		)
		(layer "In2.Cu")
	)
	(gr_arc
		(start 356.264972 -1.999996)
		(mid 355.679184 -0.585796)
		(end 354.264976 0)
		(stroke
			(width 3.048)
			(type default)
		)
		(layer "In2.Cu")
	)
	(gr_line
		(start 356.264972 -1.999996)
		(end 356.264972 -11.850116)
		(stroke
			(width 3.048)
			(type default)
		)
		(layer "In2.Cu")
	)
	(gr_line
		(start 357.26497 -12.850114)
		(end 365.264954 -12.850114)
		(stroke
			(width 3.048)
			(type default)
		)
		(layer "In2.Cu")
	)
	(gr_line
		(start 362.985812 -271.989804)
		(end 364.754922 -270.220694)
		(stroke
			(width 0.635)
			(type default)
		)
		(layer "In2.Cu")
	)
	(gr_circle
		(center 363.590078 -407.599896)
		(end 368.765074 -407.599896)
		(stroke
			(width 0.2)
			(type default)
		)
		(fill no)
		(layer "In2.Cu")
	)
	(gr_line
		(start 364.754922 -270.220694)
		(end 363.830362 -271.145254)
		(stroke
			(width 0.635)
			(type default)
		)
		(layer "In2.Cu")
	)
	(gr_line
		(start 364.754922 -270.220694)
		(end 373.096028 -270.220694)
		(stroke
			(width 0.635)
			(type default)
		)
		(layer "In2.Cu")
	)
	(gr_arc
		(start 365.264954 -12.850114)
		(mid 365.972059 -12.557221)
		(end 366.264952 -11.850116)
		(stroke
			(width 3.048)
			(type default)
		)
		(layer "In2.Cu")
	)
	(gr_line
		(start 366.264952 -11.850116)
		(end 366.264952 -1.999996)
		(stroke
			(width 3.048)
			(type default)
		)
		(layer "In2.Cu")
	)
	(gr_line
		(start 367.052352 -278.446992)
		(end 367.68913 -279.08377)
		(stroke
			(width 0.508)
			(type default)
		)
		(layer "In2.Cu")
	)
	(gr_line
		(start 367.133378 -294.174164)
		(end 349.15475 -294.174164)
		(stroke
			(width 0.508)
			(type default)
		)
		(layer "In2.Cu")
	)
	(gr_line
		(start 367.68913 -293.618412)
		(end 367.133378 -294.174164)
		(stroke
			(width 0.508)
			(type default)
		)
		(layer "In2.Cu")
	)
	(gr_line
		(start 367.68913 -279.08377)
		(end 367.68913 -293.618412)
		(stroke
			(width 0.508)
			(type default)
		)
		(layer "In2.Cu")
	)
	(gr_line
		(start 367.689384 -286.086804)
		(end 367.960402 -286.357822)
		(stroke
			(width 0.508)
			(type default)
		)
		(layer "In2.Cu")
	)
	(gr_line
		(start 367.758726 -286.621728)
		(end 367.980468 -286.399986)
		(stroke
			(width 0.508)
			(type default)
		)
		(layer "In2.Cu")
	)
	(gr_line
		(start 367.766092 -286.621728)
		(end 367.758726 -286.621728)
		(stroke
			(width 0.508)
			(type default)
		)
		(layer "In2.Cu")
	)
	(gr_line
		(start 367.960402 -286.427418)
		(end 367.766092 -286.621728)
		(stroke
			(width 0.508)
			(type default)
		)
		(layer "In2.Cu")
	)
	(gr_line
		(start 367.960402 -286.357822)
		(end 367.960402 -286.427418)
		(stroke
			(width 0.508)
			(type default)
		)
		(layer "In2.Cu")
	)
	(gr_line
		(start 367.980468 -286.399986)
		(end 430.885854 -286.399986)
		(stroke
			(width 0.508)
			(type default)
		)
		(layer "In2.Cu")
	)
	(gr_arc
		(start 368.264948 0)
		(mid 366.850705 -0.585768)
		(end 366.264952 -1.999996)
		(stroke
			(width 3.048)
			(type default)
		)
		(layer "In2.Cu")
	)
	(gr_line
		(start 368.264948 0)
		(end 380.264924 0)
		(stroke
			(width 3.048)
			(type default)
		)
		(layer "In2.Cu")
	)
	(gr_circle
		(center 368.44986 -276.010116)
		(end 370.557806 -276.010116)
		(stroke
			(width 0.2)
			(type default)
		)
		(fill no)
		(layer "In2.Cu")
	)
	(gr_line
		(start 373.096028 -270.220694)
		(end 374.232424 -271.35709)
		(stroke
			(width 0.635)
			(type default)
		)
		(layer "In2.Cu")
	)
	(gr_line
		(start 373.096028 -270.220694)
		(end 374.684798 -271.809464)
		(stroke
			(width 0.635)
			(type default)
		)
		(layer "In2.Cu")
	)
	(gr_line
		(start 374.684798 -271.989804)
		(end 430.40554 -271.989804)
		(stroke
			(width 0.635)
			(type default)
		)
		(layer "In2.Cu")
	)
	(gr_line
		(start 374.684798 -271.809464)
		(end 374.684798 -271.989804)
		(stroke
			(width 0.635)
			(type default)
		)
		(layer "In2.Cu")
	)
	(gr_circle
		(center 377.949968 -320.900044)
		(end 382.585976 -320.900044)
		(stroke
			(width 0.2)
			(type default)
		)
		(fill no)
		(layer "In2.Cu")
	)
	(gr_circle
		(center 377.949968 -270.89989)
		(end 382.585976 -270.89989)
		(stroke
			(width 0.2)
			(type default)
		)
		(fill no)
		(layer "In2.Cu")
	)
	(gr_arc
		(start 382.26492 -11.850116)
		(mid 382.557813 -12.557221)
		(end 383.264918 -12.850114)
		(stroke
			(width 3.048)
			(type default)
		)
		(layer "In2.Cu")
	)
	(gr_arc
		(start 382.26492 -1.999996)
		(mid 381.679135 -0.585779)
		(end 380.264924 0)
		(stroke
			(width 3.048)
			(type default)
		)
		(layer "In2.Cu")
	)
	(gr_line
		(start 382.26492 -1.999996)
		(end 382.26492 -11.850116)
		(stroke
			(width 3.048)
			(type default)
		)
		(layer "In2.Cu")
	)
	(gr_line
		(start 383.264918 -12.850114)
		(end 391.264902 -12.850114)
		(stroke
			(width 3.048)
			(type default)
		)
		(layer "In2.Cu")
	)
	(gr_arc
		(start 391.264902 -12.850114)
		(mid 391.972007 -12.557221)
		(end 392.2649 -11.850116)
		(stroke
			(width 3.048)
			(type default)
		)
		(layer "In2.Cu")
	)
	(gr_line
		(start 392.2649 -11.850116)
		(end 392.2649 -1.999996)
		(stroke
			(width 3.048)
			(type default)
		)
		(layer "In2.Cu")
	)
	(gr_arc
		(start 394.264896 0)
		(mid 392.850686 -0.585786)
		(end 392.2649 -1.999996)
		(stroke
			(width 3.048)
			(type default)
		)
		(layer "In2.Cu")
	)
	(gr_line
		(start 394.264896 0)
		(end 406.265126 0)
		(stroke
			(width 3.048)
			(type default)
		)
		(layer "In2.Cu")
	)
	(gr_circle
		(center 400.264884 -4.99999)
		(end 405.43988 -4.99999)
		(stroke
			(width 0.2)
			(type default)
		)
		(fill no)
		(layer "In2.Cu")
	)
	(gr_arc
		(start 408.265122 -11.850116)
		(mid 408.558015 -12.557221)
		(end 409.26512 -12.850114)
		(stroke
			(width 3.048)
			(type default)
		)
		(layer "In2.Cu")
	)
	(gr_arc
		(start 408.265122 -1.999996)
		(mid 407.679337 -0.585779)
		(end 406.265126 0)
		(stroke
			(width 3.048)
			(type default)
		)
		(layer "In2.Cu")
	)
	(gr_line
		(start 408.265122 -1.999996)
		(end 408.265122 -11.850116)
		(stroke
			(width 3.048)
			(type default)
		)
		(layer "In2.Cu")
	)
	(gr_line
		(start 409.26512 -12.850114)
		(end 417.265104 -12.850114)
		(stroke
			(width 3.048)
			(type default)
		)
		(layer "In2.Cu")
	)
	(gr_arc
		(start 417.265104 -12.850114)
		(mid 417.972209 -12.557221)
		(end 418.265102 -11.850116)
		(stroke
			(width 3.048)
			(type default)
		)
		(layer "In2.Cu")
	)
	(gr_line
		(start 418.265102 -11.850116)
		(end 418.265102 -1.999996)
		(stroke
			(width 3.048)
			(type default)
		)
		(layer "In2.Cu")
	)
	(gr_arc
		(start 420.265098 0)
		(mid 418.850887 -0.585786)
		(end 418.265102 -1.999996)
		(stroke
			(width 3.048)
			(type default)
		)
		(layer "In2.Cu")
	)
	(gr_line
		(start 420.265098 0)
		(end 432.265074 0)
		(stroke
			(width 3.048)
			(type default)
		)
		(layer "In2.Cu")
	)
	(gr_line
		(start 429.985678 -338.174838)
		(end 431.225452 -336.935064)
		(stroke
			(width 0.635)
			(type default)
		)
		(layer "In2.Cu")
	)
	(gr_line
		(start 430.405286 -271.989804)
		(end 375.017792 -271.989804)
		(stroke
			(width 0.635)
			(type default)
		)
		(layer "In2.Cu")
	)
	(gr_line
		(start 430.40554 -271.989804)
		(end 375.017792 -271.989804)
		(stroke
			(width 0.635)
			(type default)
		)
		(layer "In2.Cu")
	)
	(gr_line
		(start 430.415192 -271.99971)
		(end 430.405286 -271.989804)
		(stroke
			(width 0.635)
			(type default)
		)
		(layer "In2.Cu")
	)
	(gr_line
		(start 430.540414 -271.99971)
		(end 430.415192 -271.99971)
		(stroke
			(width 0.635)
			(type default)
		)
		(layer "In2.Cu")
	)
	(gr_line
		(start 430.885854 -286.399986)
		(end 431.219356 -286.733488)
		(stroke
			(width 0.508)
			(type default)
		)
		(layer "In2.Cu")
	)
	(gr_line
		(start 430.906682 -286.38627)
		(end 430.906682 -286.337502)
		(stroke
			(width 0.508)
			(type default)
		)
		(layer "In2.Cu")
	)
	(gr_line
		(start 430.906682 -286.337502)
		(end 431.184558 -286.059626)
		(stroke
			(width 0.508)
			(type default)
		)
		(layer "In2.Cu")
	)
	(gr_line
		(start 431.184558 -286.059626)
		(end 431.198528 -286.059626)
		(stroke
			(width 0.508)
			(type default)
		)
		(layer "In2.Cu")
	)
	(gr_line
		(start 431.219356 -286.733488)
		(end 431.219356 -286.698944)
		(stroke
			(width 0.508)
			(type default)
		)
		(layer "In2.Cu")
	)
	(gr_line
		(start 431.219356 -286.698944)
		(end 430.906682 -286.38627)
		(stroke
			(width 0.508)
			(type default)
		)
		(layer "In2.Cu")
	)
	(gr_line
		(start 431.224944 -318.224662)
		(end 431.224944 -272.68424)
		(stroke
			(width 0.635)
			(type default)
		)
		(layer "In2.Cu")
	)
	(gr_line
		(start 431.224944 -272.68424)
		(end 430.540414 -271.99971)
		(stroke
			(width 0.635)
			(type default)
		)
		(layer "In2.Cu")
	)
	(gr_line
		(start 431.225198 -326.572118)
		(end 431.225198 -318.224916)
		(stroke
			(width 0.635)
			(type default)
		)
		(layer "In2.Cu")
	)
	(gr_line
		(start 431.225198 -318.224916)
		(end 431.224944 -318.224662)
		(stroke
			(width 0.635)
			(type default)
		)
		(layer "In2.Cu")
	)
	(gr_line
		(start 431.225452 -336.935064)
		(end 431.225452 -326.572118)
		(stroke
			(width 0.635)
			(type default)
		)
		(layer "In2.Cu")
	)
	(gr_arc
		(start 434.26507 -11.850116)
		(mid 434.557963 -12.557221)
		(end 435.265068 -12.850114)
		(stroke
			(width 3.048)
			(type default)
		)
		(layer "In2.Cu")
	)
	(gr_arc
		(start 434.26507 -1.999996)
		(mid 433.679282 -0.585797)
		(end 432.265074 0)
		(stroke
			(width 3.048)
			(type default)
		)
		(layer "In2.Cu")
	)
	(gr_line
		(start 434.26507 -1.999996)
		(end 434.26507 -11.850116)
		(stroke
			(width 3.048)
			(type default)
		)
		(layer "In2.Cu")
	)
	(gr_line
		(start 435.265068 -12.850114)
		(end 443.265052 -12.850114)
		(stroke
			(width 3.048)
			(type default)
		)
		(layer "In2.Cu")
	)
	(gr_circle
		(center 437.950102 -320.900044)
		(end 442.58611 -320.900044)
		(stroke
			(width 0.2)
			(type default)
		)
		(fill no)
		(layer "In2.Cu")
	)
	(gr_circle
		(center 437.950102 -270.89989)
		(end 442.58611 -270.89989)
		(stroke
			(width 0.2)
			(type default)
		)
		(fill no)
		(layer "In2.Cu")
	)
	(gr_arc
		(start 443.265052 -12.850114)
		(mid 443.972157 -12.557221)
		(end 444.26505 -11.850116)
		(stroke
			(width 3.048)
			(type default)
		)
		(layer "In2.Cu")
	)
	(gr_line
		(start 444.26505 -11.850116)
		(end 444.26505 -1.999996)
		(stroke
			(width 3.048)
			(type default)
		)
		(layer "In2.Cu")
	)
	(gr_arc
		(start 446.265046 0)
		(mid 444.850804 -0.585769)
		(end 444.26505 -1.999996)
		(stroke
			(width 3.048)
			(type default)
		)
		(layer "In2.Cu")
	)
	(gr_line
		(start 446.265046 0)
		(end 465.600034 0)
		(stroke
			(width 3.048)
			(type default)
		)
		(layer "In2.Cu")
	)
	(gr_circle
		(center 447.449702 -308.61)
		(end 449.557648 -308.61)
		(stroke
			(width 0.2)
			(type default)
		)
		(fill no)
		(layer "In2.Cu")
	)
	(gr_circle
		(center 448.799966 -84.699856)
		(end 453.974962 -84.699856)
		(stroke
			(width 0.2)
			(type default)
		)
		(fill no)
		(layer "In2.Cu")
	)
	(gr_circle
		(center 451.79996 -194.360038)
		(end 456.974956 -194.360038)
		(stroke
			(width 0.2)
			(type default)
		)
		(fill no)
		(layer "In2.Cu")
	)
	(gr_circle
		(center 455.93254 -4.99999)
		(end 461.107536 -4.99999)
		(stroke
			(width 0.2)
			(type default)
		)
		(fill no)
		(layer "In2.Cu")
	)
	(gr_circle
		(center 461.600042 -407.599896)
		(end 466.775038 -407.599896)
		(stroke
			(width 0.2)
			(type default)
		)
		(fill no)
		(layer "In2.Cu")
	)
	(gr_arc
		(start 463.799936 -241.031522)
		(mid 463.952177 -241.796887)
		(end 464.38566 -242.445794)
		(stroke
			(width 3.048)
			(type default)
		)
		(layer "In2.Cu")
	)
	(gr_line
		(start 463.799936 -87.588344)
		(end 463.799936 -241.031522)
		(stroke
			(width 3.048)
			(type default)
		)
		(layer "In2.Cu")
	)
	(gr_circle
		(center 464.100164 -313.85002)
		(end 466.20811 -313.85002)
		(stroke
			(width 0.2)
			(type default)
		)
		(fill no)
		(layer "In2.Cu")
	)
	(gr_line
		(start 464.38566 -242.445794)
		(end 467.014306 -245.074186)
		(stroke
			(width 3.048)
			(type default)
		)
		(layer "In2.Cu")
	)
	(gr_arc
		(start 464.38566 -86.174326)
		(mid 463.952174 -86.823083)
		(end 463.799936 -87.588344)
		(stroke
			(width 3.048)
			(type default)
		)
		(layer "In2.Cu")
	)
	(gr_line
		(start 465.600034 -418.589968)
		(end 274.758658 -418.589968)
		(stroke
			(width 3.048)
			(type default)
		)
		(layer "In2.Cu")
	)
	(gr_arc
		(start 465.600034 -418.589968)
		(mid 467.014213 -418.004169)
		(end 467.60003 -416.589972)
		(stroke
			(width 3.048)
			(type default)
		)
		(layer "In2.Cu")
	)
	(gr_line
		(start 467.007448 -367.183162)
		(end 267.890244 -367.183162)
		(stroke
			(width 0.635)
			(type default)
		)
		(layer "In2.Cu")
	)
	(gr_line
		(start 467.014306 -83.54568)
		(end 464.38566 -86.174326)
		(stroke
			(width 3.048)
			(type default)
		)
		(layer "In2.Cu")
	)
	(gr_arc
		(start 467.014306 -83.54568)
		(mid 467.447803 -82.896927)
		(end 467.60003 -82.131662)
		(stroke
			(width 3.048)
			(type default)
		)
		(layer "In2.Cu")
	)
	(gr_line
		(start 467.146386 -367.238788)
		(end 467.590886 -367.683288)
		(stroke
			(width 0.635)
			(type default)
		)
		(layer "In2.Cu")
	)
	(gr_line
		(start 467.422738 -50.06975)
		(end 467.834218 -50.48123)
		(stroke
			(width 0.635)
			(type default)
		)
		(layer "In2.Cu")
	)
	(gr_line
		(start 467.590886 -367.7666)
		(end 467.007448 -367.183162)
		(stroke
			(width 0.635)
			(type default)
		)
		(layer "In2.Cu")
	)
	(gr_line
		(start 467.590886 -367.683288)
		(end 467.590886 -367.7666)
		(stroke
			(width 0.635)
			(type default)
		)
		(layer "In2.Cu")
	)
	(gr_arc
		(start 467.60003 -246.488458)
		(mid 467.447879 -245.723043)
		(end 467.014306 -245.074186)
		(stroke
			(width 3.048)
			(type default)
		)
		(layer "In2.Cu")
	)
	(gr_line
		(start 467.60003 -246.488458)
		(end 467.60003 -416.589972)
		(stroke
			(width 3.048)
			(type default)
		)
		(layer "In2.Cu")
	)
	(gr_arc
		(start 467.60003 -1.999996)
		(mid 467.014245 -0.585776)
		(end 465.600034 0)
		(stroke
			(width 3.048)
			(type default)
		)
		(layer "In2.Cu")
	)
	(gr_line
		(start 467.60003 -1.999996)
		(end 467.60003 -82.131662)
		(stroke
			(width 3.048)
			(type default)
		)
		(layer "In2.Cu")
	)
	(gr_line
		(start 467.618826 -366.766348)
		(end 467.146386 -367.238788)
		(stroke
			(width 0.635)
			(type default)
		)
		(layer "In2.Cu")
	)
	(gr_line
		(start 467.702138 -366.766348)
		(end 467.618826 -366.766348)
		(stroke
			(width 0.635)
			(type default)
		)
		(layer "In2.Cu")
	)
	(gr_line
		(start -3.50901 -242.24742)
		(end 445.85636 -242.24742)
		(stroke
			(width 0.635)
			(type default)
		)
		(layer "In3.Cu")
	)
	(gr_line
		(start 0 -416.589972)
		(end 0 -246.488458)
		(stroke
			(width 3.048)
			(type default)
		)
		(layer "In3.Cu")
	)
	(gr_arc
		(start 0 -416.589972)
		(mid 0.585785 -418.004183)
		(end 1.999996 -418.589968)
		(stroke
			(width 3.048)
			(type default)
		)
		(layer "In3.Cu")
	)
	(gr_line
		(start 0 -82.131662)
		(end 0 -1.999996)
		(stroke
			(width 3.048)
			(type default)
		)
		(layer "In3.Cu")
	)
	(gr_arc
		(start 0 -82.131662)
		(mid 0.152239 -82.89692)
		(end 0.585724 -83.54568)
		(stroke
			(width 3.048)
			(type default)
		)
		(layer "In3.Cu")
	)
	(gr_poly
		(pts
			(arc
				(start 265.615928 -377.679966)
				(mid 265.635451 -377.676065)
				(end 265.651996 -377.66498)
			)
			(arc
				(start 265.851386 -377.46559)
				(mid 265.862497 -377.449056)
				(end 265.866372 -377.429522)
			)
			(arc
				(start 265.866372 -368.888264)
				(mid 265.863947 -368.872501)
				(end 265.85672 -368.858292)
			)
			(xy 265.849608 -368.848386) (xy 265.846814 -368.844068)
			(arc
				(start 265.514582 -368.51209)
				(mid 265.498048 -368.500979)
				(end 265.478514 -368.497104)
			)
			(arc
				(start 242.901216 -368.497104)
				(mid 242.881693 -368.501005)
				(end 242.865148 -368.51209)
			)
			(arc
				(start 242.760754 -368.616484)
				(mid 242.749643 -368.633018)
				(end 242.745768 -368.652552)
			)
			(arc
				(start 242.745768 -377.268994)
				(mid 242.749669 -377.288517)
				(end 242.760754 -377.305062)
			)
			(arc
				(start 243.120672 -377.66498)
				(mid 243.137206 -377.676091)
				(end 243.15674 -377.679966)
			)
		)
		(stroke
			(width 0)
			(type solid)
		)
		(fill yes)
		(layer "In3.Cu")
		(net "P12V_STBY_R2")
	)
	(gr_poly
		(pts
			(arc
				(start 241.741198 -376.399806)
				(mid 241.763367 -376.39459)
				(end 241.781076 -376.380248)
			)
			(arc
				(start 241.781076 -376.380248)
				(mid 241.793461 -376.365378)
				(end 241.80673 -376.351292)
			)
			(xy 242.08994 -376.068082)
			(arc
				(start 242.09502 -376.063002)
				(mid 242.106647 -376.046325)
				(end 242.110768 -376.026426)
			)
			(arc
				(start 242.110768 -368.666268)
				(mid 242.106867 -368.646745)
				(end 242.095782 -368.6302)
			)
			(arc
				(start 241.977672 -368.51209)
				(mid 241.961138 -368.500979)
				(end 241.941604 -368.497104)
			)
			(arc
				(start 236.370368 -368.497104)
				(mid 236.350845 -368.501005)
				(end 236.3343 -368.51209)
			)
			(arc
				(start 236.123734 -368.722656)
				(mid 236.112623 -368.73919)
				(end 236.108748 -368.758724)
			)
			(arc
				(start 236.108748 -376.146314)
				(mid 236.112649 -376.165837)
				(end 236.123734 -376.182382)
			)
			(arc
				(start 236.326172 -376.38482)
				(mid 236.342706 -376.395931)
				(end 236.36224 -376.399806)
			)
		)
		(stroke
			(width 0)
			(type solid)
		)
		(fill yes)
		(layer "In3.Cu")
		(net "P12V_STBY_R1")
	)
	(gr_poly
		(pts
			(arc
				(start 342.894158 -293.920164)
				(mid 342.913017 -293.916534)
				(end 342.92921 -293.906194)
			)
			(arc
				(start 342.92921 -293.906194)
				(mid 343.191846 -293.801301)
				(end 343.454482 -293.906194)
			)
			(arc
				(start 343.454482 -293.906194)
				(mid 343.470659 -293.916575)
				(end 343.489534 -293.920164)
			)
			(arc
				(start 359.553256 -293.920164)
				(mid 359.572115 -293.916534)
				(end 359.588308 -293.906194)
			)
			(arc
				(start 359.588308 -293.906194)
				(mid 359.850944 -293.801301)
				(end 360.11358 -293.906194)
			)
			(arc
				(start 360.11358 -293.906194)
				(mid 360.129757 -293.916575)
				(end 360.148632 -293.920164)
			)
			(arc
				(start 367.00714 -293.920164)
				(mid 367.026663 -293.916263)
				(end 367.043208 -293.905178)
			)
			(arc
				(start 367.420144 -293.528242)
				(mid 367.431255 -293.511708)
				(end 367.43513 -293.492174)
			)
			(arc
				(start 367.43513 -279.269698)
				(mid 367.425447 -279.239864)
				(end 367.400078 -279.221438)
			)
			(arc
				(start 367.400078 -279.221438)
				(mid 366.889251 -279.006592)
				(end 366.4204 -278.711152)
			)
			(arc
				(start 366.4204 -278.711152)
				(mid 366.405984 -278.703599)
				(end 366.38992 -278.700992)
			)
			(arc
				(start 333.32928 -278.700992)
				(mid 333.309757 -278.704893)
				(end 333.293212 -278.715978)
			)
			(xy 333.276702 -278.732488) (xy 333.269082 -278.747728)
			(arc
				(start 333.268066 -278.75611)
				(mid 333.159317 -278.978323)
				(end 332.937104 -279.087072)
			)
			(xy 332.928722 -279.088088) (xy 332.913482 -279.095708)
			(arc
				(start 332.721458 -279.287732)
				(mid 332.710347 -279.304266)
				(end 332.706472 -279.3238)
			)
			(arc
				(start 332.706472 -286.692594)
				(mid 332.714606 -286.720167)
				(end 332.736444 -286.738822)
			)
			(arc
				(start 332.736444 -286.738822)
				(mid 334.728894 -289.820096)
				(end 332.736444 -292.90137)
			)
			(arc
				(start 332.736444 -292.90137)
				(mid 332.714687 -292.920077)
				(end 332.706472 -292.947598)
			)
			(arc
				(start 332.706472 -293.436548)
				(mid 332.710373 -293.456071)
				(end 332.721458 -293.472616)
			)
			(arc
				(start 333.15402 -293.905178)
				(mid 333.170554 -293.916289)
				(end 333.190088 -293.920164)
			)
		)
		(stroke
			(width 0)
			(type solid)
		)
		(fill yes)
		(layer "In3.Cu")
		(net "GND")
	)
	(gr_poly
		(pts
			(arc
				(start 110.752382 -293.920164)
				(mid 110.769948 -293.917124)
				(end 110.785402 -293.908226)
			)
			(arc
				(start 110.785402 -293.908226)
				(mid 110.900474 -293.841319)
				(end 111.031528 -293.818056)
			)
			(arc
				(start 111.031528 -293.818056)
				(mid 111.162567 -293.841359)
				(end 111.277654 -293.908226)
			)
			(arc
				(start 111.277654 -293.908226)
				(mid 111.293097 -293.917153)
				(end 111.310674 -293.920164)
			)
			(arc
				(start 127.35306 -293.920164)
				(mid 127.371919 -293.916534)
				(end 127.388112 -293.906194)
			)
			(arc
				(start 127.388112 -293.906194)
				(mid 127.650748 -293.801301)
				(end 127.913384 -293.906194)
			)
			(arc
				(start 127.913384 -293.906194)
				(mid 127.929561 -293.916575)
				(end 127.948436 -293.920164)
			)
			(arc
				(start 134.807198 -293.920164)
				(mid 134.826721 -293.916263)
				(end 134.843266 -293.905178)
			)
			(arc
				(start 135.220202 -293.528242)
				(mid 135.231313 -293.511708)
				(end 135.235188 -293.492174)
			)
			(arc
				(start 135.235188 -279.269698)
				(mid 135.225505 -279.239864)
				(end 135.200136 -279.221438)
			)
			(arc
				(start 135.200136 -279.221438)
				(mid 134.689309 -279.006592)
				(end 134.220458 -278.711152)
			)
			(arc
				(start 134.220458 -278.711152)
				(mid 134.206042 -278.703599)
				(end 134.189978 -278.700992)
			)
			(arc
				(start 101.129338 -278.700992)
				(mid 101.109815 -278.704893)
				(end 101.09327 -278.715978)
			)
			(xy 101.076252 -278.732996) (xy 101.068886 -278.747982)
			(arc
				(start 101.06787 -278.756364)
				(mid 100.959143 -278.978345)
				(end 100.737162 -279.087072)
			)
			(xy 100.72878 -279.088088) (xy 100.713794 -279.095454)
			(arc
				(start 100.521516 -279.287732)
				(mid 100.510405 -279.304266)
				(end 100.50653 -279.3238)
			)
			(arc
				(start 100.50653 -286.692594)
				(mid 100.514595 -286.720315)
				(end 100.536502 -286.739076)
			)
			(arc
				(start 100.536502 -286.739076)
				(mid 102.52857 -289.820096)
				(end 100.536502 -292.901116)
			)
			(arc
				(start 100.536502 -292.901116)
				(mid 100.514677 -292.91993)
				(end 100.50653 -292.947598)
			)
			(arc
				(start 100.50653 -293.436548)
				(mid 100.510431 -293.456071)
				(end 100.521516 -293.472616)
			)
			(arc
				(start 100.954078 -293.905178)
				(mid 100.970612 -293.916289)
				(end 100.990146 -293.920164)
			)
		)
		(stroke
			(width 0)
			(type solid)
		)
		(fill yes)
		(layer "In3.Cu")
		(net "GND")
	)
	(gr_poly
		(pts
			(arc
				(start 235.60151 -413.087058)
				(mid 235.621033 -413.083157)
				(end 235.637578 -413.072072)
			)
			(arc
				(start 236.756956 -411.952694)
				(mid 236.768067 -411.93616)
				(end 236.771942 -411.916626)
			)
			(arc
				(start 236.771942 -402.84527)
				(mid 236.796095 -402.723754)
				(end 236.864906 -402.620734)
			)
			(arc
				(start 238.766604 -400.719036)
				(mid 238.869636 -400.650255)
				(end 238.99114 -400.626072)
			)
			(arc
				(start 242.910868 -400.626072)
				(mid 242.930391 -400.622171)
				(end 242.946936 -400.611086)
			)
			(arc
				(start 243.79682 -399.761202)
				(mid 243.807931 -399.744668)
				(end 243.811806 -399.725134)
			)
			(arc
				(start 243.811806 -392.09472)
				(mid 243.835959 -391.973204)
				(end 243.90477 -391.870184)
			)
			(arc
				(start 244.93093 -390.844024)
				(mid 245.033962 -390.775243)
				(end 245.155466 -390.75106)
			)
			(arc
				(start 259.056124 -390.75106)
				(mid 259.075647 -390.747159)
				(end 259.092192 -390.736074)
			)
			(arc
				(start 262.00481 -387.823456)
				(mid 262.015921 -387.806922)
				(end 262.019796 -387.787388)
			)
			(arc
				(start 262.019796 -379.197616)
				(mid 262.015895 -379.178093)
				(end 262.00481 -379.161548)
			)
			(arc
				(start 261.967472 -379.12421)
				(mid 261.950938 -379.113099)
				(end 261.931404 -379.109224)
			)
			(arc
				(start 240.584482 -379.109224)
				(mid 240.564959 -379.113125)
				(end 240.548414 -379.12421)
			)
			(arc
				(start 239.998504 -379.67412)
				(mid 239.895472 -379.742901)
				(end 239.773968 -379.767084)
			)
			(arc
				(start 237.129066 -379.767084)
				(mid 237.00755 -379.742931)
				(end 236.90453 -379.67412)
			)
			(arc
				(start 232.953814 -375.723404)
				(mid 232.885033 -375.620372)
				(end 232.86085 -375.498868)
			)
			(arc
				(start 232.86085 -372.11508)
				(mid 232.856949 -372.095557)
				(end 232.845864 -372.079012)
			)
			(arc
				(start 232.203752 -371.4369)
				(mid 232.134971 -371.333868)
				(end 232.110788 -371.212364)
			)
			(arc
				(start 232.110788 -371.075712)
				(mid 232.106887 -371.056189)
				(end 232.095802 -371.039644)
			)
			(arc
				(start 232.035858 -370.9797)
				(mid 231.967077 -370.876668)
				(end 231.942894 -370.755164)
			)
			(arc
				(start 231.942894 -367.397792)
				(mid 231.938993 -367.378269)
				(end 231.927908 -367.361724)
			)
			(arc
				(start 231.89057 -367.324386)
				(mid 231.874036 -367.313275)
				(end 231.854502 -367.3094)
			)
			(arc
				(start 228.741986 -367.3094)
				(mid 228.722463 -367.313301)
				(end 228.705918 -367.324386)
			)
			(arc
				(start 228.66858 -367.361724)
				(mid 228.657469 -367.378258)
				(end 228.653594 -367.397792)
			)
			(arc
				(start 228.653594 -370.74856)
				(mid 228.629441 -370.870076)
				(end 228.56063 -370.973096)
			)
			(arc
				(start 228.481128 -371.052598)
				(mid 228.470017 -371.069132)
				(end 228.466142 -371.088666)
			)
			(arc
				(start 228.466142 -371.354096)
				(mid 228.441989 -371.475612)
				(end 228.373178 -371.578632)
			)
			(arc
				(start 227.178362 -372.773448)
				(mid 227.167251 -372.789982)
				(end 227.163376 -372.809516)
			)
			(arc
				(start 227.163376 -374.166384)
				(mid 227.139223 -374.2879)
				(end 227.070412 -374.39092)
			)
			(arc
				(start 225.794062 -375.66727)
				(mid 225.69103 -375.736051)
				(end 225.569526 -375.760234)
			)
			(arc
				(start 223.648016 -375.760234)
				(mid 223.5265 -375.736081)
				(end 223.42348 -375.66727)
			)
			(arc
				(start 221.55531 -373.7991)
				(mid 221.486529 -373.696068)
				(end 221.462346 -373.574564)
			)
			(arc
				(start 221.462346 -371.091714)
				(mid 221.458445 -371.072191)
				(end 221.44736 -371.055646)
			)
			(arc
				(start 221.361508 -370.969794)
				(mid 221.292727 -370.866762)
				(end 221.268544 -370.745258)
			)
			(arc
				(start 221.268544 -367.391442)
				(mid 221.264643 -367.371919)
				(end 221.253558 -367.355374)
			)
			(arc
				(start 221.225872 -367.327688)
				(mid 221.209338 -367.316577)
				(end 221.189804 -367.312702)
			)
			(arc
				(start 218.110308 -367.312702)
				(mid 218.090785 -367.316603)
				(end 218.07424 -367.327688)
			)
			(arc
				(start 217.967306 -367.434622)
				(mid 217.956195 -367.451156)
				(end 217.95232 -367.47069)
			)
			(arc
				(start 217.95232 -370.719096)
				(mid 217.928167 -370.840612)
				(end 217.859356 -370.943632)
			)
			(arc
				(start 216.82964 -371.973348)
				(mid 216.726608 -372.042129)
				(end 216.605104 -372.066312)
			)
			(arc
				(start 210.424014 -372.066312)
				(mid 210.302498 -372.042159)
				(end 210.199478 -371.973348)
			)
			(arc
				(start 210.067906 -371.841776)
				(mid 209.999125 -371.738744)
				(end 209.974942 -371.61724)
			)
			(arc
				(start 209.974942 -371.309138)
				(mid 209.971041 -371.289615)
				(end 209.959956 -371.27307)
			)
			(arc
				(start 209.949034 -371.262148)
				(mid 209.9325 -371.251037)
				(end 209.912966 -371.247162)
			)
			(arc
				(start 209.559144 -371.247162)
				(mid 209.437628 -371.223009)
				(end 209.334608 -371.154198)
			)
			(arc
				(start 208.669382 -370.488972)
				(mid 208.652848 -370.477861)
				(end 208.633314 -370.473986)
			)
			(arc
				(start 208.394554 -370.473986)
				(mid 208.273038 -370.449833)
				(end 208.170018 -370.381022)
			)
			(arc
				(start 208.11744 -370.328444)
				(mid 208.048659 -370.225412)
				(end 208.024476 -370.103908)
			)
			(arc
				(start 208.024476 -367.401348)
				(mid 208.020575 -367.381825)
				(end 208.00949 -367.36528)
			)
			(arc
				(start 207.981804 -367.337594)
				(mid 207.96527 -367.326483)
				(end 207.945736 -367.322608)
			)
			(arc
				(start 204.823822 -367.322608)
				(mid 204.804299 -367.326509)
				(end 204.787754 -367.337594)
			)
			(arc
				(start 204.740002 -367.385346)
				(mid 204.728891 -367.40188)
				(end 204.725016 -367.421414)
			)
			(arc
				(start 204.725016 -370.796312)
				(mid 204.728917 -370.815835)
				(end 204.740002 -370.83238)
			)
			(arc
				(start 204.77353 -370.865908)
				(mid 204.842311 -370.96894)
				(end 204.866494 -371.090444)
			)
			(arc
				(start 204.866494 -374.47474)
				(mid 204.870058 -374.493432)
				(end 204.88021 -374.509538)
			)
			(arc
				(start 204.88021 -374.509538)
				(mid 204.94326 -374.609679)
				(end 204.9653 -374.725946)
			)
			(arc
				(start 204.9653 -387.02361)
				(mid 204.969201 -387.043133)
				(end 204.980286 -387.059678)
			)
			(arc
				(start 207.47482 -389.554212)
				(mid 207.543601 -389.657244)
				(end 207.567784 -389.778748)
			)
			(arc
				(start 207.567784 -411.696662)
				(mid 207.571685 -411.716185)
				(end 207.58277 -411.73273)
			)
			(arc
				(start 208.922112 -413.072072)
				(mid 208.938646 -413.083183)
				(end 208.95818 -413.087058)
			)
		)
		(stroke
			(width 0)
			(type solid)
		)
		(fill yes)
		(layer "In3.Cu")
		(net "P12V_STBY")
	)
	(gr_poly
		(pts
			(xy 197.632828 -337.857338) (xy 197.642895 -337.856908) (xy 197.661486 -337.84918) (xy 197.668896 -337.842352)
			(xy 198.69277 -336.818478) (xy 198.699616 -336.81108) (xy 198.707347 -336.792481) (xy 198.707756 -336.78241)
			(xy 198.707756 -318.236346) (xy 198.707502 -318.224662) (xy 198.707502 -303.159414) (xy 198.703692 -303.150016)
			(xy 198.694406 -303.126048) (xy 198.682529 -303.076039) (xy 198.678538 -303.024794) (xy 198.682531 -302.97355)
			(xy 198.694409 -302.923542) (xy 198.703692 -302.899572) (xy 198.707502 -302.890174) (xy 198.707502 -302.167544)
			(xy 198.705724 -302.161194) (xy 198.700374 -302.140006) (xy 198.694636 -302.096684) (xy 198.694294 -302.074834)
			(xy 198.694628 -302.052983) (xy 198.700363 -302.00966) (xy 198.705724 -301.988474) (xy 198.707502 -301.982124)
			(xy 198.707502 -301.217584) (xy 198.705724 -301.211234) (xy 198.700378 -301.190046) (xy 198.694648 -301.146724)
			(xy 198.694294 -301.124874) (xy 198.694625 -301.103023) (xy 198.700355 -301.059698) (xy 198.705724 -301.038514)
			(xy 198.707502 -301.032164) (xy 198.707502 -300.267624) (xy 198.705724 -300.261274) (xy 198.700375 -300.240086)
			(xy 198.69464 -300.196764) (xy 198.694294 -300.174914) (xy 198.694629 -300.153063) (xy 198.700366 -300.109741)
			(xy 198.705724 -300.088554) (xy 198.707502 -300.082204) (xy 198.707502 -299.317664) (xy 198.705724 -299.311314)
			(xy 198.700379 -299.290126) (xy 198.694652 -299.246804) (xy 198.694294 -299.224954) (xy 198.694627 -299.203103)
			(xy 198.700359 -299.159779) (xy 198.705724 -299.138594) (xy 198.707502 -299.132244) (xy 198.707502 -298.36745)
			(xy 198.705724 -298.3611) (xy 198.700373 -298.339912) (xy 198.694635 -298.29659) (xy 198.694294 -298.27474)
			(xy 198.694628 -298.252889) (xy 198.700361 -298.209565) (xy 198.705724 -298.18838) (xy 198.707502 -298.18203)
			(xy 198.707502 -297.41749) (xy 198.705724 -297.41114) (xy 198.700377 -297.389952) (xy 198.694647 -297.34663)
			(xy 198.694294 -297.32478) (xy 198.694625 -297.302929) (xy 198.700354 -297.259604) (xy 198.705724 -297.23842)
			(xy 198.707502 -297.23207) (xy 198.707502 -296.46753) (xy 198.705724 -296.46118) (xy 198.700375 -296.439992)
			(xy 198.694639 -296.39667) (xy 198.694294 -296.37482) (xy 198.694629 -296.352969) (xy 198.700365 -296.309646)
			(xy 198.705724 -296.28846) (xy 198.707502 -296.28211) (xy 198.707502 -294.56761) (xy 198.705724 -294.56126)
			(xy 198.700376 -294.540072) (xy 198.694643 -294.49675) (xy 198.694294 -294.4749) (xy 198.69463 -294.453049)
			(xy 198.700369 -294.409727) (xy 198.705724 -294.38854) (xy 198.707502 -294.38219) (xy 198.707502 -293.61765)
			(xy 198.705724 -293.6113) (xy 198.700373 -293.590112) (xy 198.694635 -293.54679) (xy 198.694294 -293.52494)
			(xy 198.694628 -293.503089) (xy 198.700361 -293.459765) (xy 198.705724 -293.43858) (xy 198.707502 -293.43223)
			(xy 198.707502 -292.66769) (xy 198.705724 -292.66134) (xy 198.700377 -292.640152) (xy 198.694647 -292.59683)
			(xy 198.694294 -292.57498) (xy 198.694625 -292.553129) (xy 198.700354 -292.509804) (xy 198.705724 -292.48862)
			(xy 198.707502 -292.48227) (xy 198.707502 -291.717476) (xy 198.705724 -291.711126) (xy 198.700378 -291.689938)
			(xy 198.69465 -291.646616) (xy 198.694294 -291.624766) (xy 198.694626 -291.602915) (xy 198.700356 -291.55959)
			(xy 198.705724 -291.538406) (xy 198.707502 -291.532056) (xy 198.707502 -290.767516) (xy 198.705724 -290.761166)
			(xy 198.700376 -290.739978) (xy 198.694642 -290.696656) (xy 198.694294 -290.674806) (xy 198.69463 -290.652955)
			(xy 198.700368 -290.609633) (xy 198.705724 -290.588446) (xy 198.707502 -290.582096) (xy 198.707502 -289.817556)
			(xy 198.705724 -289.811206) (xy 198.700373 -289.790018) (xy 198.694634 -289.746696) (xy 198.694294 -289.724846)
			(xy 198.694627 -289.702995) (xy 198.70036 -289.659671) (xy 198.705724 -289.638486) (xy 198.707502 -289.632136)
			(xy 198.707502 -286.801814) (xy 198.707063 -286.791751) (xy 198.699327 -286.773169) (xy 198.692516 -286.765746)
			(xy 198.654924 -286.728154) (xy 198.63054 -286.720788) (xy 198.617586 -286.723328) (xy 198.600891 -286.726637)
			(xy 198.56704 -286.730198) (xy 198.550022 -286.73044) (xy 198.523374 -286.729906) (xy 198.470766 -286.721363)
			(xy 198.420209 -286.704494) (xy 198.373012 -286.679736) (xy 198.351394 -286.664146) (xy 198.344654 -286.659476)
			(xy 198.329108 -286.654291) (xy 198.320914 -286.653986) (xy 197.82917 -286.653986) (xy 197.820978 -286.654299)
			(xy 197.805437 -286.659488) (xy 197.79869 -286.664146) (xy 197.777062 -286.679723) (xy 197.729869 -286.704485)
			(xy 197.679315 -286.721357) (xy 197.62671 -286.729905) (xy 197.573414 -286.729905) (xy 197.520809 -286.721357)
			(xy 197.470255 -286.704485) (xy 197.423062 -286.679723) (xy 197.401434 -286.664146) (xy 197.394691 -286.659485)
			(xy 197.379145 -286.654318) (xy 197.370954 -286.653986) (xy 196.878956 -286.653986) (xy 196.870765 -286.654302)
			(xy 196.855226 -286.659493) (xy 196.848476 -286.664146) (xy 196.826848 -286.679723) (xy 196.779655 -286.704485)
			(xy 196.729101 -286.721357) (xy 196.676496 -286.729905) (xy 196.6232 -286.729905) (xy 196.570595 -286.721357)
			(xy 196.520041 -286.704485) (xy 196.472848 -286.679723) (xy 196.45122 -286.664146) (xy 196.444481 -286.659473)
			(xy 196.428935 -286.65428) (xy 196.42074 -286.653986) (xy 195.928996 -286.653986) (xy 195.920803 -286.654295)
			(xy 195.905256 -286.659477) (xy 195.898516 -286.664146) (xy 195.876888 -286.679723) (xy 195.829695 -286.704485)
			(xy 195.779141 -286.721357) (xy 195.726536 -286.729905) (xy 195.67324 -286.729905) (xy 195.620635 -286.721357)
			(xy 195.570081 -286.704485) (xy 195.522888 -286.679723) (xy 195.50126 -286.664146) (xy 195.494518 -286.659481)
			(xy 195.478972 -286.654307) (xy 195.47078 -286.653986) (xy 194.979036 -286.653986) (xy 194.97084 -286.654289)
			(xy 194.955287 -286.659461) (xy 194.948556 -286.664146) (xy 194.926928 -286.679723) (xy 194.879735 -286.704485)
			(xy 194.829181 -286.721357) (xy 194.776576 -286.729905) (xy 194.72328 -286.729905) (xy 194.670675 -286.721357)
			(xy 194.620121 -286.704485) (xy 194.572928 -286.679723) (xy 194.5513 -286.664146) (xy 194.54456 -286.659476)
			(xy 194.529014 -286.654289) (xy 194.52082 -286.653986) (xy 194.02933 -286.653986) (xy 194.021135 -286.65429)
			(xy 194.005582 -286.659464) (xy 193.99885 -286.664146) (xy 193.977225 -286.679803) (xy 193.92998 -286.704661)
			(xy 193.879353 -286.721602) (xy 193.826661 -286.730184) (xy 193.773275 -286.730184) (xy 193.720583 -286.721602)
			(xy 193.669956 -286.704661) (xy 193.622711 -286.679803) (xy 193.601086 -286.664146) (xy 193.594346 -286.659477)
			(xy 193.5788 -286.654295) (xy 193.570606 -286.653986) (xy 193.07937 -286.653986) (xy 193.071178 -286.654299)
			(xy 193.055637 -286.659488) (xy 193.04889 -286.664146) (xy 193.027265 -286.679803) (xy 192.98002 -286.704661)
			(xy 192.929393 -286.721602) (xy 192.876701 -286.730184) (xy 192.823315 -286.730184) (xy 192.770623 -286.721602)
			(xy 192.719996 -286.704661) (xy 192.672751 -286.679803) (xy 192.651126 -286.664146) (xy 192.644387 -286.659472)
			(xy 192.628841 -286.654277) (xy 192.620646 -286.653986) (xy 192.129156 -286.653986) (xy 192.120965 -286.654302)
			(xy 192.105426 -286.659493) (xy 192.098676 -286.664146) (xy 192.077048 -286.679723) (xy 192.029855 -286.704485)
			(xy 191.979301 -286.721357) (xy 191.926696 -286.729905) (xy 191.8734 -286.729905) (xy 191.820795 -286.721357)
			(xy 191.770241 -286.704485) (xy 191.723048 -286.679723) (xy 191.70142 -286.664146) (xy 191.694681 -286.659473)
			(xy 191.679135 -286.65428) (xy 191.67094 -286.653986) (xy 191.179196 -286.653986) (xy 191.171003 -286.654295)
			(xy 191.155456 -286.659477) (xy 191.148716 -286.664146) (xy 191.127088 -286.679723) (xy 191.079895 -286.704485)
			(xy 191.029341 -286.721357) (xy 190.976736 -286.729905) (xy 190.92344 -286.729905) (xy 190.870835 -286.721357)
			(xy 190.820281 -286.704485) (xy 190.773088 -286.679723) (xy 190.75146 -286.664146) (xy 190.744718 -286.659481)
			(xy 190.729172 -286.654307) (xy 190.72098 -286.653986) (xy 190.228982 -286.653986) (xy 190.220789 -286.654298)
			(xy 190.205246 -286.659483) (xy 190.198502 -286.664146) (xy 190.176874 -286.679723) (xy 190.129681 -286.704485)
			(xy 190.079127 -286.721357) (xy 190.026522 -286.729905) (xy 189.973226 -286.729905) (xy 189.920621 -286.721357)
			(xy 189.870067 -286.704485) (xy 189.822874 -286.679723) (xy 189.801246 -286.664146) (xy 189.794504 -286.659483)
			(xy 189.778958 -286.654313) (xy 189.770766 -286.653986) (xy 148.049742 -286.653986) (xy 148.043011 -286.654156)
			(xy 148.030007 -286.657634) (xy 148.024088 -286.660844) (xy 148.002054 -286.673313) (xy 147.955393 -286.692962)
			(xy 147.906543 -286.706263) (xy 147.856362 -286.712982) (xy 147.831048 -286.713422) (xy 147.805733 -286.712993)
			(xy 147.755552 -286.706267) (xy 147.706701 -286.692966) (xy 147.660037 -286.673324) (xy 147.638008 -286.660844)
			(xy 147.63207 -286.657683) (xy 147.619077 -286.654222) (xy 147.612354 -286.653986) (xy 144.876774 -286.653986)
			(xy 144.870041 -286.654152) (xy 144.857034 -286.657622) (xy 144.85112 -286.660844) (xy 144.829086 -286.673315)
			(xy 144.782426 -286.692967) (xy 144.733576 -286.706273) (xy 144.683395 -286.712996) (xy 144.65808 -286.713422)
			(xy 144.632767 -286.712988) (xy 144.582589 -286.706254) (xy 144.533742 -286.692946) (xy 144.487083 -286.673297)
			(xy 144.46504 -286.660844) (xy 144.459103 -286.657679) (xy 144.44611 -286.654209) (xy 144.439386 -286.653986)
			(xy 143.987774 -286.653986) (xy 143.981041 -286.654152) (xy 143.968034 -286.657622) (xy 143.96212 -286.660844)
			(xy 143.940086 -286.673315) (xy 143.893426 -286.692967) (xy 143.844576 -286.706273) (xy 143.794395 -286.712996)
			(xy 143.76908 -286.713422) (xy 143.743767 -286.712988) (xy 143.693589 -286.706254) (xy 143.644742 -286.692946)
			(xy 143.598083 -286.673297) (xy 143.57604 -286.660844) (xy 143.570103 -286.657679) (xy 143.55711 -286.654209)
			(xy 143.550386 -286.653986) (xy 142.512288 -286.653986) (xy 142.505559 -286.654163) (xy 142.492562 -286.657653)
			(xy 142.486634 -286.660844) (xy 142.4646 -286.673315) (xy 142.417941 -286.69297) (xy 142.36909 -286.706277)
			(xy 142.318909 -286.713003) (xy 142.293594 -286.713422) (xy 142.26828 -286.712989) (xy 142.218102 -286.706257)
			(xy 142.169254 -286.69295) (xy 142.122594 -286.673302) (xy 142.100554 -286.660844) (xy 142.094618 -286.657677)
			(xy 142.081625 -286.654204) (xy 142.0749 -286.653986) (xy 135.91413 -286.653986) (xy 135.904065 -286.654421)
			(xy 135.885478 -286.662152) (xy 135.878062 -286.668972) (xy 135.758174 -286.78886) (xy 135.751329 -286.796258)
			(xy 135.743604 -286.814857) (xy 135.743188 -286.824928) (xy 135.743188 -293.618412) (xy 135.742616 -293.643372)
			(xy 135.732874 -293.692332) (xy 135.713768 -293.738451) (xy 135.686031 -293.779956) (xy 135.668766 -293.79799)
			(xy 135.113014 -294.353742) (xy 135.094972 -294.370999) (xy 135.053477 -294.398749) (xy 135.007359 -294.417855)
			(xy 134.958396 -294.427579) (xy 134.933436 -294.428164) (xy 127.965708 -294.428164) (xy 127.955286 -294.428673)
			(xy 127.93615 -294.436938) (xy 127.928624 -294.444166) (xy 127.90885 -294.464436) (xy 127.864383 -294.499495)
			(xy 127.815222 -294.527595) (xy 127.762447 -294.54812) (xy 127.707218 -294.560618) (xy 127.650748 -294.564815)
			(xy 127.594278 -294.560618) (xy 127.539049 -294.54812) (xy 127.486274 -294.527595) (xy 127.437113 -294.499495)
			(xy 127.392646 -294.464436) (xy 127.372872 -294.444166) (xy 127.365371 -294.436904) (xy 127.346218 -294.428649)
			(xy 127.335788 -294.428164) (xy 118.272306 -294.428164) (xy 118.261016 -294.428766) (xy 118.24058 -294.438377)
			(xy 118.232936 -294.446706) (xy 118.216426 -294.464994) (xy 117.999764 -294.681656) (xy 117.992919 -294.689054)
			(xy 117.985195 -294.707653) (xy 117.984778 -294.717724) (xy 117.984778 -297.350788) (xy 152.144482 -297.350788)
			(xy 152.144482 -297.298812) (xy 152.152612 -297.247477) (xy 152.168672 -297.198046) (xy 152.192268 -297.151735)
			(xy 152.222816 -297.109685) (xy 152.259567 -297.072932) (xy 152.301615 -297.04238) (xy 152.347923 -297.018782)
			(xy 152.397354 -297.002717) (xy 152.448688 -296.994583) (xy 152.474676 -296.994072) (xy 153.424636 -296.994072)
			(xy 153.45062 -296.994624) (xy 153.501947 -297.002759) (xy 153.55137 -297.018822) (xy 153.597671 -297.042418)
			(xy 153.639712 -297.072967) (xy 153.676457 -297.109715) (xy 153.707001 -297.151759) (xy 153.730592 -297.198064)
			(xy 153.74665 -297.247488) (xy 153.754779 -297.298816) (xy 153.754779 -297.350784) (xy 153.74665 -297.402112)
			(xy 153.730592 -297.451536) (xy 153.707001 -297.497841) (xy 153.676457 -297.539885) (xy 153.639712 -297.576633)
			(xy 153.597671 -297.607182) (xy 153.55137 -297.630778) (xy 153.501947 -297.646841) (xy 153.45062 -297.654976)
			(xy 153.424636 -297.655488) (xy 152.474676 -297.655488) (xy 152.448688 -297.655017) (xy 152.397354 -297.646883)
			(xy 152.347923 -297.630818) (xy 152.301615 -297.60722) (xy 152.259567 -297.576668) (xy 152.222816 -297.539915)
			(xy 152.192268 -297.497865) (xy 152.168672 -297.451554) (xy 152.152612 -297.402123) (xy 152.144482 -297.350788)
			(xy 117.984778 -297.350788) (xy 117.984778 -299.25101) (xy 152.144202 -299.25101) (xy 152.144202 -299.19899)
			(xy 152.152339 -299.147612) (xy 152.168413 -299.098138) (xy 152.192028 -299.051788) (xy 152.222603 -299.009703)
			(xy 152.259385 -298.972919) (xy 152.301468 -298.942341) (xy 152.347816 -298.918722) (xy 152.397288 -298.902645)
			(xy 152.448666 -298.894504) (xy 152.474676 -298.893992) (xy 153.424636 -298.893992) (xy 153.450638 -298.894597)
			(xy 153.502 -298.902737) (xy 153.551457 -298.918811) (xy 153.59779 -298.942424) (xy 153.63986 -298.972993)
			(xy 153.67663 -299.009767) (xy 153.707195 -299.05184) (xy 153.730803 -299.098177) (xy 153.746871 -299.147635)
			(xy 153.755006 -299.198998) (xy 153.755006 -299.251002) (xy 153.755005 -299.251009) (xy 154.994602 -299.251009)
			(xy 154.994602 -299.198991) (xy 155.002739 -299.147613) (xy 155.018812 -299.098141) (xy 155.042426 -299.051792)
			(xy 155.073 -299.009707) (xy 155.10978 -298.972923) (xy 155.151861 -298.942345) (xy 155.198208 -298.918726)
			(xy 155.247678 -298.902647) (xy 155.299055 -298.894505) (xy 155.325064 -298.893992) (xy 156.275024 -298.893992)
			(xy 156.301026 -298.894596) (xy 156.35239 -298.902735) (xy 156.401848 -298.918808) (xy 156.448184 -298.94242)
			(xy 156.490255 -298.972989) (xy 156.527026 -299.009763) (xy 156.557593 -299.051837) (xy 156.581201 -299.098174)
			(xy 156.597271 -299.147633) (xy 156.605406 -299.198998) (xy 156.605406 -299.251002) (xy 156.597271 -299.302367)
			(xy 156.581201 -299.351826) (xy 156.557593 -299.398163) (xy 156.527026 -299.440237) (xy 156.490255 -299.477011)
			(xy 156.448184 -299.50758) (xy 156.401848 -299.531192) (xy 156.35239 -299.547265) (xy 156.301026 -299.555404)
			(xy 156.275024 -299.555916) (xy 155.325064 -299.555916) (xy 155.299055 -299.555495) (xy 155.247678 -299.547353)
			(xy 155.198208 -299.531274) (xy 155.151861 -299.507655) (xy 155.10978 -299.477077) (xy 155.073 -299.440293)
			(xy 155.042426 -299.398208) (xy 155.018812 -299.351859) (xy 155.002739 -299.302387) (xy 154.994602 -299.251009)
			(xy 153.755005 -299.251009) (xy 153.746871 -299.302365) (xy 153.730803 -299.351823) (xy 153.707195 -299.39816)
			(xy 153.67663 -299.440233) (xy 153.63986 -299.477007) (xy 153.59779 -299.507576) (xy 153.551457 -299.531189)
			(xy 153.502 -299.547263) (xy 153.450638 -299.555403) (xy 153.424636 -299.555916) (xy 152.474676 -299.555916)
			(xy 152.448666 -299.555496) (xy 152.397288 -299.547355) (xy 152.347816 -299.531278) (xy 152.301468 -299.507659)
			(xy 152.259385 -299.477081) (xy 152.222603 -299.440297) (xy 152.192028 -299.398212) (xy 152.168413 -299.351862)
			(xy 152.152339 -299.302388) (xy 152.144202 -299.25101) (xy 117.984778 -299.25101) (xy 117.984778 -315.781436)
			(xy 117.984967 -315.787875) (xy 117.988181 -315.800346) (xy 117.991128 -315.806074) (xy 118.003934 -315.830332)
			(xy 118.023224 -315.881681) (xy 118.034961 -315.935263) (xy 118.038903 -315.989974) (xy 118.034969 -316.044685)
			(xy 118.023239 -316.098269) (xy 118.003956 -316.14962) (xy 117.991128 -316.173866) (xy 117.988169 -316.17959)
			(xy 117.984951 -316.192063) (xy 117.984778 -316.198504) (xy 117.984778 -317.484506) (xy 117.984964 -317.490946)
			(xy 117.988171 -317.50342) (xy 117.991128 -317.509144) (xy 118.003929 -317.533402) (xy 118.023209 -317.584749)
			(xy 118.034937 -317.638328) (xy 118.03887 -317.693035) (xy 118.034927 -317.747741) (xy 118.023189 -317.801318)
			(xy 118.0039 -317.852662) (xy 117.991128 -317.876936) (xy 117.988177 -317.882662) (xy 117.984976 -317.895135)
			(xy 117.984778 -317.901574) (xy 117.984778 -318.349122) (xy 117.984966 -318.355561) (xy 117.988176 -318.368034)
			(xy 117.991128 -318.37376) (xy 118.003935 -318.398018) (xy 118.023227 -318.449367) (xy 118.034966 -318.50295)
			(xy 118.03891 -318.557661) (xy 118.034977 -318.612374) (xy 118.023249 -318.665959) (xy 118.003967 -318.717312)
			(xy 117.991128 -318.741552) (xy 117.988167 -318.747276) (xy 117.984946 -318.759749) (xy 117.984778 -318.76619)
			(xy 117.984778 -320.900044) (xy 140.998709 -320.900044) (xy 141.002715 -320.704989) (xy 141.014725 -320.510263)
			(xy 141.03472 -320.316194) (xy 141.062665 -320.12311) (xy 141.098514 -319.931335) (xy 141.142206 -319.741195)
			(xy 141.193667 -319.553008) (xy 141.252811 -319.367093) (xy 141.319538 -319.183762) (xy 141.393735 -319.003326)
			(xy 141.475277 -318.826088) (xy 141.564028 -318.652347) (xy 141.659836 -318.482396) (xy 141.762541 -318.316522)
			(xy 141.871969 -318.155004) (xy 141.987936 -317.998115) (xy 142.110247 -317.84612) (xy 142.238694 -317.699274)
			(xy 142.373062 -317.557825) (xy 142.513124 -317.422012) (xy 142.658643 -317.292063) (xy 142.809375 -317.168199)
			(xy 142.965065 -317.050627) (xy 143.125451 -316.939547) (xy 143.290262 -316.835144) (xy 143.45922 -316.737596)
			(xy 143.632041 -316.647067) (xy 143.808433 -316.563709) (xy 143.988098 -316.487663) (xy 144.170733 -316.419058)
			(xy 144.356032 -316.358008) (xy 144.54368 -316.304618) (xy 144.733362 -316.258976) (xy 144.924759 -316.22116)
			(xy 145.117546 -316.191234) (xy 145.311399 -316.169248) (xy 145.505992 -316.155239) (xy 145.700995 -316.149231)
			(xy 145.896081 -316.151234) (xy 146.09092 -316.161245) (xy 146.285184 -316.179246) (xy 146.478545 -316.205208)
			(xy 146.670678 -316.239086) (xy 146.861257 -316.280823) (xy 147.049962 -316.33035) (xy 147.236475 -316.387582)
			(xy 147.420481 -316.452423) (xy 147.601669 -316.524764) (xy 147.779735 -316.604482) (xy 147.954378 -316.691444)
			(xy 148.125304 -316.785503) (xy 148.292223 -316.886499) (xy 148.454856 -316.994264) (xy 148.612927 -317.108614)
			(xy 148.76617 -317.229357) (xy 148.914327 -317.356291) (xy 149.057148 -317.489199) (xy 149.194392 -317.627859)
			(xy 149.325828 -317.772037) (xy 149.451233 -317.92149) (xy 149.570397 -318.075964) (xy 149.683118 -318.235201)
			(xy 149.789207 -318.398932) (xy 149.888485 -318.566879) (xy 149.980783 -318.738762) (xy 150.065948 -318.914288)
			(xy 150.143834 -319.093163) (xy 150.214311 -319.275085) (xy 150.277259 -319.459747) (xy 150.332574 -319.646837)
			(xy 150.38016 -319.836041) (xy 150.419939 -320.027038) (xy 150.451843 -320.219508) (xy 150.475818 -320.413126)
			(xy 150.491824 -320.607564) (xy 150.499833 -320.802496) (xy 150.500334 -320.900044) (xy 150.499833 -320.997592)
			(xy 150.491824 -321.192524) (xy 150.475818 -321.386962) (xy 150.451843 -321.58058) (xy 150.419939 -321.77305)
			(xy 150.38016 -321.964047) (xy 150.332574 -322.153251) (xy 150.277259 -322.340341) (xy 150.214311 -322.525003)
			(xy 150.143834 -322.706925) (xy 150.065948 -322.8858) (xy 149.980783 -323.061326) (xy 149.888485 -323.233209)
			(xy 149.789207 -323.401156) (xy 149.683118 -323.564887) (xy 149.570397 -323.724124) (xy 149.451233 -323.878598)
			(xy 149.325828 -324.028051) (xy 149.194392 -324.172229) (xy 149.057148 -324.310889) (xy 148.914327 -324.443797)
			(xy 148.76617 -324.570731) (xy 148.612927 -324.691474) (xy 148.454856 -324.805824) (xy 148.292223 -324.913589)
			(xy 148.125304 -325.014585) (xy 147.954378 -325.108644) (xy 147.779735 -325.195606) (xy 147.601669 -325.275324)
			(xy 147.420481 -325.347665) (xy 147.236475 -325.412506) (xy 147.049962 -325.469738) (xy 146.861257 -325.519265)
			(xy 146.670678 -325.561002) (xy 146.478545 -325.59488) (xy 146.285184 -325.620842) (xy 146.09092 -325.638843)
			(xy 145.896081 -325.648854) (xy 145.700995 -325.650857) (xy 145.505992 -325.644849) (xy 145.311399 -325.63084)
			(xy 145.117546 -325.608854) (xy 144.924759 -325.578928) (xy 144.733362 -325.541112) (xy 144.54368 -325.49547)
			(xy 144.356032 -325.44208) (xy 144.170733 -325.38103) (xy 143.988098 -325.312425) (xy 143.808433 -325.236379)
			(xy 143.632041 -325.153021) (xy 143.45922 -325.062492) (xy 143.290262 -324.964944) (xy 143.125451 -324.860541)
			(xy 142.965065 -324.749461) (xy 142.809375 -324.631889) (xy 142.658643 -324.508025) (xy 142.513124 -324.378076)
			(xy 142.373062 -324.242263) (xy 142.238694 -324.100814) (xy 142.110247 -323.953968) (xy 141.987936 -323.801973)
			(xy 141.871969 -323.645084) (xy 141.762541 -323.483566) (xy 141.659836 -323.317692) (xy 141.564028 -323.147741)
			(xy 141.475277 -322.974) (xy 141.393735 -322.796762) (xy 141.319538 -322.616326) (xy 141.252811 -322.432995)
			(xy 141.193667 -322.24708) (xy 141.142206 -322.058893) (xy 141.098514 -321.868753) (xy 141.062665 -321.676978)
			(xy 141.03472 -321.483894) (xy 141.014725 -321.289825) (xy 141.002715 -321.095099) (xy 140.998709 -320.900044)
			(xy 117.984778 -320.900044) (xy 117.984778 -329.207368) (xy 117.985008 -329.214843) (xy 117.989276 -329.22917)
			(xy 117.99316 -329.235562) (xy 118.008289 -329.259148) (xy 118.03221 -329.309819) (xy 118.048455 -329.363446)
			(xy 118.056675 -329.418873) (xy 118.057168 -329.44689) (xy 118.056655 -329.474905) (xy 118.048425 -329.530328)
			(xy 118.032185 -329.583953) (xy 118.008282 -329.63463) (xy 117.99316 -329.658218) (xy 117.98927 -329.664606)
			(xy 117.985012 -329.678936) (xy 117.984778 -329.686412) (xy 117.984778 -337.580986) (xy 117.985285 -337.591036)
			(xy 117.993008 -337.609595) (xy 117.999764 -337.617054) (xy 118.208806 -337.826096) (xy 118.221506 -337.839812)
			(xy 118.229064 -337.847712) (xy 118.248939 -337.856772) (xy 118.25986 -337.857338)
		)
		(stroke
			(width 0)
			(type solid)
		)
		(fill yes)
		(layer "In3.Cu")
		(net "P0V8_PEX1")
	)
	(gr_poly
		(pts
			(xy 429.833024 -337.857338) (xy 429.843091 -337.856909) (xy 429.861683 -337.849181) (xy 429.869092 -337.842352)
			(xy 430.892966 -336.818478) (xy 430.899813 -336.81108) (xy 430.907545 -336.792482) (xy 430.907952 -336.78241)
			(xy 430.907952 -326.583802) (xy 430.907698 -326.572118) (xy 430.907698 -318.236346) (xy 430.907444 -318.224662)
			(xy 430.907444 -303.159414) (xy 430.903634 -303.150016) (xy 430.894349 -303.126047) (xy 430.882474 -303.076039)
			(xy 430.878485 -303.024794) (xy 430.882476 -302.97355) (xy 430.894353 -302.923542) (xy 430.903634 -302.899572)
			(xy 430.907444 -302.890174) (xy 430.907444 -302.167544) (xy 430.905666 -302.161194) (xy 430.900315 -302.140006)
			(xy 430.894577 -302.096684) (xy 430.894236 -302.074834) (xy 430.89457 -302.052983) (xy 430.900304 -302.009659)
			(xy 430.905666 -301.988474) (xy 430.907444 -301.982124) (xy 430.907444 -301.217584) (xy 430.905666 -301.211234)
			(xy 430.900319 -301.190046) (xy 430.894589 -301.146724) (xy 430.894236 -301.124874) (xy 430.894567 -301.103023)
			(xy 430.900296 -301.059698) (xy 430.905666 -301.038514) (xy 430.907444 -301.032164) (xy 430.907444 -300.267624)
			(xy 430.905666 -300.261274) (xy 430.900316 -300.240086) (xy 430.894581 -300.196764) (xy 430.894236 -300.174914)
			(xy 430.894571 -300.153063) (xy 430.900307 -300.10974) (xy 430.905666 -300.088554) (xy 430.907444 -300.082204)
			(xy 430.907444 -299.317664) (xy 430.905666 -299.311314) (xy 430.90032 -299.290126) (xy 430.894593 -299.246804)
			(xy 430.894236 -299.224954) (xy 430.894569 -299.203103) (xy 430.9003 -299.159779) (xy 430.905666 -299.138594)
			(xy 430.907444 -299.132244) (xy 430.907444 -298.36745) (xy 430.905666 -298.3611) (xy 430.900315 -298.339912)
			(xy 430.894576 -298.29659) (xy 430.894236 -298.27474) (xy 430.89457 -298.252889) (xy 430.900302 -298.209565)
			(xy 430.905666 -298.18838) (xy 430.907444 -298.18203) (xy 430.907444 -297.41749) (xy 430.905666 -297.41114)
			(xy 430.900319 -297.389952) (xy 430.894587 -297.34663) (xy 430.894236 -297.32478) (xy 430.894567 -297.302929)
			(xy 430.900295 -297.259603) (xy 430.905666 -297.23842) (xy 430.907444 -297.23207) (xy 430.907444 -296.46753)
			(xy 430.905666 -296.46118) (xy 430.900316 -296.439992) (xy 430.89458 -296.39667) (xy 430.894236 -296.37482)
			(xy 430.894571 -296.352969) (xy 430.900306 -296.309646) (xy 430.905666 -296.28846) (xy 430.907444 -296.28211)
			(xy 430.907444 -294.56761) (xy 430.905666 -294.56126) (xy 430.900317 -294.540072) (xy 430.894584 -294.49675)
			(xy 430.894236 -294.4749) (xy 430.894572 -294.453049) (xy 430.90031 -294.409727) (xy 430.905666 -294.38854)
			(xy 430.907444 -294.38219) (xy 430.907444 -293.61765) (xy 430.905666 -293.6113) (xy 430.900315 -293.590112)
			(xy 430.894576 -293.54679) (xy 430.894236 -293.52494) (xy 430.89457 -293.503089) (xy 430.900302 -293.459765)
			(xy 430.905666 -293.43858) (xy 430.907444 -293.43223) (xy 430.907444 -292.66769) (xy 430.905666 -292.66134)
			(xy 430.900319 -292.640152) (xy 430.894587 -292.59683) (xy 430.894236 -292.57498) (xy 430.894567 -292.553129)
			(xy 430.900295 -292.509803) (xy 430.905666 -292.48862) (xy 430.907444 -292.48227) (xy 430.907444 -291.717476)
			(xy 430.905666 -291.711126) (xy 430.90032 -291.689938) (xy 430.89459 -291.646616) (xy 430.894236 -291.624766)
			(xy 430.894568 -291.602915) (xy 430.900297 -291.55959) (xy 430.905666 -291.538406) (xy 430.907444 -291.532056)
			(xy 430.907444 -290.767516) (xy 430.905666 -290.761166) (xy 430.900317 -290.739978) (xy 430.894582 -290.696656)
			(xy 430.894236 -290.674806) (xy 430.894572 -290.652955) (xy 430.900309 -290.609633) (xy 430.905666 -290.588446)
			(xy 430.907444 -290.582096) (xy 430.907444 -289.817556) (xy 430.905666 -289.811206) (xy 430.900314 -289.790018)
			(xy 430.894575 -289.746696) (xy 430.894236 -289.724846) (xy 430.894569 -289.702995) (xy 430.900301 -289.659671)
			(xy 430.905666 -289.638486) (xy 430.907444 -289.632136) (xy 430.907444 -288.867596) (xy 430.905666 -288.861246)
			(xy 430.900318 -288.840058) (xy 430.894586 -288.796736) (xy 430.894236 -288.774886) (xy 430.894573 -288.753035)
			(xy 430.900313 -288.709714) (xy 430.905666 -288.688526) (xy 430.907444 -288.682176) (xy 430.907444 -286.801814)
			(xy 430.907004 -286.791752) (xy 430.899261 -286.773176) (xy 430.892458 -286.765746) (xy 430.854866 -286.728154)
			(xy 430.830482 -286.720788) (xy 430.817528 -286.723328) (xy 430.800833 -286.726639) (xy 430.766983 -286.730204)
			(xy 430.749964 -286.73044) (xy 430.723317 -286.729902) (xy 430.670714 -286.72135) (xy 430.620163 -286.704474)
			(xy 430.572972 -286.679711) (xy 430.551336 -286.664146) (xy 430.544593 -286.659485) (xy 430.529047 -286.654317)
			(xy 430.520856 -286.653986) (xy 430.029112 -286.653986) (xy 430.020918 -286.654293) (xy 430.005368 -286.659471)
			(xy 429.998632 -286.664146) (xy 429.977004 -286.679723) (xy 429.929811 -286.704485) (xy 429.879257 -286.721357)
			(xy 429.826652 -286.729905) (xy 429.773356 -286.729905) (xy 429.720751 -286.721357) (xy 429.670197 -286.704485)
			(xy 429.623004 -286.679723) (xy 429.601376 -286.664146) (xy 429.594635 -286.659479) (xy 429.579089 -286.654299)
			(xy 429.570896 -286.653986) (xy 429.078898 -286.653986) (xy 429.070704 -286.654295) (xy 429.055158 -286.659477)
			(xy 429.048418 -286.664146) (xy 429.02679 -286.679723) (xy 428.979597 -286.704485) (xy 428.929043 -286.721357)
			(xy 428.876438 -286.729905) (xy 428.823142 -286.729905) (xy 428.770537 -286.721357) (xy 428.719983 -286.704485)
			(xy 428.67279 -286.679723) (xy 428.651162 -286.664146) (xy 428.64442 -286.659481) (xy 428.628874 -286.654306)
			(xy 428.620682 -286.653986) (xy 428.128938 -286.653986) (xy 428.120742 -286.654289) (xy 428.105188 -286.659461)
			(xy 428.098458 -286.664146) (xy 428.07683 -286.679723) (xy 428.029637 -286.704485) (xy 427.979083 -286.721357)
			(xy 427.926478 -286.729905) (xy 427.873182 -286.729905) (xy 427.820577 -286.721357) (xy 427.770023 -286.704485)
			(xy 427.72283 -286.679723) (xy 427.701202 -286.664146) (xy 427.694462 -286.659475) (xy 427.678916 -286.654288)
			(xy 427.670722 -286.653986) (xy 427.178978 -286.653986) (xy 427.170786 -286.654298) (xy 427.155243 -286.659484)
			(xy 427.148498 -286.664146) (xy 427.12687 -286.679723) (xy 427.079677 -286.704485) (xy 427.029123 -286.721357)
			(xy 426.976518 -286.729905) (xy 426.923222 -286.729905) (xy 426.870617 -286.721357) (xy 426.820063 -286.704485)
			(xy 426.77287 -286.679723) (xy 426.751242 -286.664146) (xy 426.7445 -286.659484) (xy 426.728954 -286.654315)
			(xy 426.720762 -286.653986) (xy 426.229272 -286.653986) (xy 426.22108 -286.654299) (xy 426.205538 -286.659487)
			(xy 426.198792 -286.664146) (xy 426.177167 -286.679803) (xy 426.129922 -286.704661) (xy 426.079295 -286.721602)
			(xy 426.026603 -286.730184) (xy 425.973217 -286.730184) (xy 425.920525 -286.721602) (xy 425.869898 -286.704661)
			(xy 425.822653 -286.679803) (xy 425.801028 -286.664146) (xy 425.794289 -286.659472) (xy 425.778743 -286.654277)
			(xy 425.770548 -286.653986) (xy 425.279312 -286.653986) (xy 425.271118 -286.654293) (xy 425.255568 -286.659471)
			(xy 425.248832 -286.664146) (xy 425.227207 -286.679803) (xy 425.179962 -286.704661) (xy 425.129335 -286.721602)
			(xy 425.076643 -286.730184) (xy 425.023257 -286.730184) (xy 424.970565 -286.721602) (xy 424.919938 -286.704661)
			(xy 424.872693 -286.679803) (xy 424.851068 -286.664146) (xy 424.844327 -286.65948) (xy 424.828781 -286.654303)
			(xy 424.820588 -286.653986) (xy 424.329098 -286.653986) (xy 424.320904 -286.654295) (xy 424.305358 -286.659477)
			(xy 424.298618 -286.664146) (xy 424.27699 -286.679723) (xy 424.229797 -286.704485) (xy 424.179243 -286.721357)
			(xy 424.126638 -286.729905) (xy 424.073342 -286.729905) (xy 424.020737 -286.721357) (xy 423.970183 -286.704485)
			(xy 423.92299 -286.679723) (xy 423.901362 -286.664146) (xy 423.89462 -286.659481) (xy 423.879074 -286.654306)
			(xy 423.870882 -286.653986) (xy 423.379138 -286.653986) (xy 423.370942 -286.654289) (xy 423.355388 -286.659461)
			(xy 423.348658 -286.664146) (xy 423.32703 -286.679723) (xy 423.279837 -286.704485) (xy 423.229283 -286.721357)
			(xy 423.176678 -286.729905) (xy 423.123382 -286.729905) (xy 423.070777 -286.721357) (xy 423.020223 -286.704485)
			(xy 422.97303 -286.679723) (xy 422.951402 -286.664146) (xy 422.944662 -286.659475) (xy 422.929116 -286.654288)
			(xy 422.920922 -286.653986) (xy 422.428924 -286.653986) (xy 422.420729 -286.654291) (xy 422.405178 -286.659466)
			(xy 422.398444 -286.664146) (xy 422.376816 -286.679723) (xy 422.329623 -286.704485) (xy 422.279069 -286.721357)
			(xy 422.226464 -286.729905) (xy 422.173168 -286.729905) (xy 422.120563 -286.721357) (xy 422.070009 -286.704485)
			(xy 422.022816 -286.679723) (xy 422.001188 -286.664146) (xy 421.994448 -286.659477) (xy 421.978902 -286.654294)
			(xy 421.970708 -286.653986) (xy 380.249684 -286.653986) (xy 380.242951 -286.654151) (xy 380.229942 -286.657619)
			(xy 380.22403 -286.660844) (xy 380.201996 -286.673315) (xy 380.155336 -286.692969) (xy 380.106486 -286.706276)
			(xy 380.056305 -286.713001) (xy 380.03099 -286.713422) (xy 380.005676 -286.712989) (xy 379.955498 -286.706256)
			(xy 379.906651 -286.692949) (xy 379.859991 -286.673301) (xy 379.83795 -286.660844) (xy 379.832014 -286.657678)
			(xy 379.819021 -286.654206) (xy 379.812296 -286.653986) (xy 377.076716 -286.653986) (xy 377.069986 -286.65416)
			(xy 377.056986 -286.657643) (xy 377.051062 -286.660844) (xy 377.029029 -286.673317) (xy 376.982369 -286.692975)
			(xy 376.933519 -286.706286) (xy 376.883337 -286.713015) (xy 376.858022 -286.713422) (xy 376.832708 -286.712991)
			(xy 376.782528 -286.706262) (xy 376.733678 -286.692958) (xy 376.687016 -286.673313) (xy 376.664982 -286.660844)
			(xy 376.659046 -286.657674) (xy 376.646053 -286.654194) (xy 376.639328 -286.653986) (xy 376.187716 -286.653986)
			(xy 376.180986 -286.65416) (xy 376.167986 -286.657643) (xy 376.162062 -286.660844) (xy 376.140029 -286.673317)
			(xy 376.093369 -286.692975) (xy 376.044519 -286.706286) (xy 375.994337 -286.713015) (xy 375.969022 -286.713422)
			(xy 375.943708 -286.712991) (xy 375.893528 -286.706262) (xy 375.844678 -286.692958) (xy 375.798016 -286.673313)
			(xy 375.775982 -286.660844) (xy 375.770046 -286.657674) (xy 375.757053 -286.654194) (xy 375.750328 -286.653986)
			(xy 374.71223 -286.653986) (xy 374.705499 -286.654158) (xy 374.692497 -286.657638) (xy 374.686576 -286.660844)
			(xy 374.664543 -286.673318) (xy 374.617884 -286.692978) (xy 374.569034 -286.70629) (xy 374.518852 -286.713022)
			(xy 374.493536 -286.713422) (xy 374.468222 -286.712992) (xy 374.418041 -286.706264) (xy 374.369191 -286.692962)
			(xy 374.322527 -286.673319) (xy 374.300496 -286.660844) (xy 374.294561 -286.657672) (xy 374.281568 -286.654189)
			(xy 374.274842 -286.653986) (xy 368.114072 -286.653986) (xy 368.104004 -286.654414) (xy 368.085405 -286.662134)
			(xy 368.078004 -286.668972) (xy 367.958116 -286.78886) (xy 367.951277 -286.796261) (xy 367.943562 -286.814859)
			(xy 367.94313 -286.824928) (xy 367.94313 -293.618412) (xy 367.942517 -293.643368) (xy 367.932779 -293.692322)
			(xy 367.913678 -293.738436) (xy 367.885949 -293.779937) (xy 367.868708 -293.79799) (xy 367.312956 -294.353742)
			(xy 367.294915 -294.371002) (xy 367.253421 -294.398759) (xy 367.207303 -294.417872) (xy 367.158339 -294.427605)
			(xy 367.133378 -294.428164) (xy 360.165904 -294.428164) (xy 360.155483 -294.428674) (xy 360.136348 -294.43694)
			(xy 360.12882 -294.444166) (xy 360.109046 -294.464436) (xy 360.064579 -294.499495) (xy 360.015418 -294.527595)
			(xy 359.962643 -294.54812) (xy 359.907414 -294.560618) (xy 359.850944 -294.564815) (xy 359.794474 -294.560618)
			(xy 359.739245 -294.54812) (xy 359.68647 -294.527595) (xy 359.637309 -294.499495) (xy 359.592842 -294.464436)
			(xy 359.573068 -294.444166) (xy 359.565566 -294.436905) (xy 359.546414 -294.428651) (xy 359.535984 -294.428164)
			(xy 350.472502 -294.428164) (xy 350.461212 -294.428766) (xy 350.440778 -294.438379) (xy 350.433132 -294.446706)
			(xy 350.416622 -294.464994) (xy 350.19996 -294.681656) (xy 350.193116 -294.689055) (xy 350.185392 -294.707654)
			(xy 350.184974 -294.717724) (xy 350.184974 -297.350792) (xy 384.344355 -297.350792) (xy 384.344355 -297.298808)
			(xy 384.352488 -297.247465) (xy 384.368552 -297.198026) (xy 384.392153 -297.151709) (xy 384.422709 -297.109654)
			(xy 384.459467 -297.072897) (xy 384.501524 -297.042343) (xy 384.547842 -297.018745) (xy 384.597282 -297.002683)
			(xy 384.648626 -296.994554) (xy 384.674618 -296.994072) (xy 385.624578 -296.994072) (xy 385.650567 -296.994593)
			(xy 385.701905 -297.002721) (xy 385.751339 -297.018781) (xy 385.797653 -297.042376) (xy 385.839705 -297.072926)
			(xy 385.87646 -297.109678) (xy 385.907013 -297.151728) (xy 385.930611 -297.19804) (xy 385.946673 -297.247474)
			(xy 385.954805 -297.298811) (xy 385.954805 -297.350789) (xy 385.946673 -297.402126) (xy 385.930611 -297.45156)
			(xy 385.907013 -297.497872) (xy 385.87646 -297.539922) (xy 385.839705 -297.576674) (xy 385.797653 -297.607224)
			(xy 385.751339 -297.630819) (xy 385.701905 -297.646879) (xy 385.650567 -297.655007) (xy 385.624578 -297.655488)
			(xy 384.674618 -297.655488) (xy 384.648626 -297.655046) (xy 384.597282 -297.646917) (xy 384.547842 -297.630855)
			(xy 384.501524 -297.607257) (xy 384.459467 -297.576703) (xy 384.422709 -297.539946) (xy 384.392153 -297.497891)
			(xy 384.368552 -297.451574) (xy 384.352488 -297.402135) (xy 384.344355 -297.350792) (xy 350.184974 -297.350792)
			(xy 350.184974 -298.775685) (xy 387.669821 -298.775685) (xy 387.669821 -298.723715) (xy 387.677951 -298.672385)
			(xy 387.69401 -298.622959) (xy 387.717603 -298.576653) (xy 387.74815 -298.534608) (xy 387.784897 -298.497859)
			(xy 387.826941 -298.467311) (xy 387.873246 -298.443716) (xy 387.922671 -298.427654) (xy 387.974001 -298.419523)
			(xy 387.999986 -298.419012) (xy 388.949946 -298.419012) (xy 388.975932 -298.419485) (xy 389.027264 -298.427622)
			(xy 389.076692 -298.443688) (xy 389.122998 -298.467288) (xy 389.165042 -298.49784) (xy 389.20179 -298.534593)
			(xy 389.232337 -298.576642) (xy 389.25593 -298.622951) (xy 389.271989 -298.67238) (xy 389.280119 -298.723714)
			(xy 389.280119 -298.775686) (xy 389.271989 -298.82702) (xy 389.25593 -298.876449) (xy 389.232337 -298.922758)
			(xy 389.20179 -298.964807) (xy 389.165042 -299.00156) (xy 389.122998 -299.032112) (xy 389.076692 -299.055712)
			(xy 389.027264 -299.071778) (xy 388.975932 -299.079915) (xy 388.949946 -299.080428) (xy 387.999986 -299.080428)
			(xy 387.974001 -299.079877) (xy 387.922671 -299.071746) (xy 387.873246 -299.055684) (xy 387.826941 -299.032089)
			(xy 387.784897 -299.001541) (xy 387.74815 -298.964792) (xy 387.717603 -298.922747) (xy 387.69401 -298.876441)
			(xy 387.677951 -298.827015) (xy 387.669821 -298.775685) (xy 350.184974 -298.775685) (xy 350.184974 -299.251014)
			(xy 384.344076 -299.251014) (xy 384.344076 -299.198986) (xy 384.352215 -299.147599) (xy 384.368293 -299.098118)
			(xy 384.391913 -299.051762) (xy 384.422495 -299.009672) (xy 384.459285 -298.972884) (xy 384.501377 -298.942304)
			(xy 384.547735 -298.918686) (xy 384.597217 -298.902611) (xy 384.648604 -298.894474) (xy 384.674618 -298.893992)
			(xy 385.624578 -298.893992) (xy 385.650585 -298.894566) (xy 385.701958 -298.902699) (xy 385.751427 -298.91877)
			(xy 385.797772 -298.942381) (xy 385.839853 -298.972952) (xy 385.876634 -299.00973) (xy 385.907207 -299.051809)
			(xy 385.930822 -299.098153) (xy 385.946896 -299.14762) (xy 385.955033 -299.198993) (xy 385.955033 -299.251007)
			(xy 385.946896 -299.30238) (xy 385.930822 -299.351847) (xy 385.907207 -299.398191) (xy 385.876634 -299.44027)
			(xy 385.839853 -299.477048) (xy 385.797772 -299.507619) (xy 385.751427 -299.53123) (xy 385.701958 -299.547301)
			(xy 385.650585 -299.555434) (xy 385.624578 -299.555916) (xy 384.674618 -299.555916) (xy 384.648604 -299.555526)
			(xy 384.597217 -299.547389) (xy 384.547735 -299.531314) (xy 384.501377 -299.507696) (xy 384.459285 -299.477116)
			(xy 384.422495 -299.440328) (xy 384.391913 -299.398238) (xy 384.368293 -299.351882) (xy 384.352215 -299.302401)
			(xy 384.344076 -299.251014) (xy 350.184974 -299.251014) (xy 350.184974 -315.781436) (xy 350.185163 -315.787875)
			(xy 350.188377 -315.800346) (xy 350.191324 -315.806074) (xy 350.20413 -315.830332) (xy 350.223421 -315.881681)
			(xy 350.235158 -315.935263) (xy 350.2391 -315.989974) (xy 350.235165 -316.044685) (xy 350.223435 -316.098269)
			(xy 350.204152 -316.14962) (xy 350.191324 -316.173866) (xy 350.188365 -316.17959) (xy 350.185148 -316.192063)
			(xy 350.184974 -316.198504) (xy 350.184974 -317.484506) (xy 350.18516 -317.490946) (xy 350.188367 -317.503421)
			(xy 350.191324 -317.509144) (xy 350.204125 -317.533402) (xy 350.223406 -317.584749) (xy 350.235133 -317.638328)
			(xy 350.239066 -317.693035) (xy 350.235123 -317.747741) (xy 350.223386 -317.801318) (xy 350.204096 -317.852662)
			(xy 350.191324 -317.876936) (xy 350.188373 -317.882662) (xy 350.185173 -317.895135) (xy 350.184974 -317.901574)
			(xy 350.184974 -318.349122) (xy 350.185162 -318.355562) (xy 350.188372 -318.368034) (xy 350.191324 -318.37376)
			(xy 350.204131 -318.398018) (xy 350.223424 -318.449367) (xy 350.235163 -318.50295) (xy 350.239107 -318.557661)
			(xy 350.235174 -318.612374) (xy 350.223445 -318.665959) (xy 350.204163 -318.717312) (xy 350.191324 -318.741552)
			(xy 350.188364 -318.747276) (xy 350.185143 -318.759749) (xy 350.184974 -318.76619) (xy 350.184974 -320.900044)
			(xy 373.198651 -320.900044) (xy 373.202657 -320.704989) (xy 373.214667 -320.510263) (xy 373.234662 -320.316194)
			(xy 373.262607 -320.12311) (xy 373.298456 -319.931335) (xy 373.342148 -319.741195) (xy 373.393609 -319.553008)
			(xy 373.452753 -319.367093) (xy 373.51948 -319.183762) (xy 373.593677 -319.003326) (xy 373.675219 -318.826088)
			(xy 373.76397 -318.652347) (xy 373.859778 -318.482396) (xy 373.962483 -318.316522) (xy 374.071911 -318.155004)
			(xy 374.187878 -317.998115) (xy 374.310189 -317.84612) (xy 374.438636 -317.699274) (xy 374.573004 -317.557825)
			(xy 374.713066 -317.422012) (xy 374.858585 -317.292063) (xy 375.009317 -317.168199) (xy 375.165007 -317.050627)
			(xy 375.325393 -316.939547) (xy 375.490204 -316.835144) (xy 375.659162 -316.737596) (xy 375.831983 -316.647067)
			(xy 376.008375 -316.563709) (xy 376.18804 -316.487663) (xy 376.370675 -316.419058) (xy 376.555974 -316.358008)
			(xy 376.743622 -316.304618) (xy 376.933304 -316.258976) (xy 377.124701 -316.22116) (xy 377.317488 -316.191234)
			(xy 377.511341 -316.169248) (xy 377.705934 -316.155239) (xy 377.900937 -316.149231) (xy 378.096023 -316.151234)
			(xy 378.290862 -316.161245) (xy 378.485126 -316.179246) (xy 378.678487 -316.205208) (xy 378.87062 -316.239086)
			(xy 379.061199 -316.280823) (xy 379.249904 -316.33035) (xy 379.436417 -316.387582) (xy 379.620423 -316.452423)
			(xy 379.801611 -316.524764) (xy 379.979677 -316.604482) (xy 380.15432 -316.691444) (xy 380.325246 -316.785503)
			(xy 380.492165 -316.886499) (xy 380.654798 -316.994264) (xy 380.812869 -317.108614) (xy 380.966112 -317.229357)
			(xy 381.114269 -317.356291) (xy 381.25709 -317.489199) (xy 381.394334 -317.627859) (xy 381.52577 -317.772037)
			(xy 381.651175 -317.92149) (xy 381.770339 -318.075964) (xy 381.88306 -318.235201) (xy 381.989149 -318.398932)
			(xy 382.088427 -318.566879) (xy 382.180725 -318.738762) (xy 382.26589 -318.914288) (xy 382.343776 -319.093163)
			(xy 382.414253 -319.275085) (xy 382.477201 -319.459747) (xy 382.532516 -319.646837) (xy 382.580102 -319.836041)
			(xy 382.619881 -320.027038) (xy 382.651785 -320.219508) (xy 382.67576 -320.413126) (xy 382.691766 -320.607564)
			(xy 382.699775 -320.802496) (xy 382.700276 -320.900044) (xy 382.699775 -320.997592) (xy 382.691766 -321.192524)
			(xy 382.67576 -321.386962) (xy 382.651785 -321.58058) (xy 382.619881 -321.77305) (xy 382.580102 -321.964047)
			(xy 382.532516 -322.153251) (xy 382.477201 -322.340341) (xy 382.414253 -322.525003) (xy 382.343776 -322.706925)
			(xy 382.26589 -322.8858) (xy 382.180725 -323.061326) (xy 382.088427 -323.233209) (xy 381.989149 -323.401156)
			(xy 381.88306 -323.564887) (xy 381.770339 -323.724124) (xy 381.651175 -323.878598) (xy 381.52577 -324.028051)
			(xy 381.394334 -324.172229) (xy 381.25709 -324.310889) (xy 381.114269 -324.443797) (xy 380.966112 -324.570731)
			(xy 380.812869 -324.691474) (xy 380.654798 -324.805824) (xy 380.492165 -324.913589) (xy 380.325246 -325.014585)
			(xy 380.15432 -325.108644) (xy 379.979677 -325.195606) (xy 379.801611 -325.275324) (xy 379.620423 -325.347665)
			(xy 379.436417 -325.412506) (xy 379.249904 -325.469738) (xy 379.061199 -325.519265) (xy 378.87062 -325.561002)
			(xy 378.678487 -325.59488) (xy 378.485126 -325.620842) (xy 378.290862 -325.638843) (xy 378.096023 -325.648854)
			(xy 377.900937 -325.650857) (xy 377.705934 -325.644849) (xy 377.511341 -325.63084) (xy 377.317488 -325.608854)
			(xy 377.124701 -325.578928) (xy 376.933304 -325.541112) (xy 376.743622 -325.49547) (xy 376.555974 -325.44208)
			(xy 376.370675 -325.38103) (xy 376.18804 -325.312425) (xy 376.008375 -325.236379) (xy 375.831983 -325.153021)
			(xy 375.659162 -325.062492) (xy 375.490204 -324.964944) (xy 375.325393 -324.860541) (xy 375.165007 -324.749461)
			(xy 375.009317 -324.631889) (xy 374.858585 -324.508025) (xy 374.713066 -324.378076) (xy 374.573004 -324.242263)
			(xy 374.438636 -324.100814) (xy 374.310189 -323.953968) (xy 374.187878 -323.801973) (xy 374.071911 -323.645084)
			(xy 373.962483 -323.483566) (xy 373.859778 -323.317692) (xy 373.76397 -323.147741) (xy 373.675219 -322.974)
			(xy 373.593677 -322.796762) (xy 373.51948 -322.616326) (xy 373.452753 -322.432995) (xy 373.393609 -322.24708)
			(xy 373.342148 -322.058893) (xy 373.298456 -321.868753) (xy 373.262607 -321.676978) (xy 373.234662 -321.483894)
			(xy 373.214667 -321.289825) (xy 373.202657 -321.095099) (xy 373.198651 -320.900044) (xy 350.184974 -320.900044)
			(xy 350.184974 -332.947271) (xy 365.368753 -332.947271) (xy 365.368753 -332.887329) (xy 365.376578 -332.827899)
			(xy 365.392093 -332.77) (xy 365.415033 -332.71462) (xy 365.445006 -332.66271) (xy 365.481498 -332.615155)
			(xy 365.523886 -332.572772) (xy 365.571443 -332.536283) (xy 365.623356 -332.506315) (xy 365.678737 -332.48338)
			(xy 365.736639 -332.46787) (xy 365.796069 -332.460051) (xy 365.82604 -332.459584) (xy 366.68964 -332.459584)
			(xy 366.719605 -332.460093) (xy 366.779023 -332.46792) (xy 366.836911 -332.483435) (xy 366.892278 -332.506374)
			(xy 366.944178 -332.536342) (xy 366.991723 -332.572828) (xy 367.034098 -332.615207) (xy 367.07058 -332.662755)
			(xy 367.100544 -332.714658) (xy 367.123478 -332.770027) (xy 367.138988 -332.827916) (xy 367.14681 -332.887335)
			(xy 367.14681 -332.947265) (xy 367.138988 -333.006684) (xy 367.123478 -333.064573) (xy 367.100544 -333.119942)
			(xy 367.07058 -333.171845) (xy 367.034098 -333.219393) (xy 366.991723 -333.261772) (xy 366.944178 -333.298258)
			(xy 366.892278 -333.328226) (xy 366.836911 -333.351165) (xy 366.779023 -333.36668) (xy 366.719605 -333.374507)
			(xy 366.68964 -333.375) (xy 365.82604 -333.375) (xy 365.796069 -333.374549) (xy 365.736639 -333.36673)
			(xy 365.678737 -333.35122) (xy 365.623356 -333.328285) (xy 365.571443 -333.298317) (xy 365.523886 -333.261828)
			(xy 365.481498 -333.219445) (xy 365.445006 -333.17189) (xy 365.415033 -333.11998) (xy 365.392093 -333.0646)
			(xy 365.376578 -333.006701) (xy 365.368753 -332.947271) (xy 350.184974 -332.947271) (xy 350.184974 -337.580986)
			(xy 350.185481 -337.591036) (xy 350.193204 -337.609595) (xy 350.19996 -337.617054) (xy 350.409002 -337.826096)
			(xy 350.421702 -337.839812) (xy 350.42926 -337.847713) (xy 350.449135 -337.856775) (xy 350.460056 -337.857338)
		)
		(stroke
			(width 0)
			(type solid)
		)
		(fill yes)
		(layer "In3.Cu")
		(net "P0V8_PEX3")
	)
	(gr_poly
		(pts
			(xy 465.600034 -461.99552) (xy 465.655841 -461.994997) (xy 465.767141 -461.986654) (xy 465.877508 -461.970017)
			(xy 465.986322 -461.945179) (xy 466.092976 -461.912278) (xy 466.196873 -461.8715) (xy 466.297432 -461.823072)
			(xy 466.394091 -461.767264) (xy 466.48631 -461.70439) (xy 466.573572 -461.6348) (xy 466.65539 -461.558883)
			(xy 466.731306 -461.477065) (xy 466.800896 -461.389802) (xy 466.86377 -461.297583) (xy 466.919577 -461.200923)
			(xy 466.968004 -461.100364) (xy 467.008782 -460.996466) (xy 467.041681 -460.889812) (xy 467.066519 -460.780998)
			(xy 467.083155 -460.670631) (xy 467.091497 -460.559331) (xy 467.09203 -460.503524) (xy 467.09203 -422.58996)
			(xy 467.091507 -422.534153) (xy 467.083163 -422.422853) (xy 467.066526 -422.312487) (xy 467.041687 -422.203672)
			(xy 467.008787 -422.097019) (xy 466.968009 -421.993121) (xy 466.91958 -421.892562) (xy 466.863773 -421.795903)
			(xy 466.800898 -421.703684) (xy 466.731308 -421.616422) (xy 466.655392 -421.534604) (xy 466.573573 -421.458688)
			(xy 466.486311 -421.389098) (xy 466.394092 -421.326224) (xy 466.297433 -421.270417) (xy 466.196873 -421.221989)
			(xy 466.092976 -421.181211) (xy 465.986322 -421.148311) (xy 465.877508 -421.123473) (xy 465.767141 -421.106836)
			(xy 465.655841 -421.098493) (xy 465.600034 -421.097964) (xy 447.939922 -421.097964) (xy 447.884114 -421.098485)
			(xy 447.77281 -421.106824) (xy 447.66244 -421.123458) (xy 447.553622 -421.148293) (xy 447.446964 -421.181191)
			(xy 447.343062 -421.221967) (xy 447.242499 -421.270394) (xy 447.145835 -421.3262) (xy 447.053613 -421.389074)
			(xy 446.966346 -421.458664) (xy 446.884524 -421.53458) (xy 446.808604 -421.616399) (xy 446.739011 -421.703663)
			(xy 446.676133 -421.795883) (xy 446.620323 -421.892544) (xy 446.571892 -421.993106) (xy 446.531111 -422.097005)
			(xy 446.498209 -422.203662) (xy 446.47337 -422.312479) (xy 446.456731 -422.422848) (xy 446.448387 -422.534152)
			(xy 446.447926 -422.58996) (xy 446.447926 -429.090074) (xy 446.447433 -429.160429) (xy 446.439545 -429.300916)
			(xy 446.423792 -429.440741) (xy 446.400224 -429.579462) (xy 446.368915 -429.716643) (xy 446.329963 -429.851854)
			(xy 446.283491 -429.984667) (xy 446.229646 -430.114666) (xy 446.168596 -430.241441) (xy 446.100533 -430.364593)
			(xy 446.025673 -430.483736) (xy 445.94425 -430.598494) (xy 445.856521 -430.708505) (xy 445.762761 -430.813425)
			(xy 445.663266 -430.912922) (xy 445.558348 -431.006684) (xy 445.448338 -431.094416) (xy 445.333582 -431.175842)
			(xy 445.214442 -431.250705) (xy 445.091291 -431.31877) (xy 444.964517 -431.379823) (xy 444.834519 -431.433671)
			(xy 444.701707 -431.480146) (xy 444.566498 -431.519101) (xy 444.429317 -431.550413) (xy 444.290596 -431.573985)
			(xy 444.150772 -431.589741) (xy 444.010285 -431.597632) (xy 443.93993 -431.59807) (xy 371.24005 -431.59807)
			(xy 371.169695 -431.597587) (xy 371.029207 -431.5897) (xy 370.889383 -431.573948) (xy 370.750661 -431.550381)
			(xy 370.613479 -431.519072) (xy 370.478269 -431.480121) (xy 370.345455 -431.433649) (xy 370.215456 -431.379804)
			(xy 370.088681 -431.318754) (xy 369.965528 -431.250691) (xy 369.846385 -431.175831) (xy 369.731628 -431.094407)
			(xy 369.621616 -431.006677) (xy 369.516697 -430.912917) (xy 369.4172 -430.813421) (xy 369.323438 -430.708502)
			(xy 369.235707 -430.598492) (xy 369.154283 -430.483735) (xy 369.079421 -430.364593) (xy 369.011357 -430.241441)
			(xy 368.950306 -430.114666) (xy 368.896459 -429.984667) (xy 368.849986 -429.851854) (xy 368.811034 -429.716644)
			(xy 368.779724 -429.579463) (xy 368.756155 -429.440741) (xy 368.740402 -429.300917) (xy 368.732514 -429.160429)
			(xy 368.732054 -429.090074) (xy 368.732054 -422.58996) (xy 368.731543 -422.534154) (xy 368.7232 -422.422854)
			(xy 368.706562 -422.31249) (xy 368.681723 -422.203677) (xy 368.648822 -422.097024) (xy 368.608042 -421.993129)
			(xy 368.559613 -421.892571) (xy 368.503804 -421.795914) (xy 368.440929 -421.703697) (xy 368.371337 -421.616438)
			(xy 368.29542 -421.534622) (xy 368.2136 -421.458709) (xy 368.126337 -421.389123) (xy 368.034117 -421.326252)
			(xy 367.937456 -421.270449) (xy 367.836896 -421.222025) (xy 367.732998 -421.181251) (xy 367.626344 -421.148356)
			(xy 367.51753 -421.123523) (xy 367.407164 -421.106891) (xy 367.295864 -421.098554) (xy 367.240058 -421.097964)
			(xy 359.940098 -421.097964) (xy 359.88429 -421.098486) (xy 359.772988 -421.106827) (xy 359.662619 -421.123462)
			(xy 359.553802 -421.148298) (xy 359.447146 -421.181197) (xy 359.343246 -421.221974) (xy 359.242684 -421.270401)
			(xy 359.146022 -421.326208) (xy 359.053801 -421.389082) (xy 358.966536 -421.458672) (xy 358.884716 -421.534589)
			(xy 358.808797 -421.616407) (xy 358.739205 -421.70367) (xy 358.676328 -421.79589) (xy 358.620519 -421.892551)
			(xy 358.572089 -421.993111) (xy 358.53131 -422.09701) (xy 358.498408 -422.203666) (xy 358.473569 -422.312482)
			(xy 358.456931 -422.42285) (xy 358.448587 -422.534152) (xy 358.448102 -422.58996) (xy 358.448102 -429.090074)
			(xy 358.447618 -429.160429) (xy 358.43973 -429.300916) (xy 358.423977 -429.440741) (xy 358.400409 -429.579462)
			(xy 358.369099 -429.716643) (xy 358.330147 -429.851853) (xy 358.283675 -429.984667) (xy 358.229829 -430.114665)
			(xy 358.168779 -430.24144) (xy 358.100716 -430.364593) (xy 358.025856 -430.483735) (xy 357.944432 -430.598492)
			(xy 357.856702 -430.708504) (xy 357.762942 -430.813423) (xy 357.663446 -430.91292) (xy 357.558528 -431.006682)
			(xy 357.448518 -431.094413) (xy 357.333762 -431.175838) (xy 357.21462 -431.2507) (xy 357.091469 -431.318764)
			(xy 356.964695 -431.379816) (xy 356.834697 -431.433664) (xy 356.701884 -431.480138) (xy 356.566674 -431.519091)
			(xy 356.429493 -431.550403) (xy 356.290772 -431.573973) (xy 356.150948 -431.589728) (xy 356.010461 -431.597618)
			(xy 355.940106 -431.59807) (xy 283.239972 -431.59807) (xy 283.169619 -431.597576) (xy 283.029135 -431.589685)
			(xy 282.889313 -431.573929) (xy 282.750596 -431.550359) (xy 282.613418 -431.519047) (xy 282.478212 -431.480093)
			(xy 282.345402 -431.43362) (xy 282.215407 -431.379772) (xy 282.088636 -431.318721) (xy 281.965488 -431.250657)
			(xy 281.84635 -431.175796) (xy 281.731596 -431.094372) (xy 281.621589 -431.006642) (xy 281.516674 -430.912882)
			(xy 281.417181 -430.813387) (xy 281.323423 -430.70847) (xy 281.235695 -430.598461) (xy 281.154274 -430.483705)
			(xy 281.079415 -430.364565) (xy 281.011354 -430.241416) (xy 280.950306 -430.114643) (xy 280.896461 -429.984647)
			(xy 280.84999 -429.851837) (xy 280.811039 -429.71663) (xy 280.779731 -429.579451) (xy 280.756163 -429.440733)
			(xy 280.740411 -429.300912) (xy 280.732523 -429.160427) (xy 280.731976 -429.090074) (xy 280.731976 -422.58996)
			(xy 280.731453 -422.534154) (xy 280.723109 -422.422855) (xy 280.706471 -422.31249) (xy 280.681633 -422.203678)
			(xy 280.648732 -422.097025) (xy 280.607953 -421.99313) (xy 280.559525 -421.892573) (xy 280.503717 -421.795915)
			(xy 280.440842 -421.703699) (xy 280.371251 -421.616439) (xy 280.295334 -421.534623) (xy 280.213516 -421.45871)
			(xy 280.126253 -421.389123) (xy 280.034034 -421.326251) (xy 279.937374 -421.270447) (xy 279.836815 -421.222023)
			(xy 279.732918 -421.181248) (xy 279.626264 -421.148352) (xy 279.517451 -421.123517) (xy 279.407085 -421.106884)
			(xy 279.295786 -421.098545) (xy 279.23998 -421.097964) (xy 276.880066 -421.097964) (xy 276.824259 -421.098487)
			(xy 276.712958 -421.10683) (xy 276.602591 -421.123467) (xy 276.493777 -421.148305) (xy 276.387122 -421.181205)
			(xy 276.283225 -421.221984) (xy 276.182665 -421.270412) (xy 276.086005 -421.326219) (xy 275.993786 -421.389094)
			(xy 275.906523 -421.458684) (xy 275.824704 -421.5346) (xy 275.748787 -421.616418) (xy 275.679197 -421.703681)
			(xy 275.616322 -421.7959) (xy 275.560514 -421.892559) (xy 275.512086 -421.993119) (xy 275.471307 -422.097017)
			(xy 275.438407 -422.203671) (xy 275.413568 -422.312485) (xy 275.396931 -422.422852) (xy 275.388587 -422.534153)
			(xy 275.38807 -422.58996) (xy 275.38807 -430.55794) (xy 275.387576 -430.628293) (xy 275.379684 -430.768777)
			(xy 275.363928 -430.908597) (xy 275.340357 -431.047314) (xy 275.309045 -431.184492) (xy 275.27009 -431.319698)
			(xy 275.223616 -431.452506) (xy 275.169769 -431.582501) (xy 275.108717 -431.709271) (xy 275.040653 -431.832419)
			(xy 274.965792 -431.951557) (xy 274.884368 -432.066309) (xy 274.796638 -432.176316) (xy 274.702878 -432.281231)
			(xy 274.603383 -432.380723) (xy 274.498466 -432.474481) (xy 274.388457 -432.562208) (xy 274.273702 -432.643629)
			(xy 274.154562 -432.718487) (xy 274.031412 -432.786547) (xy 273.90464 -432.847596) (xy 273.774645 -432.90144)
			(xy 273.641835 -432.94791) (xy 273.506628 -432.986861) (xy 273.36945 -433.018169) (xy 273.230732 -433.041737)
			(xy 273.090911 -433.05749) (xy 272.950427 -433.065377) (xy 272.880074 -433.065936) (xy 202.360022 -433.065936)
			(xy 202.289667 -433.065443) (xy 202.14918 -433.057555) (xy 202.009355 -433.041802) (xy 201.870634 -433.018234)
			(xy 201.733452 -432.986924) (xy 201.598242 -432.947972) (xy 201.465429 -432.9015) (xy 201.33543 -432.847655)
			(xy 201.208655 -432.786605) (xy 201.085502 -432.718542) (xy 200.96636 -432.643682) (xy 200.851602 -432.562259)
			(xy 200.74159 -432.47453) (xy 200.63667 -432.38077) (xy 200.537173 -432.281275) (xy 200.44341 -432.176357)
			(xy 200.355678 -432.066348) (xy 200.274252 -431.951592) (xy 200.199389 -431.832451) (xy 200.131324 -431.7093)
			(xy 200.070271 -431.582527) (xy 200.016422 -431.452529) (xy 199.969947 -431.319717) (xy 199.930991 -431.184508)
			(xy 199.899679 -431.047327) (xy 199.876107 -430.908606) (xy 199.86035 -430.768782) (xy 199.852458 -430.628295)
			(xy 199.852026 -430.55794) (xy 199.852026 -422.58996) (xy 199.851503 -422.534154) (xy 199.843159 -422.422853)
			(xy 199.826522 -422.312487) (xy 199.801683 -422.203673) (xy 199.768783 -422.097019) (xy 199.728004 -421.993122)
			(xy 199.679576 -421.892563) (xy 199.623769 -421.795904) (xy 199.560894 -421.703685) (xy 199.491304 -421.616423)
			(xy 199.415387 -421.534606) (xy 199.333569 -421.45869) (xy 199.246306 -421.3891) (xy 199.154088 -421.326226)
			(xy 199.057428 -421.270419) (xy 198.956869 -421.221992) (xy 198.852972 -421.181214) (xy 198.746318 -421.148314)
			(xy 198.637503 -421.123476) (xy 198.527137 -421.10684) (xy 198.415836 -421.098497) (xy 198.36003 -421.097964)
			(xy 188.36005 -421.097964) (xy 188.304244 -421.098488) (xy 188.192943 -421.106832) (xy 188.082578 -421.12347)
			(xy 187.973764 -421.148309) (xy 187.86711 -421.18121) (xy 187.763214 -421.221988) (xy 187.662655 -421.270417)
			(xy 187.565996 -421.326225) (xy 187.473778 -421.389099) (xy 187.386516 -421.458689) (xy 187.304699 -421.534606)
			(xy 187.228783 -421.616424) (xy 187.159193 -421.703686) (xy 187.096319 -421.795905) (xy 187.040512 -421.892564)
			(xy 186.992084 -421.993123) (xy 186.951306 -422.09702) (xy 186.918406 -422.203673) (xy 186.893568 -422.312487)
			(xy 186.876931 -422.422853) (xy 186.868587 -422.534154) (xy 186.868054 -422.58996) (xy 186.868054 -429.090074)
			(xy 186.86757 -429.160428) (xy 186.859682 -429.300915) (xy 186.843929 -429.440738) (xy 186.820361 -429.579458)
			(xy 186.789051 -429.716639) (xy 186.750099 -429.851848) (xy 186.703626 -429.98466) (xy 186.64978 -430.114658)
			(xy 186.58873 -430.241431) (xy 186.520667 -430.364582) (xy 186.445806 -430.483723) (xy 186.364382 -430.598479)
			(xy 186.276652 -430.708489) (xy 186.182891 -430.813407) (xy 186.083395 -430.912902) (xy 185.978477 -431.006662)
			(xy 185.868467 -431.094392) (xy 185.75371 -431.175815) (xy 185.634569 -431.250675) (xy 185.511417 -431.318737)
			(xy 185.384643 -431.379787) (xy 185.254645 -431.433632) (xy 185.121833 -431.480104) (xy 184.986623 -431.519055)
			(xy 184.849443 -431.550364) (xy 184.710722 -431.573931) (xy 184.570899 -431.589684) (xy 184.430412 -431.597571)
			(xy 184.360058 -431.59807) (xy 111.660178 -431.59807) (xy 111.589825 -431.597585) (xy 111.449339 -431.589694)
			(xy 111.309518 -431.573939) (xy 111.170799 -431.550369) (xy 111.033621 -431.519057) (xy 110.898414 -431.480103)
			(xy 110.765603 -431.43363) (xy 110.635608 -431.379782) (xy 110.508836 -431.318731) (xy 110.385687 -431.250667)
			(xy 110.266548 -431.175806) (xy 110.151794 -431.094382) (xy 110.041786 -431.006651) (xy 109.93687 -430.912891)
			(xy 109.837376 -430.813395) (xy 109.743618 -430.708478) (xy 109.65589 -430.598468) (xy 109.574468 -430.483712)
			(xy 109.499608 -430.364572) (xy 109.431547 -430.241421) (xy 109.370498 -430.114648) (xy 109.316653 -429.984652)
			(xy 109.270182 -429.851841) (xy 109.231231 -429.716633) (xy 109.199922 -429.579454) (xy 109.176354 -429.440735)
			(xy 109.160602 -429.300913) (xy 109.152714 -429.160427) (xy 109.152182 -429.090074) (xy 109.152182 -422.58996)
			(xy 109.151659 -422.534154) (xy 109.143315 -422.422855) (xy 109.126678 -422.31249) (xy 109.101839 -422.203677)
			(xy 109.068938 -422.097025) (xy 109.02816 -421.993129) (xy 108.979731 -421.892571) (xy 108.923923 -421.795914)
			(xy 108.861048 -421.703697) (xy 108.791457 -421.616437) (xy 108.715541 -421.534621) (xy 108.633722 -421.458707)
			(xy 108.546459 -421.38912) (xy 108.45424 -421.326248) (xy 108.357581 -421.270444) (xy 108.257021 -421.222019)
			(xy 108.153124 -421.181244) (xy 108.046471 -421.148347) (xy 107.937657 -421.123512) (xy 107.827292 -421.106879)
			(xy 107.715992 -421.098539) (xy 107.660186 -421.097964) (xy 100.359972 -421.097964) (xy 100.304165 -421.098487)
			(xy 100.192864 -421.106829) (xy 100.082497 -421.123466) (xy 99.973681 -421.148304) (xy 99.867027 -421.181204)
			(xy 99.763129 -421.221982) (xy 99.662568 -421.27041) (xy 99.565908 -421.326217) (xy 99.473689 -421.389091)
			(xy 99.386425 -421.458681) (xy 99.304606 -421.534598) (xy 99.228689 -421.616416) (xy 99.159099 -421.703679)
			(xy 99.096223 -421.795898) (xy 99.040415 -421.892558) (xy 98.991987 -421.993118) (xy 98.951208 -422.097015)
			(xy 98.918307 -422.20367) (xy 98.893468 -422.312485) (xy 98.876831 -422.422852) (xy 98.868487 -422.534153)
			(xy 98.867976 -422.58996) (xy 98.867976 -429.090074) (xy 98.867492 -429.160428) (xy 98.859604 -429.300915)
			(xy 98.843851 -429.440739) (xy 98.820283 -429.57946) (xy 98.788973 -429.716641) (xy 98.750021 -429.85185)
			(xy 98.703549 -429.984663) (xy 98.649703 -430.114661) (xy 98.588652 -430.241435) (xy 98.520589 -430.364587)
			(xy 98.445729 -430.483729) (xy 98.364305 -430.598485) (xy 98.276575 -430.708496) (xy 98.182814 -430.813414)
			(xy 98.083319 -430.91291) (xy 97.9784 -431.006671) (xy 97.86839 -431.094401) (xy 97.753634 -431.175825)
			(xy 97.634492 -431.250686) (xy 97.511341 -431.31875) (xy 97.384567 -431.3798) (xy 97.254569 -431.433647)
			(xy 97.121756 -431.480119) (xy 96.986547 -431.519072) (xy 96.849366 -431.550382) (xy 96.710645 -431.57395)
			(xy 96.570821 -431.589704) (xy 96.430334 -431.597592) (xy 96.35998 -431.59807) (xy 23.6601 -431.59807)
			(xy 23.589746 -431.597586) (xy 23.44926 -431.589696) (xy 23.309437 -431.573942) (xy 23.170718 -431.550372)
			(xy 23.033539 -431.519062) (xy 22.89833 -431.480109) (xy 22.765519 -431.433636) (xy 22.635522 -431.379789)
			(xy 22.50875 -431.318738) (xy 22.385599 -431.250675) (xy 22.266459 -431.175813) (xy 22.151704 -431.094389)
			(xy 22.041695 -431.006659) (xy 21.936778 -430.912899) (xy 21.837283 -430.813403) (xy 21.743524 -430.708485)
			(xy 21.655795 -430.598475) (xy 21.574372 -430.483719) (xy 21.499512 -430.364578) (xy 21.43145 -430.241427)
			(xy 21.370401 -430.114654) (xy 21.316555 -429.984657) (xy 21.270083 -429.851845) (xy 21.231132 -429.716636)
			(xy 21.199823 -429.579456) (xy 21.176255 -429.440737) (xy 21.160502 -429.300914) (xy 21.152614 -429.160428)
			(xy 21.152104 -429.090074) (xy 21.152104 -422.58996) (xy 21.151595 -422.534153) (xy 21.143254 -422.42285)
			(xy 21.126618 -422.312481) (xy 21.101782 -422.203665) (xy 21.068883 -422.097009) (xy 21.028105 -421.993109)
			(xy 20.979677 -421.892548) (xy 20.92387 -421.795886) (xy 20.860995 -421.703666) (xy 20.791404 -421.616402)
			(xy 20.715486 -421.534582) (xy 20.633667 -421.458665) (xy 20.546403 -421.389074) (xy 20.454182 -421.326199)
			(xy 20.357521 -421.270392) (xy 20.256959 -421.221964) (xy 20.153059 -421.181187) (xy 20.046403 -421.148288)
			(xy 19.937587 -421.123451) (xy 19.827218 -421.106816) (xy 19.715915 -421.098475) (xy 19.660108 -421.097964)
			(xy 1.999996 -421.097964) (xy 1.944189 -421.098486) (xy 1.832887 -421.106827) (xy 1.72252 -421.123463)
			(xy 1.613705 -421.148299) (xy 1.50705 -421.181198) (xy 1.403151 -421.221976) (xy 1.302591 -421.270403)
			(xy 1.20593 -421.32621) (xy 1.113711 -421.389085) (xy 1.026448 -421.458675) (xy 0.944629 -421.534592)
			(xy 0.868712 -421.616411) (xy 0.799122 -421.703674) (xy 0.736248 -421.795894) (xy 0.680441 -421.892554)
			(xy 0.632014 -421.993115) (xy 0.591237 -422.097013) (xy 0.558338 -422.203669) (xy 0.533502 -422.312484)
			(xy 0.516867 -422.422851) (xy 0.508526 -422.534153) (xy 0.508 -422.58996) (xy 0.508 -457.5681) (xy 2.904225 -457.5681)
			(xy 2.904225 -457.43896) (xy 2.912175 -457.310065) (xy 2.928045 -457.181905) (xy 2.951774 -457.054964)
			(xy 2.983273 -456.929725) (xy 3.022422 -456.806662) (xy 3.069073 -456.686243) (xy 3.123048 -456.568924)
			(xy 3.184143 -456.45515) (xy 3.252126 -456.345353) (xy 3.32674 -456.23995) (xy 3.407701 -456.13934)
			(xy 3.494701 -456.043905) (xy 3.587412 -455.954006) (xy 3.685482 -455.869985) (xy 3.788537 -455.792161)
			(xy 3.896188 -455.720829) (xy 4.008027 -455.656259) (xy 4.123628 -455.598697) (xy 4.242553 -455.54836)
			(xy 4.364352 -455.50544) (xy 4.488562 -455.470099) (xy 4.614711 -455.442472) (xy 4.742323 -455.422663)
			(xy 4.870912 -455.410747) (xy 4.99999 -455.406771) (xy 5.129068 -455.410747) (xy 5.257657 -455.422663)
			(xy 5.385269 -455.442472) (xy 5.511418 -455.470099) (xy 5.635628 -455.50544) (xy 5.757427 -455.54836)
			(xy 5.876352 -455.598697) (xy 5.991953 -455.656259) (xy 6.103792 -455.720829) (xy 6.211443 -455.792161)
			(xy 6.314498 -455.869985) (xy 6.412568 -455.954006) (xy 6.505279 -456.043905) (xy 6.592279 -456.13934)
			(xy 6.67324 -456.23995) (xy 6.747854 -456.345353) (xy 6.815837 -456.45515) (xy 6.876932 -456.568924)
			(xy 6.930907 -456.686243) (xy 6.977558 -456.806662) (xy 7.016707 -456.929725) (xy 7.048206 -457.054964)
			(xy 7.071935 -457.181905) (xy 7.087805 -457.310065) (xy 7.095755 -457.43896) (xy 7.096252 -457.50353)
			(xy 7.095755 -457.5681) (xy 460.504275 -457.5681) (xy 460.504275 -457.43896) (xy 460.512225 -457.310065)
			(xy 460.528095 -457.181905) (xy 460.551824 -457.054964) (xy 460.583323 -456.929725) (xy 460.622472 -456.806662)
			(xy 460.669123 -456.686243) (xy 460.723098 -456.568924) (xy 460.784193 -456.45515) (xy 460.852176 -456.345353)
			(xy 460.92679 -456.23995) (xy 461.007751 -456.13934) (xy 461.094751 -456.043905) (xy 461.187462 -455.954006)
			(xy 461.285532 -455.869985) (xy 461.388587 -455.792161) (xy 461.496238 -455.720829) (xy 461.608077 -455.656259)
			(xy 461.723678 -455.598697) (xy 461.842603 -455.54836) (xy 461.964402 -455.50544) (xy 462.088612 -455.470099)
			(xy 462.214761 -455.442472) (xy 462.342373 -455.422663) (xy 462.470962 -455.410747) (xy 462.60004 -455.406771)
			(xy 462.729118 -455.410747) (xy 462.857707 -455.422663) (xy 462.985319 -455.442472) (xy 463.111468 -455.470099)
			(xy 463.235678 -455.50544) (xy 463.357477 -455.54836) (xy 463.476402 -455.598697) (xy 463.592003 -455.656259)
			(xy 463.703842 -455.720829) (xy 463.811493 -455.792161) (xy 463.914548 -455.869985) (xy 464.012618 -455.954006)
			(xy 464.105329 -456.043905) (xy 464.192329 -456.13934) (xy 464.27329 -456.23995) (xy 464.347904 -456.345353)
			(xy 464.415887 -456.45515) (xy 464.476982 -456.568924) (xy 464.530957 -456.686243) (xy 464.577608 -456.806662)
			(xy 464.616757 -456.929725) (xy 464.648256 -457.054964) (xy 464.671985 -457.181905) (xy 464.687855 -457.310065)
			(xy 464.695805 -457.43896) (xy 464.696302 -457.50353) (xy 464.695805 -457.5681) (xy 464.687855 -457.696995)
			(xy 464.671985 -457.825155) (xy 464.648256 -457.952096) (xy 464.616757 -458.077335) (xy 464.577608 -458.200398)
			(xy 464.530957 -458.320817) (xy 464.476982 -458.438136) (xy 464.415887 -458.55191) (xy 464.347904 -458.661707)
			(xy 464.27329 -458.76711) (xy 464.192329 -458.86772) (xy 464.105329 -458.963155) (xy 464.012618 -459.053054)
			(xy 463.914548 -459.137075) (xy 463.811493 -459.214899) (xy 463.703842 -459.286231) (xy 463.592003 -459.350801)
			(xy 463.476402 -459.408363) (xy 463.357477 -459.4587) (xy 463.235678 -459.50162) (xy 463.111468 -459.536961)
			(xy 462.985319 -459.564588) (xy 462.857707 -459.584397) (xy 462.729118 -459.596313) (xy 462.60004 -459.60029)
			(xy 462.470962 -459.596313) (xy 462.342373 -459.584397) (xy 462.214761 -459.564588) (xy 462.088612 -459.536961)
			(xy 461.964402 -459.50162) (xy 461.842603 -459.4587) (xy 461.723678 -459.408363) (xy 461.608077 -459.350801)
			(xy 461.496238 -459.286231) (xy 461.388587 -459.214899) (xy 461.285532 -459.137075) (xy 461.187462 -459.053054)
			(xy 461.094751 -458.963155) (xy 461.007751 -458.86772) (xy 460.92679 -458.76711) (xy 460.852176 -458.661707)
			(xy 460.784193 -458.55191) (xy 460.723098 -458.438136) (xy 460.669123 -458.320817) (xy 460.622472 -458.200398)
			(xy 460.583323 -458.077335) (xy 460.551824 -457.952096) (xy 460.528095 -457.825155) (xy 460.512225 -457.696995)
			(xy 460.504275 -457.5681) (xy 7.095755 -457.5681) (xy 7.087805 -457.696995) (xy 7.071935 -457.825155)
			(xy 7.048206 -457.952096) (xy 7.016707 -458.077335) (xy 6.977558 -458.200398) (xy 6.930907 -458.320817)
			(xy 6.876932 -458.438136) (xy 6.815837 -458.55191) (xy 6.747854 -458.661707) (xy 6.67324 -458.76711)
			(xy 6.592279 -458.86772) (xy 6.505279 -458.963155) (xy 6.412568 -459.053054) (xy 6.314498 -459.137075)
			(xy 6.211443 -459.214899) (xy 6.103792 -459.286231) (xy 5.991953 -459.350801) (xy 5.876352 -459.408363)
			(xy 5.757427 -459.4587) (xy 5.635628 -459.50162) (xy 5.511418 -459.536961) (xy 5.385269 -459.564588)
			(xy 5.257657 -459.584397) (xy 5.129068 -459.596313) (xy 4.99999 -459.60029) (xy 4.870912 -459.596313)
			(xy 4.742323 -459.584397) (xy 4.614711 -459.564588) (xy 4.488562 -459.536961) (xy 4.364352 -459.50162)
			(xy 4.242553 -459.4587) (xy 4.123628 -459.408363) (xy 4.008027 -459.350801) (xy 3.896188 -459.286231)
			(xy 3.788537 -459.214899) (xy 3.685482 -459.137075) (xy 3.587412 -459.053054) (xy 3.494701 -458.963155)
			(xy 3.407701 -458.86772) (xy 3.32674 -458.76711) (xy 3.252126 -458.661707) (xy 3.184143 -458.55191)
			(xy 3.123048 -458.438136) (xy 3.069073 -458.320817) (xy 3.022422 -458.200398) (xy 2.983273 -458.077335)
			(xy 2.951774 -457.952096) (xy 2.928045 -457.825155) (xy 2.912175 -457.696995) (xy 2.904225 -457.5681)
			(xy 0.508 -457.5681) (xy 0.508 -460.503524) (xy 0.508522 -460.559331) (xy 0.516863 -460.670633) (xy 0.533498 -460.781)
			(xy 0.558335 -460.889816) (xy 0.591234 -460.996471) (xy 0.632011 -461.10037) (xy 0.680438 -461.20093)
			(xy 0.736246 -461.297591) (xy 0.79912 -461.389811) (xy 0.86871 -461.477074) (xy 0.944627 -461.558893)
			(xy 1.026446 -461.63481) (xy 1.113709 -461.7044) (xy 1.205929 -461.767274) (xy 1.30259 -461.823082)
			(xy 1.40315 -461.871509) (xy 1.507049 -461.912286) (xy 1.613704 -461.945185) (xy 1.72252 -461.970022)
			(xy 1.832887 -461.986657) (xy 1.944189 -461.994998) (xy 1.999996 -461.99552)
		)
		(stroke
			(width 0)
			(type solid)
		)
		(fill yes)
		(layer "In3.Cu")
		(net "COUPON_GND1")
	)
	(gr_poly
		(pts
			(xy 349.494348 -337.850226) (xy 349.661988 -337.682586) (xy 349.668833 -337.675187) (xy 349.676565 -337.656589)
			(xy 349.676974 -337.646518) (xy 349.676974 -326.560942) (xy 349.67672 -326.550782) (xy 349.67672 -318.922908)
			(xy 349.676395 -318.914361) (xy 349.670771 -318.898218) (xy 349.660148 -318.884825) (xy 349.653098 -318.879982)
			(xy 349.630156 -318.864917) (xy 349.588447 -318.829244) (xy 349.552283 -318.787959) (xy 349.522414 -318.741915)
			(xy 349.499455 -318.692064) (xy 349.483881 -318.639436) (xy 349.476015 -318.585118) (xy 349.476018 -318.530235)
			(xy 349.483891 -318.475918) (xy 349.499471 -318.423292) (xy 349.522436 -318.373444) (xy 349.552312 -318.327404)
			(xy 349.58848 -318.286123) (xy 349.630194 -318.250456) (xy 349.653098 -318.23533) (xy 349.660143 -318.230481)
			(xy 349.670767 -318.217091) (xy 349.676394 -318.20095) (xy 349.67672 -318.192404) (xy 349.67672 -318.058292)
			(xy 349.676393 -318.049746) (xy 349.670765 -318.033607) (xy 349.660141 -318.020218) (xy 349.653098 -318.015366)
			(xy 349.63015 -318.0003) (xy 349.588429 -317.964626) (xy 349.552254 -317.923337) (xy 349.522373 -317.877288)
			(xy 349.499404 -317.827431) (xy 349.483821 -317.774795) (xy 349.475947 -317.720468) (xy 349.475944 -317.665574)
			(xy 349.483812 -317.611247) (xy 349.499389 -317.558609) (xy 349.522352 -317.508749) (xy 349.552228 -317.462697)
			(xy 349.588398 -317.421404) (xy 349.630116 -317.385725) (xy 349.653098 -317.370714) (xy 349.660141 -317.365864)
			(xy 349.670761 -317.352473) (xy 349.676383 -317.336333) (xy 349.67672 -317.327788) (xy 349.67672 -316.355222)
			(xy 349.676397 -316.346673) (xy 349.670777 -316.330527) (xy 349.660155 -316.31713) (xy 349.653098 -316.312296)
			(xy 349.630155 -316.29723) (xy 349.588444 -316.261557) (xy 349.552279 -316.220272) (xy 349.522407 -316.174227)
			(xy 349.499446 -316.124375) (xy 349.483871 -316.071746) (xy 349.476003 -316.017427) (xy 349.476006 -315.962541)
			(xy 349.483878 -315.908223) (xy 349.499457 -315.855595) (xy 349.522422 -315.805745) (xy 349.552298 -315.759703)
			(xy 349.588467 -315.71842) (xy 349.630181 -315.68275) (xy 349.653098 -315.667644) (xy 349.660144 -315.662795)
			(xy 349.670772 -315.649406) (xy 349.676403 -315.633265) (xy 349.67672 -315.624718) (xy 349.67672 -295.255442)
			(xy 349.654622 -295.227756) (xy 349.63735 -295.223692) (xy 349.609668 -295.216792) (xy 349.556588 -295.19589)
			(xy 349.507212 -295.167316) (xy 349.462643 -295.131708) (xy 349.423873 -295.089859) (xy 349.391767 -295.042704)
			(xy 349.367043 -294.991292) (xy 349.35025 -294.936773) (xy 349.341764 -294.88036) (xy 349.341186 -294.851836)
			(xy 349.341764 -294.8226) (xy 349.350719 -294.764818) (xy 349.36838 -294.709076) (xy 349.394333 -294.656679)
			(xy 349.427972 -294.608852) (xy 349.447866 -294.587422) (xy 349.454724 -294.580056) (xy 349.46209 -294.561768)
			(xy 349.461328 -294.480488) (xy 349.46076 -294.470564) (xy 349.453051 -294.452262) (xy 349.446342 -294.444928)
			(xy 349.444564 -294.44315) (xy 349.437166 -294.436304) (xy 349.418567 -294.428575) (xy 349.408496 -294.428164)
			(xy 343.506806 -294.428164) (xy 343.496385 -294.428673) (xy 343.477249 -294.436939) (xy 343.469722 -294.444166)
			(xy 343.449948 -294.464436) (xy 343.405481 -294.499495) (xy 343.35632 -294.527595) (xy 343.303545 -294.54812)
			(xy 343.248316 -294.560618) (xy 343.191846 -294.564815) (xy 343.135376 -294.560618) (xy 343.080147 -294.54812)
			(xy 343.027372 -294.527595) (xy 342.978211 -294.499495) (xy 342.933744 -294.464436) (xy 342.91397 -294.444166)
			(xy 342.906468 -294.436905) (xy 342.887316 -294.42865) (xy 342.876886 -294.428164) (xy 333.06385 -294.428164)
			(xy 333.038892 -294.427588) (xy 332.989936 -294.417839) (xy 332.943823 -294.398727) (xy 332.902325 -294.370985)
			(xy 332.884272 -294.353742) (xy 332.272894 -293.742364) (xy 332.255632 -293.724324) (xy 332.227869 -293.682832)
			(xy 332.208751 -293.636713) (xy 332.199016 -293.587748) (xy 332.198472 -293.562786) (xy 332.198472 -293.219378)
			(xy 332.197958 -293.20793) (xy 332.188054 -293.187289) (xy 332.179422 -293.179754) (xy 332.10881 -293.122858)
			(xy 332.086458 -293.117524) (xy 332.075028 -293.120064) (xy 331.985694 -293.139067) (xy 331.805431 -293.168577)
			(xy 331.623837 -293.188304) (xy 331.441443 -293.19819) (xy 331.350112 -293.198804) (xy 331.268458 -293.198319)
			(xy 331.105339 -293.190429) (xy 330.942793 -293.174668) (xy 330.781198 -293.151072) (xy 330.620931 -293.119697)
			(xy 330.462368 -293.080615) (xy 330.305877 -293.033918) (xy 330.151826 -292.979715) (xy 330.000573 -292.918132)
			(xy 329.852473 -292.849314) (xy 329.70787 -292.773421) (xy 329.567102 -292.69063) (xy 329.430499 -292.601135)
			(xy 329.298379 -292.505145) (xy 329.171051 -292.402884) (xy 329.048812 -292.29459) (xy 328.931949 -292.180517)
			(xy 328.820732 -292.060932) (xy 328.715424 -291.936112) (xy 328.616269 -291.806351) (xy 328.523498 -291.67195)
			(xy 328.43733 -291.533225) (xy 328.357964 -291.390498) (xy 328.285587 -291.244104) (xy 328.220367 -291.094384)
			(xy 328.162457 -290.941687) (xy 328.111992 -290.786371) (xy 328.069089 -290.628798) (xy 328.033849 -290.469337)
			(xy 328.006355 -290.308359) (xy 327.98667 -290.146241) (xy 327.974841 -289.983361) (xy 327.970895 -289.8201)
			(xy 327.974841 -289.656839) (xy 327.98667 -289.493959) (xy 328.006355 -289.331841) (xy 328.033849 -289.170863)
			(xy 328.069089 -289.011402) (xy 328.111992 -288.853829) (xy 328.162457 -288.698513) (xy 328.220367 -288.545816)
			(xy 328.285587 -288.396096) (xy 328.357964 -288.249702) (xy 328.43733 -288.106975) (xy 328.523498 -287.96825)
			(xy 328.616269 -287.833849) (xy 328.715424 -287.704088) (xy 328.820732 -287.579268) (xy 328.931949 -287.459683)
			(xy 329.048812 -287.34561) (xy 329.171051 -287.237316) (xy 329.298379 -287.135055) (xy 329.430499 -287.039065)
			(xy 329.567102 -286.94957) (xy 329.70787 -286.866779) (xy 329.852473 -286.790886) (xy 330.000573 -286.722068)
			(xy 330.151826 -286.660485) (xy 330.305877 -286.606282) (xy 330.462368 -286.559585) (xy 330.620931 -286.520503)
			(xy 330.781198 -286.489128) (xy 330.942793 -286.465532) (xy 331.105339 -286.449771) (xy 331.268458 -286.441881)
			(xy 331.350112 -286.441388) (xy 331.441443 -286.442009) (xy 331.623838 -286.45189) (xy 331.805432 -286.471613)
			(xy 331.985695 -286.501119) (xy 332.075028 -286.520128) (xy 332.086458 -286.522668) (xy 332.10881 -286.517334)
			(xy 332.179422 -286.460438) (xy 332.187945 -286.452811) (xy 332.197857 -286.432233) (xy 332.198472 -286.420814)
			(xy 332.198472 -286.227774) (xy 332.198047 -286.217758) (xy 332.190372 -286.199255) (xy 332.1762 -286.185098)
			(xy 332.157688 -286.177442) (xy 332.147672 -286.176974) (xy 332.144878 -286.176974) (xy 332.142084 -286.177228)
			(xy 332.114906 -286.178752) (xy 303.00422 -286.178752) (xy 302.996025 -286.179057) (xy 302.980472 -286.184231)
			(xy 302.97374 -286.188912) (xy 302.952115 -286.204569) (xy 302.90487 -286.229427) (xy 302.854243 -286.246368)
			(xy 302.801551 -286.25495) (xy 302.748165 -286.25495) (xy 302.695473 -286.246368) (xy 302.644846 -286.229427)
			(xy 302.597601 -286.204569) (xy 302.575976 -286.188912) (xy 302.569234 -286.184247) (xy 302.553688 -286.179072)
			(xy 302.545496 -286.178752) (xy 302.05426 -286.178752) (xy 302.046068 -286.179067) (xy 302.030527 -286.184254)
			(xy 302.02378 -286.188912) (xy 302.002155 -286.204569) (xy 301.95491 -286.229427) (xy 301.904283 -286.246368)
			(xy 301.851591 -286.25495) (xy 301.798205 -286.25495) (xy 301.745513 -286.246368) (xy 301.694886 -286.229427)
			(xy 301.647641 -286.204569) (xy 301.626016 -286.188912) (xy 301.619276 -286.184242) (xy 301.60373 -286.179054)
			(xy 301.595536 -286.178752) (xy 301.104046 -286.178752) (xy 301.095849 -286.179053) (xy 301.080292 -286.18422)
			(xy 301.073566 -286.188912) (xy 301.051941 -286.204569) (xy 301.004696 -286.229427) (xy 300.954069 -286.246368)
			(xy 300.901377 -286.25495) (xy 300.847991 -286.25495) (xy 300.795299 -286.246368) (xy 300.744672 -286.229427)
			(xy 300.697427 -286.204569) (xy 300.675802 -286.188912) (xy 300.669061 -286.184244) (xy 300.653515 -286.17906)
			(xy 300.645322 -286.178752) (xy 300.154086 -286.178752) (xy 300.145893 -286.179063) (xy 300.130347 -286.184244)
			(xy 300.123606 -286.188912) (xy 300.101981 -286.204569) (xy 300.054736 -286.229427) (xy 300.004109 -286.246368)
			(xy 299.951417 -286.25495) (xy 299.898031 -286.25495) (xy 299.845339 -286.246368) (xy 299.794712 -286.229427)
			(xy 299.747467 -286.204569) (xy 299.725842 -286.188912) (xy 299.719099 -286.184252) (xy 299.703553 -286.179087)
			(xy 299.695362 -286.178752) (xy 299.204126 -286.178752) (xy 299.19593 -286.179056) (xy 299.180377 -286.184228)
			(xy 299.173646 -286.188912) (xy 299.152021 -286.204569) (xy 299.104776 -286.229427) (xy 299.054149 -286.246368)
			(xy 299.001457 -286.25495) (xy 298.948071 -286.25495) (xy 298.895379 -286.246368) (xy 298.844752 -286.229427)
			(xy 298.797507 -286.204569) (xy 298.775882 -286.188912) (xy 298.76914 -286.184247) (xy 298.753595 -286.179069)
			(xy 298.745402 -286.178752) (xy 298.254166 -286.178752) (xy 298.245974 -286.179066) (xy 298.230431 -286.184252)
			(xy 298.223686 -286.188912) (xy 298.202061 -286.204569) (xy 298.154816 -286.229427) (xy 298.104189 -286.246368)
			(xy 298.051497 -286.25495) (xy 297.998111 -286.25495) (xy 297.945419 -286.246368) (xy 297.894792 -286.229427)
			(xy 297.847547 -286.204569) (xy 297.825922 -286.188912) (xy 297.819182 -286.184241) (xy 297.803636 -286.179052)
			(xy 297.795442 -286.178752) (xy 297.304206 -286.178752) (xy 297.296012 -286.17906) (xy 297.280462 -286.184236)
			(xy 297.273726 -286.188912) (xy 297.252101 -286.204569) (xy 297.204856 -286.229427) (xy 297.154229 -286.246368)
			(xy 297.101537 -286.25495) (xy 297.048151 -286.25495) (xy 296.995459 -286.246368) (xy 296.944832 -286.229427)
			(xy 296.897587 -286.204569) (xy 296.875962 -286.188912) (xy 296.86922 -286.184249) (xy 296.853674 -286.179078)
			(xy 296.845482 -286.178752) (xy 296.354246 -286.178752) (xy 296.346049 -286.179053) (xy 296.330492 -286.18422)
			(xy 296.323766 -286.188912) (xy 296.302141 -286.204569) (xy 296.254896 -286.229427) (xy 296.204269 -286.246368)
			(xy 296.151577 -286.25495) (xy 296.098191 -286.25495) (xy 296.045499 -286.246368) (xy 295.994872 -286.229427)
			(xy 295.947627 -286.204569) (xy 295.926002 -286.188912) (xy 295.919261 -286.184244) (xy 295.903715 -286.17906)
			(xy 295.895522 -286.178752) (xy 295.404286 -286.178752) (xy 295.396093 -286.179063) (xy 295.380547 -286.184244)
			(xy 295.373806 -286.188912) (xy 295.352181 -286.204569) (xy 295.304936 -286.229427) (xy 295.254309 -286.246368)
			(xy 295.201617 -286.25495) (xy 295.148231 -286.25495) (xy 295.095539 -286.246368) (xy 295.044912 -286.229427)
			(xy 294.997667 -286.204569) (xy 294.976042 -286.188912) (xy 294.969299 -286.184252) (xy 294.953753 -286.179087)
			(xy 294.945562 -286.178752) (xy 294.454072 -286.178752) (xy 294.445879 -286.179065) (xy 294.430336 -286.18425)
			(xy 294.423592 -286.188912) (xy 294.401967 -286.204569) (xy 294.354722 -286.229427) (xy 294.304095 -286.246368)
			(xy 294.251403 -286.25495) (xy 294.198017 -286.25495) (xy 294.145325 -286.246368) (xy 294.094698 -286.229427)
			(xy 294.047453 -286.204569) (xy 294.025828 -286.188912) (xy 294.019088 -286.184241) (xy 294.003543 -286.179049)
			(xy 293.995348 -286.178752) (xy 293.504112 -286.178752) (xy 293.495917 -286.179059) (xy 293.480366 -286.184234)
			(xy 293.473632 -286.188912) (xy 293.452007 -286.204569) (xy 293.404762 -286.229427) (xy 293.354135 -286.246368)
			(xy 293.301443 -286.25495) (xy 293.248057 -286.25495) (xy 293.195365 -286.246368) (xy 293.144738 -286.229427)
			(xy 293.097493 -286.204569) (xy 293.075868 -286.188912) (xy 293.069126 -286.184249) (xy 293.05358 -286.179075)
			(xy 293.045388 -286.178752) (xy 292.554152 -286.178752) (xy 292.545961 -286.179068) (xy 292.530421 -286.184257)
			(xy 292.523672 -286.188912) (xy 292.502047 -286.204569) (xy 292.454802 -286.229427) (xy 292.404175 -286.246368)
			(xy 292.351483 -286.25495) (xy 292.298097 -286.25495) (xy 292.245405 -286.246368) (xy 292.194778 -286.229427)
			(xy 292.147533 -286.204569) (xy 292.125908 -286.188912) (xy 292.119167 -286.184243) (xy 292.103622 -286.179058)
			(xy 292.095428 -286.178752) (xy 290.654232 -286.178752) (xy 290.646036 -286.179056) (xy 290.630482 -286.184226)
			(xy 290.623752 -286.188912) (xy 290.602127 -286.204569) (xy 290.554882 -286.229427) (xy 290.504255 -286.246368)
			(xy 290.451563 -286.25495) (xy 290.398177 -286.25495) (xy 290.345485 -286.246368) (xy 290.294858 -286.229427)
			(xy 290.247613 -286.204569) (xy 290.225988 -286.188912) (xy 290.219247 -286.184246) (xy 290.203701 -286.179066)
			(xy 290.195508 -286.178752) (xy 289.704272 -286.178752) (xy 289.696079 -286.179065) (xy 289.680536 -286.18425)
			(xy 289.673792 -286.188912) (xy 289.652167 -286.204569) (xy 289.604922 -286.229427) (xy 289.554295 -286.246368)
			(xy 289.501603 -286.25495) (xy 289.448217 -286.25495) (xy 289.395525 -286.246368) (xy 289.344898 -286.229427)
			(xy 289.297653 -286.204569) (xy 289.276028 -286.188912) (xy 289.269288 -286.184241) (xy 289.253743 -286.179049)
			(xy 289.245548 -286.178752) (xy 288.754058 -286.178752) (xy 288.745866 -286.179067) (xy 288.730325 -286.184255)
			(xy 288.723578 -286.188912) (xy 288.701953 -286.204569) (xy 288.654708 -286.229427) (xy 288.604081 -286.246368)
			(xy 288.551389 -286.25495) (xy 288.498003 -286.25495) (xy 288.445311 -286.246368) (xy 288.394684 -286.229427)
			(xy 288.347439 -286.204569) (xy 288.325814 -286.188912) (xy 288.319074 -286.184242) (xy 288.303528 -286.179055)
			(xy 288.295334 -286.178752) (xy 287.804098 -286.178752) (xy 287.795904 -286.179061) (xy 287.780356 -286.184239)
			(xy 287.773618 -286.188912) (xy 287.751993 -286.204569) (xy 287.704748 -286.229427) (xy 287.654121 -286.246368)
			(xy 287.601429 -286.25495) (xy 287.548043 -286.25495) (xy 287.495351 -286.246368) (xy 287.444724 -286.229427)
			(xy 287.397479 -286.204569) (xy 287.375854 -286.188912) (xy 287.369111 -286.18425) (xy 287.353566 -286.179081)
			(xy 287.345374 -286.178752) (xy 286.854138 -286.178752) (xy 286.845942 -286.179055) (xy 286.830386 -286.184223)
			(xy 286.823658 -286.188912) (xy 286.802033 -286.204569) (xy 286.754788 -286.229427) (xy 286.704161 -286.246368)
			(xy 286.651469 -286.25495) (xy 286.598083 -286.25495) (xy 286.545391 -286.246368) (xy 286.494764 -286.229427)
			(xy 286.447519 -286.204569) (xy 286.425894 -286.188912) (xy 286.419153 -286.184245) (xy 286.403607 -286.179064)
			(xy 286.395414 -286.178752) (xy 285.904178 -286.178752) (xy 285.895985 -286.179064) (xy 285.880441 -286.184247)
			(xy 285.873698 -286.188912) (xy 285.852073 -286.204569) (xy 285.804828 -286.229427) (xy 285.754201 -286.246368)
			(xy 285.701509 -286.25495) (xy 285.648123 -286.25495) (xy 285.595431 -286.246368) (xy 285.544804 -286.229427)
			(xy 285.497559 -286.204569) (xy 285.475934 -286.188912) (xy 285.469191 -286.184253) (xy 285.453645 -286.17909)
			(xy 285.445454 -286.178752) (xy 284.954218 -286.178752) (xy 284.946023 -286.179058) (xy 284.930471 -286.184231)
			(xy 284.923738 -286.188912) (xy 284.902113 -286.204569) (xy 284.854868 -286.229427) (xy 284.804241 -286.246368)
			(xy 284.751549 -286.25495) (xy 284.698163 -286.25495) (xy 284.645471 -286.246368) (xy 284.594844 -286.229427)
			(xy 284.547599 -286.204569) (xy 284.525974 -286.188912) (xy 284.519232 -286.184248) (xy 284.503686 -286.179073)
			(xy 284.495494 -286.178752) (xy 284.004258 -286.178752) (xy 283.996066 -286.179067) (xy 283.980525 -286.184255)
			(xy 283.973778 -286.188912) (xy 283.952153 -286.204569) (xy 283.904908 -286.229427) (xy 283.854281 -286.246368)
			(xy 283.801589 -286.25495) (xy 283.748203 -286.25495) (xy 283.695511 -286.246368) (xy 283.644884 -286.229427)
			(xy 283.597639 -286.204569) (xy 283.576014 -286.188912) (xy 283.569274 -286.184242) (xy 283.553728 -286.179055)
			(xy 283.545534 -286.178752) (xy 283.054298 -286.178752) (xy 283.046104 -286.179061) (xy 283.030556 -286.184239)
			(xy 283.023818 -286.188912) (xy 283.002193 -286.204569) (xy 282.954948 -286.229427) (xy 282.904321 -286.246368)
			(xy 282.851629 -286.25495) (xy 282.798243 -286.25495) (xy 282.745551 -286.246368) (xy 282.694924 -286.229427)
			(xy 282.647679 -286.204569) (xy 282.626054 -286.188912) (xy 282.619311 -286.18425) (xy 282.603766 -286.179081)
			(xy 282.595574 -286.178752) (xy 282.104084 -286.178752) (xy 282.095891 -286.179063) (xy 282.080345 -286.184245)
			(xy 282.073604 -286.188912) (xy 282.051979 -286.204569) (xy 282.004734 -286.229427) (xy 281.954107 -286.246368)
			(xy 281.901415 -286.25495) (xy 281.848029 -286.25495) (xy 281.795337 -286.246368) (xy 281.74471 -286.229427)
			(xy 281.697465 -286.204569) (xy 281.67584 -286.188912) (xy 281.669097 -286.184252) (xy 281.653551 -286.179087)
			(xy 281.64536 -286.178752) (xy 281.154124 -286.178752) (xy 281.145929 -286.179057) (xy 281.130375 -286.184229)
			(xy 281.123644 -286.188912) (xy 281.102019 -286.204569) (xy 281.054774 -286.229427) (xy 281.004147 -286.246368)
			(xy 280.951455 -286.25495) (xy 280.898069 -286.25495) (xy 280.845377 -286.246368) (xy 280.79475 -286.229427)
			(xy 280.747505 -286.204569) (xy 280.72588 -286.188912) (xy 280.719138 -286.184247) (xy 280.703593 -286.17907)
			(xy 280.6954 -286.178752) (xy 280.204164 -286.178752) (xy 280.195972 -286.179066) (xy 280.18043 -286.184253)
			(xy 280.173684 -286.188912) (xy 280.152059 -286.204569) (xy 280.104814 -286.229427) (xy 280.054187 -286.246368)
			(xy 280.001495 -286.25495) (xy 279.948109 -286.25495) (xy 279.895417 -286.246368) (xy 279.84479 -286.229427)
			(xy 279.797545 -286.204569) (xy 279.77592 -286.188912) (xy 279.76918 -286.184242) (xy 279.753634 -286.179052)
			(xy 279.74544 -286.178752) (xy 279.254204 -286.178752) (xy 279.24601 -286.17906) (xy 279.23046 -286.184237)
			(xy 279.223724 -286.188912) (xy 279.202099 -286.204569) (xy 279.154854 -286.229427) (xy 279.104227 -286.246368)
			(xy 279.051535 -286.25495) (xy 278.998149 -286.25495) (xy 278.945457 -286.246368) (xy 278.89483 -286.229427)
			(xy 278.847585 -286.204569) (xy 278.82596 -286.188912) (xy 278.819218 -286.18425) (xy 278.803672 -286.179079)
			(xy 278.79548 -286.178752) (xy 278.304244 -286.178752) (xy 278.296047 -286.179054) (xy 278.280491 -286.184221)
			(xy 278.273764 -286.188912) (xy 278.252139 -286.204569) (xy 278.204894 -286.229427) (xy 278.154267 -286.246368)
			(xy 278.101575 -286.25495) (xy 278.048189 -286.25495) (xy 277.995497 -286.246368) (xy 277.94487 -286.229427)
			(xy 277.897625 -286.204569) (xy 277.876 -286.188912) (xy 277.869259 -286.184244) (xy 277.853713 -286.179061)
			(xy 277.84552 -286.178752) (xy 277.354284 -286.178752) (xy 277.346091 -286.179063) (xy 277.330545 -286.184245)
			(xy 277.323804 -286.188912) (xy 277.302179 -286.204569) (xy 277.254934 -286.229427) (xy 277.204307 -286.246368)
			(xy 277.151615 -286.25495) (xy 277.098229 -286.25495) (xy 277.045537 -286.246368) (xy 276.99491 -286.229427)
			(xy 276.947665 -286.204569) (xy 276.92604 -286.188912) (xy 276.919297 -286.184252) (xy 276.903751 -286.179087)
			(xy 276.89556 -286.178752) (xy 273.55419 -286.178752) (xy 273.545996 -286.179062) (xy 273.53045 -286.184242)
			(xy 273.52371 -286.188912) (xy 273.502085 -286.204569) (xy 273.45484 -286.229427) (xy 273.404213 -286.246368)
			(xy 273.351521 -286.25495) (xy 273.298135 -286.25495) (xy 273.245443 -286.246368) (xy 273.194816 -286.229427)
			(xy 273.147571 -286.204569) (xy 273.125946 -286.188912) (xy 273.119203 -286.184252) (xy 273.103657 -286.179085)
			(xy 273.095466 -286.178752) (xy 272.60423 -286.178752) (xy 272.596034 -286.179056) (xy 272.58048 -286.184227)
			(xy 272.57375 -286.188912) (xy 272.552125 -286.204569) (xy 272.50488 -286.229427) (xy 272.454253 -286.246368)
			(xy 272.401561 -286.25495) (xy 272.348175 -286.25495) (xy 272.295483 -286.246368) (xy 272.244856 -286.229427)
			(xy 272.197611 -286.204569) (xy 272.175986 -286.188912) (xy 272.169245 -286.184246) (xy 272.153699 -286.179067)
			(xy 272.145506 -286.178752) (xy 271.65427 -286.178752) (xy 271.646078 -286.179065) (xy 271.630534 -286.18425)
			(xy 271.62379 -286.188912) (xy 271.602165 -286.204569) (xy 271.55492 -286.229427) (xy 271.504293 -286.246368)
			(xy 271.451601 -286.25495) (xy 271.398215 -286.25495) (xy 271.345523 -286.246368) (xy 271.294896 -286.229427)
			(xy 271.247651 -286.204569) (xy 271.226026 -286.188912) (xy 271.219286 -286.184241) (xy 271.20374 -286.17905)
			(xy 271.195546 -286.178752) (xy 270.70431 -286.178752) (xy 270.696115 -286.179059) (xy 270.680565 -286.184234)
			(xy 270.67383 -286.188912) (xy 270.652205 -286.204569) (xy 270.60496 -286.229427) (xy 270.554333 -286.246368)
			(xy 270.501641 -286.25495) (xy 270.448255 -286.25495) (xy 270.395563 -286.246368) (xy 270.344936 -286.229427)
			(xy 270.297691 -286.204569) (xy 270.276066 -286.188912) (xy 270.269324 -286.184249) (xy 270.253778 -286.179076)
			(xy 270.245586 -286.178752) (xy 269.754096 -286.178752) (xy 269.745902 -286.179061) (xy 269.730354 -286.18424)
			(xy 269.723616 -286.188912) (xy 269.701991 -286.204569) (xy 269.654746 -286.229427) (xy 269.604119 -286.246368)
			(xy 269.551427 -286.25495) (xy 269.498041 -286.25495) (xy 269.445349 -286.246368) (xy 269.394722 -286.229427)
			(xy 269.347477 -286.204569) (xy 269.325852 -286.188912) (xy 269.319109 -286.184251) (xy 269.303563 -286.179082)
			(xy 269.295372 -286.178752) (xy 268.998954 -286.178752) (xy 268.988889 -286.179185) (xy 268.970301 -286.186917)
			(xy 268.962886 -286.193738) (xy 268.907006 -286.249618) (xy 268.900162 -286.257017) (xy 268.892433 -286.275615)
			(xy 268.89202 -286.285686) (xy 268.89202 -286.78124) (xy 268.893798 -286.787844) (xy 268.899256 -286.80921)
			(xy 268.905119 -286.852917) (xy 268.905482 -286.874966) (xy 268.905148 -286.896817) (xy 268.899415 -286.940141)
			(xy 268.894052 -286.961326) (xy 268.892274 -286.967676) (xy 268.892274 -287.732216) (xy 268.894052 -287.738566)
			(xy 268.899399 -287.759754) (xy 268.905129 -287.803076) (xy 268.905482 -287.824926) (xy 268.905151 -287.846777)
			(xy 268.899423 -287.890102) (xy 268.894052 -287.911286) (xy 268.892274 -287.917636) (xy 268.892274 -288.682176)
			(xy 268.894052 -288.688526) (xy 268.899401 -288.709714) (xy 268.905137 -288.753036) (xy 268.905482 -288.774886)
			(xy 268.905147 -288.796737) (xy 268.899411 -288.84006) (xy 268.894052 -288.861246) (xy 268.892274 -288.867596)
			(xy 268.892274 -289.632136) (xy 268.894052 -289.638486) (xy 268.899397 -289.659674) (xy 268.905125 -289.702996)
			(xy 268.905482 -289.724846) (xy 268.905149 -289.746697) (xy 268.899419 -289.790022) (xy 268.894052 -289.811206)
			(xy 268.892274 -289.817556) (xy 268.892274 -290.582096) (xy 268.894052 -290.588446) (xy 268.8994 -290.609634)
			(xy 268.905133 -290.652956) (xy 268.905482 -290.674806) (xy 268.905145 -290.696657) (xy 268.899407 -290.739979)
			(xy 268.894052 -290.761166) (xy 268.892274 -290.767516) (xy 268.892274 -291.532056) (xy 268.894052 -291.538406)
			(xy 268.899403 -291.559594) (xy 268.90514 -291.602916) (xy 268.905482 -291.624766) (xy 268.905148 -291.646617)
			(xy 268.899415 -291.689941) (xy 268.894052 -291.711126) (xy 268.892274 -291.717476) (xy 268.892274 -292.48227)
			(xy 268.894052 -292.48862) (xy 268.899402 -292.509808) (xy 268.905138 -292.55313) (xy 268.905482 -292.57498)
			(xy 268.905147 -292.596831) (xy 268.899412 -292.640154) (xy 268.894052 -292.66134) (xy 268.892274 -292.66769)
			(xy 268.892274 -294.38219) (xy 268.894052 -294.38854) (xy 268.8994 -294.409728) (xy 268.905134 -294.45305)
			(xy 268.905482 -294.4749) (xy 268.905146 -294.496751) (xy 268.899408 -294.540073) (xy 268.894052 -294.56126)
			(xy 268.892274 -294.56761) (xy 268.892274 -296.943272) (xy 268.892689 -296.953299) (xy 268.900353 -296.97183)
			(xy 268.914525 -296.986017) (xy 268.933048 -296.993701) (xy 268.943074 -296.994072) (xy 269.52448 -296.994072)
			(xy 269.550472 -296.994554) (xy 269.601816 -297.002683) (xy 269.651256 -297.018744) (xy 269.697575 -297.042342)
			(xy 269.739632 -297.072896) (xy 269.776391 -297.109653) (xy 269.806947 -297.151708) (xy 269.830548 -297.198025)
			(xy 269.846612 -297.247465) (xy 269.854745 -297.298808) (xy 269.854745 -297.350792) (xy 269.846612 -297.402135)
			(xy 269.830548 -297.451575) (xy 269.806947 -297.497892) (xy 269.776391 -297.539947) (xy 269.739632 -297.576704)
			(xy 269.697575 -297.607258) (xy 269.651256 -297.630856) (xy 269.601816 -297.646917) (xy 269.550472 -297.655046)
			(xy 269.52448 -297.655488) (xy 268.943074 -297.655488) (xy 268.933069 -297.655981) (xy 268.914584 -297.663644)
			(xy 268.900436 -297.677796) (xy 268.892778 -297.696283) (xy 268.892274 -297.706288) (xy 268.892274 -298.843192)
			(xy 268.89276 -298.853203) (xy 268.900417 -298.871702) (xy 268.91457 -298.885864) (xy 268.933064 -298.893533)
			(xy 268.943074 -298.893992) (xy 269.52448 -298.893992) (xy 269.550494 -298.894474) (xy 269.601881 -298.90261)
			(xy 269.651363 -298.918685) (xy 269.697721 -298.942303) (xy 269.739814 -298.972883) (xy 269.776604 -299.009671)
			(xy 269.807186 -299.051761) (xy 269.830807 -299.098118) (xy 269.846885 -299.147599) (xy 269.855024 -299.198986)
			(xy 269.855024 -299.251013) (xy 271.094376 -299.251013) (xy 271.094376 -299.198987) (xy 271.102514 -299.147601)
			(xy 271.118592 -299.098121) (xy 271.142212 -299.051765) (xy 271.172792 -299.009675) (xy 271.209581 -298.972887)
			(xy 271.251672 -298.942307) (xy 271.298028 -298.918689) (xy 271.347509 -298.902613) (xy 271.398895 -298.894475)
			(xy 271.424908 -298.893992) (xy 272.374868 -298.893992) (xy 272.400875 -298.894565) (xy 272.45225 -298.902697)
			(xy 272.50172 -298.918767) (xy 272.548067 -298.942378) (xy 272.590149 -298.972949) (xy 272.626931 -299.009727)
			(xy 272.657506 -299.051806) (xy 272.681121 -299.09815) (xy 272.697195 -299.147619) (xy 272.705333 -299.198993)
			(xy 272.705333 -299.251007) (xy 272.697195 -299.302381) (xy 272.681121 -299.35185) (xy 272.657506 -299.398194)
			(xy 272.626931 -299.440273) (xy 272.590149 -299.477051) (xy 272.548067 -299.507622) (xy 272.50172 -299.531233)
			(xy 272.45225 -299.547303) (xy 272.400875 -299.555435) (xy 272.374868 -299.555916) (xy 271.424908 -299.555916)
			(xy 271.398895 -299.555525) (xy 271.347509 -299.547387) (xy 271.298028 -299.531311) (xy 271.251672 -299.507693)
			(xy 271.209581 -299.477113) (xy 271.172792 -299.440325) (xy 271.142212 -299.398235) (xy 271.118592 -299.351879)
			(xy 271.102514 -299.302399) (xy 271.094376 -299.251013) (xy 269.855024 -299.251013) (xy 269.855024 -299.251014)
			(xy 269.846885 -299.302401) (xy 269.830807 -299.351882) (xy 269.807186 -299.398239) (xy 269.776604 -299.440329)
			(xy 269.739814 -299.477117) (xy 269.697721 -299.507697) (xy 269.651363 -299.531315) (xy 269.601881 -299.54739)
			(xy 269.550494 -299.555526) (xy 269.52448 -299.555916) (xy 268.943074 -299.555916) (xy 268.933071 -299.556409)
			(xy 268.914591 -299.564073) (xy 268.90045 -299.578226) (xy 268.8928 -299.596713) (xy 268.892274 -299.606716)
			(xy 268.892274 -320.900044) (xy 317.098687 -320.900044) (xy 317.102693 -320.704989) (xy 317.114703 -320.510263)
			(xy 317.134698 -320.316194) (xy 317.162643 -320.12311) (xy 317.198492 -319.931335) (xy 317.242184 -319.741195)
			(xy 317.293645 -319.553008) (xy 317.352789 -319.367093) (xy 317.419516 -319.183762) (xy 317.493713 -319.003326)
			(xy 317.575255 -318.826088) (xy 317.664006 -318.652347) (xy 317.759814 -318.482396) (xy 317.862519 -318.316522)
			(xy 317.971947 -318.155004) (xy 318.087914 -317.998115) (xy 318.210225 -317.84612) (xy 318.338672 -317.699274)
			(xy 318.47304 -317.557825) (xy 318.613102 -317.422012) (xy 318.758621 -317.292063) (xy 318.909353 -317.168199)
			(xy 319.065043 -317.050627) (xy 319.225429 -316.939547) (xy 319.39024 -316.835144) (xy 319.559198 -316.737596)
			(xy 319.732019 -316.647067) (xy 319.908411 -316.563709) (xy 320.088076 -316.487663) (xy 320.270711 -316.419058)
			(xy 320.45601 -316.358008) (xy 320.643658 -316.304618) (xy 320.83334 -316.258976) (xy 321.024737 -316.22116)
			(xy 321.217524 -316.191234) (xy 321.411377 -316.169248) (xy 321.60597 -316.155239) (xy 321.800973 -316.149231)
			(xy 321.996059 -316.151234) (xy 322.190898 -316.161245) (xy 322.385162 -316.179246) (xy 322.578523 -316.205208)
			(xy 322.770656 -316.239086) (xy 322.961235 -316.280823) (xy 323.14994 -316.33035) (xy 323.336453 -316.387582)
			(xy 323.520459 -316.452423) (xy 323.701647 -316.524764) (xy 323.879713 -316.604482) (xy 324.054356 -316.691444)
			(xy 324.225282 -316.785503) (xy 324.392201 -316.886499) (xy 324.554834 -316.994264) (xy 324.712905 -317.108614)
			(xy 324.866148 -317.229357) (xy 325.014305 -317.356291) (xy 325.157126 -317.489199) (xy 325.29437 -317.627859)
			(xy 325.425806 -317.772037) (xy 325.551211 -317.92149) (xy 325.670375 -318.075964) (xy 325.783096 -318.235201)
			(xy 325.889185 -318.398932) (xy 325.988463 -318.566879) (xy 326.080761 -318.738762) (xy 326.165926 -318.914288)
			(xy 326.243812 -319.093163) (xy 326.314289 -319.275085) (xy 326.377237 -319.459747) (xy 326.432552 -319.646837)
			(xy 326.480138 -319.836041) (xy 326.519917 -320.027038) (xy 326.551821 -320.219508) (xy 326.575796 -320.413126)
			(xy 326.591802 -320.607564) (xy 326.599811 -320.802496) (xy 326.600312 -320.900044) (xy 326.599811 -320.997592)
			(xy 326.591802 -321.192524) (xy 326.575796 -321.386962) (xy 326.551821 -321.58058) (xy 326.519917 -321.77305)
			(xy 326.480138 -321.964047) (xy 326.432552 -322.153251) (xy 326.377237 -322.340341) (xy 326.314289 -322.525003)
			(xy 326.243812 -322.706925) (xy 326.165926 -322.8858) (xy 326.080761 -323.061326) (xy 325.988463 -323.233209)
			(xy 325.889185 -323.401156) (xy 325.783096 -323.564887) (xy 325.670375 -323.724124) (xy 325.551211 -323.878598)
			(xy 325.425806 -324.028051) (xy 325.29437 -324.172229) (xy 325.157126 -324.310889) (xy 325.014305 -324.443797)
			(xy 324.866148 -324.570731) (xy 324.712905 -324.691474) (xy 324.554834 -324.805824) (xy 324.392201 -324.913589)
			(xy 324.225282 -325.014585) (xy 324.054356 -325.108644) (xy 323.879713 -325.195606) (xy 323.701647 -325.275324)
			(xy 323.520459 -325.347665) (xy 323.336453 -325.412506) (xy 323.14994 -325.469738) (xy 322.961235 -325.519265)
			(xy 322.770656 -325.561002) (xy 322.578523 -325.59488) (xy 322.385162 -325.620842) (xy 322.190898 -325.638843)
			(xy 321.996059 -325.648854) (xy 321.800973 -325.650857) (xy 321.60597 -325.644849) (xy 321.411377 -325.63084)
			(xy 321.217524 -325.608854) (xy 321.024737 -325.578928) (xy 320.83334 -325.541112) (xy 320.643658 -325.49547)
			(xy 320.45601 -325.44208) (xy 320.270711 -325.38103) (xy 320.088076 -325.312425) (xy 319.908411 -325.236379)
			(xy 319.732019 -325.153021) (xy 319.559198 -325.062492) (xy 319.39024 -324.964944) (xy 319.225429 -324.860541)
			(xy 319.065043 -324.749461) (xy 318.909353 -324.631889) (xy 318.758621 -324.508025) (xy 318.613102 -324.378076)
			(xy 318.47304 -324.242263) (xy 318.338672 -324.100814) (xy 318.210225 -323.953968) (xy 318.087914 -323.801973)
			(xy 317.971947 -323.645084) (xy 317.862519 -323.483566) (xy 317.759814 -323.317692) (xy 317.664006 -323.147741)
			(xy 317.575255 -322.974) (xy 317.493713 -322.796762) (xy 317.419516 -322.616326) (xy 317.352789 -322.432995)
			(xy 317.293645 -322.24708) (xy 317.242184 -322.058893) (xy 317.198492 -321.868753) (xy 317.162643 -321.676978)
			(xy 317.134698 -321.483894) (xy 317.114703 -321.289825) (xy 317.102693 -321.095099) (xy 317.098687 -320.900044)
			(xy 268.892274 -320.900044) (xy 268.892274 -337.464908) (xy 268.892698 -337.474978) (xy 268.900411 -337.493583)
			(xy 268.90726 -337.500976) (xy 269.248636 -337.842352) (xy 269.256034 -337.849198) (xy 269.274633 -337.856927)
			(xy 269.284704 -337.857338) (xy 349.48749 -337.857338)
		)
		(stroke
			(width 0)
			(type solid)
		)
		(fill yes)
		(layer "In3.Cu")
		(net "P0V8_PEX2")
	)
	(gr_poly
		(pts
			(xy 117.294152 -337.850226) (xy 117.461792 -337.682586) (xy 117.468637 -337.675187) (xy 117.476368 -337.656589)
			(xy 117.476778 -337.646518) (xy 117.476778 -329.799696) (xy 117.476086 -329.787534) (xy 117.464949 -329.765909)
			(xy 117.455442 -329.758294) (xy 117.432822 -329.741708) (xy 117.392245 -329.702983) (xy 117.357779 -329.658731)
			(xy 117.330169 -329.609907) (xy 117.310011 -329.557564) (xy 117.29774 -329.502833) (xy 117.293621 -329.446894)
			(xy 117.297742 -329.390956) (xy 117.310015 -329.336225) (xy 117.330174 -329.283883) (xy 117.357785 -329.235059)
			(xy 117.392252 -329.190808) (xy 117.432831 -329.152085) (xy 117.455442 -329.135486) (xy 117.46495 -329.127869)
			(xy 117.476098 -329.106247) (xy 117.476778 -329.094084) (xy 117.476778 -318.923162) (xy 117.476445 -318.91462)
			(xy 117.470808 -318.898491) (xy 117.460177 -318.885117) (xy 117.453156 -318.880236) (xy 117.430191 -318.865163)
			(xy 117.388436 -318.829468) (xy 117.352233 -318.788153) (xy 117.32233 -318.742073) (xy 117.299345 -318.692181)
			(xy 117.283754 -318.639508) (xy 117.275879 -318.585143) (xy 117.275882 -318.53021) (xy 117.283764 -318.475847)
			(xy 117.299362 -318.423175) (xy 117.322353 -318.373286) (xy 117.352262 -318.327209) (xy 117.38847 -318.285899)
			(xy 117.430228 -318.250209) (xy 117.453156 -318.235076) (xy 117.4602 -318.230227) (xy 117.470819 -318.216837)
			(xy 117.476433 -318.200695) (xy 117.476778 -318.19215) (xy 117.476778 -318.058546) (xy 117.476443 -318.050005)
			(xy 117.470802 -318.03388) (xy 117.460169 -318.020511) (xy 117.453156 -318.01562) (xy 117.430184 -318.000547)
			(xy 117.388418 -317.96485) (xy 117.352203 -317.923532) (xy 117.322289 -317.877447) (xy 117.299294 -317.827548)
			(xy 117.283694 -317.774867) (xy 117.27581 -317.720493) (xy 117.275807 -317.66555) (xy 117.283685 -317.611175)
			(xy 117.299279 -317.558492) (xy 117.322268 -317.50859) (xy 117.352177 -317.462502) (xy 117.388387 -317.42118)
			(xy 117.43015 -317.385478) (xy 117.453156 -317.37046) (xy 117.460198 -317.365611) (xy 117.470813 -317.352219)
			(xy 117.476422 -317.336078) (xy 117.476778 -317.327534) (xy 117.476778 -316.355476) (xy 117.476447 -316.346933)
			(xy 117.470814 -316.330801) (xy 117.460183 -316.317423) (xy 117.453156 -316.31255) (xy 117.43019 -316.297477)
			(xy 117.388433 -316.261781) (xy 117.352228 -316.220466) (xy 117.322323 -316.174385) (xy 117.299337 -316.124492)
			(xy 117.283744 -316.071817) (xy 117.275867 -316.017451) (xy 117.27587 -315.962517) (xy 117.283751 -315.908151)
			(xy 117.299348 -315.855478) (xy 117.322339 -315.805587) (xy 117.352248 -315.759508) (xy 117.388456 -315.718196)
			(xy 117.430215 -315.682504) (xy 117.453156 -315.66739) (xy 117.460201 -315.662542) (xy 117.470824 -315.649152)
			(xy 117.476443 -315.63301) (xy 117.476778 -315.624464) (xy 117.476778 -295.255442) (xy 117.45468 -295.227756)
			(xy 117.437408 -295.223692) (xy 117.409715 -295.216802) (xy 117.356609 -295.195917) (xy 117.307206 -295.167355)
			(xy 117.262608 -295.131753) (xy 117.22381 -295.089906) (xy 117.191678 -295.042747) (xy 117.166929 -294.991328)
			(xy 117.150114 -294.936796) (xy 117.14161 -294.880369) (xy 117.14099 -294.851836) (xy 117.141519 -294.822573)
			(xy 117.150452 -294.764733) (xy 117.168113 -294.708936) (xy 117.194088 -294.656491) (xy 117.227767 -294.608627)
			(xy 117.24767 -294.587168) (xy 117.254782 -294.579802) (xy 117.261894 -294.561514) (xy 117.261132 -294.480234)
			(xy 117.260572 -294.470403) (xy 117.252984 -294.452252) (xy 117.2464 -294.444928) (xy 117.244622 -294.44315)
			(xy 117.237222 -294.43631) (xy 117.218623 -294.428596) (xy 117.208554 -294.428164) (xy 111.361474 -294.428164)
			(xy 111.350366 -294.428725) (xy 111.330213 -294.438078) (xy 111.322612 -294.446198) (xy 111.304394 -294.466944)
			(xy 111.263004 -294.503483) (xy 111.216779 -294.533675) (xy 111.166685 -294.556888) (xy 111.113768 -294.572639)
			(xy 111.059134 -294.580597) (xy 111.003922 -294.580597) (xy 110.949288 -294.572639) (xy 110.896371 -294.556888)
			(xy 110.846277 -294.533675) (xy 110.800052 -294.503483) (xy 110.758662 -294.466944) (xy 110.740444 -294.446198)
			(xy 110.732855 -294.438061) (xy 110.712696 -294.428706) (xy 110.701582 -294.428164) (xy 100.863908 -294.428164)
			(xy 100.838955 -294.427544) (xy 100.790012 -294.41779) (xy 100.743912 -294.398675) (xy 100.702427 -294.370934)
			(xy 100.68433 -294.353742) (xy 100.072952 -293.742364) (xy 100.055692 -293.724323) (xy 100.027934 -293.682829)
			(xy 100.00882 -293.636711) (xy 99.999086 -293.587747) (xy 99.99853 -293.562786) (xy 99.99853 -293.219378)
			(xy 99.998014 -293.207931) (xy 99.988105 -293.187296) (xy 99.97948 -293.179754) (xy 99.908868 -293.122858)
			(xy 99.886516 -293.117524) (xy 99.875086 -293.120064) (xy 99.78572 -293.139072) (xy 99.605394 -293.168585)
			(xy 99.423737 -293.188309) (xy 99.241279 -293.198186) (xy 99.149916 -293.198804) (xy 99.068262 -293.198319)
			(xy 98.905143 -293.190429) (xy 98.742597 -293.174669) (xy 98.581001 -293.151073) (xy 98.420734 -293.119698)
			(xy 98.262171 -293.080616) (xy 98.10568 -293.033919) (xy 97.951629 -292.979716) (xy 97.800376 -292.918133)
			(xy 97.652275 -292.849315) (xy 97.507672 -292.773422) (xy 97.366904 -292.690632) (xy 97.230301 -292.601137)
			(xy 97.098181 -292.505147) (xy 96.970853 -292.402885) (xy 96.848614 -292.294592) (xy 96.73175 -292.180519)
			(xy 96.620534 -292.060933) (xy 96.515225 -291.936114) (xy 96.416069 -291.806352) (xy 96.323299 -291.671952)
			(xy 96.237131 -291.533226) (xy 96.157765 -291.390499) (xy 96.085387 -291.244105) (xy 96.020167 -291.094384)
			(xy 95.962257 -290.941688) (xy 95.911792 -290.786372) (xy 95.868889 -290.628799) (xy 95.83365 -290.469337)
			(xy 95.806155 -290.30836) (xy 95.78647 -290.146241) (xy 95.774641 -289.983361) (xy 95.770695 -289.8201)
			(xy 95.774641 -289.656839) (xy 95.78647 -289.493959) (xy 95.806155 -289.33184) (xy 95.83365 -289.170863)
			(xy 95.868889 -289.011401) (xy 95.911792 -288.853828) (xy 95.962257 -288.698512) (xy 96.020167 -288.545816)
			(xy 96.085387 -288.396095) (xy 96.157765 -288.249701) (xy 96.237131 -288.106974) (xy 96.323299 -287.968248)
			(xy 96.416069 -287.833848) (xy 96.515225 -287.704086) (xy 96.620534 -287.579267) (xy 96.73175 -287.459681)
			(xy 96.848614 -287.345608) (xy 96.970853 -287.237315) (xy 97.098181 -287.135053) (xy 97.230301 -287.039063)
			(xy 97.366904 -286.949568) (xy 97.507672 -286.866778) (xy 97.652275 -286.790885) (xy 97.800376 -286.722067)
			(xy 97.951629 -286.660484) (xy 98.10568 -286.606281) (xy 98.262171 -286.559584) (xy 98.420734 -286.520502)
			(xy 98.581001 -286.489127) (xy 98.742597 -286.465531) (xy 98.905143 -286.449771) (xy 99.068262 -286.441881)
			(xy 99.149916 -286.441388) (xy 99.241279 -286.442004) (xy 99.423737 -286.451882) (xy 99.605394 -286.471609)
			(xy 99.785719 -286.501126) (xy 99.875086 -286.520128) (xy 99.886516 -286.522668) (xy 99.908868 -286.517334)
			(xy 99.97948 -286.460438) (xy 99.987995 -286.452807) (xy 99.997896 -286.43223) (xy 99.99853 -286.420814)
			(xy 99.99853 -286.227774) (xy 99.998038 -286.217768) (xy 99.990375 -286.199279) (xy 99.976224 -286.185127)
			(xy 99.957736 -286.177463) (xy 99.94773 -286.176974) (xy 99.944936 -286.176974) (xy 99.942142 -286.177228)
			(xy 99.914964 -286.178752) (xy 70.804278 -286.178752) (xy 70.796085 -286.179064) (xy 70.780541 -286.184247)
			(xy 70.773798 -286.188912) (xy 70.752173 -286.204569) (xy 70.704928 -286.229427) (xy 70.654301 -286.246368)
			(xy 70.601609 -286.25495) (xy 70.548223 -286.25495) (xy 70.495531 -286.246368) (xy 70.444904 -286.229427)
			(xy 70.397659 -286.204569) (xy 70.376034 -286.188912) (xy 70.369291 -286.184253) (xy 70.353745 -286.17909)
			(xy 70.345554 -286.178752) (xy 69.854318 -286.178752) (xy 69.846123 -286.179058) (xy 69.830571 -286.184231)
			(xy 69.823838 -286.188912) (xy 69.802213 -286.204569) (xy 69.754968 -286.229427) (xy 69.704341 -286.246368)
			(xy 69.651649 -286.25495) (xy 69.598263 -286.25495) (xy 69.545571 -286.246368) (xy 69.494944 -286.229427)
			(xy 69.447699 -286.204569) (xy 69.426074 -286.188912) (xy 69.419332 -286.184248) (xy 69.403786 -286.179073)
			(xy 69.395594 -286.178752) (xy 68.904104 -286.178752) (xy 68.89591 -286.17906) (xy 68.88036 -286.184237)
			(xy 68.873624 -286.188912) (xy 68.851999 -286.204569) (xy 68.804754 -286.229427) (xy 68.754127 -286.246368)
			(xy 68.701435 -286.25495) (xy 68.648049 -286.25495) (xy 68.595357 -286.246368) (xy 68.54473 -286.229427)
			(xy 68.497485 -286.204569) (xy 68.47586 -286.188912) (xy 68.469118 -286.18425) (xy 68.453572 -286.179079)
			(xy 68.44538 -286.178752) (xy 67.954144 -286.178752) (xy 67.945947 -286.179054) (xy 67.930391 -286.184221)
			(xy 67.923664 -286.188912) (xy 67.902039 -286.204569) (xy 67.854794 -286.229427) (xy 67.804167 -286.246368)
			(xy 67.751475 -286.25495) (xy 67.698089 -286.25495) (xy 67.645397 -286.246368) (xy 67.59477 -286.229427)
			(xy 67.547525 -286.204569) (xy 67.5259 -286.188912) (xy 67.519159 -286.184244) (xy 67.503613 -286.179061)
			(xy 67.49542 -286.178752) (xy 67.004184 -286.178752) (xy 66.995991 -286.179063) (xy 66.980445 -286.184245)
			(xy 66.973704 -286.188912) (xy 66.952079 -286.204569) (xy 66.904834 -286.229427) (xy 66.854207 -286.246368)
			(xy 66.801515 -286.25495) (xy 66.748129 -286.25495) (xy 66.695437 -286.246368) (xy 66.64481 -286.229427)
			(xy 66.597565 -286.204569) (xy 66.57594 -286.188912) (xy 66.569197 -286.184252) (xy 66.553651 -286.179087)
			(xy 66.54546 -286.178752) (xy 66.054224 -286.178752) (xy 66.046029 -286.179057) (xy 66.030475 -286.184229)
			(xy 66.023744 -286.188912) (xy 66.002119 -286.204569) (xy 65.954874 -286.229427) (xy 65.904247 -286.246368)
			(xy 65.851555 -286.25495) (xy 65.798169 -286.25495) (xy 65.745477 -286.246368) (xy 65.69485 -286.229427)
			(xy 65.647605 -286.204569) (xy 65.62598 -286.188912) (xy 65.619238 -286.184247) (xy 65.603693 -286.17907)
			(xy 65.5955 -286.178752) (xy 65.104264 -286.178752) (xy 65.096072 -286.179066) (xy 65.08053 -286.184253)
			(xy 65.073784 -286.188912) (xy 65.052159 -286.204569) (xy 65.004914 -286.229427) (xy 64.954287 -286.246368)
			(xy 64.901595 -286.25495) (xy 64.848209 -286.25495) (xy 64.795517 -286.246368) (xy 64.74489 -286.229427)
			(xy 64.697645 -286.204569) (xy 64.67602 -286.188912) (xy 64.66928 -286.184242) (xy 64.653734 -286.179052)
			(xy 64.64554 -286.178752) (xy 64.154304 -286.178752) (xy 64.14611 -286.17906) (xy 64.13056 -286.184237)
			(xy 64.123824 -286.188912) (xy 64.102199 -286.204569) (xy 64.054954 -286.229427) (xy 64.004327 -286.246368)
			(xy 63.951635 -286.25495) (xy 63.898249 -286.25495) (xy 63.845557 -286.246368) (xy 63.79493 -286.229427)
			(xy 63.747685 -286.204569) (xy 63.72606 -286.188912) (xy 63.719318 -286.18425) (xy 63.703772 -286.179079)
			(xy 63.69558 -286.178752) (xy 63.204344 -286.178752) (xy 63.196147 -286.179054) (xy 63.180591 -286.184221)
			(xy 63.173864 -286.188912) (xy 63.152239 -286.204569) (xy 63.104994 -286.229427) (xy 63.054367 -286.246368)
			(xy 63.001675 -286.25495) (xy 62.948289 -286.25495) (xy 62.895597 -286.246368) (xy 62.84497 -286.229427)
			(xy 62.797725 -286.204569) (xy 62.7761 -286.188912) (xy 62.769359 -286.184244) (xy 62.753813 -286.179061)
			(xy 62.74562 -286.178752) (xy 62.25413 -286.178752) (xy 62.245934 -286.179056) (xy 62.23038 -286.184227)
			(xy 62.22365 -286.188912) (xy 62.202025 -286.204569) (xy 62.15478 -286.229427) (xy 62.104153 -286.246368)
			(xy 62.051461 -286.25495) (xy 61.998075 -286.25495) (xy 61.945383 -286.246368) (xy 61.894756 -286.229427)
			(xy 61.847511 -286.204569) (xy 61.825886 -286.188912) (xy 61.819145 -286.184246) (xy 61.803599 -286.179067)
			(xy 61.795406 -286.178752) (xy 61.30417 -286.178752) (xy 61.295978 -286.179065) (xy 61.280434 -286.18425)
			(xy 61.27369 -286.188912) (xy 61.252065 -286.204569) (xy 61.20482 -286.229427) (xy 61.154193 -286.246368)
			(xy 61.101501 -286.25495) (xy 61.048115 -286.25495) (xy 60.995423 -286.246368) (xy 60.944796 -286.229427)
			(xy 60.897551 -286.204569) (xy 60.875926 -286.188912) (xy 60.869186 -286.184241) (xy 60.85364 -286.17905)
			(xy 60.845446 -286.178752) (xy 60.35421 -286.178752) (xy 60.346015 -286.179059) (xy 60.330465 -286.184234)
			(xy 60.32373 -286.188912) (xy 60.302105 -286.204569) (xy 60.25486 -286.229427) (xy 60.204233 -286.246368)
			(xy 60.151541 -286.25495) (xy 60.098155 -286.25495) (xy 60.045463 -286.246368) (xy 59.994836 -286.229427)
			(xy 59.947591 -286.204569) (xy 59.925966 -286.188912) (xy 59.919224 -286.184249) (xy 59.903678 -286.179076)
			(xy 59.895486 -286.178752) (xy 58.45429 -286.178752) (xy 58.446096 -286.179062) (xy 58.43055 -286.184242)
			(xy 58.42381 -286.188912) (xy 58.402185 -286.204569) (xy 58.35494 -286.229427) (xy 58.304313 -286.246368)
			(xy 58.251621 -286.25495) (xy 58.198235 -286.25495) (xy 58.145543 -286.246368) (xy 58.094916 -286.229427)
			(xy 58.047671 -286.204569) (xy 58.026046 -286.188912) (xy 58.019303 -286.184252) (xy 58.003757 -286.179085)
			(xy 57.995566 -286.178752) (xy 57.50433 -286.178752) (xy 57.496134 -286.179056) (xy 57.48058 -286.184227)
			(xy 57.47385 -286.188912) (xy 57.452225 -286.204569) (xy 57.40498 -286.229427) (xy 57.354353 -286.246368)
			(xy 57.301661 -286.25495) (xy 57.248275 -286.25495) (xy 57.195583 -286.246368) (xy 57.144956 -286.229427)
			(xy 57.097711 -286.204569) (xy 57.076086 -286.188912) (xy 57.069345 -286.184246) (xy 57.053799 -286.179067)
			(xy 57.045606 -286.178752) (xy 56.554116 -286.178752) (xy 56.545921 -286.179058) (xy 56.530369 -286.184232)
			(xy 56.523636 -286.188912) (xy 56.502011 -286.204569) (xy 56.454766 -286.229427) (xy 56.404139 -286.246368)
			(xy 56.351447 -286.25495) (xy 56.298061 -286.25495) (xy 56.245369 -286.246368) (xy 56.194742 -286.229427)
			(xy 56.147497 -286.204569) (xy 56.125872 -286.188912) (xy 56.11913 -286.184248) (xy 56.103584 -286.179073)
			(xy 56.095392 -286.178752) (xy 55.604156 -286.178752) (xy 55.595964 -286.179067) (xy 55.580424 -286.184256)
			(xy 55.573676 -286.188912) (xy 55.552051 -286.204569) (xy 55.504806 -286.229427) (xy 55.454179 -286.246368)
			(xy 55.401487 -286.25495) (xy 55.348101 -286.25495) (xy 55.295409 -286.246368) (xy 55.244782 -286.229427)
			(xy 55.197537 -286.204569) (xy 55.175912 -286.188912) (xy 55.169171 -286.184243) (xy 55.153626 -286.179056)
			(xy 55.145432 -286.178752) (xy 54.654196 -286.178752) (xy 54.646002 -286.179061) (xy 54.630454 -286.18424)
			(xy 54.623716 -286.188912) (xy 54.602091 -286.204569) (xy 54.554846 -286.229427) (xy 54.504219 -286.246368)
			(xy 54.451527 -286.25495) (xy 54.398141 -286.25495) (xy 54.345449 -286.246368) (xy 54.294822 -286.229427)
			(xy 54.247577 -286.204569) (xy 54.225952 -286.188912) (xy 54.219209 -286.184251) (xy 54.203663 -286.179082)
			(xy 54.195472 -286.178752) (xy 53.704236 -286.178752) (xy 53.69604 -286.179055) (xy 53.680485 -286.184224)
			(xy 53.673756 -286.188912) (xy 53.652131 -286.204569) (xy 53.604886 -286.229427) (xy 53.554259 -286.246368)
			(xy 53.501567 -286.25495) (xy 53.448181 -286.25495) (xy 53.395489 -286.246368) (xy 53.344862 -286.229427)
			(xy 53.297617 -286.204569) (xy 53.275992 -286.188912) (xy 53.269251 -286.184245) (xy 53.253705 -286.179065)
			(xy 53.245512 -286.178752) (xy 52.754276 -286.178752) (xy 52.746083 -286.179064) (xy 52.730539 -286.184248)
			(xy 52.723796 -286.188912) (xy 52.702171 -286.204569) (xy 52.654926 -286.229427) (xy 52.604299 -286.246368)
			(xy 52.551607 -286.25495) (xy 52.498221 -286.25495) (xy 52.445529 -286.246368) (xy 52.394902 -286.229427)
			(xy 52.347657 -286.204569) (xy 52.326032 -286.188912) (xy 52.319289 -286.184253) (xy 52.303743 -286.179091)
			(xy 52.295552 -286.178752) (xy 51.804316 -286.178752) (xy 51.796121 -286.179058) (xy 51.780569 -286.184232)
			(xy 51.773836 -286.188912) (xy 51.752211 -286.204569) (xy 51.704966 -286.229427) (xy 51.654339 -286.246368)
			(xy 51.601647 -286.25495) (xy 51.548261 -286.25495) (xy 51.495569 -286.246368) (xy 51.444942 -286.229427)
			(xy 51.397697 -286.204569) (xy 51.376072 -286.188912) (xy 51.36933 -286.184248) (xy 51.353784 -286.179073)
			(xy 51.345592 -286.178752) (xy 50.854356 -286.178752) (xy 50.846164 -286.179067) (xy 50.830624 -286.184256)
			(xy 50.823876 -286.188912) (xy 50.802251 -286.204569) (xy 50.755006 -286.229427) (xy 50.704379 -286.246368)
			(xy 50.651687 -286.25495) (xy 50.598301 -286.25495) (xy 50.545609 -286.246368) (xy 50.494982 -286.229427)
			(xy 50.447737 -286.204569) (xy 50.426112 -286.188912) (xy 50.419371 -286.184243) (xy 50.403826 -286.179056)
			(xy 50.395632 -286.178752) (xy 49.904142 -286.178752) (xy 49.895946 -286.179054) (xy 49.880389 -286.184222)
			(xy 49.873662 -286.188912) (xy 49.852037 -286.204569) (xy 49.804792 -286.229427) (xy 49.754165 -286.246368)
			(xy 49.701473 -286.25495) (xy 49.648087 -286.25495) (xy 49.595395 -286.246368) (xy 49.544768 -286.229427)
			(xy 49.497523 -286.204569) (xy 49.475898 -286.188912) (xy 49.469157 -286.184245) (xy 49.453611 -286.179062)
			(xy 49.445418 -286.178752) (xy 48.954182 -286.178752) (xy 48.945989 -286.179063) (xy 48.930444 -286.184246)
			(xy 48.923702 -286.188912) (xy 48.902077 -286.204569) (xy 48.854832 -286.229427) (xy 48.804205 -286.246368)
			(xy 48.751513 -286.25495) (xy 48.698127 -286.25495) (xy 48.645435 -286.246368) (xy 48.594808 -286.229427)
			(xy 48.547563 -286.204569) (xy 48.525938 -286.188912) (xy 48.519195 -286.184253) (xy 48.503649 -286.179088)
			(xy 48.495458 -286.178752) (xy 48.004222 -286.178752) (xy 47.996027 -286.179057) (xy 47.980474 -286.18423)
			(xy 47.973742 -286.188912) (xy 47.952117 -286.204569) (xy 47.904872 -286.229427) (xy 47.854245 -286.246368)
			(xy 47.801553 -286.25495) (xy 47.748167 -286.25495) (xy 47.695475 -286.246368) (xy 47.644848 -286.229427)
			(xy 47.597603 -286.204569) (xy 47.575978 -286.188912) (xy 47.569236 -286.184247) (xy 47.55369 -286.179071)
			(xy 47.545498 -286.178752) (xy 47.054262 -286.178752) (xy 47.04607 -286.179066) (xy 47.030528 -286.184254)
			(xy 47.023782 -286.188912) (xy 47.002157 -286.204569) (xy 46.954912 -286.229427) (xy 46.904285 -286.246368)
			(xy 46.851593 -286.25495) (xy 46.798207 -286.25495) (xy 46.745515 -286.246368) (xy 46.694888 -286.229427)
			(xy 46.647643 -286.204569) (xy 46.626018 -286.188912) (xy 46.619278 -286.184242) (xy 46.603732 -286.179053)
			(xy 46.595538 -286.178752) (xy 46.104302 -286.178752) (xy 46.096108 -286.17906) (xy 46.080559 -286.184238)
			(xy 46.073822 -286.188912) (xy 46.052197 -286.204569) (xy 46.004952 -286.229427) (xy 45.954325 -286.246368)
			(xy 45.901633 -286.25495) (xy 45.848247 -286.25495) (xy 45.795555 -286.246368) (xy 45.744928 -286.229427)
			(xy 45.697683 -286.204569) (xy 45.676058 -286.188912) (xy 45.669316 -286.18425) (xy 45.65377 -286.17908)
			(xy 45.645578 -286.178752) (xy 45.154342 -286.178752) (xy 45.146146 -286.179054) (xy 45.130589 -286.184222)
			(xy 45.123862 -286.188912) (xy 45.102237 -286.204569) (xy 45.054992 -286.229427) (xy 45.004365 -286.246368)
			(xy 44.951673 -286.25495) (xy 44.898287 -286.25495) (xy 44.845595 -286.246368) (xy 44.794968 -286.229427)
			(xy 44.747723 -286.204569) (xy 44.726098 -286.188912) (xy 44.719357 -286.184245) (xy 44.703811 -286.179062)
			(xy 44.695618 -286.178752) (xy 41.354248 -286.178752) (xy 41.346051 -286.179053) (xy 41.330494 -286.184219)
			(xy 41.323768 -286.188912) (xy 41.302143 -286.204569) (xy 41.254898 -286.229427) (xy 41.204271 -286.246368)
			(xy 41.151579 -286.25495) (xy 41.098193 -286.25495) (xy 41.045501 -286.246368) (xy 40.994874 -286.229427)
			(xy 40.947629 -286.204569) (xy 40.926004 -286.188912) (xy 40.919263 -286.184244) (xy 40.903718 -286.179059)
			(xy 40.895524 -286.178752) (xy 40.404288 -286.178752) (xy 40.396095 -286.179062) (xy 40.380548 -286.184243)
			(xy 40.373808 -286.188912) (xy 40.352183 -286.204569) (xy 40.304938 -286.229427) (xy 40.254311 -286.246368)
			(xy 40.201619 -286.25495) (xy 40.148233 -286.25495) (xy 40.095541 -286.246368) (xy 40.044914 -286.229427)
			(xy 39.997669 -286.204569) (xy 39.976044 -286.188912) (xy 39.969301 -286.184252) (xy 39.953755 -286.179086)
			(xy 39.945564 -286.178752) (xy 39.454328 -286.178752) (xy 39.446132 -286.179056) (xy 39.430578 -286.184227)
			(xy 39.423848 -286.188912) (xy 39.402223 -286.204569) (xy 39.354978 -286.229427) (xy 39.304351 -286.246368)
			(xy 39.251659 -286.25495) (xy 39.198273 -286.25495) (xy 39.145581 -286.246368) (xy 39.094954 -286.229427)
			(xy 39.047709 -286.204569) (xy 39.026084 -286.188912) (xy 39.019342 -286.184246) (xy 39.003797 -286.179068)
			(xy 38.995604 -286.178752) (xy 38.504368 -286.178752) (xy 38.496176 -286.179065) (xy 38.480633 -286.184251)
			(xy 38.473888 -286.188912) (xy 38.452263 -286.204569) (xy 38.405018 -286.229427) (xy 38.354391 -286.246368)
			(xy 38.301699 -286.25495) (xy 38.248313 -286.25495) (xy 38.195621 -286.246368) (xy 38.144994 -286.229427)
			(xy 38.097749 -286.204569) (xy 38.076124 -286.188912) (xy 38.069384 -286.184241) (xy 38.053838 -286.179051)
			(xy 38.045644 -286.178752) (xy 37.554154 -286.178752) (xy 37.545962 -286.179067) (xy 37.530422 -286.184257)
			(xy 37.523674 -286.188912) (xy 37.502049 -286.204569) (xy 37.454804 -286.229427) (xy 37.404177 -286.246368)
			(xy 37.351485 -286.25495) (xy 37.298099 -286.25495) (xy 37.245407 -286.246368) (xy 37.19478 -286.229427)
			(xy 37.147535 -286.204569) (xy 37.12591 -286.188912) (xy 37.119169 -286.184243) (xy 37.103624 -286.179057)
			(xy 37.09543 -286.178752) (xy 36.799012 -286.178752) (xy 36.788942 -286.179174) (xy 36.770339 -286.186892)
			(xy 36.762944 -286.193738) (xy 36.707064 -286.249618) (xy 36.700214 -286.257015) (xy 36.692476 -286.275613)
			(xy 36.692078 -286.285686) (xy 36.692078 -286.78124) (xy 36.693856 -286.787844) (xy 36.700989 -286.816382)
			(xy 36.706214 -286.874967) (xy 36.701001 -286.933553) (xy 36.693856 -286.962088) (xy 36.692078 -286.968692)
			(xy 36.692078 -287.7312) (xy 36.693856 -287.737804) (xy 36.700984 -287.766342) (xy 36.706199 -287.824925)
			(xy 36.703927 -287.850408) (xy 37.944539 -287.850408) (xy 37.944539 -287.798392) (xy 37.952677 -287.747016)
			(xy 37.968751 -287.697546) (xy 37.992366 -287.651199) (xy 38.02294 -287.609117) (xy 38.059722 -287.572337)
			(xy 38.101804 -287.541763) (xy 38.148151 -287.518148) (xy 38.197622 -287.502075) (xy 38.248998 -287.493939)
			(xy 38.275006 -287.493456) (xy 39.224966 -287.493456) (xy 39.250978 -287.493901) (xy 39.302363 -287.502035)
			(xy 39.351843 -287.518107) (xy 39.398199 -287.541722) (xy 39.44029 -287.572299) (xy 39.477079 -287.609084)
			(xy 39.50766 -287.651172) (xy 39.53128 -287.697525) (xy 39.547357 -287.747004) (xy 39.555496 -287.798388)
			(xy 39.555496 -287.850405) (xy 40.794466 -287.850405) (xy 40.794466 -287.798395) (xy 40.802602 -287.747025)
			(xy 40.818674 -287.697561) (xy 40.842285 -287.651219) (xy 40.872855 -287.609142) (xy 40.909631 -287.572364)
			(xy 40.951707 -287.541792) (xy 40.998048 -287.518179) (xy 41.047512 -287.502105) (xy 41.098881 -287.493967)
			(xy 41.124886 -287.493456) (xy 42.074846 -287.493456) (xy 42.100852 -287.493934) (xy 42.152223 -287.502077)
			(xy 42.201688 -287.518155) (xy 42.248029 -287.541773) (xy 42.290106 -287.572348) (xy 42.326882 -287.609129)
			(xy 42.357451 -287.65121) (xy 42.381063 -287.697554) (xy 42.397134 -287.747022) (xy 42.40527 -287.798394)
			(xy 42.40527 -287.850406) (xy 42.397134 -287.901778) (xy 42.381063 -287.951246) (xy 42.357451 -287.99759)
			(xy 42.326882 -288.039671) (xy 42.290106 -288.076452) (xy 42.248029 -288.107027) (xy 42.201688 -288.130645)
			(xy 42.152223 -288.146723) (xy 42.100852 -288.154866) (xy 42.074846 -288.15538) (xy 41.124886 -288.15538)
			(xy 41.098881 -288.154833) (xy 41.047512 -288.146695) (xy 40.998048 -288.130621) (xy 40.951707 -288.107008)
			(xy 40.909631 -288.076436) (xy 40.872855 -288.039658) (xy 40.842285 -287.997581) (xy 40.818674 -287.951239)
			(xy 40.802602 -287.901775) (xy 40.794466 -287.850405) (xy 39.555496 -287.850405) (xy 39.555496 -287.850412)
			(xy 39.547357 -287.901796) (xy 39.53128 -287.951275) (xy 39.50766 -287.997628) (xy 39.477079 -288.039716)
			(xy 39.44029 -288.076501) (xy 39.398199 -288.107078) (xy 39.351843 -288.130693) (xy 39.302363 -288.146765)
			(xy 39.250978 -288.154899) (xy 39.224966 -288.15538) (xy 38.275006 -288.15538) (xy 38.248998 -288.154861)
			(xy 38.197622 -288.146725) (xy 38.148151 -288.130652) (xy 38.101804 -288.107037) (xy 38.059722 -288.076463)
			(xy 38.02294 -288.039683) (xy 37.992366 -287.997601) (xy 37.968751 -287.951254) (xy 37.952677 -287.901784)
			(xy 37.944539 -287.850408) (xy 36.703927 -287.850408) (xy 36.700975 -287.883508) (xy 36.693856 -287.912048)
			(xy 36.692078 -287.918652) (xy 36.692078 -288.392616) (xy 36.692568 -288.402623) (xy 36.70023 -288.421113)
			(xy 36.714382 -288.435267) (xy 36.732871 -288.442931) (xy 36.742878 -288.443416) (xy 37.324792 -288.443416)
			(xy 37.350803 -288.443899) (xy 37.402186 -288.452036) (xy 37.451663 -288.468111) (xy 37.498016 -288.491728)
			(xy 37.540103 -288.522305) (xy 37.576889 -288.559091) (xy 37.607468 -288.601178) (xy 37.631086 -288.64753)
			(xy 37.647162 -288.697006) (xy 37.6553 -288.748389) (xy 37.6553 -288.800411) (xy 42.694299 -288.800411)
			(xy 42.694299 -288.748389) (xy 42.702438 -288.697007) (xy 42.718514 -288.64753) (xy 42.742132 -288.601178)
			(xy 42.77271 -288.559091) (xy 42.809496 -288.522306) (xy 42.851583 -288.491729) (xy 42.897936 -288.468111)
			(xy 42.947413 -288.452036) (xy 42.998795 -288.443899) (xy 43.024806 -288.443416) (xy 43.974766 -288.443416)
			(xy 44.000775 -288.443941) (xy 44.052154 -288.452074) (xy 44.101628 -288.468144) (xy 44.147978 -288.491757)
			(xy 44.190064 -288.52233) (xy 44.226848 -288.55911) (xy 44.257426 -288.601193) (xy 44.281043 -288.647541)
			(xy 44.297119 -288.697013) (xy 44.305257 -288.748391) (xy 44.305257 -288.800409) (xy 44.297119 -288.851787)
			(xy 44.281043 -288.901259) (xy 44.257426 -288.947607) (xy 44.226848 -288.98969) (xy 44.190064 -289.02647)
			(xy 44.147978 -289.057043) (xy 44.101628 -289.080656) (xy 44.052154 -289.096726) (xy 44.000775 -289.104859)
			(xy 43.974766 -289.10534) (xy 43.024806 -289.10534) (xy 42.998795 -289.104901) (xy 42.947413 -289.096764)
			(xy 42.897936 -289.080689) (xy 42.851583 -289.057071) (xy 42.809496 -289.026494) (xy 42.77271 -288.989709)
			(xy 42.742132 -288.947622) (xy 42.718514 -288.90127) (xy 42.702438 -288.851793) (xy 42.694299 -288.800411)
			(xy 37.6553 -288.800411) (xy 37.647162 -288.851794) (xy 37.631086 -288.90127) (xy 37.607468 -288.947622)
			(xy 37.576889 -288.989709) (xy 37.540103 -289.026495) (xy 37.498016 -289.057072) (xy 37.451663 -289.080689)
			(xy 37.402186 -289.096764) (xy 37.350803 -289.104901) (xy 37.324792 -289.10534) (xy 36.742878 -289.10534)
			(xy 36.732863 -289.105764) (xy 36.71436 -289.113439) (xy 36.700205 -289.127612) (xy 36.692552 -289.146124)
			(xy 36.692078 -289.15614) (xy 36.692078 -289.63112) (xy 36.693856 -289.637724) (xy 36.700982 -289.666262)
			(xy 36.706193 -289.724844) (xy 36.700967 -289.783426) (xy 36.693856 -289.811968) (xy 36.692078 -289.818572)
			(xy 36.692078 -290.58108) (xy 36.693856 -290.587684) (xy 36.700986 -290.616222) (xy 36.706204 -290.674806)
			(xy 36.700984 -290.73339) (xy 36.693856 -290.761928) (xy 36.692078 -290.768532) (xy 36.692078 -291.53104)
			(xy 36.693856 -291.537644) (xy 36.700989 -291.566182) (xy 36.706214 -291.624767) (xy 36.701001 -291.683353)
			(xy 36.693856 -291.711888) (xy 36.692078 -291.718492) (xy 36.692078 -292.481254) (xy 36.693856 -292.487858)
			(xy 36.700988 -292.516396) (xy 36.706211 -292.574981) (xy 36.700995 -292.633566) (xy 36.693856 -292.662102)
			(xy 36.692078 -292.668706) (xy 36.692078 -294.381174) (xy 36.693856 -294.387778) (xy 36.700986 -294.416316)
			(xy 36.706206 -294.4749) (xy 36.700986 -294.533484) (xy 36.693856 -294.562022) (xy 36.692078 -294.568626)
			(xy 36.692078 -296.943272) (xy 36.692493 -296.953299) (xy 36.700157 -296.971829) (xy 36.714329 -296.986015)
			(xy 36.732852 -296.993698) (xy 36.742878 -296.994072) (xy 37.324538 -296.994072) (xy 37.350525 -296.994584)
			(xy 37.401858 -297.00272) (xy 37.451286 -297.018786) (xy 37.497593 -297.042385) (xy 37.539639 -297.072937)
			(xy 37.576388 -297.10969) (xy 37.606935 -297.151739) (xy 37.630529 -297.198049) (xy 37.646589 -297.247479)
			(xy 37.654719 -297.298813) (xy 37.654719 -297.350787) (xy 37.646589 -297.402121) (xy 37.630529 -297.451551)
			(xy 37.606935 -297.497861) (xy 37.576388 -297.53991) (xy 37.539639 -297.576663) (xy 37.497593 -297.607215)
			(xy 37.451286 -297.630814) (xy 37.401858 -297.64688) (xy 37.350525 -297.655016) (xy 37.324538 -297.655488)
			(xy 36.742878 -297.655488) (xy 36.732872 -297.65598) (xy 36.714386 -297.663643) (xy 36.700237 -297.677795)
			(xy 36.692578 -297.696282) (xy 36.692078 -297.706288) (xy 36.692078 -298.77569) (xy 39.369695 -298.77569)
			(xy 39.369695 -298.72371) (xy 39.377827 -298.67237) (xy 39.393891 -298.622935) (xy 39.417492 -298.576621)
			(xy 39.448047 -298.53457) (xy 39.484805 -298.497817) (xy 39.52686 -298.467268) (xy 39.573177 -298.443674)
			(xy 39.622615 -298.427617) (xy 39.673956 -298.419492) (xy 39.699946 -298.419012) (xy 40.649906 -298.419012)
			(xy 40.675894 -298.419482) (xy 40.727231 -298.427614) (xy 40.776664 -298.443676) (xy 40.822975 -298.467274)
			(xy 40.865025 -298.497826) (xy 40.901778 -298.534579) (xy 40.932329 -298.57663) (xy 40.955926 -298.622942)
			(xy 40.971988 -298.672375) (xy 40.980118 -298.723712) (xy 40.980118 -298.775688) (xy 40.971988 -298.827025)
			(xy 40.955926 -298.876458) (xy 40.932329 -298.92277) (xy 40.901778 -298.964821) (xy 40.865025 -299.001574)
			(xy 40.822975 -299.032126) (xy 40.776664 -299.055724) (xy 40.727231 -299.071786) (xy 40.675894 -299.079918)
			(xy 40.649906 -299.080428) (xy 39.699946 -299.080428) (xy 39.673956 -299.079908) (xy 39.622615 -299.071783)
			(xy 39.573177 -299.055726) (xy 39.52686 -299.032132) (xy 39.484805 -299.001583) (xy 39.448047 -298.96483)
			(xy 39.417492 -298.922779) (xy 39.393891 -298.876465) (xy 39.377827 -298.82703) (xy 39.369695 -298.77569)
			(xy 36.692078 -298.77569) (xy 36.692078 -298.843192) (xy 36.692564 -298.853202) (xy 36.700222 -298.871701)
			(xy 36.714374 -298.885862) (xy 36.732868 -298.89353) (xy 36.742878 -298.893992) (xy 37.324538 -298.893992)
			(xy 37.350547 -298.894505) (xy 37.401923 -298.902647) (xy 37.451394 -298.918726) (xy 37.49774 -298.942346)
			(xy 37.539821 -298.972924) (xy 37.576601 -299.009708) (xy 37.607174 -299.051793) (xy 37.630788 -299.098142)
			(xy 37.646861 -299.147614) (xy 37.654998 -299.198991) (xy 37.654998 -299.251009) (xy 37.646861 -299.302386)
			(xy 37.630788 -299.351858) (xy 37.607174 -299.398207) (xy 37.576601 -299.440292) (xy 37.539821 -299.477076)
			(xy 37.49774 -299.507654) (xy 37.451394 -299.531274) (xy 37.401923 -299.547353) (xy 37.350547 -299.555495)
			(xy 37.324538 -299.555916) (xy 36.742878 -299.555916) (xy 36.732874 -299.556408) (xy 36.714393 -299.564072)
			(xy 36.700251 -299.578225) (xy 36.692601 -299.596712) (xy 36.692078 -299.606716) (xy 36.692078 -320.900044)
			(xy 84.898745 -320.900044) (xy 84.902751 -320.704989) (xy 84.914761 -320.510263) (xy 84.934756 -320.316194)
			(xy 84.962701 -320.12311) (xy 84.99855 -319.931335) (xy 85.042242 -319.741195) (xy 85.093703 -319.553008)
			(xy 85.152847 -319.367093) (xy 85.219574 -319.183762) (xy 85.293771 -319.003326) (xy 85.375313 -318.826088)
			(xy 85.464064 -318.652347) (xy 85.559872 -318.482396) (xy 85.662577 -318.316522) (xy 85.772005 -318.155004)
			(xy 85.887972 -317.998115) (xy 86.010283 -317.84612) (xy 86.13873 -317.699274) (xy 86.273098 -317.557825)
			(xy 86.41316 -317.422012) (xy 86.558679 -317.292063) (xy 86.709411 -317.168199) (xy 86.865101 -317.050627)
			(xy 87.025487 -316.939547) (xy 87.190298 -316.835144) (xy 87.359256 -316.737596) (xy 87.532077 -316.647067)
			(xy 87.708469 -316.563709) (xy 87.888134 -316.487663) (xy 88.070769 -316.419058) (xy 88.256068 -316.358008)
			(xy 88.443716 -316.304618) (xy 88.633398 -316.258976) (xy 88.824795 -316.22116) (xy 89.017582 -316.191234)
			(xy 89.211435 -316.169248) (xy 89.406028 -316.155239) (xy 89.601031 -316.149231) (xy 89.796117 -316.151234)
			(xy 89.990956 -316.161245) (xy 90.18522 -316.179246) (xy 90.378581 -316.205208) (xy 90.570714 -316.239086)
			(xy 90.761293 -316.280823) (xy 90.949998 -316.33035) (xy 91.136511 -316.387582) (xy 91.320517 -316.452423)
			(xy 91.501705 -316.524764) (xy 91.679771 -316.604482) (xy 91.854414 -316.691444) (xy 92.02534 -316.785503)
			(xy 92.192259 -316.886499) (xy 92.354892 -316.994264) (xy 92.512963 -317.108614) (xy 92.666206 -317.229357)
			(xy 92.814363 -317.356291) (xy 92.957184 -317.489199) (xy 93.094428 -317.627859) (xy 93.225864 -317.772037)
			(xy 93.351269 -317.92149) (xy 93.470433 -318.075964) (xy 93.583154 -318.235201) (xy 93.689243 -318.398932)
			(xy 93.788521 -318.566879) (xy 93.880819 -318.738762) (xy 93.965984 -318.914288) (xy 94.04387 -319.093163)
			(xy 94.114347 -319.275085) (xy 94.177295 -319.459747) (xy 94.23261 -319.646837) (xy 94.280196 -319.836041)
			(xy 94.319975 -320.027038) (xy 94.351879 -320.219508) (xy 94.375854 -320.413126) (xy 94.39186 -320.607564)
			(xy 94.399869 -320.802496) (xy 94.40037 -320.900044) (xy 94.399869 -320.997592) (xy 94.39186 -321.192524)
			(xy 94.375854 -321.386962) (xy 94.351879 -321.58058) (xy 94.319975 -321.77305) (xy 94.280196 -321.964047)
			(xy 94.23261 -322.153251) (xy 94.177295 -322.340341) (xy 94.114347 -322.525003) (xy 94.04387 -322.706925)
			(xy 93.965984 -322.8858) (xy 93.880819 -323.061326) (xy 93.788521 -323.233209) (xy 93.689243 -323.401156)
			(xy 93.583154 -323.564887) (xy 93.470433 -323.724124) (xy 93.351269 -323.878598) (xy 93.225864 -324.028051)
			(xy 93.094428 -324.172229) (xy 92.957184 -324.310889) (xy 92.814363 -324.443797) (xy 92.666206 -324.570731)
			(xy 92.512963 -324.691474) (xy 92.354892 -324.805824) (xy 92.192259 -324.913589) (xy 92.02534 -325.014585)
			(xy 91.854414 -325.108644) (xy 91.679771 -325.195606) (xy 91.501705 -325.275324) (xy 91.320517 -325.347665)
			(xy 91.136511 -325.412506) (xy 90.949998 -325.469738) (xy 90.761293 -325.519265) (xy 90.570714 -325.561002)
			(xy 90.378581 -325.59488) (xy 90.18522 -325.620842) (xy 89.990956 -325.638843) (xy 89.796117 -325.648854)
			(xy 89.601031 -325.650857) (xy 89.406028 -325.644849) (xy 89.211435 -325.63084) (xy 89.017582 -325.608854)
			(xy 88.824795 -325.578928) (xy 88.633398 -325.541112) (xy 88.443716 -325.49547) (xy 88.256068 -325.44208)
			(xy 88.070769 -325.38103) (xy 87.888134 -325.312425) (xy 87.708469 -325.236379) (xy 87.532077 -325.153021)
			(xy 87.359256 -325.062492) (xy 87.190298 -324.964944) (xy 87.025487 -324.860541) (xy 86.865101 -324.749461)
			(xy 86.709411 -324.631889) (xy 86.558679 -324.508025) (xy 86.41316 -324.378076) (xy 86.273098 -324.242263)
			(xy 86.13873 -324.100814) (xy 86.010283 -323.953968) (xy 85.887972 -323.801973) (xy 85.772005 -323.645084)
			(xy 85.662577 -323.483566) (xy 85.559872 -323.317692) (xy 85.464064 -323.147741) (xy 85.375313 -322.974)
			(xy 85.293771 -322.796762) (xy 85.219574 -322.616326) (xy 85.152847 -322.432995) (xy 85.093703 -322.24708)
			(xy 85.042242 -322.058893) (xy 84.99855 -321.868753) (xy 84.962701 -321.676978) (xy 84.934756 -321.483894)
			(xy 84.914761 -321.289825) (xy 84.902751 -321.095099) (xy 84.898745 -320.900044) (xy 36.692078 -320.900044)
			(xy 36.692078 -330.416662) (xy 97.355152 -330.416662) (xy 97.355152 -329.553062) (xy 97.355642 -329.523078)
			(xy 97.36347 -329.463622) (xy 97.378991 -329.405697) (xy 97.40194 -329.350293) (xy 97.431924 -329.298359)
			(xy 97.46843 -329.250783) (xy 97.510835 -329.208378) (xy 97.558411 -329.171872) (xy 97.610345 -329.141888)
			(xy 97.665749 -329.118939) (xy 97.723674 -329.103418) (xy 97.78313 -329.09559) (xy 97.843098 -329.09559)
			(xy 97.902554 -329.103418) (xy 97.960479 -329.118939) (xy 98.015883 -329.141888) (xy 98.067817 -329.171872)
			(xy 98.115393 -329.208378) (xy 98.157798 -329.250783) (xy 98.194304 -329.298359) (xy 98.224288 -329.350293)
			(xy 98.247237 -329.405697) (xy 98.262758 -329.463622) (xy 98.270586 -329.523078) (xy 98.271076 -329.553062)
			(xy 98.271076 -330.416662) (xy 98.270586 -330.446646) (xy 98.262758 -330.506102) (xy 98.247237 -330.564027)
			(xy 98.224288 -330.619431) (xy 98.194304 -330.671365) (xy 98.157798 -330.718941) (xy 98.115393 -330.761346)
			(xy 98.067817 -330.797852) (xy 98.015883 -330.827836) (xy 97.960479 -330.850785) (xy 97.902554 -330.866306)
			(xy 97.843098 -330.874134) (xy 97.78313 -330.874134) (xy 97.723674 -330.866306) (xy 97.665749 -330.850785)
			(xy 97.610345 -330.827836) (xy 97.558411 -330.797852) (xy 97.510835 -330.761346) (xy 97.46843 -330.718941)
			(xy 97.431924 -330.671365) (xy 97.40194 -330.619431) (xy 97.378991 -330.564027) (xy 97.36347 -330.506102)
			(xy 97.355642 -330.446646) (xy 97.355152 -330.416662) (xy 36.692078 -330.416662) (xy 36.692078 -331.53223)
			(xy 114.955828 -331.53223) (xy 114.955828 -330.66863) (xy 114.956318 -330.638646) (xy 114.964146 -330.57919)
			(xy 114.979667 -330.521265) (xy 115.002616 -330.465861) (xy 115.0326 -330.413927) (xy 115.069106 -330.366351)
			(xy 115.111511 -330.323946) (xy 115.159087 -330.28744) (xy 115.211021 -330.257456) (xy 115.266425 -330.234507)
			(xy 115.32435 -330.218986) (xy 115.383806 -330.211158) (xy 115.443774 -330.211158) (xy 115.50323 -330.218986)
			(xy 115.561155 -330.234507) (xy 115.616559 -330.257456) (xy 115.668493 -330.28744) (xy 115.716069 -330.323946)
			(xy 115.758474 -330.366351) (xy 115.79498 -330.413927) (xy 115.824964 -330.465861) (xy 115.847913 -330.521265)
			(xy 115.863434 -330.57919) (xy 115.871262 -330.638646) (xy 115.871752 -330.66863) (xy 115.871752 -331.53223)
			(xy 115.871262 -331.562214) (xy 115.863434 -331.62167) (xy 115.847913 -331.679595) (xy 115.824964 -331.734999)
			(xy 115.79498 -331.786933) (xy 115.758474 -331.834509) (xy 115.716069 -331.876914) (xy 115.668493 -331.91342)
			(xy 115.616559 -331.943404) (xy 115.561155 -331.966353) (xy 115.50323 -331.981874) (xy 115.443774 -331.989702)
			(xy 115.383806 -331.989702) (xy 115.32435 -331.981874) (xy 115.266425 -331.966353) (xy 115.211021 -331.943404)
			(xy 115.159087 -331.91342) (xy 115.111511 -331.876914) (xy 115.069106 -331.834509) (xy 115.0326 -331.786933)
			(xy 115.002616 -331.734999) (xy 114.979667 -331.679595) (xy 114.964146 -331.62167) (xy 114.956318 -331.562214)
			(xy 114.955828 -331.53223) (xy 36.692078 -331.53223) (xy 36.692078 -333.950056) (xy 93.5736 -333.950056)
			(xy 93.5736 -333.086456) (xy 93.57409 -333.056488) (xy 93.581913 -332.997066) (xy 93.597426 -332.939173)
			(xy 93.620362 -332.8838) (xy 93.650329 -332.831894) (xy 93.686816 -332.784344) (xy 93.729196 -332.741964)
			(xy 93.776746 -332.705477) (xy 93.828652 -332.67551) (xy 93.884025 -332.652574) (xy 93.941918 -332.637061)
			(xy 94.00134 -332.629238) (xy 94.061276 -332.629238) (xy 94.120698 -332.637061) (xy 94.178591 -332.652574)
			(xy 94.233964 -332.67551) (xy 94.28587 -332.705477) (xy 94.33342 -332.741964) (xy 94.3758 -332.784344)
			(xy 94.412287 -332.831894) (xy 94.442254 -332.8838) (xy 94.46519 -332.939173) (xy 94.480703 -332.997066)
			(xy 94.488526 -333.056488) (xy 94.489016 -333.086456) (xy 94.489016 -333.950056) (xy 94.488526 -333.980024)
			(xy 94.480703 -334.039446) (xy 94.46519 -334.097339) (xy 94.442254 -334.152712) (xy 94.412287 -334.204618)
			(xy 94.3758 -334.252168) (xy 94.33342 -334.294548) (xy 94.28587 -334.331035) (xy 94.233964 -334.361002)
			(xy 94.178591 -334.383938) (xy 94.120698 -334.399451) (xy 94.061276 -334.407274) (xy 94.00134 -334.407274)
			(xy 93.941918 -334.399451) (xy 93.884025 -334.383938) (xy 93.828652 -334.361002) (xy 93.776746 -334.331035)
			(xy 93.729196 -334.294548) (xy 93.686816 -334.252168) (xy 93.650329 -334.204618) (xy 93.620362 -334.152712)
			(xy 93.597426 -334.097339) (xy 93.581913 -334.039446) (xy 93.57409 -333.980024) (xy 93.5736 -333.950056)
			(xy 36.692078 -333.950056) (xy 36.692078 -337.464908) (xy 36.692502 -337.474978) (xy 36.700216 -337.493583)
			(xy 36.707064 -337.500976) (xy 37.04844 -337.842352) (xy 37.055838 -337.849197) (xy 37.074437 -337.856925)
			(xy 37.084508 -337.857338) (xy 117.287294 -337.857338)
		)
		(stroke
			(width 0)
			(type solid)
		)
		(fill yes)
		(layer "In3.Cu")
		(net "P0V8_PEX0")
	)
	(gr_poly
		(pts
			(arc
				(start 141.931898 -286.145986)
				(mid 141.955993 -286.139908)
				(end 141.974316 -286.123126)
			)
			(arc
				(start 141.974316 -286.123126)
				(mid 142.293594 -285.950429)
				(end 142.612872 -286.123126)
			)
			(arc
				(start 142.612872 -286.123126)
				(mid 142.631199 -286.139902)
				(end 142.65529 -286.145986)
			)
			(arc
				(start 143.407384 -286.145986)
				(mid 143.431479 -286.139908)
				(end 143.449802 -286.123126)
			)
			(arc
				(start 143.449802 -286.123126)
				(mid 143.76908 -285.950429)
				(end 144.088358 -286.123126)
			)
			(arc
				(start 144.088358 -286.123126)
				(mid 144.106685 -286.139902)
				(end 144.130776 -286.145986)
			)
			(arc
				(start 144.296384 -286.145986)
				(mid 144.320479 -286.139908)
				(end 144.338802 -286.123126)
			)
			(arc
				(start 144.338802 -286.123126)
				(mid 144.65808 -285.950429)
				(end 144.977358 -286.123126)
			)
			(arc
				(start 144.977358 -286.123126)
				(mid 144.995685 -286.139902)
				(end 145.019776 -286.145986)
			)
			(arc
				(start 147.469352 -286.145986)
				(mid 147.493447 -286.139908)
				(end 147.51177 -286.123126)
			)
			(arc
				(start 147.51177 -286.123126)
				(mid 147.831048 -285.950429)
				(end 148.150326 -286.123126)
			)
			(arc
				(start 148.150326 -286.123126)
				(mid 148.168653 -286.139902)
				(end 148.192744 -286.145986)
			)
			(arc
				(start 189.770004 -286.145986)
				(mid 189.786202 -286.14342)
				(end 189.800738 -286.135826)
			)
			(arc
				(start 189.800738 -286.135826)
				(mid 189.894858 -286.08617)
				(end 189.999874 -286.069024)
			)
			(arc
				(start 189.999874 -286.069024)
				(mid 190.104873 -286.08622)
				(end 190.19901 -286.135826)
			)
			(arc
				(start 190.19901 -286.135826)
				(mid 190.213546 -286.143419)
				(end 190.229744 -286.145986)
			)
			(arc
				(start 190.720218 -286.145986)
				(mid 190.736416 -286.14342)
				(end 190.750952 -286.135826)
			)
			(arc
				(start 190.750952 -286.135826)
				(mid 190.845072 -286.08617)
				(end 190.950088 -286.069024)
			)
			(arc
				(start 190.950088 -286.069024)
				(mid 191.055087 -286.08622)
				(end 191.149224 -286.135826)
			)
			(arc
				(start 191.149224 -286.135826)
				(mid 191.16376 -286.143419)
				(end 191.179958 -286.145986)
			)
			(arc
				(start 191.670178 -286.145986)
				(mid 191.686376 -286.14342)
				(end 191.700912 -286.135826)
			)
			(arc
				(start 191.700912 -286.135826)
				(mid 191.795032 -286.08617)
				(end 191.900048 -286.069024)
			)
			(arc
				(start 191.900048 -286.069024)
				(mid 192.005047 -286.08622)
				(end 192.099184 -286.135826)
			)
			(arc
				(start 192.099184 -286.135826)
				(mid 192.11372 -286.143419)
				(end 192.129918 -286.145986)
			)
			(arc
				(start 192.620646 -286.145986)
				(mid 192.63671 -286.143379)
				(end 192.651126 -286.135826)
			)
			(arc
				(start 192.651126 -286.135826)
				(mid 192.850008 -286.069277)
				(end 193.04889 -286.135826)
			)
			(arc
				(start 193.04889 -286.135826)
				(mid 193.063306 -286.143379)
				(end 193.07937 -286.145986)
			)
			(arc
				(start 193.570606 -286.145986)
				(mid 193.58667 -286.143379)
				(end 193.601086 -286.135826)
			)
			(arc
				(start 193.601086 -286.135826)
				(mid 193.799968 -286.069277)
				(end 193.99885 -286.135826)
			)
			(arc
				(start 193.99885 -286.135826)
				(mid 194.013266 -286.143379)
				(end 194.02933 -286.145986)
			)
			(arc
				(start 194.520058 -286.145986)
				(mid 194.536256 -286.14342)
				(end 194.550792 -286.135826)
			)
			(arc
				(start 194.550792 -286.135826)
				(mid 194.644912 -286.08617)
				(end 194.749928 -286.069024)
			)
			(arc
				(start 194.749928 -286.069024)
				(mid 194.854927 -286.08622)
				(end 194.949064 -286.135826)
			)
			(arc
				(start 194.949064 -286.135826)
				(mid 194.9636 -286.143419)
				(end 194.979798 -286.145986)
			)
			(arc
				(start 195.470018 -286.145986)
				(mid 195.486216 -286.14342)
				(end 195.500752 -286.135826)
			)
			(arc
				(start 195.500752 -286.135826)
				(mid 195.594872 -286.08617)
				(end 195.699888 -286.069024)
			)
			(arc
				(start 195.699888 -286.069024)
				(mid 195.804887 -286.08622)
				(end 195.899024 -286.135826)
			)
			(arc
				(start 195.899024 -286.135826)
				(mid 195.91356 -286.143419)
				(end 195.929758 -286.145986)
			)
			(arc
				(start 196.419978 -286.145986)
				(mid 196.436176 -286.14342)
				(end 196.450712 -286.135826)
			)
			(arc
				(start 196.450712 -286.135826)
				(mid 196.544832 -286.08617)
				(end 196.649848 -286.069024)
			)
			(arc
				(start 196.649848 -286.069024)
				(mid 196.754847 -286.08622)
				(end 196.848984 -286.135826)
			)
			(arc
				(start 196.848984 -286.135826)
				(mid 196.86352 -286.143419)
				(end 196.879718 -286.145986)
			)
			(arc
				(start 197.370192 -286.145986)
				(mid 197.38639 -286.14342)
				(end 197.400926 -286.135826)
			)
			(arc
				(start 197.400926 -286.135826)
				(mid 197.495046 -286.08617)
				(end 197.600062 -286.069024)
			)
			(arc
				(start 197.600062 -286.069024)
				(mid 197.705061 -286.08622)
				(end 197.799198 -286.135826)
			)
			(arc
				(start 197.799198 -286.135826)
				(mid 197.813734 -286.143419)
				(end 197.829932 -286.145986)
			)
			(arc
				(start 198.320152 -286.145986)
				(mid 198.33635 -286.14342)
				(end 198.350886 -286.135826)
			)
			(arc
				(start 198.350886 -286.135826)
				(mid 198.445006 -286.08617)
				(end 198.550022 -286.069024)
			)
			(arc
				(start 198.550022 -286.069024)
				(mid 198.568465 -286.069525)
				(end 198.586852 -286.071056)
			)
			(xy 198.598536 -286.072326) (xy 198.620126 -286.06496)
			(arc
				(start 198.692516 -285.99257)
				(mid 198.703627 -285.976036)
				(end 198.707502 -285.956502)
			)
			(arc
				(start 198.707502 -272.836894)
				(mid 198.703601 -272.817371)
				(end 198.692516 -272.800826)
			)
			(xy 198.216266 -272.324576) (xy 198.199756 -272.316956)
			(arc
				(start 198.190866 -272.316194)
				(mid 198.166332 -272.31334)
				(end 198.142098 -272.308574)
			)
			(xy 198.136256 -272.307304)
			(arc
				(start 196.96938 -272.307304)
				(mid 196.945131 -272.313465)
				(end 196.926708 -272.330418)
			)
			(arc
				(start 196.926708 -272.330418)
				(mid 196.649848 -272.480262)
				(end 196.372988 -272.330418)
			)
			(arc
				(start 196.372988 -272.330418)
				(mid 196.354597 -272.313407)
				(end 196.330316 -272.307304)
			)
			(arc
				(start 195.06946 -272.307304)
				(mid 195.045211 -272.313465)
				(end 195.026788 -272.330418)
			)
			(arc
				(start 195.026788 -272.330418)
				(mid 194.749928 -272.480262)
				(end 194.473068 -272.330418)
			)
			(arc
				(start 194.473068 -272.330418)
				(mid 194.454677 -272.313407)
				(end 194.430396 -272.307304)
			)
			(arc
				(start 193.16954 -272.307304)
				(mid 193.145291 -272.313465)
				(end 193.126868 -272.330418)
			)
			(arc
				(start 193.126868 -272.330418)
				(mid 192.850008 -272.480262)
				(end 192.573148 -272.330418)
			)
			(arc
				(start 192.573148 -272.330418)
				(mid 192.554757 -272.313407)
				(end 192.530476 -272.307304)
			)
			(arc
				(start 191.269366 -272.307304)
				(mid 191.245117 -272.313465)
				(end 191.226694 -272.330418)
			)
			(arc
				(start 191.226694 -272.330418)
				(mid 190.949834 -272.480262)
				(end 190.672974 -272.330418)
			)
			(arc
				(start 190.672974 -272.330418)
				(mid 190.654583 -272.313407)
				(end 190.630302 -272.307304)
			)
			(arc
				(start 189.369192 -272.307304)
				(mid 189.344943 -272.313465)
				(end 189.32652 -272.330418)
			)
			(arc
				(start 189.32652 -272.330418)
				(mid 189.04966 -272.480262)
				(end 188.7728 -272.330418)
			)
			(arc
				(start 188.7728 -272.330418)
				(mid 188.754409 -272.313407)
				(end 188.730128 -272.307304)
			)
			(arc
				(start 187.469272 -272.307304)
				(mid 187.445023 -272.313465)
				(end 187.4266 -272.330418)
			)
			(arc
				(start 187.4266 -272.330418)
				(mid 187.14974 -272.480262)
				(end 186.87288 -272.330418)
			)
			(arc
				(start 186.87288 -272.330418)
				(mid 186.854489 -272.313407)
				(end 186.830208 -272.307304)
			)
			(arc
				(start 185.569352 -272.307304)
				(mid 185.545103 -272.313465)
				(end 185.52668 -272.330418)
			)
			(arc
				(start 185.52668 -272.330418)
				(mid 185.24982 -272.480262)
				(end 184.97296 -272.330418)
			)
			(arc
				(start 184.97296 -272.330418)
				(mid 184.954569 -272.313407)
				(end 184.930288 -272.307304)
			)
			(arc
				(start 183.669178 -272.307304)
				(mid 183.644929 -272.313465)
				(end 183.626506 -272.330418)
			)
			(arc
				(start 183.626506 -272.330418)
				(mid 183.349646 -272.480262)
				(end 183.072786 -272.330418)
			)
			(arc
				(start 183.072786 -272.330418)
				(mid 183.054395 -272.313407)
				(end 183.030114 -272.307304)
			)
			(arc
				(start 181.769258 -272.307304)
				(mid 181.745009 -272.313465)
				(end 181.726586 -272.330418)
			)
			(arc
				(start 181.726586 -272.330418)
				(mid 181.449726 -272.480262)
				(end 181.172866 -272.330418)
			)
			(arc
				(start 181.172866 -272.330418)
				(mid 181.154475 -272.313407)
				(end 181.130194 -272.307304)
			)
			(arc
				(start 179.869338 -272.307304)
				(mid 179.845089 -272.313465)
				(end 179.826666 -272.330418)
			)
			(arc
				(start 179.826666 -272.330418)
				(mid 179.549806 -272.480262)
				(end 179.272946 -272.330418)
			)
			(arc
				(start 179.272946 -272.330418)
				(mid 179.254555 -272.313407)
				(end 179.230274 -272.307304)
			)
			(arc
				(start 177.969164 -272.307304)
				(mid 177.944915 -272.313465)
				(end 177.926492 -272.330418)
			)
			(arc
				(start 177.926492 -272.330418)
				(mid 177.649632 -272.480262)
				(end 177.372772 -272.330418)
			)
			(arc
				(start 177.372772 -272.330418)
				(mid 177.354381 -272.313407)
				(end 177.3301 -272.307304)
			)
			(arc
				(start 176.06899 -272.307304)
				(mid 176.044883 -272.313525)
				(end 176.026572 -272.330418)
			)
			(arc
				(start 176.026572 -272.330418)
				(mid 175.749712 -272.480032)
				(end 175.472852 -272.330418)
			)
			(arc
				(start 175.472852 -272.330418)
				(mid 175.454573 -272.313467)
				(end 175.430434 -272.307304)
			)
			(arc
				(start 174.169324 -272.307304)
				(mid 174.145075 -272.313465)
				(end 174.126652 -272.330418)
			)
			(arc
				(start 174.126652 -272.330418)
				(mid 173.849792 -272.480262)
				(end 173.572932 -272.330418)
			)
			(arc
				(start 173.572932 -272.330418)
				(mid 173.554541 -272.313407)
				(end 173.53026 -272.307304)
			)
			(arc
				(start 172.26915 -272.307304)
				(mid 172.244901 -272.313465)
				(end 172.226478 -272.330418)
			)
			(arc
				(start 172.226478 -272.330418)
				(mid 171.949618 -272.480262)
				(end 171.672758 -272.330418)
			)
			(arc
				(start 171.672758 -272.330418)
				(mid 171.654367 -272.313407)
				(end 171.630086 -272.307304)
			)
			(arc
				(start 170.36923 -272.307304)
				(mid 170.344981 -272.313465)
				(end 170.326558 -272.330418)
			)
			(arc
				(start 170.326558 -272.330418)
				(mid 170.049698 -272.480262)
				(end 169.772838 -272.330418)
			)
			(arc
				(start 169.772838 -272.330418)
				(mid 169.754447 -272.313407)
				(end 169.730166 -272.307304)
			)
			(arc
				(start 168.46931 -272.307304)
				(mid 168.445061 -272.313465)
				(end 168.426638 -272.330418)
			)
			(arc
				(start 168.426638 -272.330418)
				(mid 168.149778 -272.480262)
				(end 167.872918 -272.330418)
			)
			(arc
				(start 167.872918 -272.330418)
				(mid 167.854527 -272.313407)
				(end 167.830246 -272.307304)
			)
			(arc
				(start 166.569136 -272.307304)
				(mid 166.544887 -272.313465)
				(end 166.526464 -272.330418)
			)
			(arc
				(start 166.526464 -272.330418)
				(mid 166.249604 -272.480262)
				(end 165.972744 -272.330418)
			)
			(arc
				(start 165.972744 -272.330418)
				(mid 165.954353 -272.313407)
				(end 165.930072 -272.307304)
			)
			(arc
				(start 164.669216 -272.307304)
				(mid 164.644967 -272.313465)
				(end 164.626544 -272.330418)
			)
			(arc
				(start 164.626544 -272.330418)
				(mid 164.349684 -272.480262)
				(end 164.072824 -272.330418)
			)
			(arc
				(start 164.072824 -272.330418)
				(mid 164.054433 -272.313407)
				(end 164.030152 -272.307304)
			)
			(arc
				(start 162.769296 -272.307304)
				(mid 162.745047 -272.313465)
				(end 162.726624 -272.330418)
			)
			(arc
				(start 162.726624 -272.330418)
				(mid 162.449764 -272.480262)
				(end 162.172904 -272.330418)
			)
			(arc
				(start 162.172904 -272.330418)
				(mid 162.154513 -272.313407)
				(end 162.130232 -272.307304)
			)
			(arc
				(start 160.869122 -272.307304)
				(mid 160.844873 -272.313465)
				(end 160.82645 -272.330418)
			)
			(arc
				(start 160.82645 -272.330418)
				(mid 160.54959 -272.480262)
				(end 160.27273 -272.330418)
			)
			(arc
				(start 160.27273 -272.330418)
				(mid 160.254339 -272.313407)
				(end 160.230058 -272.307304)
			)
			(arc
				(start 150.324312 -272.307304)
				(mid 150.294229 -272.316983)
				(end 150.275798 -272.34261)
			)
			(arc
				(start 150.275798 -272.34261)
				(mid 148.552755 -274.735363)
				(end 145.749772 -275.650452)
			)
			(arc
				(start 145.749772 -275.650452)
				(mid 142.390707 -274.259029)
				(end 140.999464 -270.89989)
			)
			(xy 141.00048 -270.796258) (xy 141.000734 -270.785844) (xy 140.993114 -270.766794)
			(arc
				(start 140.7795 -270.55318)
				(mid 140.762966 -270.542069)
				(end 140.743432 -270.538194)
			)
			(arc
				(start 132.70738 -270.538194)
				(mid 132.687857 -270.542095)
				(end 132.671312 -270.55318)
			)
			(arc
				(start 131.010152 -272.21434)
				(mid 130.90712 -272.283121)
				(end 130.785616 -272.307304)
			)
			(arc
				(start 94.224348 -272.307304)
				(mid 94.194265 -272.316983)
				(end 94.175834 -272.34261)
			)
			(arc
				(start 94.175834 -272.34261)
				(mid 89.649808 -275.650472)
				(end 85.123782 -272.34261)
			)
			(arc
				(start 85.123782 -272.34261)
				(mid 85.105284 -272.317076)
				(end 85.075268 -272.307304)
			)
			(arc
				(start 80.869282 -272.307304)
				(mid 80.845033 -272.313465)
				(end 80.82661 -272.330418)
			)
			(arc
				(start 80.82661 -272.330418)
				(mid 80.54975 -272.480262)
				(end 80.27289 -272.330418)
			)
			(arc
				(start 80.27289 -272.330418)
				(mid 80.254499 -272.313407)
				(end 80.230218 -272.307304)
			)
			(arc
				(start 78.969362 -272.307304)
				(mid 78.945113 -272.313465)
				(end 78.92669 -272.330418)
			)
			(arc
				(start 78.92669 -272.330418)
				(mid 78.64983 -272.480262)
				(end 78.37297 -272.330418)
			)
			(arc
				(start 78.37297 -272.330418)
				(mid 78.354579 -272.313407)
				(end 78.330298 -272.307304)
			)
			(arc
				(start 77.069442 -272.307304)
				(mid 77.045193 -272.313465)
				(end 77.02677 -272.330418)
			)
			(arc
				(start 77.02677 -272.330418)
				(mid 76.74991 -272.480262)
				(end 76.47305 -272.330418)
			)
			(arc
				(start 76.47305 -272.330418)
				(mid 76.454659 -272.313407)
				(end 76.430378 -272.307304)
			)
			(arc
				(start 75.169268 -272.307304)
				(mid 75.145019 -272.313465)
				(end 75.126596 -272.330418)
			)
			(arc
				(start 75.126596 -272.330418)
				(mid 74.849736 -272.480262)
				(end 74.572876 -272.330418)
			)
			(arc
				(start 74.572876 -272.330418)
				(mid 74.554485 -272.313407)
				(end 74.530204 -272.307304)
			)
			(arc
				(start 73.269094 -272.307304)
				(mid 73.244845 -272.313465)
				(end 73.226422 -272.330418)
			)
			(arc
				(start 73.226422 -272.330418)
				(mid 72.949562 -272.480262)
				(end 72.672702 -272.330418)
			)
			(arc
				(start 72.672702 -272.330418)
				(mid 72.654311 -272.313407)
				(end 72.63003 -272.307304)
			)
			(arc
				(start 71.369174 -272.307304)
				(mid 71.344925 -272.313465)
				(end 71.326502 -272.330418)
			)
			(arc
				(start 71.326502 -272.330418)
				(mid 71.049642 -272.480262)
				(end 70.772782 -272.330418)
			)
			(arc
				(start 70.772782 -272.330418)
				(mid 70.754391 -272.313407)
				(end 70.73011 -272.307304)
			)
			(arc
				(start 69.469254 -272.307304)
				(mid 69.445005 -272.313465)
				(end 69.426582 -272.330418)
			)
			(arc
				(start 69.426582 -272.330418)
				(mid 69.149722 -272.480262)
				(end 68.872862 -272.330418)
			)
			(arc
				(start 68.872862 -272.330418)
				(mid 68.854471 -272.313407)
				(end 68.83019 -272.307304)
			)
			(arc
				(start 67.56908 -272.307304)
				(mid 67.544831 -272.313465)
				(end 67.526408 -272.330418)
			)
			(arc
				(start 67.526408 -272.330418)
				(mid 67.249548 -272.480262)
				(end 66.972688 -272.330418)
			)
			(arc
				(start 66.972688 -272.330418)
				(mid 66.954297 -272.313407)
				(end 66.930016 -272.307304)
			)
			(arc
				(start 65.66916 -272.307304)
				(mid 65.644911 -272.313465)
				(end 65.626488 -272.330418)
			)
			(arc
				(start 65.626488 -272.330418)
				(mid 65.349628 -272.480262)
				(end 65.072768 -272.330418)
			)
			(arc
				(start 65.072768 -272.330418)
				(mid 65.054377 -272.313407)
				(end 65.030096 -272.307304)
			)
			(arc
				(start 63.76924 -272.307304)
				(mid 63.744991 -272.313465)
				(end 63.726568 -272.330418)
			)
			(arc
				(start 63.726568 -272.330418)
				(mid 63.449708 -272.480262)
				(end 63.172848 -272.330418)
			)
			(arc
				(start 63.172848 -272.330418)
				(mid 63.154457 -272.313407)
				(end 63.130176 -272.307304)
			)
			(arc
				(start 61.869066 -272.307304)
				(mid 61.844817 -272.313465)
				(end 61.826394 -272.330418)
			)
			(arc
				(start 61.826394 -272.330418)
				(mid 61.549534 -272.480262)
				(end 61.272674 -272.330418)
			)
			(arc
				(start 61.272674 -272.330418)
				(mid 61.254283 -272.313407)
				(end 61.230002 -272.307304)
			)
			(arc
				(start 59.968892 -272.307304)
				(mid 59.944785 -272.313525)
				(end 59.926474 -272.330418)
			)
			(arc
				(start 59.926474 -272.330418)
				(mid 59.649614 -272.480032)
				(end 59.372754 -272.330418)
			)
			(arc
				(start 59.372754 -272.330418)
				(mid 59.354475 -272.313467)
				(end 59.330336 -272.307304)
			)
			(arc
				(start 58.069226 -272.307304)
				(mid 58.044977 -272.313465)
				(end 58.026554 -272.330418)
			)
			(arc
				(start 58.026554 -272.330418)
				(mid 57.749694 -272.480262)
				(end 57.472834 -272.330418)
			)
			(arc
				(start 57.472834 -272.330418)
				(mid 57.454443 -272.313407)
				(end 57.430162 -272.307304)
			)
			(arc
				(start 56.169052 -272.307304)
				(mid 56.144803 -272.313465)
				(end 56.12638 -272.330418)
			)
			(arc
				(start 56.12638 -272.330418)
				(mid 55.84952 -272.480262)
				(end 55.57266 -272.330418)
			)
			(arc
				(start 55.57266 -272.330418)
				(mid 55.554269 -272.313407)
				(end 55.529988 -272.307304)
			)
			(arc
				(start 54.269132 -272.307304)
				(mid 54.244883 -272.313465)
				(end 54.22646 -272.330418)
			)
			(arc
				(start 54.22646 -272.330418)
				(mid 53.9496 -272.480262)
				(end 53.67274 -272.330418)
			)
			(arc
				(start 53.67274 -272.330418)
				(mid 53.654349 -272.313407)
				(end 53.630068 -272.307304)
			)
			(arc
				(start 52.369212 -272.307304)
				(mid 52.344963 -272.313465)
				(end 52.32654 -272.330418)
			)
			(arc
				(start 52.32654 -272.330418)
				(mid 52.04968 -272.480262)
				(end 51.77282 -272.330418)
			)
			(arc
				(start 51.77282 -272.330418)
				(mid 51.754429 -272.313407)
				(end 51.730148 -272.307304)
			)
			(arc
				(start 50.469038 -272.307304)
				(mid 50.444789 -272.313465)
				(end 50.426366 -272.330418)
			)
			(arc
				(start 50.426366 -272.330418)
				(mid 50.149506 -272.480262)
				(end 49.872646 -272.330418)
			)
			(arc
				(start 49.872646 -272.330418)
				(mid 49.854255 -272.313407)
				(end 49.829974 -272.307304)
			)
			(arc
				(start 48.569118 -272.307304)
				(mid 48.544869 -272.313465)
				(end 48.526446 -272.330418)
			)
			(arc
				(start 48.526446 -272.330418)
				(mid 48.249586 -272.480262)
				(end 47.972726 -272.330418)
			)
			(arc
				(start 47.972726 -272.330418)
				(mid 47.954335 -272.313407)
				(end 47.930054 -272.307304)
			)
			(arc
				(start 46.669198 -272.307304)
				(mid 46.644949 -272.313465)
				(end 46.626526 -272.330418)
			)
			(arc
				(start 46.626526 -272.330418)
				(mid 46.349666 -272.480262)
				(end 46.072806 -272.330418)
			)
			(arc
				(start 46.072806 -272.330418)
				(mid 46.054415 -272.313407)
				(end 46.030134 -272.307304)
			)
			(arc
				(start 44.769024 -272.307304)
				(mid 44.744775 -272.313465)
				(end 44.726352 -272.330418)
			)
			(arc
				(start 44.726352 -272.330418)
				(mid 44.449492 -272.480262)
				(end 44.172632 -272.330418)
			)
			(arc
				(start 44.172632 -272.330418)
				(mid 44.154241 -272.313407)
				(end 44.12996 -272.307304)
			)
			(arc
				(start 37.075618 -272.307304)
				(mid 37.056095 -272.311205)
				(end 37.03955 -272.32229)
			)
			(arc
				(start 36.707064 -272.654776)
				(mid 36.695953 -272.67131)
				(end 36.692078 -272.690844)
			)
			(xy 36.692078 -275.381212)
			(arc
				(start 36.693856 -275.387816)
				(mid 36.705538 -275.474938)
				(end 36.693856 -275.56206)
			)
			(xy 36.692078 -275.568664) (xy 36.692078 -276.331172)
			(arc
				(start 36.693856 -276.337776)
				(mid 36.705538 -276.424898)
				(end 36.693856 -276.51202)
			)
			(xy 36.692078 -276.518624) (xy 36.692078 -277.281132)
			(arc
				(start 36.693856 -277.287736)
				(mid 36.705538 -277.374858)
				(end 36.693856 -277.46198)
			)
			(xy 36.692078 -277.468584) (xy 36.692078 -278.231092)
			(arc
				(start 36.693856 -278.237696)
				(mid 36.705538 -278.324818)
				(end 36.693856 -278.41194)
			)
			(xy 36.692078 -278.418544) (xy 36.692078 -279.181052)
			(arc
				(start 36.693856 -279.187656)
				(mid 36.705538 -279.274778)
				(end 36.693856 -279.3619)
			)
			(xy 36.692078 -279.368504) (xy 36.692078 -280.131012)
			(arc
				(start 36.693856 -280.137616)
				(mid 36.705538 -280.224738)
				(end 36.693856 -280.31186)
			)
			(xy 36.692078 -280.318464) (xy 36.692078 -281.081226)
			(arc
				(start 36.693856 -281.08783)
				(mid 36.705538 -281.174952)
				(end 36.693856 -281.262074)
			)
			(xy 36.692078 -281.268678) (xy 36.692078 -282.031186)
			(arc
				(start 36.693856 -282.03779)
				(mid 36.705538 -282.124912)
				(end 36.693856 -282.212034)
			)
			(xy 36.692078 -282.218638) (xy 36.692078 -282.981146)
			(arc
				(start 36.693856 -282.98775)
				(mid 36.705538 -283.074872)
				(end 36.693856 -283.161994)
			)
			(xy 36.692078 -283.168598) (xy 36.692078 -283.931106)
			(arc
				(start 36.693856 -283.93771)
				(mid 36.705538 -284.024832)
				(end 36.693856 -284.111954)
			)
			(xy 36.692078 -284.118558) (xy 36.692078 -284.881066)
			(arc
				(start 36.693856 -284.88767)
				(mid 36.705538 -284.974792)
				(end 36.693856 -285.061914)
			)
			(xy 36.692078 -285.068518)
			(arc
				(start 36.692078 -285.56331)
				(mid 36.695979 -285.582833)
				(end 36.707064 -285.599378)
			)
			(arc
				(start 36.763452 -285.655766)
				(mid 36.779986 -285.666877)
				(end 36.79952 -285.670752)
			)
			(arc
				(start 37.09543 -285.670752)
				(mid 37.111494 -285.668145)
				(end 37.12591 -285.660592)
			)
			(arc
				(start 37.12591 -285.660592)
				(mid 37.324792 -285.594043)
				(end 37.523674 -285.660592)
			)
			(arc
				(start 37.523674 -285.660592)
				(mid 37.53809 -285.668145)
				(end 37.554154 -285.670752)
			)
			(arc
				(start 38.045644 -285.670752)
				(mid 38.061708 -285.668145)
				(end 38.076124 -285.660592)
			)
			(arc
				(start 38.076124 -285.660592)
				(mid 38.275006 -285.594043)
				(end 38.473888 -285.660592)
			)
			(arc
				(start 38.473888 -285.660592)
				(mid 38.488304 -285.668145)
				(end 38.504368 -285.670752)
			)
			(arc
				(start 38.995604 -285.670752)
				(mid 39.011668 -285.668145)
				(end 39.026084 -285.660592)
			)
			(arc
				(start 39.026084 -285.660592)
				(mid 39.224966 -285.594043)
				(end 39.423848 -285.660592)
			)
			(arc
				(start 39.423848 -285.660592)
				(mid 39.438264 -285.668145)
				(end 39.454328 -285.670752)
			)
			(arc
				(start 39.945564 -285.670752)
				(mid 39.961628 -285.668145)
				(end 39.976044 -285.660592)
			)
			(arc
				(start 39.976044 -285.660592)
				(mid 40.174926 -285.594043)
				(end 40.373808 -285.660592)
			)
			(arc
				(start 40.373808 -285.660592)
				(mid 40.388224 -285.668145)
				(end 40.404288 -285.670752)
			)
			(arc
				(start 40.895524 -285.670752)
				(mid 40.911588 -285.668145)
				(end 40.926004 -285.660592)
			)
			(arc
				(start 40.926004 -285.660592)
				(mid 41.124886 -285.594043)
				(end 41.323768 -285.660592)
			)
			(arc
				(start 41.323768 -285.660592)
				(mid 41.338184 -285.668145)
				(end 41.354248 -285.670752)
			)
			(arc
				(start 44.695618 -285.670752)
				(mid 44.711682 -285.668145)
				(end 44.726098 -285.660592)
			)
			(arc
				(start 44.726098 -285.660592)
				(mid 44.92498 -285.594043)
				(end 45.123862 -285.660592)
			)
			(arc
				(start 45.123862 -285.660592)
				(mid 45.138278 -285.668145)
				(end 45.154342 -285.670752)
			)
			(arc
				(start 45.645578 -285.670752)
				(mid 45.661642 -285.668145)
				(end 45.676058 -285.660592)
			)
			(arc
				(start 45.676058 -285.660592)
				(mid 45.87494 -285.594043)
				(end 46.073822 -285.660592)
			)
			(arc
				(start 46.073822 -285.660592)
				(mid 46.088238 -285.668145)
				(end 46.104302 -285.670752)
			)
			(arc
				(start 46.595538 -285.670752)
				(mid 46.611602 -285.668145)
				(end 46.626018 -285.660592)
			)
			(arc
				(start 46.626018 -285.660592)
				(mid 46.8249 -285.594043)
				(end 47.023782 -285.660592)
			)
			(arc
				(start 47.023782 -285.660592)
				(mid 47.038198 -285.668145)
				(end 47.054262 -285.670752)
			)
			(arc
				(start 47.545498 -285.670752)
				(mid 47.561562 -285.668145)
				(end 47.575978 -285.660592)
			)
			(arc
				(start 47.575978 -285.660592)
				(mid 47.77486 -285.594043)
				(end 47.973742 -285.660592)
			)
			(arc
				(start 47.973742 -285.660592)
				(mid 47.988158 -285.668145)
				(end 48.004222 -285.670752)
			)
			(arc
				(start 48.495458 -285.670752)
				(mid 48.511522 -285.668145)
				(end 48.525938 -285.660592)
			)
			(arc
				(start 48.525938 -285.660592)
				(mid 48.72482 -285.594043)
				(end 48.923702 -285.660592)
			)
			(arc
				(start 48.923702 -285.660592)
				(mid 48.938118 -285.668145)
				(end 48.954182 -285.670752)
			)
			(arc
				(start 49.445418 -285.670752)
				(mid 49.461482 -285.668145)
				(end 49.475898 -285.660592)
			)
			(arc
				(start 49.475898 -285.660592)
				(mid 49.67478 -285.594043)
				(end 49.873662 -285.660592)
			)
			(arc
				(start 49.873662 -285.660592)
				(mid 49.888078 -285.668145)
				(end 49.904142 -285.670752)
			)
			(arc
				(start 50.395632 -285.670752)
				(mid 50.411696 -285.668145)
				(end 50.426112 -285.660592)
			)
			(arc
				(start 50.426112 -285.660592)
				(mid 50.624994 -285.594043)
				(end 50.823876 -285.660592)
			)
			(arc
				(start 50.823876 -285.660592)
				(mid 50.838292 -285.668145)
				(end 50.854356 -285.670752)
			)
			(arc
				(start 51.345592 -285.670752)
				(mid 51.361656 -285.668145)
				(end 51.376072 -285.660592)
			)
			(arc
				(start 51.376072 -285.660592)
				(mid 51.574954 -285.594043)
				(end 51.773836 -285.660592)
			)
			(arc
				(start 51.773836 -285.660592)
				(mid 51.788252 -285.668145)
				(end 51.804316 -285.670752)
			)
			(arc
				(start 52.295552 -285.670752)
				(mid 52.311616 -285.668145)
				(end 52.326032 -285.660592)
			)
			(arc
				(start 52.326032 -285.660592)
				(mid 52.524914 -285.594043)
				(end 52.723796 -285.660592)
			)
			(arc
				(start 52.723796 -285.660592)
				(mid 52.738212 -285.668145)
				(end 52.754276 -285.670752)
			)
			(arc
				(start 53.245512 -285.670752)
				(mid 53.261576 -285.668145)
				(end 53.275992 -285.660592)
			)
			(arc
				(start 53.275992 -285.660592)
				(mid 53.474874 -285.594043)
				(end 53.673756 -285.660592)
			)
			(arc
				(start 53.673756 -285.660592)
				(mid 53.688172 -285.668145)
				(end 53.704236 -285.670752)
			)
			(arc
				(start 54.195472 -285.670752)
				(mid 54.211536 -285.668145)
				(end 54.225952 -285.660592)
			)
			(arc
				(start 54.225952 -285.660592)
				(mid 54.424834 -285.594043)
				(end 54.623716 -285.660592)
			)
			(arc
				(start 54.623716 -285.660592)
				(mid 54.638132 -285.668145)
				(end 54.654196 -285.670752)
			)
			(arc
				(start 55.145432 -285.670752)
				(mid 55.161496 -285.668145)
				(end 55.175912 -285.660592)
			)
			(arc
				(start 55.175912 -285.660592)
				(mid 55.374794 -285.594043)
				(end 55.573676 -285.660592)
			)
			(arc
				(start 55.573676 -285.660592)
				(mid 55.588092 -285.668145)
				(end 55.604156 -285.670752)
			)
			(arc
				(start 56.095392 -285.670752)
				(mid 56.111456 -285.668145)
				(end 56.125872 -285.660592)
			)
			(arc
				(start 56.125872 -285.660592)
				(mid 56.324754 -285.594043)
				(end 56.523636 -285.660592)
			)
			(arc
				(start 56.523636 -285.660592)
				(mid 56.538052 -285.668145)
				(end 56.554116 -285.670752)
			)
			(arc
				(start 57.045606 -285.670752)
				(mid 57.06167 -285.668145)
				(end 57.076086 -285.660592)
			)
			(arc
				(start 57.076086 -285.660592)
				(mid 57.274968 -285.594043)
				(end 57.47385 -285.660592)
			)
			(arc
				(start 57.47385 -285.660592)
				(mid 57.488266 -285.668145)
				(end 57.50433 -285.670752)
			)
			(arc
				(start 57.995566 -285.670752)
				(mid 58.01163 -285.668145)
				(end 58.026046 -285.660592)
			)
			(arc
				(start 58.026046 -285.660592)
				(mid 58.224928 -285.594043)
				(end 58.42381 -285.660592)
			)
			(arc
				(start 58.42381 -285.660592)
				(mid 58.438226 -285.668145)
				(end 58.45429 -285.670752)
			)
			(arc
				(start 59.895486 -285.670752)
				(mid 59.91155 -285.668145)
				(end 59.925966 -285.660592)
			)
			(arc
				(start 59.925966 -285.660592)
				(mid 60.124848 -285.594043)
				(end 60.32373 -285.660592)
			)
			(arc
				(start 60.32373 -285.660592)
				(mid 60.338146 -285.668145)
				(end 60.35421 -285.670752)
			)
			(arc
				(start 60.845446 -285.670752)
				(mid 60.86151 -285.668145)
				(end 60.875926 -285.660592)
			)
			(arc
				(start 60.875926 -285.660592)
				(mid 61.074808 -285.594043)
				(end 61.27369 -285.660592)
			)
			(arc
				(start 61.27369 -285.660592)
				(mid 61.288106 -285.668145)
				(end 61.30417 -285.670752)
			)
			(arc
				(start 61.795406 -285.670752)
				(mid 61.81147 -285.668145)
				(end 61.825886 -285.660592)
			)
			(arc
				(start 61.825886 -285.660592)
				(mid 62.024768 -285.594043)
				(end 62.22365 -285.660592)
			)
			(arc
				(start 62.22365 -285.660592)
				(mid 62.238066 -285.668145)
				(end 62.25413 -285.670752)
			)
			(arc
				(start 62.74562 -285.670752)
				(mid 62.761684 -285.668145)
				(end 62.7761 -285.660592)
			)
			(arc
				(start 62.7761 -285.660592)
				(mid 62.974982 -285.594043)
				(end 63.173864 -285.660592)
			)
			(arc
				(start 63.173864 -285.660592)
				(mid 63.18828 -285.668145)
				(end 63.204344 -285.670752)
			)
			(arc
				(start 63.69558 -285.670752)
				(mid 63.711644 -285.668145)
				(end 63.72606 -285.660592)
			)
			(arc
				(start 63.72606 -285.660592)
				(mid 63.924942 -285.594043)
				(end 64.123824 -285.660592)
			)
			(arc
				(start 64.123824 -285.660592)
				(mid 64.13824 -285.668145)
				(end 64.154304 -285.670752)
			)
			(arc
				(start 64.64554 -285.670752)
				(mid 64.661604 -285.668145)
				(end 64.67602 -285.660592)
			)
			(arc
				(start 64.67602 -285.660592)
				(mid 64.874902 -285.594043)
				(end 65.073784 -285.660592)
			)
			(arc
				(start 65.073784 -285.660592)
				(mid 65.0882 -285.668145)
				(end 65.104264 -285.670752)
			)
			(arc
				(start 65.5955 -285.670752)
				(mid 65.611564 -285.668145)
				(end 65.62598 -285.660592)
			)
			(arc
				(start 65.62598 -285.660592)
				(mid 65.824862 -285.594043)
				(end 66.023744 -285.660592)
			)
			(arc
				(start 66.023744 -285.660592)
				(mid 66.03816 -285.668145)
				(end 66.054224 -285.670752)
			)
			(arc
				(start 66.54546 -285.670752)
				(mid 66.561524 -285.668145)
				(end 66.57594 -285.660592)
			)
			(arc
				(start 66.57594 -285.660592)
				(mid 66.774822 -285.594043)
				(end 66.973704 -285.660592)
			)
			(arc
				(start 66.973704 -285.660592)
				(mid 66.98812 -285.668145)
				(end 67.004184 -285.670752)
			)
			(arc
				(start 67.49542 -285.670752)
				(mid 67.511484 -285.668145)
				(end 67.5259 -285.660592)
			)
			(arc
				(start 67.5259 -285.660592)
				(mid 67.724782 -285.594043)
				(end 67.923664 -285.660592)
			)
			(arc
				(start 67.923664 -285.660592)
				(mid 67.93808 -285.668145)
				(end 67.954144 -285.670752)
			)
			(arc
				(start 68.44538 -285.670752)
				(mid 68.461444 -285.668145)
				(end 68.47586 -285.660592)
			)
			(arc
				(start 68.47586 -285.660592)
				(mid 68.674742 -285.594043)
				(end 68.873624 -285.660592)
			)
			(arc
				(start 68.873624 -285.660592)
				(mid 68.88804 -285.668145)
				(end 68.904104 -285.670752)
			)
			(arc
				(start 69.395594 -285.670752)
				(mid 69.411658 -285.668145)
				(end 69.426074 -285.660592)
			)
			(arc
				(start 69.426074 -285.660592)
				(mid 69.624956 -285.594043)
				(end 69.823838 -285.660592)
			)
			(arc
				(start 69.823838 -285.660592)
				(mid 69.838254 -285.668145)
				(end 69.854318 -285.670752)
			)
			(arc
				(start 70.345554 -285.670752)
				(mid 70.361618 -285.668145)
				(end 70.376034 -285.660592)
			)
			(arc
				(start 70.376034 -285.660592)
				(mid 70.574916 -285.594043)
				(end 70.773798 -285.660592)
			)
			(arc
				(start 70.773798 -285.660592)
				(mid 70.788214 -285.668145)
				(end 70.804278 -285.670752)
			)
			(arc
				(start 99.788726 -285.670752)
				(mid 99.808249 -285.666851)
				(end 99.824794 -285.655766)
			)
			(arc
				(start 99.983544 -285.497016)
				(mid 99.994655 -285.480482)
				(end 99.99853 -285.460948)
			)
			(arc
				(start 99.99853 -279.197562)
				(mid 100.01788 -279.100375)
				(end 100.072952 -279.017984)
			)
			(xy 100.304092 -278.786844) (xy 100.311966 -278.764746)
			(arc
				(start 100.310442 -278.753062)
				(mid 100.308524 -278.730874)
				(end 100.307902 -278.708612)
			)
			(arc
				(start 100.307902 -278.708612)
				(mid 100.419643 -278.438845)
				(end 100.68941 -278.327104)
			)
			(arc
				(start 100.68941 -278.327104)
				(mid 100.711672 -278.327724)
				(end 100.73386 -278.329644)
			)
			(xy 100.745544 -278.331168) (xy 100.767642 -278.323294)
			(arc
				(start 100.823522 -278.267414)
				(mid 100.905899 -278.212308)
				(end 101.0031 -278.192992)
			)
			(arc
				(start 133.460744 -278.192992)
				(mid 133.487403 -278.185435)
				(end 133.50621 -278.165052)
			)
			(xy 133.553454 -278.070818) (xy 133.550914 -278.04237)
			(arc
				(start 133.542278 -278.030686)
				(mid 133.043543 -277.074624)
				(end 132.871464 -276.010116)
			)
			(arc
				(start 132.871464 -276.010116)
				(mid 138.639279 -273.621009)
				(end 136.250172 -279.388824)
			)
			(arc
				(start 136.250172 -279.388824)
				(mid 136.053111 -279.383013)
				(end 135.856726 -279.36571)
			)
			(xy 135.84555 -279.36444) (xy 135.82523 -279.371044)
			(arc
				(start 135.760206 -279.428702)
				(mid 135.747637 -279.44593)
				(end 135.743188 -279.466802)
			)
			(arc
				(start 135.743188 -285.960312)
				(mid 135.747089 -285.979835)
				(end 135.758174 -285.99638)
			)
			(arc
				(start 135.892794 -286.131)
				(mid 135.909328 -286.142111)
				(end 135.928862 -286.145986)
			)
		)
		(stroke
			(width 0)
			(type solid)
		)
		(fill yes)
		(layer "In3.Cu")
		(net "P1V8_PEX")
	)
	(gr_poly
		(pts
			(arc
				(start 374.13184 -286.145986)
				(mid 374.155935 -286.139908)
				(end 374.174258 -286.123126)
			)
			(arc
				(start 374.174258 -286.123126)
				(mid 374.493536 -285.950429)
				(end 374.812814 -286.123126)
			)
			(arc
				(start 374.812814 -286.123126)
				(mid 374.831141 -286.139902)
				(end 374.855232 -286.145986)
			)
			(arc
				(start 375.607326 -286.145986)
				(mid 375.631421 -286.139908)
				(end 375.649744 -286.123126)
			)
			(arc
				(start 375.649744 -286.123126)
				(mid 375.969022 -285.950429)
				(end 376.2883 -286.123126)
			)
			(arc
				(start 376.2883 -286.123126)
				(mid 376.306627 -286.139902)
				(end 376.330718 -286.145986)
			)
			(arc
				(start 376.496326 -286.145986)
				(mid 376.520421 -286.139908)
				(end 376.538744 -286.123126)
			)
			(arc
				(start 376.538744 -286.123126)
				(mid 376.858022 -285.950429)
				(end 377.1773 -286.123126)
			)
			(arc
				(start 377.1773 -286.123126)
				(mid 377.195627 -286.139902)
				(end 377.219718 -286.145986)
			)
			(arc
				(start 379.669294 -286.145986)
				(mid 379.693389 -286.139908)
				(end 379.711712 -286.123126)
			)
			(arc
				(start 379.711712 -286.123126)
				(mid 380.03099 -285.950429)
				(end 380.350268 -286.123126)
			)
			(arc
				(start 380.350268 -286.123126)
				(mid 380.368595 -286.139902)
				(end 380.392686 -286.145986)
			)
			(arc
				(start 421.969946 -286.145986)
				(mid 421.986144 -286.14342)
				(end 422.00068 -286.135826)
			)
			(arc
				(start 422.00068 -286.135826)
				(mid 422.0948 -286.08617)
				(end 422.199816 -286.069024)
			)
			(arc
				(start 422.199816 -286.069024)
				(mid 422.304815 -286.08622)
				(end 422.398952 -286.135826)
			)
			(arc
				(start 422.398952 -286.135826)
				(mid 422.413488 -286.143419)
				(end 422.429686 -286.145986)
			)
			(arc
				(start 422.92016 -286.145986)
				(mid 422.936358 -286.14342)
				(end 422.950894 -286.135826)
			)
			(arc
				(start 422.950894 -286.135826)
				(mid 423.045014 -286.08617)
				(end 423.15003 -286.069024)
			)
			(arc
				(start 423.15003 -286.069024)
				(mid 423.255029 -286.08622)
				(end 423.349166 -286.135826)
			)
			(arc
				(start 423.349166 -286.135826)
				(mid 423.363702 -286.143419)
				(end 423.3799 -286.145986)
			)
			(arc
				(start 423.87012 -286.145986)
				(mid 423.886318 -286.14342)
				(end 423.900854 -286.135826)
			)
			(arc
				(start 423.900854 -286.135826)
				(mid 423.994974 -286.08617)
				(end 424.09999 -286.069024)
			)
			(arc
				(start 424.09999 -286.069024)
				(mid 424.204989 -286.08622)
				(end 424.299126 -286.135826)
			)
			(arc
				(start 424.299126 -286.135826)
				(mid 424.313662 -286.143419)
				(end 424.32986 -286.145986)
			)
			(arc
				(start 424.820588 -286.145986)
				(mid 424.836652 -286.143379)
				(end 424.851068 -286.135826)
			)
			(arc
				(start 424.851068 -286.135826)
				(mid 425.04995 -286.069277)
				(end 425.248832 -286.135826)
			)
			(arc
				(start 425.248832 -286.135826)
				(mid 425.263248 -286.143379)
				(end 425.279312 -286.145986)
			)
			(arc
				(start 425.770548 -286.145986)
				(mid 425.786612 -286.143379)
				(end 425.801028 -286.135826)
			)
			(arc
				(start 425.801028 -286.135826)
				(mid 425.99991 -286.069277)
				(end 426.198792 -286.135826)
			)
			(arc
				(start 426.198792 -286.135826)
				(mid 426.213208 -286.143379)
				(end 426.229272 -286.145986)
			)
			(arc
				(start 426.72 -286.145986)
				(mid 426.736198 -286.14342)
				(end 426.750734 -286.135826)
			)
			(arc
				(start 426.750734 -286.135826)
				(mid 426.844854 -286.08617)
				(end 426.94987 -286.069024)
			)
			(arc
				(start 426.94987 -286.069024)
				(mid 427.054869 -286.08622)
				(end 427.149006 -286.135826)
			)
			(arc
				(start 427.149006 -286.135826)
				(mid 427.163542 -286.143419)
				(end 427.17974 -286.145986)
			)
			(arc
				(start 427.66996 -286.145986)
				(mid 427.686158 -286.14342)
				(end 427.700694 -286.135826)
			)
			(arc
				(start 427.700694 -286.135826)
				(mid 427.794814 -286.08617)
				(end 427.89983 -286.069024)
			)
			(arc
				(start 427.89983 -286.069024)
				(mid 428.004829 -286.08622)
				(end 428.098966 -286.135826)
			)
			(arc
				(start 428.098966 -286.135826)
				(mid 428.113502 -286.143419)
				(end 428.1297 -286.145986)
			)
			(arc
				(start 428.61992 -286.145986)
				(mid 428.636118 -286.14342)
				(end 428.650654 -286.135826)
			)
			(arc
				(start 428.650654 -286.135826)
				(mid 428.744774 -286.08617)
				(end 428.84979 -286.069024)
			)
			(arc
				(start 428.84979 -286.069024)
				(mid 428.954789 -286.08622)
				(end 429.048926 -286.135826)
			)
			(arc
				(start 429.048926 -286.135826)
				(mid 429.063462 -286.143419)
				(end 429.07966 -286.145986)
			)
			(arc
				(start 429.570134 -286.145986)
				(mid 429.586332 -286.14342)
				(end 429.600868 -286.135826)
			)
			(arc
				(start 429.600868 -286.135826)
				(mid 429.694988 -286.08617)
				(end 429.800004 -286.069024)
			)
			(arc
				(start 429.800004 -286.069024)
				(mid 429.905003 -286.08622)
				(end 429.99914 -286.135826)
			)
			(arc
				(start 429.99914 -286.135826)
				(mid 430.013676 -286.143419)
				(end 430.029874 -286.145986)
			)
			(arc
				(start 430.520094 -286.145986)
				(mid 430.536292 -286.14342)
				(end 430.550828 -286.135826)
			)
			(arc
				(start 430.550828 -286.135826)
				(mid 430.644948 -286.08617)
				(end 430.749964 -286.069024)
			)
			(arc
				(start 430.749964 -286.069024)
				(mid 430.768407 -286.069525)
				(end 430.786794 -286.071056)
			)
			(xy 430.798478 -286.072326) (xy 430.820068 -286.06496)
			(arc
				(start 430.892458 -285.99257)
				(mid 430.903569 -285.976036)
				(end 430.907444 -285.956502)
			)
			(arc
				(start 430.907444 -272.836894)
				(mid 430.903543 -272.817371)
				(end 430.892458 -272.800826)
			)
			(xy 430.416208 -272.324576) (xy 430.399698 -272.316956)
			(arc
				(start 430.390808 -272.316194)
				(mid 430.366274 -272.31334)
				(end 430.34204 -272.308574)
			)
			(xy 430.336198 -272.307304)
			(arc
				(start 429.169322 -272.307304)
				(mid 429.145073 -272.313465)
				(end 429.12665 -272.330418)
			)
			(arc
				(start 429.12665 -272.330418)
				(mid 428.84979 -272.480262)
				(end 428.57293 -272.330418)
			)
			(arc
				(start 428.57293 -272.330418)
				(mid 428.554539 -272.313407)
				(end 428.530258 -272.307304)
			)
			(arc
				(start 427.269402 -272.307304)
				(mid 427.245153 -272.313465)
				(end 427.22673 -272.330418)
			)
			(arc
				(start 427.22673 -272.330418)
				(mid 426.94987 -272.480262)
				(end 426.67301 -272.330418)
			)
			(arc
				(start 426.67301 -272.330418)
				(mid 426.654619 -272.313407)
				(end 426.630338 -272.307304)
			)
			(arc
				(start 425.369482 -272.307304)
				(mid 425.345233 -272.313465)
				(end 425.32681 -272.330418)
			)
			(arc
				(start 425.32681 -272.330418)
				(mid 425.04995 -272.480262)
				(end 424.77309 -272.330418)
			)
			(arc
				(start 424.77309 -272.330418)
				(mid 424.754699 -272.313407)
				(end 424.730418 -272.307304)
			)
			(arc
				(start 423.469308 -272.307304)
				(mid 423.445059 -272.313465)
				(end 423.426636 -272.330418)
			)
			(arc
				(start 423.426636 -272.330418)
				(mid 423.149776 -272.480262)
				(end 422.872916 -272.330418)
			)
			(arc
				(start 422.872916 -272.330418)
				(mid 422.854525 -272.313407)
				(end 422.830244 -272.307304)
			)
			(arc
				(start 421.569134 -272.307304)
				(mid 421.544885 -272.313465)
				(end 421.526462 -272.330418)
			)
			(arc
				(start 421.526462 -272.330418)
				(mid 421.249602 -272.480262)
				(end 420.972742 -272.330418)
			)
			(arc
				(start 420.972742 -272.330418)
				(mid 420.954351 -272.313407)
				(end 420.93007 -272.307304)
			)
			(arc
				(start 419.669214 -272.307304)
				(mid 419.644965 -272.313465)
				(end 419.626542 -272.330418)
			)
			(arc
				(start 419.626542 -272.330418)
				(mid 419.349682 -272.480262)
				(end 419.072822 -272.330418)
			)
			(arc
				(start 419.072822 -272.330418)
				(mid 419.054431 -272.313407)
				(end 419.03015 -272.307304)
			)
			(arc
				(start 417.769294 -272.307304)
				(mid 417.745045 -272.313465)
				(end 417.726622 -272.330418)
			)
			(arc
				(start 417.726622 -272.330418)
				(mid 417.449762 -272.480262)
				(end 417.172902 -272.330418)
			)
			(arc
				(start 417.172902 -272.330418)
				(mid 417.154511 -272.313407)
				(end 417.13023 -272.307304)
			)
			(arc
				(start 415.86912 -272.307304)
				(mid 415.844871 -272.313465)
				(end 415.826448 -272.330418)
			)
			(arc
				(start 415.826448 -272.330418)
				(mid 415.549588 -272.480262)
				(end 415.272728 -272.330418)
			)
			(arc
				(start 415.272728 -272.330418)
				(mid 415.254337 -272.313407)
				(end 415.230056 -272.307304)
			)
			(arc
				(start 413.9692 -272.307304)
				(mid 413.944951 -272.313465)
				(end 413.926528 -272.330418)
			)
			(arc
				(start 413.926528 -272.330418)
				(mid 413.649668 -272.480262)
				(end 413.372808 -272.330418)
			)
			(arc
				(start 413.372808 -272.330418)
				(mid 413.354417 -272.313407)
				(end 413.330136 -272.307304)
			)
			(arc
				(start 412.06928 -272.307304)
				(mid 412.045031 -272.313465)
				(end 412.026608 -272.330418)
			)
			(arc
				(start 412.026608 -272.330418)
				(mid 411.749748 -272.480262)
				(end 411.472888 -272.330418)
			)
			(arc
				(start 411.472888 -272.330418)
				(mid 411.454497 -272.313407)
				(end 411.430216 -272.307304)
			)
			(arc
				(start 410.169106 -272.307304)
				(mid 410.144857 -272.313465)
				(end 410.126434 -272.330418)
			)
			(arc
				(start 410.126434 -272.330418)
				(mid 409.849574 -272.480262)
				(end 409.572714 -272.330418)
			)
			(arc
				(start 409.572714 -272.330418)
				(mid 409.554323 -272.313407)
				(end 409.530042 -272.307304)
			)
			(arc
				(start 408.268932 -272.307304)
				(mid 408.244825 -272.313525)
				(end 408.226514 -272.330418)
			)
			(arc
				(start 408.226514 -272.330418)
				(mid 407.949654 -272.480032)
				(end 407.672794 -272.330418)
			)
			(arc
				(start 407.672794 -272.330418)
				(mid 407.654515 -272.313467)
				(end 407.630376 -272.307304)
			)
			(arc
				(start 406.369266 -272.307304)
				(mid 406.345017 -272.313465)
				(end 406.326594 -272.330418)
			)
			(arc
				(start 406.326594 -272.330418)
				(mid 406.049734 -272.480262)
				(end 405.772874 -272.330418)
			)
			(arc
				(start 405.772874 -272.330418)
				(mid 405.754483 -272.313407)
				(end 405.730202 -272.307304)
			)
			(arc
				(start 404.469092 -272.307304)
				(mid 404.444843 -272.313465)
				(end 404.42642 -272.330418)
			)
			(arc
				(start 404.42642 -272.330418)
				(mid 404.14956 -272.480262)
				(end 403.8727 -272.330418)
			)
			(arc
				(start 403.8727 -272.330418)
				(mid 403.854309 -272.313407)
				(end 403.830028 -272.307304)
			)
			(arc
				(start 402.569172 -272.307304)
				(mid 402.544923 -272.313465)
				(end 402.5265 -272.330418)
			)
			(arc
				(start 402.5265 -272.330418)
				(mid 402.24964 -272.480262)
				(end 401.97278 -272.330418)
			)
			(arc
				(start 401.97278 -272.330418)
				(mid 401.954389 -272.313407)
				(end 401.930108 -272.307304)
			)
			(arc
				(start 400.669252 -272.307304)
				(mid 400.645003 -272.313465)
				(end 400.62658 -272.330418)
			)
			(arc
				(start 400.62658 -272.330418)
				(mid 400.34972 -272.480262)
				(end 400.07286 -272.330418)
			)
			(arc
				(start 400.07286 -272.330418)
				(mid 400.054469 -272.313407)
				(end 400.030188 -272.307304)
			)
			(arc
				(start 398.769078 -272.307304)
				(mid 398.744829 -272.313465)
				(end 398.726406 -272.330418)
			)
			(arc
				(start 398.726406 -272.330418)
				(mid 398.449546 -272.480262)
				(end 398.172686 -272.330418)
			)
			(arc
				(start 398.172686 -272.330418)
				(mid 398.154295 -272.313407)
				(end 398.130014 -272.307304)
			)
			(arc
				(start 396.869158 -272.307304)
				(mid 396.844909 -272.313465)
				(end 396.826486 -272.330418)
			)
			(arc
				(start 396.826486 -272.330418)
				(mid 396.549626 -272.480262)
				(end 396.272766 -272.330418)
			)
			(arc
				(start 396.272766 -272.330418)
				(mid 396.254375 -272.313407)
				(end 396.230094 -272.307304)
			)
			(arc
				(start 394.969238 -272.307304)
				(mid 394.944989 -272.313465)
				(end 394.926566 -272.330418)
			)
			(arc
				(start 394.926566 -272.330418)
				(mid 394.649706 -272.480262)
				(end 394.372846 -272.330418)
			)
			(arc
				(start 394.372846 -272.330418)
				(mid 394.354455 -272.313407)
				(end 394.330174 -272.307304)
			)
			(arc
				(start 393.069064 -272.307304)
				(mid 393.044815 -272.313465)
				(end 393.026392 -272.330418)
			)
			(arc
				(start 393.026392 -272.330418)
				(mid 392.749532 -272.480262)
				(end 392.472672 -272.330418)
			)
			(arc
				(start 392.472672 -272.330418)
				(mid 392.454281 -272.313407)
				(end 392.43 -272.307304)
			)
			(arc
				(start 382.524254 -272.307304)
				(mid 382.494171 -272.316983)
				(end 382.47574 -272.34261)
			)
			(arc
				(start 382.47574 -272.34261)
				(mid 380.752697 -274.735363)
				(end 377.949714 -275.650452)
			)
			(arc
				(start 377.949714 -275.650452)
				(mid 374.590559 -274.259045)
				(end 373.199152 -270.89989)
			)
			(xy 373.200422 -270.796004) (xy 373.200676 -270.78559) (xy 373.193056 -270.76654)
			(arc
				(start 372.979696 -270.55318)
				(mid 372.963162 -270.542069)
				(end 372.943628 -270.538194)
			)
			(arc
				(start 364.907576 -270.538194)
				(mid 364.888053 -270.542095)
				(end 364.871508 -270.55318)
			)
			(arc
				(start 363.210348 -272.21434)
				(mid 363.107316 -272.283121)
				(end 362.985812 -272.307304)
			)
			(arc
				(start 326.42429 -272.307304)
				(mid 326.394207 -272.316983)
				(end 326.375776 -272.34261)
			)
			(arc
				(start 326.375776 -272.34261)
				(mid 321.84975 -275.650472)
				(end 317.323724 -272.34261)
			)
			(arc
				(start 317.323724 -272.34261)
				(mid 317.305226 -272.317076)
				(end 317.27521 -272.307304)
			)
			(arc
				(start 313.069224 -272.307304)
				(mid 313.044975 -272.313465)
				(end 313.026552 -272.330418)
			)
			(arc
				(start 313.026552 -272.330418)
				(mid 312.749692 -272.480262)
				(end 312.472832 -272.330418)
			)
			(arc
				(start 312.472832 -272.330418)
				(mid 312.454441 -272.313407)
				(end 312.43016 -272.307304)
			)
			(arc
				(start 311.169304 -272.307304)
				(mid 311.145055 -272.313465)
				(end 311.126632 -272.330418)
			)
			(arc
				(start 311.126632 -272.330418)
				(mid 310.849772 -272.480262)
				(end 310.572912 -272.330418)
			)
			(arc
				(start 310.572912 -272.330418)
				(mid 310.554521 -272.313407)
				(end 310.53024 -272.307304)
			)
			(arc
				(start 309.269384 -272.307304)
				(mid 309.245135 -272.313465)
				(end 309.226712 -272.330418)
			)
			(arc
				(start 309.226712 -272.330418)
				(mid 308.949852 -272.480262)
				(end 308.672992 -272.330418)
			)
			(arc
				(start 308.672992 -272.330418)
				(mid 308.654601 -272.313407)
				(end 308.63032 -272.307304)
			)
			(arc
				(start 307.36921 -272.307304)
				(mid 307.344961 -272.313465)
				(end 307.326538 -272.330418)
			)
			(arc
				(start 307.326538 -272.330418)
				(mid 307.049678 -272.480262)
				(end 306.772818 -272.330418)
			)
			(arc
				(start 306.772818 -272.330418)
				(mid 306.754427 -272.313407)
				(end 306.730146 -272.307304)
			)
			(arc
				(start 305.469036 -272.307304)
				(mid 305.444787 -272.313465)
				(end 305.426364 -272.330418)
			)
			(arc
				(start 305.426364 -272.330418)
				(mid 305.149504 -272.480262)
				(end 304.872644 -272.330418)
			)
			(arc
				(start 304.872644 -272.330418)
				(mid 304.854253 -272.313407)
				(end 304.829972 -272.307304)
			)
			(arc
				(start 303.569116 -272.307304)
				(mid 303.544867 -272.313465)
				(end 303.526444 -272.330418)
			)
			(arc
				(start 303.526444 -272.330418)
				(mid 303.249584 -272.480262)
				(end 302.972724 -272.330418)
			)
			(arc
				(start 302.972724 -272.330418)
				(mid 302.954333 -272.313407)
				(end 302.930052 -272.307304)
			)
			(arc
				(start 301.669196 -272.307304)
				(mid 301.644947 -272.313465)
				(end 301.626524 -272.330418)
			)
			(arc
				(start 301.626524 -272.330418)
				(mid 301.349664 -272.480262)
				(end 301.072804 -272.330418)
			)
			(arc
				(start 301.072804 -272.330418)
				(mid 301.054413 -272.313407)
				(end 301.030132 -272.307304)
			)
			(arc
				(start 299.769022 -272.307304)
				(mid 299.744773 -272.313465)
				(end 299.72635 -272.330418)
			)
			(arc
				(start 299.72635 -272.330418)
				(mid 299.44949 -272.480262)
				(end 299.17263 -272.330418)
			)
			(arc
				(start 299.17263 -272.330418)
				(mid 299.154239 -272.313407)
				(end 299.129958 -272.307304)
			)
			(arc
				(start 297.869102 -272.307304)
				(mid 297.844853 -272.313465)
				(end 297.82643 -272.330418)
			)
			(arc
				(start 297.82643 -272.330418)
				(mid 297.54957 -272.480262)
				(end 297.27271 -272.330418)
			)
			(arc
				(start 297.27271 -272.330418)
				(mid 297.254319 -272.313407)
				(end 297.230038 -272.307304)
			)
			(arc
				(start 295.969182 -272.307304)
				(mid 295.944933 -272.313465)
				(end 295.92651 -272.330418)
			)
			(arc
				(start 295.92651 -272.330418)
				(mid 295.64965 -272.480262)
				(end 295.37279 -272.330418)
			)
			(arc
				(start 295.37279 -272.330418)
				(mid 295.354399 -272.313407)
				(end 295.330118 -272.307304)
			)
			(arc
				(start 294.069008 -272.307304)
				(mid 294.044759 -272.313465)
				(end 294.026336 -272.330418)
			)
			(arc
				(start 294.026336 -272.330418)
				(mid 293.749476 -272.480262)
				(end 293.472616 -272.330418)
			)
			(arc
				(start 293.472616 -272.330418)
				(mid 293.454225 -272.313407)
				(end 293.429944 -272.307304)
			)
			(arc
				(start 292.168834 -272.307304)
				(mid 292.144727 -272.313525)
				(end 292.126416 -272.330418)
			)
			(arc
				(start 292.126416 -272.330418)
				(mid 291.849556 -272.480032)
				(end 291.572696 -272.330418)
			)
			(arc
				(start 291.572696 -272.330418)
				(mid 291.554417 -272.313467)
				(end 291.530278 -272.307304)
			)
			(arc
				(start 290.269168 -272.307304)
				(mid 290.244919 -272.313465)
				(end 290.226496 -272.330418)
			)
			(arc
				(start 290.226496 -272.330418)
				(mid 289.949636 -272.480262)
				(end 289.672776 -272.330418)
			)
			(arc
				(start 289.672776 -272.330418)
				(mid 289.654385 -272.313407)
				(end 289.630104 -272.307304)
			)
			(arc
				(start 288.368994 -272.307304)
				(mid 288.344745 -272.313465)
				(end 288.326322 -272.330418)
			)
			(arc
				(start 288.326322 -272.330418)
				(mid 288.049462 -272.480262)
				(end 287.772602 -272.330418)
			)
			(arc
				(start 287.772602 -272.330418)
				(mid 287.754211 -272.313407)
				(end 287.72993 -272.307304)
			)
			(arc
				(start 286.469074 -272.307304)
				(mid 286.444825 -272.313465)
				(end 286.426402 -272.330418)
			)
			(arc
				(start 286.426402 -272.330418)
				(mid 286.149542 -272.480262)
				(end 285.872682 -272.330418)
			)
			(arc
				(start 285.872682 -272.330418)
				(mid 285.854291 -272.313407)
				(end 285.83001 -272.307304)
			)
			(arc
				(start 284.569154 -272.307304)
				(mid 284.544905 -272.313465)
				(end 284.526482 -272.330418)
			)
			(arc
				(start 284.526482 -272.330418)
				(mid 284.249622 -272.480262)
				(end 283.972762 -272.330418)
			)
			(arc
				(start 283.972762 -272.330418)
				(mid 283.954371 -272.313407)
				(end 283.93009 -272.307304)
			)
			(arc
				(start 282.66898 -272.307304)
				(mid 282.644731 -272.313465)
				(end 282.626308 -272.330418)
			)
			(arc
				(start 282.626308 -272.330418)
				(mid 282.349448 -272.480262)
				(end 282.072588 -272.330418)
			)
			(arc
				(start 282.072588 -272.330418)
				(mid 282.054197 -272.313407)
				(end 282.029916 -272.307304)
			)
			(arc
				(start 280.76906 -272.307304)
				(mid 280.744811 -272.313465)
				(end 280.726388 -272.330418)
			)
			(arc
				(start 280.726388 -272.330418)
				(mid 280.449528 -272.480262)
				(end 280.172668 -272.330418)
			)
			(arc
				(start 280.172668 -272.330418)
				(mid 280.154277 -272.313407)
				(end 280.129996 -272.307304)
			)
			(arc
				(start 278.86914 -272.307304)
				(mid 278.844891 -272.313465)
				(end 278.826468 -272.330418)
			)
			(arc
				(start 278.826468 -272.330418)
				(mid 278.549608 -272.480262)
				(end 278.272748 -272.330418)
			)
			(arc
				(start 278.272748 -272.330418)
				(mid 278.254357 -272.313407)
				(end 278.230076 -272.307304)
			)
			(arc
				(start 276.968966 -272.307304)
				(mid 276.944717 -272.313465)
				(end 276.926294 -272.330418)
			)
			(arc
				(start 276.926294 -272.330418)
				(mid 276.649434 -272.480262)
				(end 276.372574 -272.330418)
			)
			(arc
				(start 276.372574 -272.330418)
				(mid 276.354183 -272.313407)
				(end 276.329902 -272.307304)
			)
			(arc
				(start 269.27556 -272.307304)
				(mid 269.256037 -272.311205)
				(end 269.239492 -272.32229)
			)
			(arc
				(start 268.907006 -272.654776)
				(mid 268.895895 -272.67131)
				(end 268.89202 -272.690844)
			)
			(xy 268.89202 -275.381212)
			(arc
				(start 268.893798 -275.387816)
				(mid 268.90548 -275.474938)
				(end 268.893798 -275.56206)
			)
			(xy 268.89202 -275.568664) (xy 268.89202 -276.331172)
			(arc
				(start 268.893798 -276.337776)
				(mid 268.90548 -276.424898)
				(end 268.893798 -276.51202)
			)
			(xy 268.89202 -276.518624) (xy 268.89202 -277.281132)
			(arc
				(start 268.893798 -277.287736)
				(mid 268.90548 -277.374858)
				(end 268.893798 -277.46198)
			)
			(xy 268.89202 -277.468584) (xy 268.89202 -278.231092)
			(arc
				(start 268.893798 -278.237696)
				(mid 268.90548 -278.324818)
				(end 268.893798 -278.41194)
			)
			(xy 268.89202 -278.418544) (xy 268.89202 -279.181052)
			(arc
				(start 268.893798 -279.187656)
				(mid 268.90548 -279.274778)
				(end 268.893798 -279.3619)
			)
			(xy 268.89202 -279.368504) (xy 268.89202 -280.131012)
			(arc
				(start 268.893798 -280.137616)
				(mid 268.90548 -280.224738)
				(end 268.893798 -280.31186)
			)
			(xy 268.89202 -280.318464) (xy 268.89202 -281.081226)
			(arc
				(start 268.893798 -281.08783)
				(mid 268.90548 -281.174952)
				(end 268.893798 -281.262074)
			)
			(xy 268.89202 -281.268678) (xy 268.89202 -282.031186)
			(arc
				(start 268.893798 -282.03779)
				(mid 268.90548 -282.124912)
				(end 268.893798 -282.212034)
			)
			(xy 268.89202 -282.218638) (xy 268.89202 -282.981146)
			(arc
				(start 268.893798 -282.98775)
				(mid 268.90548 -283.074872)
				(end 268.893798 -283.161994)
			)
			(xy 268.89202 -283.168598) (xy 268.89202 -283.931106)
			(arc
				(start 268.893798 -283.93771)
				(mid 268.90548 -284.024832)
				(end 268.893798 -284.111954)
			)
			(xy 268.89202 -284.118558) (xy 268.89202 -284.881066)
			(arc
				(start 268.893798 -284.88767)
				(mid 268.90548 -284.974792)
				(end 268.893798 -285.061914)
			)
			(xy 268.89202 -285.068518)
			(arc
				(start 268.89202 -285.56331)
				(mid 268.895921 -285.582833)
				(end 268.907006 -285.599378)
			)
			(arc
				(start 268.963394 -285.655766)
				(mid 268.979928 -285.666877)
				(end 268.999462 -285.670752)
			)
			(arc
				(start 269.295372 -285.670752)
				(mid 269.311436 -285.668145)
				(end 269.325852 -285.660592)
			)
			(arc
				(start 269.325852 -285.660592)
				(mid 269.524734 -285.594043)
				(end 269.723616 -285.660592)
			)
			(arc
				(start 269.723616 -285.660592)
				(mid 269.738032 -285.668145)
				(end 269.754096 -285.670752)
			)
			(arc
				(start 270.245586 -285.670752)
				(mid 270.26165 -285.668145)
				(end 270.276066 -285.660592)
			)
			(arc
				(start 270.276066 -285.660592)
				(mid 270.474948 -285.594043)
				(end 270.67383 -285.660592)
			)
			(arc
				(start 270.67383 -285.660592)
				(mid 270.688246 -285.668145)
				(end 270.70431 -285.670752)
			)
			(arc
				(start 271.195546 -285.670752)
				(mid 271.21161 -285.668145)
				(end 271.226026 -285.660592)
			)
			(arc
				(start 271.226026 -285.660592)
				(mid 271.424908 -285.594043)
				(end 271.62379 -285.660592)
			)
			(arc
				(start 271.62379 -285.660592)
				(mid 271.638206 -285.668145)
				(end 271.65427 -285.670752)
			)
			(arc
				(start 272.145506 -285.670752)
				(mid 272.16157 -285.668145)
				(end 272.175986 -285.660592)
			)
			(arc
				(start 272.175986 -285.660592)
				(mid 272.374868 -285.594043)
				(end 272.57375 -285.660592)
			)
			(arc
				(start 272.57375 -285.660592)
				(mid 272.588166 -285.668145)
				(end 272.60423 -285.670752)
			)
			(arc
				(start 273.095466 -285.670752)
				(mid 273.11153 -285.668145)
				(end 273.125946 -285.660592)
			)
			(arc
				(start 273.125946 -285.660592)
				(mid 273.324828 -285.594043)
				(end 273.52371 -285.660592)
			)
			(arc
				(start 273.52371 -285.660592)
				(mid 273.538126 -285.668145)
				(end 273.55419 -285.670752)
			)
			(arc
				(start 276.89556 -285.670752)
				(mid 276.911624 -285.668145)
				(end 276.92604 -285.660592)
			)
			(arc
				(start 276.92604 -285.660592)
				(mid 277.124922 -285.594043)
				(end 277.323804 -285.660592)
			)
			(arc
				(start 277.323804 -285.660592)
				(mid 277.33822 -285.668145)
				(end 277.354284 -285.670752)
			)
			(arc
				(start 277.84552 -285.670752)
				(mid 277.861584 -285.668145)
				(end 277.876 -285.660592)
			)
			(arc
				(start 277.876 -285.660592)
				(mid 278.074882 -285.594043)
				(end 278.273764 -285.660592)
			)
			(arc
				(start 278.273764 -285.660592)
				(mid 278.28818 -285.668145)
				(end 278.304244 -285.670752)
			)
			(arc
				(start 278.79548 -285.670752)
				(mid 278.811544 -285.668145)
				(end 278.82596 -285.660592)
			)
			(arc
				(start 278.82596 -285.660592)
				(mid 279.024842 -285.594043)
				(end 279.223724 -285.660592)
			)
			(arc
				(start 279.223724 -285.660592)
				(mid 279.23814 -285.668145)
				(end 279.254204 -285.670752)
			)
			(arc
				(start 279.74544 -285.670752)
				(mid 279.761504 -285.668145)
				(end 279.77592 -285.660592)
			)
			(arc
				(start 279.77592 -285.660592)
				(mid 279.974802 -285.594043)
				(end 280.173684 -285.660592)
			)
			(arc
				(start 280.173684 -285.660592)
				(mid 280.1881 -285.668145)
				(end 280.204164 -285.670752)
			)
			(arc
				(start 280.6954 -285.670752)
				(mid 280.711464 -285.668145)
				(end 280.72588 -285.660592)
			)
			(arc
				(start 280.72588 -285.660592)
				(mid 280.924762 -285.594043)
				(end 281.123644 -285.660592)
			)
			(arc
				(start 281.123644 -285.660592)
				(mid 281.13806 -285.668145)
				(end 281.154124 -285.670752)
			)
			(arc
				(start 281.64536 -285.670752)
				(mid 281.661424 -285.668145)
				(end 281.67584 -285.660592)
			)
			(arc
				(start 281.67584 -285.660592)
				(mid 281.874722 -285.594043)
				(end 282.073604 -285.660592)
			)
			(arc
				(start 282.073604 -285.660592)
				(mid 282.08802 -285.668145)
				(end 282.104084 -285.670752)
			)
			(arc
				(start 282.595574 -285.670752)
				(mid 282.611638 -285.668145)
				(end 282.626054 -285.660592)
			)
			(arc
				(start 282.626054 -285.660592)
				(mid 282.824936 -285.594043)
				(end 283.023818 -285.660592)
			)
			(arc
				(start 283.023818 -285.660592)
				(mid 283.038234 -285.668145)
				(end 283.054298 -285.670752)
			)
			(arc
				(start 283.545534 -285.670752)
				(mid 283.561598 -285.668145)
				(end 283.576014 -285.660592)
			)
			(arc
				(start 283.576014 -285.660592)
				(mid 283.774896 -285.594043)
				(end 283.973778 -285.660592)
			)
			(arc
				(start 283.973778 -285.660592)
				(mid 283.988194 -285.668145)
				(end 284.004258 -285.670752)
			)
			(arc
				(start 284.495494 -285.670752)
				(mid 284.511558 -285.668145)
				(end 284.525974 -285.660592)
			)
			(arc
				(start 284.525974 -285.660592)
				(mid 284.724856 -285.594043)
				(end 284.923738 -285.660592)
			)
			(arc
				(start 284.923738 -285.660592)
				(mid 284.938154 -285.668145)
				(end 284.954218 -285.670752)
			)
			(arc
				(start 285.445454 -285.670752)
				(mid 285.461518 -285.668145)
				(end 285.475934 -285.660592)
			)
			(arc
				(start 285.475934 -285.660592)
				(mid 285.674816 -285.594043)
				(end 285.873698 -285.660592)
			)
			(arc
				(start 285.873698 -285.660592)
				(mid 285.888114 -285.668145)
				(end 285.904178 -285.670752)
			)
			(arc
				(start 286.395414 -285.670752)
				(mid 286.411478 -285.668145)
				(end 286.425894 -285.660592)
			)
			(arc
				(start 286.425894 -285.660592)
				(mid 286.624776 -285.594043)
				(end 286.823658 -285.660592)
			)
			(arc
				(start 286.823658 -285.660592)
				(mid 286.838074 -285.668145)
				(end 286.854138 -285.670752)
			)
			(arc
				(start 287.345374 -285.670752)
				(mid 287.361438 -285.668145)
				(end 287.375854 -285.660592)
			)
			(arc
				(start 287.375854 -285.660592)
				(mid 287.574736 -285.594043)
				(end 287.773618 -285.660592)
			)
			(arc
				(start 287.773618 -285.660592)
				(mid 287.788034 -285.668145)
				(end 287.804098 -285.670752)
			)
			(arc
				(start 288.295334 -285.670752)
				(mid 288.311398 -285.668145)
				(end 288.325814 -285.660592)
			)
			(arc
				(start 288.325814 -285.660592)
				(mid 288.524696 -285.594043)
				(end 288.723578 -285.660592)
			)
			(arc
				(start 288.723578 -285.660592)
				(mid 288.737994 -285.668145)
				(end 288.754058 -285.670752)
			)
			(arc
				(start 289.245548 -285.670752)
				(mid 289.261612 -285.668145)
				(end 289.276028 -285.660592)
			)
			(arc
				(start 289.276028 -285.660592)
				(mid 289.47491 -285.594043)
				(end 289.673792 -285.660592)
			)
			(arc
				(start 289.673792 -285.660592)
				(mid 289.688208 -285.668145)
				(end 289.704272 -285.670752)
			)
			(arc
				(start 290.195508 -285.670752)
				(mid 290.211572 -285.668145)
				(end 290.225988 -285.660592)
			)
			(arc
				(start 290.225988 -285.660592)
				(mid 290.42487 -285.594043)
				(end 290.623752 -285.660592)
			)
			(arc
				(start 290.623752 -285.660592)
				(mid 290.638168 -285.668145)
				(end 290.654232 -285.670752)
			)
			(arc
				(start 292.095428 -285.670752)
				(mid 292.111492 -285.668145)
				(end 292.125908 -285.660592)
			)
			(arc
				(start 292.125908 -285.660592)
				(mid 292.32479 -285.594043)
				(end 292.523672 -285.660592)
			)
			(arc
				(start 292.523672 -285.660592)
				(mid 292.538088 -285.668145)
				(end 292.554152 -285.670752)
			)
			(arc
				(start 293.045388 -285.670752)
				(mid 293.061452 -285.668145)
				(end 293.075868 -285.660592)
			)
			(arc
				(start 293.075868 -285.660592)
				(mid 293.27475 -285.594043)
				(end 293.473632 -285.660592)
			)
			(arc
				(start 293.473632 -285.660592)
				(mid 293.488048 -285.668145)
				(end 293.504112 -285.670752)
			)
			(arc
				(start 293.995348 -285.670752)
				(mid 294.011412 -285.668145)
				(end 294.025828 -285.660592)
			)
			(arc
				(start 294.025828 -285.660592)
				(mid 294.22471 -285.594043)
				(end 294.423592 -285.660592)
			)
			(arc
				(start 294.423592 -285.660592)
				(mid 294.438008 -285.668145)
				(end 294.454072 -285.670752)
			)
			(arc
				(start 294.945562 -285.670752)
				(mid 294.961626 -285.668145)
				(end 294.976042 -285.660592)
			)
			(arc
				(start 294.976042 -285.660592)
				(mid 295.174924 -285.594043)
				(end 295.373806 -285.660592)
			)
			(arc
				(start 295.373806 -285.660592)
				(mid 295.388222 -285.668145)
				(end 295.404286 -285.670752)
			)
			(arc
				(start 295.895522 -285.670752)
				(mid 295.911586 -285.668145)
				(end 295.926002 -285.660592)
			)
			(arc
				(start 295.926002 -285.660592)
				(mid 296.124884 -285.594043)
				(end 296.323766 -285.660592)
			)
			(arc
				(start 296.323766 -285.660592)
				(mid 296.338182 -285.668145)
				(end 296.354246 -285.670752)
			)
			(arc
				(start 296.845482 -285.670752)
				(mid 296.861546 -285.668145)
				(end 296.875962 -285.660592)
			)
			(arc
				(start 296.875962 -285.660592)
				(mid 297.074844 -285.594043)
				(end 297.273726 -285.660592)
			)
			(arc
				(start 297.273726 -285.660592)
				(mid 297.288142 -285.668145)
				(end 297.304206 -285.670752)
			)
			(arc
				(start 297.795442 -285.670752)
				(mid 297.811506 -285.668145)
				(end 297.825922 -285.660592)
			)
			(arc
				(start 297.825922 -285.660592)
				(mid 298.024804 -285.594043)
				(end 298.223686 -285.660592)
			)
			(arc
				(start 298.223686 -285.660592)
				(mid 298.238102 -285.668145)
				(end 298.254166 -285.670752)
			)
			(arc
				(start 298.745402 -285.670752)
				(mid 298.761466 -285.668145)
				(end 298.775882 -285.660592)
			)
			(arc
				(start 298.775882 -285.660592)
				(mid 298.974764 -285.594043)
				(end 299.173646 -285.660592)
			)
			(arc
				(start 299.173646 -285.660592)
				(mid 299.188062 -285.668145)
				(end 299.204126 -285.670752)
			)
			(arc
				(start 299.695362 -285.670752)
				(mid 299.711426 -285.668145)
				(end 299.725842 -285.660592)
			)
			(arc
				(start 299.725842 -285.660592)
				(mid 299.924724 -285.594043)
				(end 300.123606 -285.660592)
			)
			(arc
				(start 300.123606 -285.660592)
				(mid 300.138022 -285.668145)
				(end 300.154086 -285.670752)
			)
			(arc
				(start 300.645322 -285.670752)
				(mid 300.661386 -285.668145)
				(end 300.675802 -285.660592)
			)
			(arc
				(start 300.675802 -285.660592)
				(mid 300.874684 -285.594043)
				(end 301.073566 -285.660592)
			)
			(arc
				(start 301.073566 -285.660592)
				(mid 301.087982 -285.668145)
				(end 301.104046 -285.670752)
			)
			(arc
				(start 301.595536 -285.670752)
				(mid 301.6116 -285.668145)
				(end 301.626016 -285.660592)
			)
			(arc
				(start 301.626016 -285.660592)
				(mid 301.824898 -285.594043)
				(end 302.02378 -285.660592)
			)
			(arc
				(start 302.02378 -285.660592)
				(mid 302.038196 -285.668145)
				(end 302.05426 -285.670752)
			)
			(arc
				(start 302.545496 -285.670752)
				(mid 302.56156 -285.668145)
				(end 302.575976 -285.660592)
			)
			(arc
				(start 302.575976 -285.660592)
				(mid 302.774858 -285.594043)
				(end 302.97374 -285.660592)
			)
			(arc
				(start 302.97374 -285.660592)
				(mid 302.988156 -285.668145)
				(end 303.00422 -285.670752)
			)
			(xy 328.737722 -285.670752) (xy 328.764646 -285.650178)
			(arc
				(start 328.769472 -285.633414)
				(mid 329.13701 -285.354064)
				(end 329.504548 -285.633414)
			)
			(xy 329.509374 -285.650178) (xy 329.536298 -285.670752)
			(arc
				(start 331.988668 -285.670752)
				(mid 332.008191 -285.666851)
				(end 332.024736 -285.655766)
			)
			(arc
				(start 332.183486 -285.497016)
				(mid 332.194597 -285.480482)
				(end 332.198472 -285.460948)
			)
			(arc
				(start 332.198472 -279.197562)
				(mid 332.217822 -279.100375)
				(end 332.272894 -279.017984)
			)
			(xy 332.504542 -278.786336) (xy 332.512162 -278.764746)
			(arc
				(start 332.510638 -278.752808)
				(mid 332.508727 -278.730747)
				(end 332.508098 -278.708612)
			)
			(arc
				(start 332.508098 -278.708612)
				(mid 332.619839 -278.438845)
				(end 332.889606 -278.327104)
			)
			(arc
				(start 332.889606 -278.327104)
				(mid 332.911741 -278.327732)
				(end 332.933802 -278.329644)
			)
			(xy 332.94574 -278.331168) (xy 332.96733 -278.323548)
			(arc
				(start 333.023464 -278.267414)
				(mid 333.105841 -278.212308)
				(end 333.203042 -278.192992)
			)
			(arc
				(start 365.660686 -278.192992)
				(mid 365.687345 -278.185435)
				(end 365.706152 -278.165052)
			)
			(xy 365.753396 -278.070818) (xy 365.750856 -278.04237)
			(arc
				(start 365.74222 -278.030686)
				(mid 365.243485 -277.074624)
				(end 365.071406 -276.010116)
			)
			(arc
				(start 365.071406 -276.010116)
				(mid 370.839221 -273.621009)
				(end 368.450114 -279.388824)
			)
			(arc
				(start 368.450114 -279.388824)
				(mid 368.253053 -279.383013)
				(end 368.056668 -279.36571)
			)
			(xy 368.045492 -279.36444) (xy 368.025172 -279.371044)
			(arc
				(start 367.960148 -279.428702)
				(mid 367.947579 -279.44593)
				(end 367.94313 -279.466802)
			)
			(arc
				(start 367.94313 -285.960312)
				(mid 367.947031 -285.979835)
				(end 367.958116 -285.99638)
			)
			(arc
				(start 368.092736 -286.131)
				(mid 368.10927 -286.142111)
				(end 368.128804 -286.145986)
			)
		)
		(stroke
			(width 0)
			(type solid)
		)
		(fill yes)
		(layer "In3.Cu")
		(net "P1V8_PEX")
	)
	(gr_poly
		(pts
			(xy 13.96492 -10.342118) (xy 14.020727 -10.341596) (xy 14.132028 -10.333253) (xy 14.242395 -10.316617)
			(xy 14.35121 -10.29178) (xy 14.457865 -10.25888) (xy 14.561763 -10.218102) (xy 14.662323 -10.169674)
			(xy 14.758983 -10.113867) (xy 14.851203 -10.050993) (xy 14.938466 -9.981402) (xy 15.020284 -9.905486)
			(xy 15.096201 -9.823667) (xy 15.165791 -9.736404) (xy 15.228666 -9.644185) (xy 15.284473 -9.547525)
			(xy 15.332901 -9.446965) (xy 15.373679 -9.343067) (xy 15.406579 -9.236412) (xy 15.431417 -9.127597)
			(xy 15.448053 -9.01723) (xy 15.456395 -8.905929) (xy 15.456916 -8.850122) (xy 15.456916 0) (xy 15.4574 0.070354)
			(xy 15.46529 0.21084) (xy 15.481044 0.350663) (xy 15.504614 0.489383) (xy 15.535924 0.626563) (xy 15.574877 0.761771)
			(xy 15.62135 0.894583) (xy 15.675197 1.02458) (xy 15.736248 1.151353) (xy 15.804311 1.274504) (xy 15.879172 1.393644)
			(xy 15.960596 1.5084) (xy 16.048326 1.618409) (xy 16.142086 1.723327) (xy 16.241582 1.822822) (xy 16.3465 1.916582)
			(xy 16.45651 2.004311) (xy 16.571266 2.085734) (xy 16.690407 2.160595) (xy 16.813558 2.228658) (xy 16.940331 2.289708)
			(xy 17.070328 2.343554) (xy 17.20314 2.390026) (xy 17.338349 2.428979) (xy 17.475529 2.460289) (xy 17.614249 2.483858)
			(xy 17.754072 2.499611) (xy 17.894558 2.5075) (xy 17.964912 2.507996) (xy 33.96488 2.507996) (xy 34.035234 2.507512)
			(xy 34.175722 2.499624) (xy 34.315546 2.48387) (xy 34.454267 2.460302) (xy 34.591448 2.428992) (xy 34.726657 2.39004)
			(xy 34.85947 2.343568) (xy 34.989468 2.289721) (xy 35.116243 2.228671) (xy 35.239395 2.160608) (xy 35.358537 2.085747)
			(xy 35.473294 2.004324) (xy 35.583304 1.916594) (xy 35.688223 1.822833) (xy 35.78772 1.723338) (xy 35.881481 1.61842)
			(xy 35.969212 1.50841) (xy 36.050636 1.393653) (xy 36.125498 1.274512) (xy 36.193562 1.151361) (xy 36.254613 1.024587)
			(xy 36.30846 0.894589) (xy 36.354934 0.761776) (xy 36.393887 0.626567) (xy 36.425198 0.489386) (xy 36.448768 0.350666)
			(xy 36.464522 0.210842) (xy 36.472412 0.070354) (xy 36.472876 0) (xy 36.472876 -8.850122) (xy 36.473399 -8.905929)
			(xy 36.481741 -9.01723) (xy 36.498377 -9.127597) (xy 36.523215 -9.236413) (xy 36.556114 -9.343067)
			(xy 36.596892 -9.446965) (xy 36.64532 -9.547526) (xy 36.701127 -9.644186) (xy 36.764002 -9.736405)
			(xy 36.833592 -9.823668) (xy 36.909508 -9.905487) (xy 36.991327 -9.981404) (xy 37.07859 -10.050995)
			(xy 37.170809 -10.113869) (xy 37.267469 -10.169677) (xy 37.368029 -10.218105) (xy 37.471927 -10.258884)
			(xy 37.578582 -10.291784) (xy 37.687397 -10.316622) (xy 37.797764 -10.333258) (xy 37.909065 -10.341601)
			(xy 37.964872 -10.342118) (xy 39.965122 -10.342118) (xy 40.020929 -10.341595) (xy 40.13223 -10.333253)
			(xy 40.242597 -10.316617) (xy 40.351412 -10.291779) (xy 40.458067 -10.258879) (xy 40.561964 -10.218102)
			(xy 40.662525 -10.169674) (xy 40.759184 -10.113866) (xy 40.851404 -10.050992) (xy 40.938667 -9.981402)
			(xy 41.020485 -9.905485) (xy 41.096402 -9.823667) (xy 41.165992 -9.736404) (xy 41.228866 -9.644184)
			(xy 41.284674 -9.547525) (xy 41.333102 -9.446964) (xy 41.373879 -9.343067) (xy 41.406779 -9.236412)
			(xy 41.431617 -9.127597) (xy 41.448253 -9.01723) (xy 41.456595 -8.905929) (xy 41.457118 -8.850122)
			(xy 41.457118 0) (xy 41.457602 0.070354) (xy 41.465492 0.21084) (xy 41.481246 0.350663) (xy 41.504816 0.489383)
			(xy 41.536126 0.626563) (xy 41.575079 0.761771) (xy 41.621552 0.894583) (xy 41.675399 1.02458) (xy 41.73645 1.151353)
			(xy 41.804513 1.274503) (xy 41.879374 1.393644) (xy 41.960798 1.508399) (xy 42.048528 1.618409) (xy 42.142288 1.723326)
			(xy 42.241784 1.822821) (xy 42.346702 1.916581) (xy 42.456712 2.00431) (xy 42.571468 2.085733) (xy 42.690609 2.160594)
			(xy 42.81376 2.228657) (xy 42.940533 2.289707) (xy 43.07053 2.343553) (xy 43.203342 2.390025) (xy 43.338551 2.428977)
			(xy 43.475731 2.460287) (xy 43.614451 2.483856) (xy 43.754274 2.499609) (xy 43.89476 2.507498) (xy 43.965114 2.507996)
			(xy 59.965082 2.507996) (xy 60.035436 2.507512) (xy 60.175924 2.499624) (xy 60.315748 2.48387) (xy 60.454468 2.460301)
			(xy 60.591649 2.428992) (xy 60.726859 2.390039) (xy 60.859672 2.343567) (xy 60.98967 2.289721) (xy 61.116444 2.22867)
			(xy 61.239596 2.160607) (xy 61.358738 2.085747) (xy 61.473495 2.004323) (xy 61.583505 1.916593) (xy 61.688424 1.822833)
			(xy 61.78792 1.723337) (xy 61.881681 1.618419) (xy 61.969412 1.508409) (xy 62.050837 1.393653) (xy 62.125698 1.274512)
			(xy 62.193762 1.15136) (xy 62.254813 1.024586) (xy 62.308661 0.894588) (xy 62.355134 0.761776) (xy 62.394087 0.626567)
			(xy 62.425398 0.489386) (xy 62.448968 0.350665) (xy 62.464722 0.210842) (xy 62.472612 0.070354) (xy 62.473078 0)
			(xy 62.473078 -8.850122) (xy 62.473601 -8.905929) (xy 62.481943 -9.01723) (xy 62.498579 -9.127597)
			(xy 62.523417 -9.236412) (xy 62.556316 -9.343067) (xy 62.597094 -9.446965) (xy 62.645522 -9.547525)
			(xy 62.701329 -9.644185) (xy 62.764204 -9.736405) (xy 62.833794 -9.823668) (xy 62.909711 -9.905487)
			(xy 62.991529 -9.981403) (xy 63.078792 -10.050994) (xy 63.171011 -10.113868) (xy 63.267671 -10.169676)
			(xy 63.368231 -10.218104) (xy 63.472129 -10.258882) (xy 63.578784 -10.291782) (xy 63.687599 -10.31662)
			(xy 63.797966 -10.333257) (xy 63.909267 -10.341599) (xy 63.965074 -10.342118) (xy 65.96507 -10.342118)
			(xy 66.020879 -10.34161) (xy 66.132184 -10.333271) (xy 66.242554 -10.316637) (xy 66.351373 -10.291802)
			(xy 66.458032 -10.258905) (xy 66.561934 -10.218128) (xy 66.662499 -10.169702) (xy 66.759163 -10.113895)
			(xy 66.851386 -10.05102) (xy 66.938653 -9.98143) (xy 67.020476 -9.905512) (xy 67.096396 -9.823693)
			(xy 67.165989 -9.736428) (xy 67.228867 -9.644207) (xy 67.284677 -9.547545) (xy 67.333108 -9.446982)
			(xy 67.373888 -9.343081) (xy 67.406789 -9.236424) (xy 67.431628 -9.127605) (xy 67.448265 -9.017235)
			(xy 67.456608 -8.905931) (xy 67.457066 -8.850122) (xy 67.457066 0) (xy 67.457559 0.070354) (xy 67.465449 0.210841)
			(xy 67.481203 0.350665) (xy 67.504772 0.489385) (xy 67.536082 0.626565) (xy 67.575035 0.761774) (xy 67.621508 0.894587)
			(xy 67.675354 1.024584) (xy 67.736404 1.151358) (xy 67.804467 1.27451) (xy 67.879328 1.393651) (xy 67.960751 1.508408)
			(xy 68.04848 1.618419) (xy 68.14224 1.723337) (xy 68.241735 1.822834) (xy 68.346652 1.916595) (xy 68.456662 2.004326)
			(xy 68.571417 2.085751) (xy 68.690557 2.160614) (xy 68.813708 2.228678) (xy 68.940481 2.289731) (xy 69.070478 2.343579)
			(xy 69.203289 2.390053) (xy 69.338498 2.429008) (xy 69.475678 2.46032) (xy 69.614398 2.483892) (xy 69.754221 2.499648)
			(xy 69.894708 2.50754) (xy 69.965062 2.507996) (xy 85.96503 2.507996) (xy 86.035383 2.507502) (xy 86.175868 2.499611)
			(xy 86.31569 2.483855) (xy 86.454408 2.460284) (xy 86.591586 2.428973) (xy 86.726793 2.390019) (xy 86.859603 2.343545)
			(xy 86.989598 2.289698) (xy 87.11637 2.228647) (xy 87.239519 2.160584) (xy 87.358658 2.085722) (xy 87.473412 2.004299)
			(xy 87.58342 1.916569) (xy 87.688336 1.822809) (xy 87.78783 1.723314) (xy 87.881588 1.618397) (xy 87.969317 1.508388)
			(xy 88.050739 1.393633) (xy 88.125599 1.274493) (xy 88.193661 1.151343) (xy 88.254711 1.024571) (xy 88.308556 0.894575)
			(xy 88.355028 0.761764) (xy 88.39398 0.626557) (xy 88.42529 0.489378) (xy 88.448859 0.35066) (xy 88.464613 0.210838)
			(xy 88.472503 0.070353) (xy 88.473026 0) (xy 88.473026 -8.850122) (xy 88.473549 -8.905928) (xy 88.481891 -9.017228)
			(xy 88.498528 -9.127594) (xy 88.523365 -9.236408) (xy 88.556265 -9.343061) (xy 88.597043 -9.446957)
			(xy 88.645472 -9.547516) (xy 88.701279 -9.644174) (xy 88.764154 -9.736392) (xy 88.833745 -9.823653)
			(xy 88.909662 -9.90547) (xy 88.99148 -9.981384) (xy 89.078743 -10.050972) (xy 89.170963 -10.113844)
			(xy 89.267623 -10.169649) (xy 89.368183 -10.218074) (xy 89.472081 -10.258849) (xy 89.578735 -10.291746)
			(xy 89.687549 -10.316581) (xy 89.797915 -10.333214) (xy 89.909216 -10.341553) (xy 89.965022 -10.342118)
			(xy 91.965018 -10.342118) (xy 92.020825 -10.341596) (xy 92.132127 -10.333254) (xy 92.242494 -10.316617)
			(xy 92.351309 -10.29178) (xy 92.457964 -10.258881) (xy 92.561862 -10.218103) (xy 92.662422 -10.169675)
			(xy 92.759082 -10.113868) (xy 92.851302 -10.050993) (xy 92.938565 -9.981403) (xy 93.020384 -9.905487)
			(xy 93.096301 -9.823668) (xy 93.165891 -9.736405) (xy 93.228766 -9.644186) (xy 93.284573 -9.547526)
			(xy 93.333001 -9.446965) (xy 93.373779 -9.343067) (xy 93.406679 -9.236413) (xy 93.431517 -9.127597)
			(xy 93.448153 -9.01723) (xy 93.456495 -8.905929) (xy 93.457014 -8.850122) (xy 93.457014 0) (xy 93.457498 0.070354)
			(xy 93.465388 0.21084) (xy 93.481142 0.350663) (xy 93.504712 0.489383) (xy 93.536022 0.626563) (xy 93.574975 0.761771)
			(xy 93.621448 0.894583) (xy 93.675295 1.02458) (xy 93.736346 1.151353) (xy 93.804409 1.274504) (xy 93.87927 1.393645)
			(xy 93.960694 1.5084) (xy 94.048424 1.61841) (xy 94.142184 1.723327) (xy 94.24168 1.822823) (xy 94.346598 1.916583)
			(xy 94.456608 2.004312) (xy 94.571364 2.085735) (xy 94.690505 2.160596) (xy 94.813655 2.228659) (xy 94.940429 2.289709)
			(xy 95.070426 2.343555) (xy 95.203238 2.390028) (xy 95.338447 2.42898) (xy 95.475627 2.46029) (xy 95.614347 2.483859)
			(xy 95.75417 2.499613) (xy 95.894656 2.507502) (xy 95.96501 2.507996) (xy 124.06503 2.507996) (xy 124.135383 2.507502)
			(xy 124.275868 2.499611) (xy 124.41569 2.483855) (xy 124.554408 2.460284) (xy 124.691586 2.428973)
			(xy 124.826793 2.390019) (xy 124.959603 2.343545) (xy 125.089598 2.289698) (xy 125.21637 2.228647)
			(xy 125.339519 2.160584) (xy 125.458658 2.085722) (xy 125.573412 2.004299) (xy 125.68342 1.916569)
			(xy 125.788336 1.822809) (xy 125.88783 1.723314) (xy 125.981588 1.618397) (xy 126.069317 1.508388)
			(xy 126.150739 1.393633) (xy 126.225599 1.274493) (xy 126.293661 1.151343) (xy 126.354711 1.024571)
			(xy 126.408556 0.894575) (xy 126.455028 0.761764) (xy 126.49398 0.626557) (xy 126.52529 0.489378)
			(xy 126.548859 0.35066) (xy 126.564613 0.210838) (xy 126.572503 0.070353) (xy 126.573026 0) (xy 126.573026 -8.850122)
			(xy 126.573549 -8.905928) (xy 126.581891 -9.017228) (xy 126.598528 -9.127594) (xy 126.623365 -9.236408)
			(xy 126.656265 -9.343061) (xy 126.697043 -9.446957) (xy 126.745472 -9.547516) (xy 126.801279 -9.644174)
			(xy 126.864154 -9.736392) (xy 126.933745 -9.823653) (xy 127.009662 -9.90547) (xy 127.09148 -9.981384)
			(xy 127.178743 -10.050972) (xy 127.270963 -10.113844) (xy 127.367623 -10.169649) (xy 127.468183 -10.218074)
			(xy 127.572081 -10.258849) (xy 127.678735 -10.291746) (xy 127.787549 -10.316581) (xy 127.897915 -10.333214)
			(xy 128.009216 -10.341553) (xy 128.065022 -10.342118) (xy 130.065018 -10.342118) (xy 130.120825 -10.341596)
			(xy 130.232127 -10.333254) (xy 130.342494 -10.316617) (xy 130.451309 -10.29178) (xy 130.557964 -10.258881)
			(xy 130.661862 -10.218103) (xy 130.762422 -10.169675) (xy 130.859082 -10.113868) (xy 130.951302 -10.050993)
			(xy 131.038565 -9.981403) (xy 131.120384 -9.905487) (xy 131.196301 -9.823668) (xy 131.265891 -9.736405)
			(xy 131.328766 -9.644186) (xy 131.384573 -9.547526) (xy 131.433001 -9.446965) (xy 131.473779 -9.343067)
			(xy 131.506679 -9.236413) (xy 131.531517 -9.127597) (xy 131.548153 -9.01723) (xy 131.556495 -8.905929)
			(xy 131.557014 -8.850122) (xy 131.557014 0) (xy 131.557498 0.070354) (xy 131.565388 0.21084) (xy 131.581142 0.350663)
			(xy 131.604712 0.489383) (xy 131.636022 0.626563) (xy 131.674975 0.761771) (xy 131.721448 0.894583)
			(xy 131.775295 1.02458) (xy 131.836346 1.151353) (xy 131.904409 1.274504) (xy 131.97927 1.393645)
			(xy 132.060694 1.5084) (xy 132.148424 1.61841) (xy 132.242184 1.723327) (xy 132.34168 1.822823) (xy 132.446598 1.916583)
			(xy 132.556608 2.004312) (xy 132.671364 2.085735) (xy 132.790505 2.160596) (xy 132.913655 2.228659)
			(xy 133.040429 2.289709) (xy 133.170426 2.343555) (xy 133.303238 2.390028) (xy 133.438447 2.42898)
			(xy 133.575627 2.46029) (xy 133.714347 2.483859) (xy 133.85417 2.499613) (xy 133.994656 2.507502)
			(xy 134.06501 2.507996) (xy 150.064978 2.507996) (xy 150.135332 2.507512) (xy 150.27582 2.499624)
			(xy 150.415644 2.483871) (xy 150.554365 2.460302) (xy 150.691546 2.428993) (xy 150.826756 2.39004)
			(xy 150.959569 2.343568) (xy 151.089567 2.289722) (xy 151.216342 2.228672) (xy 151.339494 2.160609)
			(xy 151.458636 2.085748) (xy 151.573393 2.004324) (xy 151.683404 1.916594) (xy 151.788322 1.822834)
			(xy 151.887819 1.723338) (xy 151.98158 1.61842) (xy 152.069311 1.50841) (xy 152.150736 1.393654)
			(xy 152.225598 1.274513) (xy 152.293661 1.151361) (xy 152.354713 1.024587) (xy 152.40856 0.894589)
			(xy 152.455034 0.761777) (xy 152.493987 0.626567) (xy 152.525298 0.489386) (xy 152.548868 0.350666)
			(xy 152.564622 0.210842) (xy 152.572512 0.070354) (xy 152.572974 0) (xy 152.572974 -8.850122) (xy 152.573497 -8.905929)
			(xy 152.581839 -9.017231) (xy 152.598475 -9.127598) (xy 152.623313 -9.236413) (xy 152.656212 -9.343068)
			(xy 152.69699 -9.446966) (xy 152.745418 -9.547526) (xy 152.801225 -9.644186) (xy 152.8641 -9.736406)
			(xy 152.93369 -9.823669) (xy 153.009606 -9.905488) (xy 153.091425 -9.981405) (xy 153.178688 -10.050995)
			(xy 153.270907 -10.11387) (xy 153.367567 -10.169678) (xy 153.468127 -10.218107) (xy 153.572025 -10.258885)
			(xy 153.67868 -10.291785) (xy 153.787495 -10.316623) (xy 153.897862 -10.33326) (xy 154.009163 -10.341603)
			(xy 154.06497 -10.342118) (xy 156.064966 -10.342118) (xy 156.120775 -10.34161) (xy 156.23208 -10.333271)
			(xy 156.342451 -10.316638) (xy 156.45127 -10.291803) (xy 156.557929 -10.258906) (xy 156.661832 -10.21813)
			(xy 156.762396 -10.169703) (xy 156.859061 -10.113896) (xy 156.951284 -10.051022) (xy 157.038552 -9.981431)
			(xy 157.120374 -9.905514) (xy 157.196295 -9.823694) (xy 157.265888 -9.736429) (xy 157.328766 -9.644208)
			(xy 157.384577 -9.547546) (xy 157.433007 -9.446983) (xy 157.473787 -9.343082) (xy 157.506689 -9.236424)
			(xy 157.531528 -9.127606) (xy 157.548165 -9.017236) (xy 157.556508 -8.905931) (xy 157.556962 -8.850122)
			(xy 157.556962 0) (xy 157.557455 0.070354) (xy 157.565345 0.210841) (xy 157.581099 0.350665) (xy 157.604668 0.489385)
			(xy 157.635978 0.626566) (xy 157.674931 0.761775) (xy 157.721404 0.894587) (xy 157.77525 1.024585)
			(xy 157.8363 1.151359) (xy 157.904363 1.274511) (xy 157.979224 1.393652) (xy 158.060647 1.508409)
			(xy 158.148376 1.61842) (xy 158.242136 1.723339) (xy 158.341631 1.822835) (xy 158.446548 1.916597)
			(xy 158.556557 2.004328) (xy 158.671313 2.085753) (xy 158.790453 2.160616) (xy 158.913604 2.22868)
			(xy 159.040377 2.289733) (xy 159.170374 2.343581) (xy 159.303185 2.390056) (xy 159.438394 2.429011)
			(xy 159.575574 2.460324) (xy 159.714294 2.483895) (xy 159.854117 2.499652) (xy 159.994604 2.507544)
			(xy 160.064958 2.507996) (xy 176.064926 2.507996) (xy 176.135279 2.507502) (xy 176.275764 2.499611)
			(xy 176.415586 2.483856) (xy 176.554304 2.460285) (xy 176.691483 2.428974) (xy 176.82669 2.39002)
			(xy 176.9595 2.343547) (xy 177.089496 2.289699) (xy 177.216267 2.228648) (xy 177.339416 2.160585)
			(xy 177.458556 2.085724) (xy 177.57331 2.0043) (xy 177.683318 1.91657) (xy 177.788234 1.822811) (xy 177.887728 1.723315)
			(xy 177.981487 1.618398) (xy 178.069216 1.508389) (xy 178.150638 1.393634) (xy 178.225498 1.274494)
			(xy 178.29356 1.151344) (xy 178.35461 1.024572) (xy 178.408456 0.894576) (xy 178.454928 0.761765)
			(xy 178.49388 0.626558) (xy 178.52519 0.489379) (xy 178.548759 0.35066) (xy 178.564513 0.210838)
			(xy 178.572403 0.070353) (xy 178.572922 0) (xy 178.572922 -8.850122) (xy 178.573445 -8.905928) (xy 178.581787 -9.017229)
			(xy 178.598424 -9.127594) (xy 178.623261 -9.236408) (xy 178.656161 -9.343061) (xy 178.696939 -9.446958)
			(xy 178.745367 -9.547517) (xy 178.801175 -9.644175) (xy 178.86405 -9.736393) (xy 178.93364 -9.823654)
			(xy 179.009557 -9.905471) (xy 179.091376 -9.981386) (xy 179.178639 -10.050974) (xy 179.270859 -10.113846)
			(xy 179.367519 -10.169651) (xy 179.468079 -10.218077) (xy 179.571976 -10.258852) (xy 179.678631 -10.291749)
			(xy 179.787445 -10.316584) (xy 179.897811 -10.333218) (xy 180.009112 -10.341557) (xy 180.064918 -10.342118)
			(xy 182.064914 -10.342118) (xy 182.120721 -10.341596) (xy 182.232023 -10.333254) (xy 182.34239 -10.316618)
			(xy 182.451206 -10.291781) (xy 182.557861 -10.258882) (xy 182.661759 -10.218104) (xy 182.76232 -10.169676)
			(xy 182.85898 -10.113869) (xy 182.9512 -10.050995) (xy 183.038463 -9.981405) (xy 183.120282 -9.905488)
			(xy 183.196199 -9.823669) (xy 183.26579 -9.736406) (xy 183.328665 -9.644187) (xy 183.384473 -9.547527)
			(xy 183.432901 -9.446966) (xy 183.473679 -9.343068) (xy 183.506579 -9.236413) (xy 183.531416 -9.127598)
			(xy 183.548053 -9.017231) (xy 183.556395 -8.905929) (xy 183.55691 -8.850122) (xy 183.55691 0) (xy 183.557394 0.070354)
			(xy 183.565284 0.21084) (xy 183.581038 0.350664) (xy 183.604608 0.489383) (xy 183.635918 0.626563)
			(xy 183.674871 0.761772) (xy 183.721344 0.894584) (xy 183.775191 1.024581) (xy 183.836242 1.151354)
			(xy 183.904305 1.274505) (xy 183.979166 1.393646) (xy 184.06059 1.508401) (xy 184.14832 1.618411)
			(xy 184.24208 1.723329) (xy 184.341576 1.822824) (xy 184.446493 1.916584) (xy 184.556503 2.004314)
			(xy 184.671259 2.085737) (xy 184.7904 2.160598) (xy 184.913551 2.228661) (xy 185.040325 2.289712)
			(xy 185.170322 2.343558) (xy 185.303134 2.390031) (xy 185.438342 2.428983) (xy 185.575523 2.460294)
			(xy 185.714242 2.483863) (xy 185.854066 2.499617) (xy 185.994552 2.507506) (xy 186.064906 2.507996)
			(xy 202.064874 2.507996) (xy 202.135228 2.507512) (xy 202.275716 2.499624) (xy 202.41554 2.483871)
			(xy 202.554261 2.460303) (xy 202.691443 2.428993) (xy 202.826653 2.390041) (xy 202.959466 2.343569)
			(xy 203.089464 2.289723) (xy 203.216239 2.228673) (xy 203.339391 2.16061) (xy 203.458534 2.085749)
			(xy 203.573291 2.004326) (xy 203.683302 1.916596) (xy 203.788221 1.822836) (xy 203.887718 1.72334)
			(xy 203.981479 1.618422) (xy 204.06921 1.508412) (xy 204.150635 1.393655) (xy 204.225497 1.274514)
			(xy 204.293561 1.151362) (xy 204.354613 1.024588) (xy 204.40846 0.89459) (xy 204.454933 0.761778)
			(xy 204.493887 0.626568) (xy 204.525198 0.489387) (xy 204.548768 0.350666) (xy 204.564522 0.210842)
			(xy 204.572412 0.070354) (xy 204.57287 0) (xy 204.57287 -8.850122) (xy 204.573393 -8.905929) (xy 204.581735 -9.017231)
			(xy 204.598371 -9.127598) (xy 204.623209 -9.236413) (xy 204.656108 -9.343068) (xy 204.696886 -9.446966)
			(xy 204.745314 -9.547527) (xy 204.801121 -9.644187) (xy 204.863996 -9.736407) (xy 204.933586 -9.82367)
			(xy 205.009502 -9.905489) (xy 205.091321 -9.981407) (xy 205.178583 -10.050997) (xy 205.270803 -10.113872)
			(xy 205.367463 -10.16968) (xy 205.468023 -10.218109) (xy 205.571921 -10.258888) (xy 205.678575 -10.291788)
			(xy 205.78739 -10.316626) (xy 205.897757 -10.333264) (xy 206.009059 -10.341607) (xy 206.064866 -10.342118)
			(xy 208.065116 -10.342118) (xy 208.120923 -10.341596) (xy 208.232225 -10.333254) (xy 208.342592 -10.316618)
			(xy 208.451407 -10.29178) (xy 208.558062 -10.258881) (xy 208.66196 -10.218103) (xy 208.762521 -10.169676)
			(xy 208.859181 -10.113868) (xy 208.951401 -10.050994) (xy 209.038664 -9.981404) (xy 209.120483 -9.905487)
			(xy 209.1964 -9.823669) (xy 209.26599 -9.736406) (xy 209.328865 -9.644186) (xy 209.384673 -9.547526)
			(xy 209.433101 -9.446966) (xy 209.473879 -9.343068) (xy 209.506779 -9.236413) (xy 209.531617 -9.127598)
			(xy 209.548253 -9.017231) (xy 209.556595 -8.905929) (xy 209.557112 -8.850122) (xy 209.557112 0) (xy 209.557596 0.070354)
			(xy 209.565486 0.21084) (xy 209.58124 0.350663) (xy 209.60481 0.489383) (xy 209.63612 0.626563) (xy 209.675073 0.761772)
			(xy 209.721546 0.894583) (xy 209.775393 1.02458) (xy 209.836444 1.151354) (xy 209.904507 1.274505)
			(xy 209.979368 1.393645) (xy 210.060792 1.508401) (xy 210.148522 1.618411) (xy 210.242282 1.723328)
			(xy 210.341778 1.822823) (xy 210.446696 1.916583) (xy 210.556706 2.004313) (xy 210.671462 2.085736)
			(xy 210.790602 2.160597) (xy 210.913753 2.22866) (xy 211.040527 2.289711) (xy 211.170524 2.343557)
			(xy 211.303336 2.390029) (xy 211.438545 2.428982) (xy 211.575725 2.460292) (xy 211.714444 2.483861)
			(xy 211.854268 2.499615) (xy 211.994754 2.507504) (xy 212.065108 2.507996) (xy 240.164874 2.507996)
			(xy 240.235228 2.507512) (xy 240.375716 2.499624) (xy 240.51554 2.483871) (xy 240.654261 2.460303)
			(xy 240.791443 2.428993) (xy 240.926653 2.390041) (xy 241.059466 2.343569) (xy 241.189464 2.289723)
			(xy 241.316239 2.228673) (xy 241.439391 2.16061) (xy 241.558534 2.085749) (xy 241.673291 2.004326)
			(xy 241.783302 1.916596) (xy 241.888221 1.822836) (xy 241.987718 1.72334) (xy 242.081479 1.618422)
			(xy 242.16921 1.508412) (xy 242.250635 1.393655) (xy 242.325497 1.274514) (xy 242.393561 1.151362)
			(xy 242.454613 1.024588) (xy 242.50846 0.89459) (xy 242.554933 0.761778) (xy 242.593887 0.626568)
			(xy 242.625198 0.489387) (xy 242.648768 0.350666) (xy 242.664522 0.210842) (xy 242.672412 0.070354)
			(xy 242.67287 0) (xy 242.67287 -8.850122) (xy 242.673393 -8.905929) (xy 242.681735 -9.017231) (xy 242.698371 -9.127598)
			(xy 242.723209 -9.236413) (xy 242.756108 -9.343068) (xy 242.796886 -9.446966) (xy 242.845314 -9.547527)
			(xy 242.901121 -9.644187) (xy 242.963996 -9.736407) (xy 243.033586 -9.82367) (xy 243.109502 -9.905489)
			(xy 243.191321 -9.981407) (xy 243.278583 -10.050997) (xy 243.370803 -10.113872) (xy 243.467463 -10.16968)
			(xy 243.568023 -10.218109) (xy 243.671921 -10.258888) (xy 243.778575 -10.291788) (xy 243.88739 -10.316626)
			(xy 243.997757 -10.333264) (xy 244.109059 -10.341607) (xy 244.164866 -10.342118) (xy 246.165116 -10.342118)
			(xy 246.220923 -10.341596) (xy 246.332225 -10.333254) (xy 246.442592 -10.316618) (xy 246.551407 -10.29178)
			(xy 246.658062 -10.258881) (xy 246.76196 -10.218103) (xy 246.862521 -10.169676) (xy 246.959181 -10.113868)
			(xy 247.051401 -10.050994) (xy 247.138664 -9.981404) (xy 247.220483 -9.905487) (xy 247.2964 -9.823669)
			(xy 247.36599 -9.736406) (xy 247.428865 -9.644186) (xy 247.484673 -9.547526) (xy 247.533101 -9.446966)
			(xy 247.573879 -9.343068) (xy 247.606779 -9.236413) (xy 247.631617 -9.127598) (xy 247.648253 -9.017231)
			(xy 247.656595 -8.905929) (xy 247.657112 -8.850122) (xy 247.657112 0) (xy 247.657596 0.070354) (xy 247.665486 0.21084)
			(xy 247.68124 0.350663) (xy 247.70481 0.489383) (xy 247.73612 0.626563) (xy 247.775073 0.761772)
			(xy 247.821546 0.894583) (xy 247.875393 1.02458) (xy 247.936444 1.151354) (xy 248.004507 1.274505)
			(xy 248.079368 1.393645) (xy 248.160792 1.508401) (xy 248.248522 1.618411) (xy 248.342282 1.723328)
			(xy 248.441778 1.822823) (xy 248.546696 1.916583) (xy 248.656706 2.004313) (xy 248.771462 2.085736)
			(xy 248.890602 2.160597) (xy 249.013753 2.22866) (xy 249.140527 2.289711) (xy 249.270524 2.343557)
			(xy 249.403336 2.390029) (xy 249.538545 2.428982) (xy 249.675725 2.460292) (xy 249.814444 2.483861)
			(xy 249.954268 2.499615) (xy 250.094754 2.507504) (xy 250.165108 2.507996) (xy 266.165076 2.507996)
			(xy 266.23543 2.507512) (xy 266.375918 2.499624) (xy 266.515742 2.483871) (xy 266.654463 2.460303)
			(xy 266.791644 2.428993) (xy 266.926854 2.390041) (xy 267.059667 2.343569) (xy 267.189666 2.289723)
			(xy 267.31644 2.228672) (xy 267.439593 2.160609) (xy 267.558735 2.085749) (xy 267.673492 2.004325)
			(xy 267.783503 1.916595) (xy 267.888422 1.822835) (xy 267.987918 1.723339) (xy 268.08168 1.618421)
			(xy 268.169411 1.508411) (xy 268.250835 1.393655) (xy 268.325697 1.274513) (xy 268.393761 1.151362)
			(xy 268.454813 1.024588) (xy 268.50866 0.89459) (xy 268.555134 0.761777) (xy 268.594087 0.626568)
			(xy 268.625398 0.489387) (xy 268.648968 0.350666) (xy 268.664722 0.210842) (xy 268.672612 0.070354)
			(xy 268.673072 0) (xy 268.673072 -8.850122) (xy 268.673595 -8.905929) (xy 268.681937 -9.017231) (xy 268.698573 -9.127598)
			(xy 268.723411 -9.236413) (xy 268.75631 -9.343068) (xy 268.797088 -9.446966) (xy 268.845516 -9.547526)
			(xy 268.901323 -9.644187) (xy 268.964198 -9.736406) (xy 269.033788 -9.82367) (xy 269.109704 -9.905489)
			(xy 269.191523 -9.981406) (xy 269.278786 -10.050996) (xy 269.371005 -10.113871) (xy 269.467665 -10.169679)
			(xy 269.568225 -10.218108) (xy 269.672123 -10.258886) (xy 269.778777 -10.291787) (xy 269.887592 -10.316625)
			(xy 269.997959 -10.333262) (xy 270.109261 -10.341605) (xy 270.165068 -10.342118) (xy 272.165064 -10.342118)
			(xy 272.220873 -10.34161) (xy 272.332178 -10.333272) (xy 272.442549 -10.316638) (xy 272.551368 -10.291804)
			(xy 272.658028 -10.258906) (xy 272.76193 -10.21813) (xy 272.862495 -10.169703) (xy 272.95916 -10.113897)
			(xy 273.051383 -10.051022) (xy 273.138651 -9.981432) (xy 273.220473 -9.905515) (xy 273.296394 -9.823695)
			(xy 273.365988 -9.73643) (xy 273.428866 -9.644209) (xy 273.484676 -9.547546) (xy 273.533107 -9.446983)
			(xy 273.573887 -9.343082) (xy 273.606789 -9.236425) (xy 273.631628 -9.127606) (xy 273.648265 -9.017236)
			(xy 273.656608 -8.905931) (xy 273.65706 -8.850122) (xy 273.65706 0) (xy 273.657553 0.070354) (xy 273.665443 0.210841)
			(xy 273.681197 0.350665) (xy 273.704766 0.489385) (xy 273.736076 0.626566) (xy 273.775029 0.761775)
			(xy 273.821502 0.894588) (xy 273.875348 1.024585) (xy 273.936398 1.15136) (xy 274.004461 1.274511)
			(xy 274.079321 1.393653) (xy 274.160745 1.50841) (xy 274.248474 1.618421) (xy 274.342234 1.723339)
			(xy 274.441729 1.822836) (xy 274.546646 1.916598) (xy 274.656655 2.004329) (xy 274.771411 2.085754)
			(xy 274.890551 2.160617) (xy 275.013701 2.228682) (xy 275.140474 2.289734) (xy 275.270471 2.343583)
			(xy 275.403283 2.390058) (xy 275.538492 2.429013) (xy 275.675672 2.460325) (xy 275.814392 2.483897)
			(xy 275.954215 2.499654) (xy 276.094702 2.507545) (xy 276.165056 2.507996) (xy 292.165024 2.507996)
			(xy 292.235377 2.507502) (xy 292.375862 2.499611) (xy 292.515684 2.483856) (xy 292.654403 2.460285)
			(xy 292.791581 2.428974) (xy 292.926788 2.390021) (xy 293.059599 2.343547) (xy 293.189594 2.2897)
			(xy 293.316366 2.228649) (xy 293.439515 2.160586) (xy 293.558655 2.085724) (xy 293.673409 2.004301)
			(xy 293.783417 1.916571) (xy 293.888334 1.822811) (xy 293.987828 1.723316) (xy 294.081587 1.618399)
			(xy 294.169315 1.50839) (xy 294.250738 1.393635) (xy 294.325598 1.274495) (xy 294.39366 1.151345)
			(xy 294.45471 1.024572) (xy 294.508556 0.894576) (xy 294.555028 0.761765) (xy 294.59398 0.626558)
			(xy 294.62529 0.489379) (xy 294.648859 0.35066) (xy 294.664613 0.210839) (xy 294.672503 0.070353)
			(xy 294.67302 0) (xy 294.67302 -8.850122) (xy 294.673543 -8.905928) (xy 294.681885 -9.017229) (xy 294.698522 -9.127594)
			(xy 294.723359 -9.236408) (xy 294.756259 -9.343062) (xy 294.797037 -9.446958) (xy 294.845465 -9.547517)
			(xy 294.901273 -9.644176) (xy 294.964148 -9.736394) (xy 295.033738 -9.823655) (xy 295.109655 -9.905472)
			(xy 295.191474 -9.981387) (xy 295.278737 -10.050975) (xy 295.370956 -10.113847) (xy 295.467616 -10.169652)
			(xy 295.568176 -10.218078) (xy 295.672074 -10.258853) (xy 295.778728 -10.291751) (xy 295.887543 -10.316586)
			(xy 295.997909 -10.333219) (xy 296.10921 -10.341559) (xy 296.165016 -10.342118) (xy 298.165012 -10.342118)
			(xy 298.220819 -10.341596) (xy 298.332121 -10.333254) (xy 298.442488 -10.316618) (xy 298.551304 -10.291781)
			(xy 298.657959 -10.258882) (xy 298.761858 -10.218105) (xy 298.862418 -10.169677) (xy 298.959079 -10.11387)
			(xy 299.051299 -10.050995) (xy 299.138562 -9.981405) (xy 299.220382 -9.905489) (xy 299.296299 -9.82367)
			(xy 299.365889 -9.736407) (xy 299.428764 -9.644188) (xy 299.484572 -9.547527) (xy 299.533001 -9.446967)
			(xy 299.573779 -9.343069) (xy 299.606679 -9.236414) (xy 299.631516 -9.127598) (xy 299.648153 -9.017231)
			(xy 299.656495 -8.905929) (xy 299.657008 -8.850122) (xy 299.657008 0) (xy 299.657492 0.070354) (xy 299.665382 0.21084)
			(xy 299.681136 0.350664) (xy 299.704706 0.489383) (xy 299.736016 0.626564) (xy 299.774969 0.761772)
			(xy 299.821442 0.894584) (xy 299.875289 1.024581) (xy 299.93634 1.151355) (xy 300.004403 1.274505)
			(xy 300.079264 1.393646) (xy 300.160688 1.508402) (xy 300.248418 1.618412) (xy 300.342178 1.723329)
			(xy 300.441673 1.822825) (xy 300.546591 1.916585) (xy 300.656601 2.004315) (xy 300.771357 2.085738)
			(xy 300.890498 2.160599) (xy 301.013649 2.228662) (xy 301.140423 2.289713) (xy 301.27042 2.343559)
			(xy 301.403232 2.390032) (xy 301.53844 2.428985) (xy 301.67562 2.460295) (xy 301.81434 2.483864)
			(xy 301.954163 2.499618) (xy 302.09465 2.507508) (xy 302.165004 2.507996) (xy 318.164972 2.507996)
			(xy 318.235326 2.507512) (xy 318.375814 2.499624) (xy 318.515639 2.483871) (xy 318.65436 2.460303)
			(xy 318.791541 2.428994) (xy 318.926751 2.390042) (xy 319.059564 2.34357) (xy 319.189563 2.289724)
			(xy 319.316338 2.228673) (xy 319.43949 2.160611) (xy 319.558633 2.08575) (xy 319.67339 2.004327)
			(xy 319.783401 1.916597) (xy 319.88832 1.822836) (xy 319.987817 1.723341) (xy 320.081579 1.618423)
			(xy 320.16931 1.508412) (xy 320.250734 1.393656) (xy 320.325597 1.274514) (xy 320.393661 1.151363)
			(xy 320.454712 1.024589) (xy 320.50856 0.894591) (xy 320.555033 0.761778) (xy 320.593987 0.626568)
			(xy 320.625298 0.489387) (xy 320.648868 0.350666) (xy 320.664622 0.210842) (xy 320.672512 0.070354)
			(xy 320.672968 0) (xy 320.672968 -8.850122) (xy 320.673491 -8.905929) (xy 320.681833 -9.017231) (xy 320.698469 -9.127598)
			(xy 320.723307 -9.236413) (xy 320.756206 -9.343068) (xy 320.796984 -9.446967) (xy 320.845412 -9.547527)
			(xy 320.901219 -9.644188) (xy 320.964093 -9.736408) (xy 321.033684 -9.823671) (xy 321.1096 -9.90549)
			(xy 321.191418 -9.981407) (xy 321.278681 -10.050998) (xy 321.3709 -10.113873) (xy 321.46756 -10.169682)
			(xy 321.56812 -10.21811) (xy 321.672018 -10.258889) (xy 321.778673 -10.29179) (xy 321.887488 -10.316628)
			(xy 321.997855 -10.333266) (xy 322.109157 -10.341609) (xy 322.164964 -10.342118) (xy 324.16496 -10.342118)
			(xy 324.220769 -10.34161) (xy 324.332074 -10.333272) (xy 324.442446 -10.316639) (xy 324.551265 -10.291805)
			(xy 324.657925 -10.258907) (xy 324.761827 -10.218131) (xy 324.862393 -10.169705) (xy 324.959057 -10.113898)
			(xy 325.051281 -10.051024) (xy 325.138549 -9.981433) (xy 325.220372 -9.905516) (xy 325.296293 -9.823696)
			(xy 325.365887 -9.736431) (xy 325.428765 -9.64421) (xy 325.484576 -9.547547) (xy 325.533007 -9.446984)
			(xy 325.573787 -9.343083) (xy 325.606689 -9.236425) (xy 325.631528 -9.127607) (xy 325.648165 -9.017236)
			(xy 325.656508 -8.905931) (xy 325.656956 -8.850122) (xy 325.656956 0) (xy 325.657449 0.070354) (xy 325.665339 0.210841)
			(xy 325.681093 0.350665) (xy 325.704662 0.489386) (xy 325.735972 0.626566) (xy 325.774925 0.761776)
			(xy 325.821398 0.894588) (xy 325.875244 1.024586) (xy 325.936294 1.15136) (xy 326.004357 1.274512)
			(xy 326.079217 1.393654) (xy 326.16064 1.508411) (xy 326.24837 1.618422) (xy 326.342129 1.723341)
			(xy 326.441624 1.822838) (xy 326.546542 1.916599) (xy 326.656551 2.004331) (xy 326.771306 2.085756)
			(xy 326.890447 2.160619) (xy 327.013597 2.228684) (xy 327.14037 2.289737) (xy 327.270367 2.343585)
			(xy 327.403179 2.39006) (xy 327.538387 2.429016) (xy 327.675567 2.460328) (xy 327.814287 2.4839)
			(xy 327.954111 2.499657) (xy 328.094598 2.507549) (xy 328.164952 2.507996) (xy 356.264972 2.507996)
			(xy 356.335326 2.507512) (xy 356.475814 2.499624) (xy 356.615639 2.483871) (xy 356.75436 2.460303)
			(xy 356.891541 2.428994) (xy 357.026751 2.390042) (xy 357.159564 2.34357) (xy 357.289563 2.289724)
			(xy 357.416338 2.228673) (xy 357.53949 2.160611) (xy 357.658633 2.08575) (xy 357.77339 2.004327)
			(xy 357.883401 1.916597) (xy 357.98832 1.822836) (xy 358.087817 1.723341) (xy 358.181579 1.618423)
			(xy 358.26931 1.508412) (xy 358.350734 1.393656) (xy 358.425597 1.274514) (xy 358.493661 1.151363)
			(xy 358.554712 1.024589) (xy 358.60856 0.894591) (xy 358.655033 0.761778) (xy 358.693987 0.626568)
			(xy 358.725298 0.489387) (xy 358.748868 0.350666) (xy 358.764622 0.210842) (xy 358.772512 0.070354)
			(xy 358.772968 0) (xy 358.772968 -8.850122) (xy 358.773491 -8.905929) (xy 358.781833 -9.017231) (xy 358.798469 -9.127598)
			(xy 358.823307 -9.236413) (xy 358.856206 -9.343068) (xy 358.896984 -9.446967) (xy 358.945412 -9.547527)
			(xy 359.001219 -9.644188) (xy 359.064093 -9.736408) (xy 359.133684 -9.823671) (xy 359.2096 -9.90549)
			(xy 359.291418 -9.981407) (xy 359.378681 -10.050998) (xy 359.4709 -10.113873) (xy 359.56756 -10.169682)
			(xy 359.66812 -10.21811) (xy 359.772018 -10.258889) (xy 359.878673 -10.29179) (xy 359.987488 -10.316628)
			(xy 360.097855 -10.333266) (xy 360.209157 -10.341609) (xy 360.264964 -10.342118) (xy 362.26496 -10.342118)
			(xy 362.320769 -10.34161) (xy 362.432074 -10.333272) (xy 362.542446 -10.316639) (xy 362.651265 -10.291805)
			(xy 362.757925 -10.258907) (xy 362.861827 -10.218131) (xy 362.962393 -10.169705) (xy 363.059057 -10.113898)
			(xy 363.151281 -10.051024) (xy 363.238549 -9.981433) (xy 363.320372 -9.905516) (xy 363.396293 -9.823696)
			(xy 363.465887 -9.736431) (xy 363.528765 -9.64421) (xy 363.584576 -9.547547) (xy 363.633007 -9.446984)
			(xy 363.673787 -9.343083) (xy 363.706689 -9.236425) (xy 363.731528 -9.127607) (xy 363.748165 -9.017236)
			(xy 363.756508 -8.905931) (xy 363.756956 -8.850122) (xy 363.756956 0) (xy 363.757449 0.070354) (xy 363.765339 0.210841)
			(xy 363.781093 0.350665) (xy 363.804662 0.489386) (xy 363.835972 0.626566) (xy 363.874925 0.761776)
			(xy 363.921398 0.894588) (xy 363.975244 1.024586) (xy 364.036294 1.15136) (xy 364.104357 1.274512)
			(xy 364.179217 1.393654) (xy 364.26064 1.508411) (xy 364.34837 1.618422) (xy 364.442129 1.723341)
			(xy 364.541624 1.822838) (xy 364.646542 1.916599) (xy 364.756551 2.004331) (xy 364.871306 2.085756)
			(xy 364.990447 2.160619) (xy 365.113597 2.228684) (xy 365.24037 2.289737) (xy 365.370367 2.343585)
			(xy 365.503179 2.39006) (xy 365.638387 2.429016) (xy 365.775567 2.460328) (xy 365.914287 2.4839)
			(xy 366.054111 2.499657) (xy 366.194598 2.507549) (xy 366.264952 2.507996) (xy 382.26492 2.507996)
			(xy 382.335273 2.507502) (xy 382.475759 2.499612) (xy 382.615581 2.483856) (xy 382.754299 2.460286)
			(xy 382.891478 2.428975) (xy 383.026685 2.390022) (xy 383.159496 2.343548) (xy 383.289491 2.289701)
			(xy 383.416264 2.22865) (xy 383.539413 2.160587) (xy 383.658552 2.085726) (xy 383.773307 2.004302)
			(xy 383.883316 1.916573) (xy 383.988232 1.822813) (xy 384.087726 1.723318) (xy 384.181485 1.6184)
			(xy 384.269214 1.508391) (xy 384.350637 1.393636) (xy 384.425497 1.274496) (xy 384.493559 1.151346)
			(xy 384.554609 1.024573) (xy 384.608455 0.894577) (xy 384.654928 0.761766) (xy 384.69388 0.626559)
			(xy 384.72519 0.48938) (xy 384.748759 0.350661) (xy 384.764513 0.210839) (xy 384.772403 0.070353)
			(xy 384.772916 0) (xy 384.772916 -8.850122) (xy 384.773439 -8.905928) (xy 384.781781 -9.017229) (xy 384.798418 -9.127595)
			(xy 384.823255 -9.236409) (xy 384.856155 -9.343062) (xy 384.896933 -9.446959) (xy 384.945361 -9.547518)
			(xy 385.001169 -9.644177) (xy 385.064044 -9.736395) (xy 385.133634 -9.823656) (xy 385.209551 -9.905473)
			(xy 385.29137 -9.981388) (xy 385.378633 -10.050977) (xy 385.470852 -10.113849) (xy 385.567512 -10.169655)
			(xy 385.668072 -10.218081) (xy 385.77197 -10.258856) (xy 385.878624 -10.291754) (xy 385.987439 -10.316589)
			(xy 386.097805 -10.333223) (xy 386.209106 -10.341563) (xy 386.264912 -10.342118) (xy 388.264908 -10.342118)
			(xy 388.320715 -10.341596) (xy 388.432017 -10.333255) (xy 388.542385 -10.316619) (xy 388.651201 -10.291782)
			(xy 388.757856 -10.258883) (xy 388.861755 -10.218106) (xy 388.962316 -10.169678) (xy 389.058977 -10.113871)
			(xy 389.151197 -10.050997) (xy 389.238461 -9.981407) (xy 389.32028 -9.90549) (xy 389.396198 -9.823671)
			(xy 389.465789 -9.736408) (xy 389.528664 -9.644189) (xy 389.584472 -9.547528) (xy 389.6329 -9.446968)
			(xy 389.673678 -9.343069) (xy 389.706579 -9.236414) (xy 389.731416 -9.127599) (xy 389.748053 -9.017231)
			(xy 389.756395 -8.905929) (xy 389.756904 -8.850122) (xy 389.756904 0) (xy 389.757397 0.070354) (xy 389.765287 0.21084)
			(xy 389.781041 0.350663) (xy 389.80461 0.489382) (xy 389.835921 0.626562) (xy 389.874874 0.76177)
			(xy 389.921346 0.894581) (xy 389.975193 1.024578) (xy 390.036243 1.151351) (xy 390.104306 1.274502)
			(xy 390.179167 1.393642) (xy 390.260591 1.508398) (xy 390.34832 1.618407) (xy 390.44208 1.723325)
			(xy 390.541575 1.82282) (xy 390.646493 1.91658) (xy 390.756502 2.004309) (xy 390.871258 2.085733)
			(xy 390.990398 2.160594) (xy 391.113549 2.228657) (xy 391.240322 2.289707) (xy 391.370319 2.343554)
			(xy 391.50313 2.390026) (xy 391.638338 2.428979) (xy 391.775518 2.46029) (xy 391.914237 2.483859)
			(xy 392.05406 2.499613) (xy 392.194546 2.507503) (xy 392.2649 2.507996) (xy 408.265122 2.507996)
			(xy 408.335475 2.507502) (xy 408.475961 2.499611) (xy 408.615782 2.483856) (xy 408.754501 2.460286)
			(xy 408.89168 2.428975) (xy 409.026887 2.390021) (xy 409.159697 2.343548) (xy 409.289693 2.289701)
			(xy 409.416465 2.22865) (xy 409.539614 2.160586) (xy 409.658754 2.085725) (xy 409.773508 2.004302)
			(xy 409.883516 1.916572) (xy 409.988433 1.822812) (xy 410.087927 1.723317) (xy 410.181686 1.6184)
			(xy 410.269415 1.50839) (xy 410.350837 1.393635) (xy 410.425697 1.274495) (xy 410.49376 1.151345)
			(xy 410.55481 1.024573) (xy 410.608655 0.894577) (xy 410.655128 0.761766) (xy 410.69408 0.626558)
			(xy 410.72539 0.489379) (xy 410.748959 0.350661) (xy 410.764713 0.210839) (xy 410.772603 0.070353)
			(xy 410.773118 0) (xy 410.773118 -8.850122) (xy 410.773641 -8.905928) (xy 410.781983 -9.017229) (xy 410.79862 -9.127595)
			(xy 410.823457 -9.236408) (xy 410.856357 -9.343062) (xy 410.897135 -9.446959) (xy 410.945563 -9.547518)
			(xy 411.001371 -9.644176) (xy 411.064246 -9.736394) (xy 411.133836 -9.823656) (xy 411.209753 -9.905472)
			(xy 411.291572 -9.981387) (xy 411.378835 -10.050976) (xy 411.471054 -10.113848) (xy 411.567714 -10.169653)
			(xy 411.668274 -10.218079) (xy 411.772172 -10.258855) (xy 411.878826 -10.291752) (xy 411.987641 -10.316587)
			(xy 412.098007 -10.333221) (xy 412.209308 -10.341561) (xy 412.265114 -10.342118) (xy 414.26511 -10.342118)
			(xy 414.320917 -10.341596) (xy 414.432219 -10.333254) (xy 414.542587 -10.316619) (xy 414.651402 -10.291782)
			(xy 414.758058 -10.258883) (xy 414.861956 -10.218105) (xy 414.962517 -10.169678) (xy 415.059178 -10.11387)
			(xy 415.151398 -10.050996) (xy 415.238662 -9.981406) (xy 415.320481 -9.905489) (xy 415.396398 -9.823671)
			(xy 415.465989 -9.736408) (xy 415.528864 -9.644188) (xy 415.584672 -9.547528) (xy 415.6331 -9.446967)
			(xy 415.673879 -9.343069) (xy 415.706779 -9.236414) (xy 415.731616 -9.127598) (xy 415.748253 -9.017231)
			(xy 415.756595 -8.905929) (xy 415.757106 -8.850122) (xy 415.757106 0) (xy 415.75759 0.070354) (xy 415.76548 0.210841)
			(xy 415.781234 0.350664) (xy 415.804804 0.489384) (xy 415.836114 0.626564) (xy 415.875067 0.761772)
			(xy 415.92154 0.894584) (xy 415.975387 1.024581) (xy 416.036438 1.151355) (xy 416.104501 1.274506)
			(xy 416.179362 1.393647) (xy 416.260785 1.508402) (xy 416.348515 1.618412) (xy 416.442276 1.72333)
			(xy 416.541771 1.822826) (xy 416.646689 1.916586) (xy 416.756699 2.004316) (xy 416.871455 2.085739)
			(xy 416.990596 2.1606) (xy 417.113747 2.228663) (xy 417.24052 2.289714) (xy 417.370518 2.343561)
			(xy 417.503329 2.390034) (xy 417.638538 2.428986) (xy 417.775718 2.460297) (xy 417.914438 2.483866)
			(xy 418.054261 2.49962) (xy 418.194748 2.50751) (xy 418.265102 2.507996) (xy 434.26507 2.507996)
			(xy 434.335425 2.507513) (xy 434.475912 2.499625) (xy 434.615737 2.483872) (xy 434.754458 2.460304)
			(xy 434.89164 2.428994) (xy 435.02685 2.390042) (xy 435.159663 2.34357) (xy 435.289662 2.289724)
			(xy 435.416437 2.228674) (xy 435.539589 2.160612) (xy 435.658732 2.085751) (xy 435.773489 2.004327)
			(xy 435.8835 1.916597) (xy 435.988419 1.822837) (xy 436.087916 1.723341) (xy 436.181678 1.618423)
			(xy 436.269409 1.508413) (xy 436.350834 1.393656) (xy 436.425696 1.274515) (xy 436.49376 1.151363)
			(xy 436.554812 1.024589) (xy 436.60866 0.894591) (xy 436.655133 0.761778) (xy 436.694087 0.626569)
			(xy 436.725398 0.489387) (xy 436.748967 0.350667) (xy 436.764722 0.210842) (xy 436.772612 0.070355)
			(xy 436.773066 0) (xy 436.773066 -8.850122) (xy 436.773589 -8.905929) (xy 436.781931 -9.017231) (xy 436.798567 -9.127598)
			(xy 436.823405 -9.236414) (xy 436.856304 -9.343069) (xy 436.897082 -9.446967) (xy 436.94551 -9.547528)
			(xy 437.001317 -9.644188) (xy 437.064191 -9.736408) (xy 437.133781 -9.823672) (xy 437.209698 -9.905491)
			(xy 437.291516 -9.981408) (xy 437.378779 -10.050999) (xy 437.470998 -10.113874) (xy 437.567658 -10.169683)
			(xy 437.668218 -10.218112) (xy 437.772116 -10.25889) (xy 437.878771 -10.291791) (xy 437.987586 -10.31663)
			(xy 438.097953 -10.333267) (xy 438.209255 -10.341611) (xy 438.265062 -10.342118) (xy 440.265058 -10.342118)
			(xy 440.320867 -10.34161) (xy 440.432173 -10.333272) (xy 440.542544 -10.316639) (xy 440.651364 -10.291805)
			(xy 440.758023 -10.258908) (xy 440.861926 -10.218132) (xy 440.962491 -10.169705) (xy 441.059156 -10.113899)
			(xy 441.151381 -10.051025) (xy 441.238648 -9.981434) (xy 441.320471 -9.905517) (xy 441.396392 -9.823697)
			(xy 441.465987 -9.736432) (xy 441.528865 -9.64421) (xy 441.584675 -9.547548) (xy 441.633106 -9.446985)
			(xy 441.673887 -9.343084) (xy 441.706788 -9.236425) (xy 441.731628 -9.127607) (xy 441.748265 -9.017236)
			(xy 441.756608 -8.905931) (xy 441.757054 -8.850122) (xy 441.757054 0) (xy 441.757538 0.070353) (xy 441.765428 0.210839)
			(xy 441.781182 0.350661) (xy 441.804752 0.48938) (xy 441.836062 0.626559) (xy 441.875016 0.761767)
			(xy 441.921489 0.894578) (xy 441.975336 1.024574) (xy 442.036387 1.151346) (xy 442.10445 1.274495)
			(xy 442.179312 1.393635) (xy 442.260736 1.508389) (xy 442.348466 1.618398) (xy 442.442227 1.723314)
			(xy 442.541722 1.822808) (xy 442.64664 1.916566) (xy 442.756651 2.004294) (xy 442.871407 2.085716)
			(xy 442.990548 2.160575) (xy 443.113699 2.228636) (xy 443.240472 2.289685) (xy 443.370469 2.343529)
			(xy 443.503281 2.39) (xy 443.638489 2.42895) (xy 443.775669 2.460258) (xy 443.914388 2.483825) (xy 444.054211 2.499576)
			(xy 444.194697 2.507463) (xy 444.26505 2.507996) (xy 465.600034 2.507996) (xy 465.65584 2.508519)
			(xy 465.767141 2.516862) (xy 465.877506 2.533499) (xy 465.98632 2.558338) (xy 466.092974 2.591238)
			(xy 466.19687 2.632016) (xy 466.297429 2.680445) (xy 466.394088 2.736252) (xy 466.486306 2.799127)
			(xy 466.573567 2.868717) (xy 466.655384 2.944634) (xy 466.7313 3.026452) (xy 466.800888 3.113715)
			(xy 466.863762 3.205934) (xy 466.919568 3.302594) (xy 466.967994 3.403154) (xy 467.008771 3.507051)
			(xy 467.041669 3.613705) (xy 467.066505 3.722519) (xy 467.083141 3.832885) (xy 467.091482 3.944186)
			(xy 467.09203 3.999992) (xy 467.09203 24.157686) (xy 467.091509 24.213494) (xy 467.083169 24.324797)
			(xy 467.066535 24.435167) (xy 467.041699 24.543984) (xy 467.008801 24.650641) (xy 466.968025 24.754542)
			(xy 466.919598 24.855105) (xy 466.863791 24.951768) (xy 466.800917 25.04399) (xy 466.731327 25.131255)
			(xy 466.655411 25.213077) (xy 466.573592 25.288996) (xy 466.486328 25.358589) (xy 466.394108 25.421466)
			(xy 466.297447 25.477275) (xy 466.196886 25.525705) (xy 466.092987 25.566485) (xy 465.986331 25.599387)
			(xy 465.877514 25.624226) (xy 465.767145 25.640863) (xy 465.655842 25.649207) (xy 465.600034 25.649682)
			(xy 160.11398 25.649682) (xy 160.058174 25.64916) (xy 159.946873 25.640817) (xy 159.836507 25.624181)
			(xy 159.727693 25.599343) (xy 159.62104 25.566443) (xy 159.517143 25.525665) (xy 159.416584 25.477237)
			(xy 159.319925 25.42143) (xy 159.227707 25.358555) (xy 159.140445 25.288965) (xy 159.058628 25.213048)
			(xy 158.982713 25.131229) (xy 158.913125 25.043966) (xy 158.850252 24.951746) (xy 158.794447 24.855086)
			(xy 158.746021 24.754526) (xy 158.705245 24.650628) (xy 158.672348 24.543974) (xy 158.647513 24.435159)
			(xy 158.630879 24.324793) (xy 158.622539 24.213492) (xy 158.621984 24.157686) (xy 158.621984 21.802649)
			(xy 269.304757 21.802649) (xy 269.304757 21.888399) (xy 269.312669 21.973782) (xy 269.328425 22.058072)
			(xy 269.351892 22.140548) (xy 269.382868 22.220507) (xy 269.42109 22.297267) (xy 269.466231 22.370173)
			(xy 269.517907 22.438602) (xy 269.575676 22.501972) (xy 269.639046 22.559741) (xy 269.707475 22.611417)
			(xy 269.780381 22.656558) (xy 269.857141 22.69478) (xy 269.9371 22.725756) (xy 270.019576 22.749223)
			(xy 270.103866 22.764979) (xy 270.189249 22.772891) (xy 270.274999 22.772891) (xy 270.360382 22.764979)
			(xy 270.444672 22.749223) (xy 270.527148 22.725756) (xy 270.607107 22.69478) (xy 270.683867 22.656558)
			(xy 270.756773 22.611417) (xy 270.825202 22.559741) (xy 270.888572 22.501972) (xy 270.946341 22.438602)
			(xy 270.998017 22.370173) (xy 271.043158 22.297267) (xy 271.08138 22.220507) (xy 271.112356 22.140548)
			(xy 271.135823 22.058072) (xy 271.151579 21.973782) (xy 271.159491 21.888399) (xy 271.159986 21.845524)
			(xy 271.159491 21.802649) (xy 275.654757 21.802649) (xy 275.654757 21.888399) (xy 275.662669 21.973782)
			(xy 275.678425 22.058072) (xy 275.701892 22.140548) (xy 275.732868 22.220507) (xy 275.77109 22.297267)
			(xy 275.816231 22.370173) (xy 275.867907 22.438602) (xy 275.925676 22.501972) (xy 275.989046 22.559741)
			(xy 276.057475 22.611417) (xy 276.130381 22.656558) (xy 276.207141 22.69478) (xy 276.2871 22.725756)
			(xy 276.369576 22.749223) (xy 276.453866 22.764979) (xy 276.539249 22.772891) (xy 276.624999 22.772891)
			(xy 276.710382 22.764979) (xy 276.794672 22.749223) (xy 276.877148 22.725756) (xy 276.957107 22.69478)
			(xy 277.033867 22.656558) (xy 277.106773 22.611417) (xy 277.175202 22.559741) (xy 277.238572 22.501972)
			(xy 277.296341 22.438602) (xy 277.348017 22.370173) (xy 277.393158 22.297267) (xy 277.43138 22.220507)
			(xy 277.462356 22.140548) (xy 277.485823 22.058072) (xy 277.501579 21.973782) (xy 277.509491 21.888399)
			(xy 277.509986 21.845524) (xy 277.509491 21.802649) (xy 277.508832 21.795537) (xy 308.364877 21.795537)
			(xy 308.364877 21.881287) (xy 308.372789 21.96667) (xy 308.388545 22.05096) (xy 308.412012 22.133436)
			(xy 308.442988 22.213395) (xy 308.48121 22.290155) (xy 308.526351 22.363061) (xy 308.578027 22.43149)
			(xy 308.635796 22.49486) (xy 308.699166 22.552629) (xy 308.767595 22.604305) (xy 308.840501 22.649446)
			(xy 308.917261 22.687668) (xy 308.99722 22.718644) (xy 309.079696 22.742111) (xy 309.163986 22.757867)
			(xy 309.249369 22.765779) (xy 309.335119 22.765779) (xy 309.420502 22.757867) (xy 309.504792 22.742111)
			(xy 309.587268 22.718644) (xy 309.667227 22.687668) (xy 309.743987 22.649446) (xy 309.816893 22.604305)
			(xy 309.885322 22.552629) (xy 309.948692 22.49486) (xy 310.006461 22.43149) (xy 310.058137 22.363061)
			(xy 310.103278 22.290155) (xy 310.1415 22.213395) (xy 310.172476 22.133436) (xy 310.195943 22.05096)
			(xy 310.211699 21.96667) (xy 310.219611 21.881287) (xy 310.220106 21.838412) (xy 310.219611 21.795537)
			(xy 314.714877 21.795537) (xy 314.714877 21.881287) (xy 314.722789 21.96667) (xy 314.738545 22.05096)
			(xy 314.762012 22.133436) (xy 314.792988 22.213395) (xy 314.83121 22.290155) (xy 314.876351 22.363061)
			(xy 314.928027 22.43149) (xy 314.985796 22.49486) (xy 315.049166 22.552629) (xy 315.117595 22.604305)
			(xy 315.190501 22.649446) (xy 315.267261 22.687668) (xy 315.34722 22.718644) (xy 315.429696 22.742111)
			(xy 315.513986 22.757867) (xy 315.599369 22.765779) (xy 315.685119 22.765779) (xy 315.770502 22.757867)
			(xy 315.854792 22.742111) (xy 315.937268 22.718644) (xy 316.017227 22.687668) (xy 316.093987 22.649446)
			(xy 316.166893 22.604305) (xy 316.235322 22.552629) (xy 316.298692 22.49486) (xy 316.356461 22.43149)
			(xy 316.408137 22.363061) (xy 316.453278 22.290155) (xy 316.4915 22.213395) (xy 316.522476 22.133436)
			(xy 316.545943 22.05096) (xy 316.561699 21.96667) (xy 316.569611 21.881287) (xy 316.570106 21.838412)
			(xy 316.569693 21.802649) (xy 334.455757 21.802649) (xy 334.455757 21.888399) (xy 334.463669 21.973782)
			(xy 334.479425 22.058072) (xy 334.502892 22.140548) (xy 334.533868 22.220507) (xy 334.57209 22.297267)
			(xy 334.617231 22.370173) (xy 334.668907 22.438602) (xy 334.726676 22.501972) (xy 334.790046 22.559741)
			(xy 334.858475 22.611417) (xy 334.931381 22.656558) (xy 335.008141 22.69478) (xy 335.0881 22.725756)
			(xy 335.170576 22.749223) (xy 335.254866 22.764979) (xy 335.340249 22.772891) (xy 335.425999 22.772891)
			(xy 335.511382 22.764979) (xy 335.595672 22.749223) (xy 335.678148 22.725756) (xy 335.758107 22.69478)
			(xy 335.834867 22.656558) (xy 335.907773 22.611417) (xy 335.976202 22.559741) (xy 336.039572 22.501972)
			(xy 336.097341 22.438602) (xy 336.149017 22.370173) (xy 336.194158 22.297267) (xy 336.23238 22.220507)
			(xy 336.263356 22.140548) (xy 336.286823 22.058072) (xy 336.302579 21.973782) (xy 336.310491 21.888399)
			(xy 336.310986 21.845524) (xy 336.310491 21.802649) (xy 340.805757 21.802649) (xy 340.805757 21.888399)
			(xy 340.813669 21.973782) (xy 340.829425 22.058072) (xy 340.852892 22.140548) (xy 340.883868 22.220507)
			(xy 340.92209 22.297267) (xy 340.967231 22.370173) (xy 341.018907 22.438602) (xy 341.076676 22.501972)
			(xy 341.140046 22.559741) (xy 341.208475 22.611417) (xy 341.281381 22.656558) (xy 341.358141 22.69478)
			(xy 341.4381 22.725756) (xy 341.520576 22.749223) (xy 341.604866 22.764979) (xy 341.690249 22.772891)
			(xy 341.775999 22.772891) (xy 341.861382 22.764979) (xy 341.945672 22.749223) (xy 342.028148 22.725756)
			(xy 342.108107 22.69478) (xy 342.184867 22.656558) (xy 342.257773 22.611417) (xy 342.326202 22.559741)
			(xy 342.389572 22.501972) (xy 342.447341 22.438602) (xy 342.499017 22.370173) (xy 342.544158 22.297267)
			(xy 342.58238 22.220507) (xy 342.613356 22.140548) (xy 342.636823 22.058072) (xy 342.652579 21.973782)
			(xy 342.660491 21.888399) (xy 342.660986 21.845524) (xy 342.660491 21.802649) (xy 342.659832 21.795537)
			(xy 373.515877 21.795537) (xy 373.515877 21.881287) (xy 373.523789 21.96667) (xy 373.539545 22.05096)
			(xy 373.563012 22.133436) (xy 373.593988 22.213395) (xy 373.63221 22.290155) (xy 373.677351 22.363061)
			(xy 373.729027 22.43149) (xy 373.786796 22.49486) (xy 373.850166 22.552629) (xy 373.918595 22.604305)
			(xy 373.991501 22.649446) (xy 374.068261 22.687668) (xy 374.14822 22.718644) (xy 374.230696 22.742111)
			(xy 374.314986 22.757867) (xy 374.400369 22.765779) (xy 374.486119 22.765779) (xy 374.571502 22.757867)
			(xy 374.655792 22.742111) (xy 374.738268 22.718644) (xy 374.818227 22.687668) (xy 374.894987 22.649446)
			(xy 374.967893 22.604305) (xy 375.036322 22.552629) (xy 375.099692 22.49486) (xy 375.157461 22.43149)
			(xy 375.209137 22.363061) (xy 375.254278 22.290155) (xy 375.2925 22.213395) (xy 375.323476 22.133436)
			(xy 375.346943 22.05096) (xy 375.362699 21.96667) (xy 375.370611 21.881287) (xy 375.371106 21.838412)
			(xy 375.370611 21.795537) (xy 379.865877 21.795537) (xy 379.865877 21.881287) (xy 379.873789 21.96667)
			(xy 379.889545 22.05096) (xy 379.913012 22.133436) (xy 379.943988 22.213395) (xy 379.98221 22.290155)
			(xy 380.027351 22.363061) (xy 380.079027 22.43149) (xy 380.136796 22.49486) (xy 380.200166 22.552629)
			(xy 380.268595 22.604305) (xy 380.341501 22.649446) (xy 380.418261 22.687668) (xy 380.49822 22.718644)
			(xy 380.580696 22.742111) (xy 380.664986 22.757867) (xy 380.750369 22.765779) (xy 380.836119 22.765779)
			(xy 380.921502 22.757867) (xy 381.005792 22.742111) (xy 381.088268 22.718644) (xy 381.168227 22.687668)
			(xy 381.244987 22.649446) (xy 381.317893 22.604305) (xy 381.386322 22.552629) (xy 381.449692 22.49486)
			(xy 381.507461 22.43149) (xy 381.559137 22.363061) (xy 381.604278 22.290155) (xy 381.6425 22.213395)
			(xy 381.673476 22.133436) (xy 381.696943 22.05096) (xy 381.712699 21.96667) (xy 381.720611 21.881287)
			(xy 381.721106 21.838412) (xy 381.720693 21.802649) (xy 399.098757 21.802649) (xy 399.098757 21.888399)
			(xy 399.106669 21.973782) (xy 399.122425 22.058072) (xy 399.145892 22.140548) (xy 399.176868 22.220507)
			(xy 399.21509 22.297267) (xy 399.260231 22.370173) (xy 399.311907 22.438602) (xy 399.369676 22.501972)
			(xy 399.433046 22.559741) (xy 399.501475 22.611417) (xy 399.574381 22.656558) (xy 399.651141 22.69478)
			(xy 399.7311 22.725756) (xy 399.813576 22.749223) (xy 399.897866 22.764979) (xy 399.983249 22.772891)
			(xy 400.068999 22.772891) (xy 400.154382 22.764979) (xy 400.238672 22.749223) (xy 400.321148 22.725756)
			(xy 400.401107 22.69478) (xy 400.477867 22.656558) (xy 400.550773 22.611417) (xy 400.619202 22.559741)
			(xy 400.682572 22.501972) (xy 400.740341 22.438602) (xy 400.792017 22.370173) (xy 400.837158 22.297267)
			(xy 400.87538 22.220507) (xy 400.906356 22.140548) (xy 400.929823 22.058072) (xy 400.945579 21.973782)
			(xy 400.953491 21.888399) (xy 400.953986 21.845524) (xy 400.953491 21.802649) (xy 405.448757 21.802649)
			(xy 405.448757 21.888399) (xy 405.456669 21.973782) (xy 405.472425 22.058072) (xy 405.495892 22.140548)
			(xy 405.526868 22.220507) (xy 405.56509 22.297267) (xy 405.610231 22.370173) (xy 405.661907 22.438602)
			(xy 405.719676 22.501972) (xy 405.783046 22.559741) (xy 405.851475 22.611417) (xy 405.924381 22.656558)
			(xy 406.001141 22.69478) (xy 406.0811 22.725756) (xy 406.163576 22.749223) (xy 406.247866 22.764979)
			(xy 406.333249 22.772891) (xy 406.418999 22.772891) (xy 406.504382 22.764979) (xy 406.588672 22.749223)
			(xy 406.671148 22.725756) (xy 406.751107 22.69478) (xy 406.827867 22.656558) (xy 406.900773 22.611417)
			(xy 406.969202 22.559741) (xy 407.032572 22.501972) (xy 407.090341 22.438602) (xy 407.142017 22.370173)
			(xy 407.187158 22.297267) (xy 407.22538 22.220507) (xy 407.256356 22.140548) (xy 407.279823 22.058072)
			(xy 407.295579 21.973782) (xy 407.303491 21.888399) (xy 407.303986 21.845524) (xy 407.303491 21.802649)
			(xy 407.302832 21.795537) (xy 438.158877 21.795537) (xy 438.158877 21.881287) (xy 438.166789 21.96667)
			(xy 438.182545 22.05096) (xy 438.206012 22.133436) (xy 438.236988 22.213395) (xy 438.27521 22.290155)
			(xy 438.320351 22.363061) (xy 438.372027 22.43149) (xy 438.429796 22.49486) (xy 438.493166 22.552629)
			(xy 438.561595 22.604305) (xy 438.634501 22.649446) (xy 438.711261 22.687668) (xy 438.79122 22.718644)
			(xy 438.873696 22.742111) (xy 438.957986 22.757867) (xy 439.043369 22.765779) (xy 439.129119 22.765779)
			(xy 439.214502 22.757867) (xy 439.298792 22.742111) (xy 439.381268 22.718644) (xy 439.461227 22.687668)
			(xy 439.537987 22.649446) (xy 439.610893 22.604305) (xy 439.679322 22.552629) (xy 439.742692 22.49486)
			(xy 439.800461 22.43149) (xy 439.852137 22.363061) (xy 439.897278 22.290155) (xy 439.9355 22.213395)
			(xy 439.966476 22.133436) (xy 439.989943 22.05096) (xy 440.005699 21.96667) (xy 440.013611 21.881287)
			(xy 440.014106 21.838412) (xy 440.013611 21.795537) (xy 444.508877 21.795537) (xy 444.508877 21.881287)
			(xy 444.516789 21.96667) (xy 444.532545 22.05096) (xy 444.556012 22.133436) (xy 444.586988 22.213395)
			(xy 444.62521 22.290155) (xy 444.670351 22.363061) (xy 444.722027 22.43149) (xy 444.779796 22.49486)
			(xy 444.843166 22.552629) (xy 444.911595 22.604305) (xy 444.984501 22.649446) (xy 445.061261 22.687668)
			(xy 445.14122 22.718644) (xy 445.223696 22.742111) (xy 445.307986 22.757867) (xy 445.393369 22.765779)
			(xy 445.479119 22.765779) (xy 445.564502 22.757867) (xy 445.648792 22.742111) (xy 445.731268 22.718644)
			(xy 445.811227 22.687668) (xy 445.887987 22.649446) (xy 445.960893 22.604305) (xy 446.029322 22.552629)
			(xy 446.092692 22.49486) (xy 446.150461 22.43149) (xy 446.202137 22.363061) (xy 446.247278 22.290155)
			(xy 446.2855 22.213395) (xy 446.316476 22.133436) (xy 446.339943 22.05096) (xy 446.355699 21.96667)
			(xy 446.363611 21.881287) (xy 446.364106 21.838412) (xy 446.363611 21.795537) (xy 446.355699 21.710154)
			(xy 446.339943 21.625864) (xy 446.316476 21.543388) (xy 446.2855 21.463429) (xy 446.247278 21.386669)
			(xy 446.202137 21.313763) (xy 446.150461 21.245334) (xy 446.092692 21.181964) (xy 446.029322 21.124195)
			(xy 445.988175 21.093122) (xy 460.504275 21.093122) (xy 460.504275 21.222262) (xy 460.512225 21.351157)
			(xy 460.528095 21.479317) (xy 460.551824 21.606258) (xy 460.583323 21.731497) (xy 460.622472 21.85456)
			(xy 460.669123 21.974979) (xy 460.723098 22.092298) (xy 460.784193 22.206072) (xy 460.852176 22.315869)
			(xy 460.92679 22.421272) (xy 461.007751 22.521882) (xy 461.094751 22.617317) (xy 461.187462 22.707216)
			(xy 461.285532 22.791237) (xy 461.388587 22.869061) (xy 461.496238 22.940393) (xy 461.608077 23.004963)
			(xy 461.723678 23.062525) (xy 461.842603 23.112862) (xy 461.964402 23.155782) (xy 462.088612 23.191123)
			(xy 462.214761 23.21875) (xy 462.342373 23.238559) (xy 462.470962 23.250475) (xy 462.60004 23.254452)
			(xy 462.729118 23.250475) (xy 462.857707 23.238559) (xy 462.985319 23.21875) (xy 463.111468 23.191123)
			(xy 463.235678 23.155782) (xy 463.357477 23.112862) (xy 463.476402 23.062525) (xy 463.592003 23.004963)
			(xy 463.703842 22.940393) (xy 463.811493 22.869061) (xy 463.914548 22.791237) (xy 464.012618 22.707216)
			(xy 464.105329 22.617317) (xy 464.192329 22.521882) (xy 464.27329 22.421272) (xy 464.347904 22.315869)
			(xy 464.415887 22.206072) (xy 464.476982 22.092298) (xy 464.530957 21.974979) (xy 464.577608 21.85456)
			(xy 464.616757 21.731497) (xy 464.648256 21.606258) (xy 464.671985 21.479317) (xy 464.687855 21.351157)
			(xy 464.695805 21.222262) (xy 464.696302 21.157692) (xy 464.695805 21.093122) (xy 464.687855 20.964227)
			(xy 464.671985 20.836067) (xy 464.648256 20.709126) (xy 464.616757 20.583887) (xy 464.577608 20.460824)
			(xy 464.530957 20.340405) (xy 464.476982 20.223086) (xy 464.415887 20.109312) (xy 464.347904 19.999515)
			(xy 464.27329 19.894112) (xy 464.192329 19.793502) (xy 464.105329 19.698067) (xy 464.012618 19.608168)
			(xy 463.914548 19.524147) (xy 463.811493 19.446323) (xy 463.703842 19.374991) (xy 463.592003 19.310421)
			(xy 463.476402 19.252859) (xy 463.357477 19.202522) (xy 463.235678 19.159602) (xy 463.111468 19.124261)
			(xy 462.985319 19.096634) (xy 462.857707 19.076825) (xy 462.729118 19.064909) (xy 462.60004 19.060933)
			(xy 462.470962 19.064909) (xy 462.342373 19.076825) (xy 462.214761 19.096634) (xy 462.088612 19.124261)
			(xy 461.964402 19.159602) (xy 461.842603 19.202522) (xy 461.723678 19.252859) (xy 461.608077 19.310421)
			(xy 461.496238 19.374991) (xy 461.388587 19.446323) (xy 461.285532 19.524147) (xy 461.187462 19.608168)
			(xy 461.094751 19.698067) (xy 461.007751 19.793502) (xy 460.92679 19.894112) (xy 460.852176 19.999515)
			(xy 460.784193 20.109312) (xy 460.723098 20.223086) (xy 460.669123 20.340405) (xy 460.622472 20.460824)
			(xy 460.583323 20.583887) (xy 460.551824 20.709126) (xy 460.528095 20.836067) (xy 460.512225 20.964227)
			(xy 460.504275 21.093122) (xy 445.988175 21.093122) (xy 445.960893 21.072519) (xy 445.887987 21.027378)
			(xy 445.811227 20.989156) (xy 445.731268 20.95818) (xy 445.648792 20.934713) (xy 445.564502 20.918957)
			(xy 445.479119 20.911045) (xy 445.393369 20.911045) (xy 445.307986 20.918957) (xy 445.223696 20.934713)
			(xy 445.14122 20.95818) (xy 445.061261 20.989156) (xy 444.984501 21.027378) (xy 444.911595 21.072519)
			(xy 444.843166 21.124195) (xy 444.779796 21.181964) (xy 444.722027 21.245334) (xy 444.670351 21.313763)
			(xy 444.62521 21.386669) (xy 444.586988 21.463429) (xy 444.556012 21.543388) (xy 444.532545 21.625864)
			(xy 444.516789 21.710154) (xy 444.508877 21.795537) (xy 440.013611 21.795537) (xy 440.005699 21.710154)
			(xy 439.989943 21.625864) (xy 439.966476 21.543388) (xy 439.9355 21.463429) (xy 439.897278 21.386669)
			(xy 439.852137 21.313763) (xy 439.800461 21.245334) (xy 439.742692 21.181964) (xy 439.679322 21.124195)
			(xy 439.610893 21.072519) (xy 439.537987 21.027378) (xy 439.461227 20.989156) (xy 439.381268 20.95818)
			(xy 439.298792 20.934713) (xy 439.214502 20.918957) (xy 439.129119 20.911045) (xy 439.043369 20.911045)
			(xy 438.957986 20.918957) (xy 438.873696 20.934713) (xy 438.79122 20.95818) (xy 438.711261 20.989156)
			(xy 438.634501 21.027378) (xy 438.561595 21.072519) (xy 438.493166 21.124195) (xy 438.429796 21.181964)
			(xy 438.372027 21.245334) (xy 438.320351 21.313763) (xy 438.27521 21.386669) (xy 438.236988 21.463429)
			(xy 438.206012 21.543388) (xy 438.182545 21.625864) (xy 438.166789 21.710154) (xy 438.158877 21.795537)
			(xy 407.302832 21.795537) (xy 407.295579 21.717266) (xy 407.279823 21.632976) (xy 407.256356 21.5505)
			(xy 407.22538 21.470541) (xy 407.187158 21.393781) (xy 407.142017 21.320875) (xy 407.090341 21.252446)
			(xy 407.032572 21.189076) (xy 406.969202 21.131307) (xy 406.900773 21.079631) (xy 406.827867 21.03449)
			(xy 406.751107 20.996268) (xy 406.671148 20.965292) (xy 406.588672 20.941825) (xy 406.504382 20.926069)
			(xy 406.418999 20.918157) (xy 406.333249 20.918157) (xy 406.247866 20.926069) (xy 406.163576 20.941825)
			(xy 406.0811 20.965292) (xy 406.001141 20.996268) (xy 405.924381 21.03449) (xy 405.851475 21.079631)
			(xy 405.783046 21.131307) (xy 405.719676 21.189076) (xy 405.661907 21.252446) (xy 405.610231 21.320875)
			(xy 405.56509 21.393781) (xy 405.526868 21.470541) (xy 405.495892 21.5505) (xy 405.472425 21.632976)
			(xy 405.456669 21.717266) (xy 405.448757 21.802649) (xy 400.953491 21.802649) (xy 400.945579 21.717266)
			(xy 400.929823 21.632976) (xy 400.906356 21.5505) (xy 400.87538 21.470541) (xy 400.837158 21.393781)
			(xy 400.792017 21.320875) (xy 400.740341 21.252446) (xy 400.682572 21.189076) (xy 400.619202 21.131307)
			(xy 400.550773 21.079631) (xy 400.477867 21.03449) (xy 400.401107 20.996268) (xy 400.321148 20.965292)
			(xy 400.238672 20.941825) (xy 400.154382 20.926069) (xy 400.068999 20.918157) (xy 399.983249 20.918157)
			(xy 399.897866 20.926069) (xy 399.813576 20.941825) (xy 399.7311 20.965292) (xy 399.651141 20.996268)
			(xy 399.574381 21.03449) (xy 399.501475 21.079631) (xy 399.433046 21.131307) (xy 399.369676 21.189076)
			(xy 399.311907 21.252446) (xy 399.260231 21.320875) (xy 399.21509 21.393781) (xy 399.176868 21.470541)
			(xy 399.145892 21.5505) (xy 399.122425 21.632976) (xy 399.106669 21.717266) (xy 399.098757 21.802649)
			(xy 381.720693 21.802649) (xy 381.720611 21.795537) (xy 381.712699 21.710154) (xy 381.696943 21.625864)
			(xy 381.673476 21.543388) (xy 381.6425 21.463429) (xy 381.604278 21.386669) (xy 381.559137 21.313763)
			(xy 381.507461 21.245334) (xy 381.449692 21.181964) (xy 381.386322 21.124195) (xy 381.317893 21.072519)
			(xy 381.244987 21.027378) (xy 381.168227 20.989156) (xy 381.088268 20.95818) (xy 381.005792 20.934713)
			(xy 380.921502 20.918957) (xy 380.836119 20.911045) (xy 380.750369 20.911045) (xy 380.664986 20.918957)
			(xy 380.580696 20.934713) (xy 380.49822 20.95818) (xy 380.418261 20.989156) (xy 380.341501 21.027378)
			(xy 380.268595 21.072519) (xy 380.200166 21.124195) (xy 380.136796 21.181964) (xy 380.079027 21.245334)
			(xy 380.027351 21.313763) (xy 379.98221 21.386669) (xy 379.943988 21.463429) (xy 379.913012 21.543388)
			(xy 379.889545 21.625864) (xy 379.873789 21.710154) (xy 379.865877 21.795537) (xy 375.370611 21.795537)
			(xy 375.362699 21.710154) (xy 375.346943 21.625864) (xy 375.323476 21.543388) (xy 375.2925 21.463429)
			(xy 375.254278 21.386669) (xy 375.209137 21.313763) (xy 375.157461 21.245334) (xy 375.099692 21.181964)
			(xy 375.036322 21.124195) (xy 374.967893 21.072519) (xy 374.894987 21.027378) (xy 374.818227 20.989156)
			(xy 374.738268 20.95818) (xy 374.655792 20.934713) (xy 374.571502 20.918957) (xy 374.486119 20.911045)
			(xy 374.400369 20.911045) (xy 374.314986 20.918957) (xy 374.230696 20.934713) (xy 374.14822 20.95818)
			(xy 374.068261 20.989156) (xy 373.991501 21.027378) (xy 373.918595 21.072519) (xy 373.850166 21.124195)
			(xy 373.786796 21.181964) (xy 373.729027 21.245334) (xy 373.677351 21.313763) (xy 373.63221 21.386669)
			(xy 373.593988 21.463429) (xy 373.563012 21.543388) (xy 373.539545 21.625864) (xy 373.523789 21.710154)
			(xy 373.515877 21.795537) (xy 342.659832 21.795537) (xy 342.652579 21.717266) (xy 342.636823 21.632976)
			(xy 342.613356 21.5505) (xy 342.58238 21.470541) (xy 342.544158 21.393781) (xy 342.499017 21.320875)
			(xy 342.447341 21.252446) (xy 342.389572 21.189076) (xy 342.326202 21.131307) (xy 342.257773 21.079631)
			(xy 342.184867 21.03449) (xy 342.108107 20.996268) (xy 342.028148 20.965292) (xy 341.945672 20.941825)
			(xy 341.861382 20.926069) (xy 341.775999 20.918157) (xy 341.690249 20.918157) (xy 341.604866 20.926069)
			(xy 341.520576 20.941825) (xy 341.4381 20.965292) (xy 341.358141 20.996268) (xy 341.281381 21.03449)
			(xy 341.208475 21.079631) (xy 341.140046 21.131307) (xy 341.076676 21.189076) (xy 341.018907 21.252446)
			(xy 340.967231 21.320875) (xy 340.92209 21.393781) (xy 340.883868 21.470541) (xy 340.852892 21.5505)
			(xy 340.829425 21.632976) (xy 340.813669 21.717266) (xy 340.805757 21.802649) (xy 336.310491 21.802649)
			(xy 336.302579 21.717266) (xy 336.286823 21.632976) (xy 336.263356 21.5505) (xy 336.23238 21.470541)
			(xy 336.194158 21.393781) (xy 336.149017 21.320875) (xy 336.097341 21.252446) (xy 336.039572 21.189076)
			(xy 335.976202 21.131307) (xy 335.907773 21.079631) (xy 335.834867 21.03449) (xy 335.758107 20.996268)
			(xy 335.678148 20.965292) (xy 335.595672 20.941825) (xy 335.511382 20.926069) (xy 335.425999 20.918157)
			(xy 335.340249 20.918157) (xy 335.254866 20.926069) (xy 335.170576 20.941825) (xy 335.0881 20.965292)
			(xy 335.008141 20.996268) (xy 334.931381 21.03449) (xy 334.858475 21.079631) (xy 334.790046 21.131307)
			(xy 334.726676 21.189076) (xy 334.668907 21.252446) (xy 334.617231 21.320875) (xy 334.57209 21.393781)
			(xy 334.533868 21.470541) (xy 334.502892 21.5505) (xy 334.479425 21.632976) (xy 334.463669 21.717266)
			(xy 334.455757 21.802649) (xy 316.569693 21.802649) (xy 316.569611 21.795537) (xy 316.561699 21.710154)
			(xy 316.545943 21.625864) (xy 316.522476 21.543388) (xy 316.4915 21.463429) (xy 316.453278 21.386669)
			(xy 316.408137 21.313763) (xy 316.356461 21.245334) (xy 316.298692 21.181964) (xy 316.235322 21.124195)
			(xy 316.166893 21.072519) (xy 316.093987 21.027378) (xy 316.017227 20.989156) (xy 315.937268 20.95818)
			(xy 315.854792 20.934713) (xy 315.770502 20.918957) (xy 315.685119 20.911045) (xy 315.599369 20.911045)
			(xy 315.513986 20.918957) (xy 315.429696 20.934713) (xy 315.34722 20.95818) (xy 315.267261 20.989156)
			(xy 315.190501 21.027378) (xy 315.117595 21.072519) (xy 315.049166 21.124195) (xy 314.985796 21.181964)
			(xy 314.928027 21.245334) (xy 314.876351 21.313763) (xy 314.83121 21.386669) (xy 314.792988 21.463429)
			(xy 314.762012 21.543388) (xy 314.738545 21.625864) (xy 314.722789 21.710154) (xy 314.714877 21.795537)
			(xy 310.219611 21.795537) (xy 310.211699 21.710154) (xy 310.195943 21.625864) (xy 310.172476 21.543388)
			(xy 310.1415 21.463429) (xy 310.103278 21.386669) (xy 310.058137 21.313763) (xy 310.006461 21.245334)
			(xy 309.948692 21.181964) (xy 309.885322 21.124195) (xy 309.816893 21.072519) (xy 309.743987 21.027378)
			(xy 309.667227 20.989156) (xy 309.587268 20.95818) (xy 309.504792 20.934713) (xy 309.420502 20.918957)
			(xy 309.335119 20.911045) (xy 309.249369 20.911045) (xy 309.163986 20.918957) (xy 309.079696 20.934713)
			(xy 308.99722 20.95818) (xy 308.917261 20.989156) (xy 308.840501 21.027378) (xy 308.767595 21.072519)
			(xy 308.699166 21.124195) (xy 308.635796 21.181964) (xy 308.578027 21.245334) (xy 308.526351 21.313763)
			(xy 308.48121 21.386669) (xy 308.442988 21.463429) (xy 308.412012 21.543388) (xy 308.388545 21.625864)
			(xy 308.372789 21.710154) (xy 308.364877 21.795537) (xy 277.508832 21.795537) (xy 277.501579 21.717266)
			(xy 277.485823 21.632976) (xy 277.462356 21.5505) (xy 277.43138 21.470541) (xy 277.393158 21.393781)
			(xy 277.348017 21.320875) (xy 277.296341 21.252446) (xy 277.238572 21.189076) (xy 277.175202 21.131307)
			(xy 277.106773 21.079631) (xy 277.033867 21.03449) (xy 276.957107 20.996268) (xy 276.877148 20.965292)
			(xy 276.794672 20.941825) (xy 276.710382 20.926069) (xy 276.624999 20.918157) (xy 276.539249 20.918157)
			(xy 276.453866 20.926069) (xy 276.369576 20.941825) (xy 276.2871 20.965292) (xy 276.207141 20.996268)
			(xy 276.130381 21.03449) (xy 276.057475 21.079631) (xy 275.989046 21.131307) (xy 275.925676 21.189076)
			(xy 275.867907 21.252446) (xy 275.816231 21.320875) (xy 275.77109 21.393781) (xy 275.732868 21.470541)
			(xy 275.701892 21.5505) (xy 275.678425 21.632976) (xy 275.662669 21.717266) (xy 275.654757 21.802649)
			(xy 271.159491 21.802649) (xy 271.151579 21.717266) (xy 271.135823 21.632976) (xy 271.112356 21.5505)
			(xy 271.08138 21.470541) (xy 271.043158 21.393781) (xy 270.998017 21.320875) (xy 270.946341 21.252446)
			(xy 270.888572 21.189076) (xy 270.825202 21.131307) (xy 270.756773 21.079631) (xy 270.683867 21.03449)
			(xy 270.607107 20.996268) (xy 270.527148 20.965292) (xy 270.444672 20.941825) (xy 270.360382 20.926069)
			(xy 270.274999 20.918157) (xy 270.189249 20.918157) (xy 270.103866 20.926069) (xy 270.019576 20.941825)
			(xy 269.9371 20.965292) (xy 269.857141 20.996268) (xy 269.780381 21.03449) (xy 269.707475 21.079631)
			(xy 269.639046 21.131307) (xy 269.575676 21.189076) (xy 269.517907 21.252446) (xy 269.466231 21.320875)
			(xy 269.42109 21.393781) (xy 269.382868 21.470541) (xy 269.351892 21.5505) (xy 269.328425 21.632976)
			(xy 269.312669 21.717266) (xy 269.304757 21.802649) (xy 158.621984 21.802649) (xy 158.621984 19.262649)
			(xy 209.995757 19.262649) (xy 209.995757 19.348399) (xy 210.003669 19.433782) (xy 210.019425 19.518072)
			(xy 210.042892 19.600548) (xy 210.073868 19.680507) (xy 210.11209 19.757267) (xy 210.157231 19.830173)
			(xy 210.208907 19.898602) (xy 210.266676 19.961972) (xy 210.330046 20.019741) (xy 210.398475 20.071417)
			(xy 210.471381 20.116558) (xy 210.548141 20.15478) (xy 210.6281 20.185756) (xy 210.710576 20.209223)
			(xy 210.794866 20.224979) (xy 210.880249 20.232891) (xy 210.965999 20.232891) (xy 211.051382 20.224979)
			(xy 211.135672 20.209223) (xy 211.218148 20.185756) (xy 211.298107 20.15478) (xy 211.374867 20.116558)
			(xy 211.447773 20.071417) (xy 211.516202 20.019741) (xy 211.579572 19.961972) (xy 211.637341 19.898602)
			(xy 211.689017 19.830173) (xy 211.734158 19.757267) (xy 211.77238 19.680507) (xy 211.803356 19.600548)
			(xy 211.826823 19.518072) (xy 211.842579 19.433782) (xy 211.850491 19.348399) (xy 211.850986 19.305524)
			(xy 211.850491 19.262649) (xy 216.345757 19.262649) (xy 216.345757 19.348399) (xy 216.353669 19.433782)
			(xy 216.369425 19.518072) (xy 216.392892 19.600548) (xy 216.423868 19.680507) (xy 216.46209 19.757267)
			(xy 216.507231 19.830173) (xy 216.558907 19.898602) (xy 216.616676 19.961972) (xy 216.680046 20.019741)
			(xy 216.748475 20.071417) (xy 216.821381 20.116558) (xy 216.898141 20.15478) (xy 216.9781 20.185756)
			(xy 217.060576 20.209223) (xy 217.144866 20.224979) (xy 217.230249 20.232891) (xy 217.315999 20.232891)
			(xy 217.401382 20.224979) (xy 217.485672 20.209223) (xy 217.568148 20.185756) (xy 217.648107 20.15478)
			(xy 217.724867 20.116558) (xy 217.797773 20.071417) (xy 217.866202 20.019741) (xy 217.929572 19.961972)
			(xy 217.987341 19.898602) (xy 218.039017 19.830173) (xy 218.084158 19.757267) (xy 218.12238 19.680507)
			(xy 218.153356 19.600548) (xy 218.176823 19.518072) (xy 218.192579 19.433782) (xy 218.200491 19.348399)
			(xy 218.200986 19.305524) (xy 218.200491 19.262649) (xy 218.199832 19.255537) (xy 244.026677 19.255537)
			(xy 244.026677 19.341287) (xy 244.034589 19.42667) (xy 244.050345 19.51096) (xy 244.073812 19.593436)
			(xy 244.104788 19.673395) (xy 244.14301 19.750155) (xy 244.188151 19.823061) (xy 244.239827 19.89149)
			(xy 244.297596 19.95486) (xy 244.360966 20.012629) (xy 244.429395 20.064305) (xy 244.502301 20.109446)
			(xy 244.579061 20.147668) (xy 244.65902 20.178644) (xy 244.741496 20.202111) (xy 244.825786 20.217867)
			(xy 244.911169 20.225779) (xy 244.996919 20.225779) (xy 245.082302 20.217867) (xy 245.166592 20.202111)
			(xy 245.249068 20.178644) (xy 245.329027 20.147668) (xy 245.405787 20.109446) (xy 245.478693 20.064305)
			(xy 245.547122 20.012629) (xy 245.610492 19.95486) (xy 245.668261 19.89149) (xy 245.719937 19.823061)
			(xy 245.765078 19.750155) (xy 245.8033 19.673395) (xy 245.834276 19.593436) (xy 245.857743 19.51096)
			(xy 245.873499 19.42667) (xy 245.881411 19.341287) (xy 245.881906 19.298412) (xy 245.881411 19.255537)
			(xy 250.376677 19.255537) (xy 250.376677 19.341287) (xy 250.384589 19.42667) (xy 250.400345 19.51096)
			(xy 250.423812 19.593436) (xy 250.454788 19.673395) (xy 250.49301 19.750155) (xy 250.538151 19.823061)
			(xy 250.589827 19.89149) (xy 250.647596 19.95486) (xy 250.710966 20.012629) (xy 250.779395 20.064305)
			(xy 250.852301 20.109446) (xy 250.929061 20.147668) (xy 251.00902 20.178644) (xy 251.091496 20.202111)
			(xy 251.175786 20.217867) (xy 251.261169 20.225779) (xy 251.346919 20.225779) (xy 251.432302 20.217867)
			(xy 251.516592 20.202111) (xy 251.599068 20.178644) (xy 251.679027 20.147668) (xy 251.755787 20.109446)
			(xy 251.828693 20.064305) (xy 251.897122 20.012629) (xy 251.960492 19.95486) (xy 252.018261 19.89149)
			(xy 252.069937 19.823061) (xy 252.115078 19.750155) (xy 252.1533 19.673395) (xy 252.184276 19.593436)
			(xy 252.207743 19.51096) (xy 252.223499 19.42667) (xy 252.231411 19.341287) (xy 252.231906 19.298412)
			(xy 252.231493 19.262649) (xy 269.304757 19.262649) (xy 269.304757 19.348399) (xy 269.312669 19.433782)
			(xy 269.328425 19.518072) (xy 269.351892 19.600548) (xy 269.382868 19.680507) (xy 269.42109 19.757267)
			(xy 269.466231 19.830173) (xy 269.517907 19.898602) (xy 269.575676 19.961972) (xy 269.639046 20.019741)
			(xy 269.707475 20.071417) (xy 269.780381 20.116558) (xy 269.857141 20.15478) (xy 269.9371 20.185756)
			(xy 270.019576 20.209223) (xy 270.103866 20.224979) (xy 270.189249 20.232891) (xy 270.274999 20.232891)
			(xy 270.360382 20.224979) (xy 270.444672 20.209223) (xy 270.527148 20.185756) (xy 270.607107 20.15478)
			(xy 270.62931 20.143724) (xy 274.239736 20.143724) (xy 274.239736 21.007324) (xy 274.240222 21.034593)
			(xy 274.247984 21.088577) (xy 274.263349 21.140907) (xy 274.286006 21.190517) (xy 274.315492 21.236398)
			(xy 274.351207 21.277615) (xy 274.392424 21.31333) (xy 274.438305 21.342816) (xy 274.487915 21.365473)
			(xy 274.540245 21.380838) (xy 274.594229 21.3886) (xy 274.648767 21.3886) (xy 274.702751 21.380838)
			(xy 274.755081 21.365473) (xy 274.804691 21.342816) (xy 274.850572 21.31333) (xy 274.891789 21.277615)
			(xy 274.927504 21.236398) (xy 274.95699 21.190517) (xy 274.979647 21.140907) (xy 274.995012 21.088577)
			(xy 275.002774 21.034593) (xy 275.00326 21.007324) (xy 275.00326 20.143724) (xy 275.002774 20.116455)
			(xy 274.995012 20.062471) (xy 274.979647 20.010141) (xy 274.95699 19.960531) (xy 274.927504 19.91465)
			(xy 274.891789 19.873433) (xy 274.850572 19.837718) (xy 274.804691 19.808232) (xy 274.755081 19.785575)
			(xy 274.702751 19.77021) (xy 274.648767 19.762448) (xy 274.594229 19.762448) (xy 274.540245 19.77021)
			(xy 274.487915 19.785575) (xy 274.438305 19.808232) (xy 274.392424 19.837718) (xy 274.351207 19.873433)
			(xy 274.315492 19.91465) (xy 274.286006 19.960531) (xy 274.263349 20.010141) (xy 274.247984 20.062471)
			(xy 274.240222 20.116455) (xy 274.239736 20.143724) (xy 270.62931 20.143724) (xy 270.683867 20.116558)
			(xy 270.756773 20.071417) (xy 270.825202 20.019741) (xy 270.888572 19.961972) (xy 270.946341 19.898602)
			(xy 270.998017 19.830173) (xy 271.043158 19.757267) (xy 271.08138 19.680507) (xy 271.112356 19.600548)
			(xy 271.135823 19.518072) (xy 271.151579 19.433782) (xy 271.159491 19.348399) (xy 271.159986 19.305524)
			(xy 271.159491 19.262649) (xy 275.654757 19.262649) (xy 275.654757 19.348399) (xy 275.662669 19.433782)
			(xy 275.678425 19.518072) (xy 275.701892 19.600548) (xy 275.732868 19.680507) (xy 275.77109 19.757267)
			(xy 275.816231 19.830173) (xy 275.867907 19.898602) (xy 275.925676 19.961972) (xy 275.989046 20.019741)
			(xy 276.057475 20.071417) (xy 276.130381 20.116558) (xy 276.207141 20.15478) (xy 276.2871 20.185756)
			(xy 276.369576 20.209223) (xy 276.453866 20.224979) (xy 276.539249 20.232891) (xy 276.624999 20.232891)
			(xy 276.710382 20.224979) (xy 276.794672 20.209223) (xy 276.877148 20.185756) (xy 276.957107 20.15478)
			(xy 277.033867 20.116558) (xy 277.106773 20.071417) (xy 277.175202 20.019741) (xy 277.238572 19.961972)
			(xy 277.296341 19.898602) (xy 277.348017 19.830173) (xy 277.393158 19.757267) (xy 277.43138 19.680507)
			(xy 277.462356 19.600548) (xy 277.485823 19.518072) (xy 277.501579 19.433782) (xy 277.509491 19.348399)
			(xy 277.509986 19.305524) (xy 277.509491 19.262649) (xy 277.508832 19.255537) (xy 308.364877 19.255537)
			(xy 308.364877 19.341287) (xy 308.372789 19.42667) (xy 308.388545 19.51096) (xy 308.412012 19.593436)
			(xy 308.442988 19.673395) (xy 308.48121 19.750155) (xy 308.526351 19.823061) (xy 308.578027 19.89149)
			(xy 308.635796 19.95486) (xy 308.699166 20.012629) (xy 308.767595 20.064305) (xy 308.840501 20.109446)
			(xy 308.917261 20.147668) (xy 308.99722 20.178644) (xy 309.079696 20.202111) (xy 309.163986 20.217867)
			(xy 309.249369 20.225779) (xy 309.335119 20.225779) (xy 309.420502 20.217867) (xy 309.504792 20.202111)
			(xy 309.587268 20.178644) (xy 309.667227 20.147668) (xy 309.68943 20.136612) (xy 310.871108 20.136612)
			(xy 310.871108 21.000212) (xy 310.871594 21.027481) (xy 310.879356 21.081465) (xy 310.894721 21.133795)
			(xy 310.917378 21.183405) (xy 310.946864 21.229286) (xy 310.982579 21.270503) (xy 311.023796 21.306218)
			(xy 311.069677 21.335704) (xy 311.119287 21.358361) (xy 311.171617 21.373726) (xy 311.225601 21.381488)
			(xy 311.280139 21.381488) (xy 311.334123 21.373726) (xy 311.386453 21.358361) (xy 311.436063 21.335704)
			(xy 311.481944 21.306218) (xy 311.523161 21.270503) (xy 311.558876 21.229286) (xy 311.588362 21.183405)
			(xy 311.611019 21.133795) (xy 311.626384 21.081465) (xy 311.634146 21.027481) (xy 311.634632 21.000212)
			(xy 311.634632 20.136612) (xy 311.634146 20.109343) (xy 311.626384 20.055359) (xy 311.611019 20.003029)
			(xy 311.588362 19.953419) (xy 311.558876 19.907538) (xy 311.523161 19.866321) (xy 311.481944 19.830606)
			(xy 311.436063 19.80112) (xy 311.386453 19.778463) (xy 311.334123 19.763098) (xy 311.280139 19.755336)
			(xy 311.225601 19.755336) (xy 311.171617 19.763098) (xy 311.119287 19.778463) (xy 311.069677 19.80112)
			(xy 311.023796 19.830606) (xy 310.982579 19.866321) (xy 310.946864 19.907538) (xy 310.917378 19.953419)
			(xy 310.894721 20.003029) (xy 310.879356 20.055359) (xy 310.871594 20.109343) (xy 310.871108 20.136612)
			(xy 309.68943 20.136612) (xy 309.743987 20.109446) (xy 309.816893 20.064305) (xy 309.885322 20.012629)
			(xy 309.948692 19.95486) (xy 310.006461 19.89149) (xy 310.058137 19.823061) (xy 310.103278 19.750155)
			(xy 310.1415 19.673395) (xy 310.172476 19.593436) (xy 310.195943 19.51096) (xy 310.211699 19.42667)
			(xy 310.219611 19.341287) (xy 310.220106 19.298412) (xy 310.219611 19.255537) (xy 314.714877 19.255537)
			(xy 314.714877 19.341287) (xy 314.722789 19.42667) (xy 314.738545 19.51096) (xy 314.762012 19.593436)
			(xy 314.792988 19.673395) (xy 314.83121 19.750155) (xy 314.876351 19.823061) (xy 314.928027 19.89149)
			(xy 314.985796 19.95486) (xy 315.049166 20.012629) (xy 315.117595 20.064305) (xy 315.190501 20.109446)
			(xy 315.267261 20.147668) (xy 315.34722 20.178644) (xy 315.429696 20.202111) (xy 315.513986 20.217867)
			(xy 315.599369 20.225779) (xy 315.685119 20.225779) (xy 315.770502 20.217867) (xy 315.854792 20.202111)
			(xy 315.937268 20.178644) (xy 316.017227 20.147668) (xy 316.093987 20.109446) (xy 316.166893 20.064305)
			(xy 316.235322 20.012629) (xy 316.298692 19.95486) (xy 316.356461 19.89149) (xy 316.408137 19.823061)
			(xy 316.453278 19.750155) (xy 316.4915 19.673395) (xy 316.522476 19.593436) (xy 316.545943 19.51096)
			(xy 316.561699 19.42667) (xy 316.569611 19.341287) (xy 316.570106 19.298412) (xy 316.569693 19.262649)
			(xy 334.455757 19.262649) (xy 334.455757 19.348399) (xy 334.463669 19.433782) (xy 334.479425 19.518072)
			(xy 334.502892 19.600548) (xy 334.533868 19.680507) (xy 334.57209 19.757267) (xy 334.617231 19.830173)
			(xy 334.668907 19.898602) (xy 334.726676 19.961972) (xy 334.790046 20.019741) (xy 334.858475 20.071417)
			(xy 334.931381 20.116558) (xy 335.008141 20.15478) (xy 335.0881 20.185756) (xy 335.170576 20.209223)
			(xy 335.254866 20.224979) (xy 335.340249 20.232891) (xy 335.425999 20.232891) (xy 335.511382 20.224979)
			(xy 335.595672 20.209223) (xy 335.678148 20.185756) (xy 335.758107 20.15478) (xy 335.78031 20.143724)
			(xy 339.390736 20.143724) (xy 339.390736 21.007324) (xy 339.391222 21.034593) (xy 339.398984 21.088577)
			(xy 339.414349 21.140907) (xy 339.437006 21.190517) (xy 339.466492 21.236398) (xy 339.502207 21.277615)
			(xy 339.543424 21.31333) (xy 339.589305 21.342816) (xy 339.638915 21.365473) (xy 339.691245 21.380838)
			(xy 339.745229 21.3886) (xy 339.799767 21.3886) (xy 339.853751 21.380838) (xy 339.906081 21.365473)
			(xy 339.955691 21.342816) (xy 340.001572 21.31333) (xy 340.042789 21.277615) (xy 340.078504 21.236398)
			(xy 340.10799 21.190517) (xy 340.130647 21.140907) (xy 340.146012 21.088577) (xy 340.153774 21.034593)
			(xy 340.15426 21.007324) (xy 340.15426 20.143724) (xy 340.153774 20.116455) (xy 340.146012 20.062471)
			(xy 340.130647 20.010141) (xy 340.10799 19.960531) (xy 340.078504 19.91465) (xy 340.042789 19.873433)
			(xy 340.001572 19.837718) (xy 339.955691 19.808232) (xy 339.906081 19.785575) (xy 339.853751 19.77021)
			(xy 339.799767 19.762448) (xy 339.745229 19.762448) (xy 339.691245 19.77021) (xy 339.638915 19.785575)
			(xy 339.589305 19.808232) (xy 339.543424 19.837718) (xy 339.502207 19.873433) (xy 339.466492 19.91465)
			(xy 339.437006 19.960531) (xy 339.414349 20.010141) (xy 339.398984 20.062471) (xy 339.391222 20.116455)
			(xy 339.390736 20.143724) (xy 335.78031 20.143724) (xy 335.834867 20.116558) (xy 335.907773 20.071417)
			(xy 335.976202 20.019741) (xy 336.039572 19.961972) (xy 336.097341 19.898602) (xy 336.149017 19.830173)
			(xy 336.194158 19.757267) (xy 336.23238 19.680507) (xy 336.263356 19.600548) (xy 336.286823 19.518072)
			(xy 336.302579 19.433782) (xy 336.310491 19.348399) (xy 336.310986 19.305524) (xy 336.310491 19.262649)
			(xy 340.805757 19.262649) (xy 340.805757 19.348399) (xy 340.813669 19.433782) (xy 340.829425 19.518072)
			(xy 340.852892 19.600548) (xy 340.883868 19.680507) (xy 340.92209 19.757267) (xy 340.967231 19.830173)
			(xy 341.018907 19.898602) (xy 341.076676 19.961972) (xy 341.140046 20.019741) (xy 341.208475 20.071417)
			(xy 341.281381 20.116558) (xy 341.358141 20.15478) (xy 341.4381 20.185756) (xy 341.520576 20.209223)
			(xy 341.604866 20.224979) (xy 341.690249 20.232891) (xy 341.775999 20.232891) (xy 341.861382 20.224979)
			(xy 341.945672 20.209223) (xy 342.028148 20.185756) (xy 342.108107 20.15478) (xy 342.184867 20.116558)
			(xy 342.257773 20.071417) (xy 342.326202 20.019741) (xy 342.389572 19.961972) (xy 342.447341 19.898602)
			(xy 342.499017 19.830173) (xy 342.544158 19.757267) (xy 342.58238 19.680507) (xy 342.613356 19.600548)
			(xy 342.636823 19.518072) (xy 342.652579 19.433782) (xy 342.660491 19.348399) (xy 342.660986 19.305524)
			(xy 342.660491 19.262649) (xy 342.659832 19.255537) (xy 373.515877 19.255537) (xy 373.515877 19.341287)
			(xy 373.523789 19.42667) (xy 373.539545 19.51096) (xy 373.563012 19.593436) (xy 373.593988 19.673395)
			(xy 373.63221 19.750155) (xy 373.677351 19.823061) (xy 373.729027 19.89149) (xy 373.786796 19.95486)
			(xy 373.850166 20.012629) (xy 373.918595 20.064305) (xy 373.991501 20.109446) (xy 374.068261 20.147668)
			(xy 374.14822 20.178644) (xy 374.230696 20.202111) (xy 374.314986 20.217867) (xy 374.400369 20.225779)
			(xy 374.486119 20.225779) (xy 374.571502 20.217867) (xy 374.655792 20.202111) (xy 374.738268 20.178644)
			(xy 374.818227 20.147668) (xy 374.84043 20.136612) (xy 376.022108 20.136612) (xy 376.022108 21.000212)
			(xy 376.022594 21.027481) (xy 376.030356 21.081465) (xy 376.045721 21.133795) (xy 376.068378 21.183405)
			(xy 376.097864 21.229286) (xy 376.133579 21.270503) (xy 376.174796 21.306218) (xy 376.220677 21.335704)
			(xy 376.270287 21.358361) (xy 376.322617 21.373726) (xy 376.376601 21.381488) (xy 376.431139 21.381488)
			(xy 376.485123 21.373726) (xy 376.537453 21.358361) (xy 376.587063 21.335704) (xy 376.632944 21.306218)
			(xy 376.674161 21.270503) (xy 376.709876 21.229286) (xy 376.739362 21.183405) (xy 376.762019 21.133795)
			(xy 376.777384 21.081465) (xy 376.785146 21.027481) (xy 376.785632 21.000212) (xy 376.785632 20.136612)
			(xy 376.785146 20.109343) (xy 376.777384 20.055359) (xy 376.762019 20.003029) (xy 376.739362 19.953419)
			(xy 376.709876 19.907538) (xy 376.674161 19.866321) (xy 376.632944 19.830606) (xy 376.587063 19.80112)
			(xy 376.537453 19.778463) (xy 376.485123 19.763098) (xy 376.431139 19.755336) (xy 376.376601 19.755336)
			(xy 376.322617 19.763098) (xy 376.270287 19.778463) (xy 376.220677 19.80112) (xy 376.174796 19.830606)
			(xy 376.133579 19.866321) (xy 376.097864 19.907538) (xy 376.068378 19.953419) (xy 376.045721 20.003029)
			(xy 376.030356 20.055359) (xy 376.022594 20.109343) (xy 376.022108 20.136612) (xy 374.84043 20.136612)
			(xy 374.894987 20.109446) (xy 374.967893 20.064305) (xy 375.036322 20.012629) (xy 375.099692 19.95486)
			(xy 375.157461 19.89149) (xy 375.209137 19.823061) (xy 375.254278 19.750155) (xy 375.2925 19.673395)
			(xy 375.323476 19.593436) (xy 375.346943 19.51096) (xy 375.362699 19.42667) (xy 375.370611 19.341287)
			(xy 375.371106 19.298412) (xy 375.370611 19.255537) (xy 379.865877 19.255537) (xy 379.865877 19.341287)
			(xy 379.873789 19.42667) (xy 379.889545 19.51096) (xy 379.913012 19.593436) (xy 379.943988 19.673395)
			(xy 379.98221 19.750155) (xy 380.027351 19.823061) (xy 380.079027 19.89149) (xy 380.136796 19.95486)
			(xy 380.200166 20.012629) (xy 380.268595 20.064305) (xy 380.341501 20.109446) (xy 380.418261 20.147668)
			(xy 380.49822 20.178644) (xy 380.580696 20.202111) (xy 380.664986 20.217867) (xy 380.750369 20.225779)
			(xy 380.836119 20.225779) (xy 380.921502 20.217867) (xy 381.005792 20.202111) (xy 381.088268 20.178644)
			(xy 381.168227 20.147668) (xy 381.244987 20.109446) (xy 381.317893 20.064305) (xy 381.386322 20.012629)
			(xy 381.449692 19.95486) (xy 381.507461 19.89149) (xy 381.559137 19.823061) (xy 381.604278 19.750155)
			(xy 381.6425 19.673395) (xy 381.673476 19.593436) (xy 381.696943 19.51096) (xy 381.712699 19.42667)
			(xy 381.720611 19.341287) (xy 381.721106 19.298412) (xy 381.720693 19.262649) (xy 399.098757 19.262649)
			(xy 399.098757 19.348399) (xy 399.106669 19.433782) (xy 399.122425 19.518072) (xy 399.145892 19.600548)
			(xy 399.176868 19.680507) (xy 399.21509 19.757267) (xy 399.260231 19.830173) (xy 399.311907 19.898602)
			(xy 399.369676 19.961972) (xy 399.433046 20.019741) (xy 399.501475 20.071417) (xy 399.574381 20.116558)
			(xy 399.651141 20.15478) (xy 399.7311 20.185756) (xy 399.813576 20.209223) (xy 399.897866 20.224979)
			(xy 399.983249 20.232891) (xy 400.068999 20.232891) (xy 400.154382 20.224979) (xy 400.238672 20.209223)
			(xy 400.321148 20.185756) (xy 400.401107 20.15478) (xy 400.42331 20.143724) (xy 404.033736 20.143724)
			(xy 404.033736 21.007324) (xy 404.034222 21.034593) (xy 404.041984 21.088577) (xy 404.057349 21.140907)
			(xy 404.080006 21.190517) (xy 404.109492 21.236398) (xy 404.145207 21.277615) (xy 404.186424 21.31333)
			(xy 404.232305 21.342816) (xy 404.281915 21.365473) (xy 404.334245 21.380838) (xy 404.388229 21.3886)
			(xy 404.442767 21.3886) (xy 404.496751 21.380838) (xy 404.549081 21.365473) (xy 404.598691 21.342816)
			(xy 404.644572 21.31333) (xy 404.685789 21.277615) (xy 404.721504 21.236398) (xy 404.75099 21.190517)
			(xy 404.773647 21.140907) (xy 404.789012 21.088577) (xy 404.796774 21.034593) (xy 404.79726 21.007324)
			(xy 404.79726 20.143724) (xy 404.796774 20.116455) (xy 404.789012 20.062471) (xy 404.773647 20.010141)
			(xy 404.75099 19.960531) (xy 404.721504 19.91465) (xy 404.685789 19.873433) (xy 404.644572 19.837718)
			(xy 404.598691 19.808232) (xy 404.549081 19.785575) (xy 404.496751 19.77021) (xy 404.442767 19.762448)
			(xy 404.388229 19.762448) (xy 404.334245 19.77021) (xy 404.281915 19.785575) (xy 404.232305 19.808232)
			(xy 404.186424 19.837718) (xy 404.145207 19.873433) (xy 404.109492 19.91465) (xy 404.080006 19.960531)
			(xy 404.057349 20.010141) (xy 404.041984 20.062471) (xy 404.034222 20.116455) (xy 404.033736 20.143724)
			(xy 400.42331 20.143724) (xy 400.477867 20.116558) (xy 400.550773 20.071417) (xy 400.619202 20.019741)
			(xy 400.682572 19.961972) (xy 400.740341 19.898602) (xy 400.792017 19.830173) (xy 400.837158 19.757267)
			(xy 400.87538 19.680507) (xy 400.906356 19.600548) (xy 400.929823 19.518072) (xy 400.945579 19.433782)
			(xy 400.953491 19.348399) (xy 400.953986 19.305524) (xy 400.953491 19.262649) (xy 405.448757 19.262649)
			(xy 405.448757 19.348399) (xy 405.456669 19.433782) (xy 405.472425 19.518072) (xy 405.495892 19.600548)
			(xy 405.526868 19.680507) (xy 405.56509 19.757267) (xy 405.610231 19.830173) (xy 405.661907 19.898602)
			(xy 405.719676 19.961972) (xy 405.783046 20.019741) (xy 405.851475 20.071417) (xy 405.924381 20.116558)
			(xy 406.001141 20.15478) (xy 406.0811 20.185756) (xy 406.163576 20.209223) (xy 406.247866 20.224979)
			(xy 406.333249 20.232891) (xy 406.418999 20.232891) (xy 406.504382 20.224979) (xy 406.588672 20.209223)
			(xy 406.671148 20.185756) (xy 406.751107 20.15478) (xy 406.827867 20.116558) (xy 406.900773 20.071417)
			(xy 406.969202 20.019741) (xy 407.032572 19.961972) (xy 407.090341 19.898602) (xy 407.142017 19.830173)
			(xy 407.187158 19.757267) (xy 407.22538 19.680507) (xy 407.256356 19.600548) (xy 407.279823 19.518072)
			(xy 407.295579 19.433782) (xy 407.303491 19.348399) (xy 407.303986 19.305524) (xy 407.303491 19.262649)
			(xy 407.302832 19.255537) (xy 438.158877 19.255537) (xy 438.158877 19.341287) (xy 438.166789 19.42667)
			(xy 438.182545 19.51096) (xy 438.206012 19.593436) (xy 438.236988 19.673395) (xy 438.27521 19.750155)
			(xy 438.320351 19.823061) (xy 438.372027 19.89149) (xy 438.429796 19.95486) (xy 438.493166 20.012629)
			(xy 438.561595 20.064305) (xy 438.634501 20.109446) (xy 438.711261 20.147668) (xy 438.79122 20.178644)
			(xy 438.873696 20.202111) (xy 438.957986 20.217867) (xy 439.043369 20.225779) (xy 439.129119 20.225779)
			(xy 439.214502 20.217867) (xy 439.298792 20.202111) (xy 439.381268 20.178644) (xy 439.461227 20.147668)
			(xy 439.48343 20.136612) (xy 440.665108 20.136612) (xy 440.665108 21.000212) (xy 440.665594 21.027481)
			(xy 440.673356 21.081465) (xy 440.688721 21.133795) (xy 440.711378 21.183405) (xy 440.740864 21.229286)
			(xy 440.776579 21.270503) (xy 440.817796 21.306218) (xy 440.863677 21.335704) (xy 440.913287 21.358361)
			(xy 440.965617 21.373726) (xy 441.019601 21.381488) (xy 441.074139 21.381488) (xy 441.128123 21.373726)
			(xy 441.180453 21.358361) (xy 441.230063 21.335704) (xy 441.275944 21.306218) (xy 441.317161 21.270503)
			(xy 441.352876 21.229286) (xy 441.382362 21.183405) (xy 441.405019 21.133795) (xy 441.420384 21.081465)
			(xy 441.428146 21.027481) (xy 441.428632 21.000212) (xy 441.428632 20.136612) (xy 441.428146 20.109343)
			(xy 441.420384 20.055359) (xy 441.405019 20.003029) (xy 441.382362 19.953419) (xy 441.352876 19.907538)
			(xy 441.317161 19.866321) (xy 441.275944 19.830606) (xy 441.230063 19.80112) (xy 441.180453 19.778463)
			(xy 441.128123 19.763098) (xy 441.074139 19.755336) (xy 441.019601 19.755336) (xy 440.965617 19.763098)
			(xy 440.913287 19.778463) (xy 440.863677 19.80112) (xy 440.817796 19.830606) (xy 440.776579 19.866321)
			(xy 440.740864 19.907538) (xy 440.711378 19.953419) (xy 440.688721 20.003029) (xy 440.673356 20.055359)
			(xy 440.665594 20.109343) (xy 440.665108 20.136612) (xy 439.48343 20.136612) (xy 439.537987 20.109446)
			(xy 439.610893 20.064305) (xy 439.679322 20.012629) (xy 439.742692 19.95486) (xy 439.800461 19.89149)
			(xy 439.852137 19.823061) (xy 439.897278 19.750155) (xy 439.9355 19.673395) (xy 439.966476 19.593436)
			(xy 439.989943 19.51096) (xy 440.005699 19.42667) (xy 440.013611 19.341287) (xy 440.014106 19.298412)
			(xy 440.013611 19.255537) (xy 444.508877 19.255537) (xy 444.508877 19.341287) (xy 444.516789 19.42667)
			(xy 444.532545 19.51096) (xy 444.556012 19.593436) (xy 444.586988 19.673395) (xy 444.62521 19.750155)
			(xy 444.670351 19.823061) (xy 444.722027 19.89149) (xy 444.779796 19.95486) (xy 444.843166 20.012629)
			(xy 444.911595 20.064305) (xy 444.984501 20.109446) (xy 445.061261 20.147668) (xy 445.14122 20.178644)
			(xy 445.223696 20.202111) (xy 445.307986 20.217867) (xy 445.393369 20.225779) (xy 445.479119 20.225779)
			(xy 445.564502 20.217867) (xy 445.648792 20.202111) (xy 445.731268 20.178644) (xy 445.811227 20.147668)
			(xy 445.887987 20.109446) (xy 445.960893 20.064305) (xy 446.029322 20.012629) (xy 446.092692 19.95486)
			(xy 446.150461 19.89149) (xy 446.202137 19.823061) (xy 446.247278 19.750155) (xy 446.2855 19.673395)
			(xy 446.316476 19.593436) (xy 446.339943 19.51096) (xy 446.355699 19.42667) (xy 446.363611 19.341287)
			(xy 446.364106 19.298412) (xy 446.363611 19.255537) (xy 446.355699 19.170154) (xy 446.339943 19.085864)
			(xy 446.316476 19.003388) (xy 446.2855 18.923429) (xy 446.247278 18.846669) (xy 446.202137 18.773763)
			(xy 446.150461 18.705334) (xy 446.092692 18.641964) (xy 446.029322 18.584195) (xy 445.960893 18.532519)
			(xy 445.887987 18.487378) (xy 445.811227 18.449156) (xy 445.731268 18.41818) (xy 445.648792 18.394713)
			(xy 445.564502 18.378957) (xy 445.479119 18.371045) (xy 445.393369 18.371045) (xy 445.307986 18.378957)
			(xy 445.223696 18.394713) (xy 445.14122 18.41818) (xy 445.061261 18.449156) (xy 444.984501 18.487378)
			(xy 444.911595 18.532519) (xy 444.843166 18.584195) (xy 444.779796 18.641964) (xy 444.722027 18.705334)
			(xy 444.670351 18.773763) (xy 444.62521 18.846669) (xy 444.586988 18.923429) (xy 444.556012 19.003388)
			(xy 444.532545 19.085864) (xy 444.516789 19.170154) (xy 444.508877 19.255537) (xy 440.013611 19.255537)
			(xy 440.005699 19.170154) (xy 439.989943 19.085864) (xy 439.966476 19.003388) (xy 439.9355 18.923429)
			(xy 439.897278 18.846669) (xy 439.852137 18.773763) (xy 439.800461 18.705334) (xy 439.742692 18.641964)
			(xy 439.679322 18.584195) (xy 439.610893 18.532519) (xy 439.537987 18.487378) (xy 439.461227 18.449156)
			(xy 439.381268 18.41818) (xy 439.298792 18.394713) (xy 439.214502 18.378957) (xy 439.129119 18.371045)
			(xy 439.043369 18.371045) (xy 438.957986 18.378957) (xy 438.873696 18.394713) (xy 438.79122 18.41818)
			(xy 438.711261 18.449156) (xy 438.634501 18.487378) (xy 438.561595 18.532519) (xy 438.493166 18.584195)
			(xy 438.429796 18.641964) (xy 438.372027 18.705334) (xy 438.320351 18.773763) (xy 438.27521 18.846669)
			(xy 438.236988 18.923429) (xy 438.206012 19.003388) (xy 438.182545 19.085864) (xy 438.166789 19.170154)
			(xy 438.158877 19.255537) (xy 407.302832 19.255537) (xy 407.295579 19.177266) (xy 407.279823 19.092976)
			(xy 407.256356 19.0105) (xy 407.22538 18.930541) (xy 407.187158 18.853781) (xy 407.142017 18.780875)
			(xy 407.090341 18.712446) (xy 407.032572 18.649076) (xy 406.969202 18.591307) (xy 406.900773 18.539631)
			(xy 406.827867 18.49449) (xy 406.751107 18.456268) (xy 406.671148 18.425292) (xy 406.588672 18.401825)
			(xy 406.504382 18.386069) (xy 406.418999 18.378157) (xy 406.333249 18.378157) (xy 406.247866 18.386069)
			(xy 406.163576 18.401825) (xy 406.0811 18.425292) (xy 406.001141 18.456268) (xy 405.924381 18.49449)
			(xy 405.851475 18.539631) (xy 405.783046 18.591307) (xy 405.719676 18.649076) (xy 405.661907 18.712446)
			(xy 405.610231 18.780875) (xy 405.56509 18.853781) (xy 405.526868 18.930541) (xy 405.495892 19.0105)
			(xy 405.472425 19.092976) (xy 405.456669 19.177266) (xy 405.448757 19.262649) (xy 400.953491 19.262649)
			(xy 400.945579 19.177266) (xy 400.929823 19.092976) (xy 400.906356 19.0105) (xy 400.87538 18.930541)
			(xy 400.837158 18.853781) (xy 400.792017 18.780875) (xy 400.740341 18.712446) (xy 400.682572 18.649076)
			(xy 400.619202 18.591307) (xy 400.550773 18.539631) (xy 400.477867 18.49449) (xy 400.401107 18.456268)
			(xy 400.321148 18.425292) (xy 400.238672 18.401825) (xy 400.154382 18.386069) (xy 400.068999 18.378157)
			(xy 399.983249 18.378157) (xy 399.897866 18.386069) (xy 399.813576 18.401825) (xy 399.7311 18.425292)
			(xy 399.651141 18.456268) (xy 399.574381 18.49449) (xy 399.501475 18.539631) (xy 399.433046 18.591307)
			(xy 399.369676 18.649076) (xy 399.311907 18.712446) (xy 399.260231 18.780875) (xy 399.21509 18.853781)
			(xy 399.176868 18.930541) (xy 399.145892 19.0105) (xy 399.122425 19.092976) (xy 399.106669 19.177266)
			(xy 399.098757 19.262649) (xy 381.720693 19.262649) (xy 381.720611 19.255537) (xy 381.712699 19.170154)
			(xy 381.696943 19.085864) (xy 381.673476 19.003388) (xy 381.6425 18.923429) (xy 381.604278 18.846669)
			(xy 381.559137 18.773763) (xy 381.507461 18.705334) (xy 381.449692 18.641964) (xy 381.386322 18.584195)
			(xy 381.317893 18.532519) (xy 381.244987 18.487378) (xy 381.168227 18.449156) (xy 381.088268 18.41818)
			(xy 381.005792 18.394713) (xy 380.921502 18.378957) (xy 380.836119 18.371045) (xy 380.750369 18.371045)
			(xy 380.664986 18.378957) (xy 380.580696 18.394713) (xy 380.49822 18.41818) (xy 380.418261 18.449156)
			(xy 380.341501 18.487378) (xy 380.268595 18.532519) (xy 380.200166 18.584195) (xy 380.136796 18.641964)
			(xy 380.079027 18.705334) (xy 380.027351 18.773763) (xy 379.98221 18.846669) (xy 379.943988 18.923429)
			(xy 379.913012 19.003388) (xy 379.889545 19.085864) (xy 379.873789 19.170154) (xy 379.865877 19.255537)
			(xy 375.370611 19.255537) (xy 375.362699 19.170154) (xy 375.346943 19.085864) (xy 375.323476 19.003388)
			(xy 375.2925 18.923429) (xy 375.254278 18.846669) (xy 375.209137 18.773763) (xy 375.157461 18.705334)
			(xy 375.099692 18.641964) (xy 375.036322 18.584195) (xy 374.967893 18.532519) (xy 374.894987 18.487378)
			(xy 374.818227 18.449156) (xy 374.738268 18.41818) (xy 374.655792 18.394713) (xy 374.571502 18.378957)
			(xy 374.486119 18.371045) (xy 374.400369 18.371045) (xy 374.314986 18.378957) (xy 374.230696 18.394713)
			(xy 374.14822 18.41818) (xy 374.068261 18.449156) (xy 373.991501 18.487378) (xy 373.918595 18.532519)
			(xy 373.850166 18.584195) (xy 373.786796 18.641964) (xy 373.729027 18.705334) (xy 373.677351 18.773763)
			(xy 373.63221 18.846669) (xy 373.593988 18.923429) (xy 373.563012 19.003388) (xy 373.539545 19.085864)
			(xy 373.523789 19.170154) (xy 373.515877 19.255537) (xy 342.659832 19.255537) (xy 342.652579 19.177266)
			(xy 342.636823 19.092976) (xy 342.613356 19.0105) (xy 342.58238 18.930541) (xy 342.544158 18.853781)
			(xy 342.499017 18.780875) (xy 342.447341 18.712446) (xy 342.389572 18.649076) (xy 342.326202 18.591307)
			(xy 342.257773 18.539631) (xy 342.184867 18.49449) (xy 342.108107 18.456268) (xy 342.028148 18.425292)
			(xy 341.945672 18.401825) (xy 341.861382 18.386069) (xy 341.775999 18.378157) (xy 341.690249 18.378157)
			(xy 341.604866 18.386069) (xy 341.520576 18.401825) (xy 341.4381 18.425292) (xy 341.358141 18.456268)
			(xy 341.281381 18.49449) (xy 341.208475 18.539631) (xy 341.140046 18.591307) (xy 341.076676 18.649076)
			(xy 341.018907 18.712446) (xy 340.967231 18.780875) (xy 340.92209 18.853781) (xy 340.883868 18.930541)
			(xy 340.852892 19.0105) (xy 340.829425 19.092976) (xy 340.813669 19.177266) (xy 340.805757 19.262649)
			(xy 336.310491 19.262649) (xy 336.302579 19.177266) (xy 336.286823 19.092976) (xy 336.263356 19.0105)
			(xy 336.23238 18.930541) (xy 336.194158 18.853781) (xy 336.149017 18.780875) (xy 336.097341 18.712446)
			(xy 336.039572 18.649076) (xy 335.976202 18.591307) (xy 335.907773 18.539631) (xy 335.834867 18.49449)
			(xy 335.758107 18.456268) (xy 335.678148 18.425292) (xy 335.595672 18.401825) (xy 335.511382 18.386069)
			(xy 335.425999 18.378157) (xy 335.340249 18.378157) (xy 335.254866 18.386069) (xy 335.170576 18.401825)
			(xy 335.0881 18.425292) (xy 335.008141 18.456268) (xy 334.931381 18.49449) (xy 334.858475 18.539631)
			(xy 334.790046 18.591307) (xy 334.726676 18.649076) (xy 334.668907 18.712446) (xy 334.617231 18.780875)
			(xy 334.57209 18.853781) (xy 334.533868 18.930541) (xy 334.502892 19.0105) (xy 334.479425 19.092976)
			(xy 334.463669 19.177266) (xy 334.455757 19.262649) (xy 316.569693 19.262649) (xy 316.569611 19.255537)
			(xy 316.561699 19.170154) (xy 316.545943 19.085864) (xy 316.522476 19.003388) (xy 316.4915 18.923429)
			(xy 316.453278 18.846669) (xy 316.408137 18.773763) (xy 316.356461 18.705334) (xy 316.298692 18.641964)
			(xy 316.235322 18.584195) (xy 316.166893 18.532519) (xy 316.093987 18.487378) (xy 316.017227 18.449156)
			(xy 315.937268 18.41818) (xy 315.854792 18.394713) (xy 315.770502 18.378957) (xy 315.685119 18.371045)
			(xy 315.599369 18.371045) (xy 315.513986 18.378957) (xy 315.429696 18.394713) (xy 315.34722 18.41818)
			(xy 315.267261 18.449156) (xy 315.190501 18.487378) (xy 315.117595 18.532519) (xy 315.049166 18.584195)
			(xy 314.985796 18.641964) (xy 314.928027 18.705334) (xy 314.876351 18.773763) (xy 314.83121 18.846669)
			(xy 314.792988 18.923429) (xy 314.762012 19.003388) (xy 314.738545 19.085864) (xy 314.722789 19.170154)
			(xy 314.714877 19.255537) (xy 310.219611 19.255537) (xy 310.211699 19.170154) (xy 310.195943 19.085864)
			(xy 310.172476 19.003388) (xy 310.1415 18.923429) (xy 310.103278 18.846669) (xy 310.058137 18.773763)
			(xy 310.006461 18.705334) (xy 309.948692 18.641964) (xy 309.885322 18.584195) (xy 309.816893 18.532519)
			(xy 309.743987 18.487378) (xy 309.667227 18.449156) (xy 309.587268 18.41818) (xy 309.504792 18.394713)
			(xy 309.420502 18.378957) (xy 309.335119 18.371045) (xy 309.249369 18.371045) (xy 309.163986 18.378957)
			(xy 309.079696 18.394713) (xy 308.99722 18.41818) (xy 308.917261 18.449156) (xy 308.840501 18.487378)
			(xy 308.767595 18.532519) (xy 308.699166 18.584195) (xy 308.635796 18.641964) (xy 308.578027 18.705334)
			(xy 308.526351 18.773763) (xy 308.48121 18.846669) (xy 308.442988 18.923429) (xy 308.412012 19.003388)
			(xy 308.388545 19.085864) (xy 308.372789 19.170154) (xy 308.364877 19.255537) (xy 277.508832 19.255537)
			(xy 277.501579 19.177266) (xy 277.485823 19.092976) (xy 277.462356 19.0105) (xy 277.43138 18.930541)
			(xy 277.393158 18.853781) (xy 277.348017 18.780875) (xy 277.296341 18.712446) (xy 277.238572 18.649076)
			(xy 277.175202 18.591307) (xy 277.106773 18.539631) (xy 277.033867 18.49449) (xy 276.957107 18.456268)
			(xy 276.877148 18.425292) (xy 276.794672 18.401825) (xy 276.710382 18.386069) (xy 276.624999 18.378157)
			(xy 276.539249 18.378157) (xy 276.453866 18.386069) (xy 276.369576 18.401825) (xy 276.2871 18.425292)
			(xy 276.207141 18.456268) (xy 276.130381 18.49449) (xy 276.057475 18.539631) (xy 275.989046 18.591307)
			(xy 275.925676 18.649076) (xy 275.867907 18.712446) (xy 275.816231 18.780875) (xy 275.77109 18.853781)
			(xy 275.732868 18.930541) (xy 275.701892 19.0105) (xy 275.678425 19.092976) (xy 275.662669 19.177266)
			(xy 275.654757 19.262649) (xy 271.159491 19.262649) (xy 271.151579 19.177266) (xy 271.135823 19.092976)
			(xy 271.112356 19.0105) (xy 271.08138 18.930541) (xy 271.043158 18.853781) (xy 270.998017 18.780875)
			(xy 270.946341 18.712446) (xy 270.888572 18.649076) (xy 270.825202 18.591307) (xy 270.756773 18.539631)
			(xy 270.683867 18.49449) (xy 270.607107 18.456268) (xy 270.527148 18.425292) (xy 270.444672 18.401825)
			(xy 270.360382 18.386069) (xy 270.274999 18.378157) (xy 270.189249 18.378157) (xy 270.103866 18.386069)
			(xy 270.019576 18.401825) (xy 269.9371 18.425292) (xy 269.857141 18.456268) (xy 269.780381 18.49449)
			(xy 269.707475 18.539631) (xy 269.639046 18.591307) (xy 269.575676 18.649076) (xy 269.517907 18.712446)
			(xy 269.466231 18.780875) (xy 269.42109 18.853781) (xy 269.382868 18.930541) (xy 269.351892 19.0105)
			(xy 269.328425 19.092976) (xy 269.312669 19.177266) (xy 269.304757 19.262649) (xy 252.231493 19.262649)
			(xy 252.231411 19.255537) (xy 252.223499 19.170154) (xy 252.207743 19.085864) (xy 252.184276 19.003388)
			(xy 252.1533 18.923429) (xy 252.115078 18.846669) (xy 252.069937 18.773763) (xy 252.018261 18.705334)
			(xy 251.960492 18.641964) (xy 251.897122 18.584195) (xy 251.828693 18.532519) (xy 251.755787 18.487378)
			(xy 251.679027 18.449156) (xy 251.599068 18.41818) (xy 251.516592 18.394713) (xy 251.432302 18.378957)
			(xy 251.346919 18.371045) (xy 251.261169 18.371045) (xy 251.175786 18.378957) (xy 251.091496 18.394713)
			(xy 251.00902 18.41818) (xy 250.929061 18.449156) (xy 250.852301 18.487378) (xy 250.779395 18.532519)
			(xy 250.710966 18.584195) (xy 250.647596 18.641964) (xy 250.589827 18.705334) (xy 250.538151 18.773763)
			(xy 250.49301 18.846669) (xy 250.454788 18.923429) (xy 250.423812 19.003388) (xy 250.400345 19.085864)
			(xy 250.384589 19.170154) (xy 250.376677 19.255537) (xy 245.881411 19.255537) (xy 245.873499 19.170154)
			(xy 245.857743 19.085864) (xy 245.834276 19.003388) (xy 245.8033 18.923429) (xy 245.765078 18.846669)
			(xy 245.719937 18.773763) (xy 245.668261 18.705334) (xy 245.610492 18.641964) (xy 245.547122 18.584195)
			(xy 245.478693 18.532519) (xy 245.405787 18.487378) (xy 245.329027 18.449156) (xy 245.249068 18.41818)
			(xy 245.166592 18.394713) (xy 245.082302 18.378957) (xy 244.996919 18.371045) (xy 244.911169 18.371045)
			(xy 244.825786 18.378957) (xy 244.741496 18.394713) (xy 244.65902 18.41818) (xy 244.579061 18.449156)
			(xy 244.502301 18.487378) (xy 244.429395 18.532519) (xy 244.360966 18.584195) (xy 244.297596 18.641964)
			(xy 244.239827 18.705334) (xy 244.188151 18.773763) (xy 244.14301 18.846669) (xy 244.104788 18.923429)
			(xy 244.073812 19.003388) (xy 244.050345 19.085864) (xy 244.034589 19.170154) (xy 244.026677 19.255537)
			(xy 218.199832 19.255537) (xy 218.192579 19.177266) (xy 218.176823 19.092976) (xy 218.153356 19.0105)
			(xy 218.12238 18.930541) (xy 218.084158 18.853781) (xy 218.039017 18.780875) (xy 217.987341 18.712446)
			(xy 217.929572 18.649076) (xy 217.866202 18.591307) (xy 217.797773 18.539631) (xy 217.724867 18.49449)
			(xy 217.648107 18.456268) (xy 217.568148 18.425292) (xy 217.485672 18.401825) (xy 217.401382 18.386069)
			(xy 217.315999 18.378157) (xy 217.230249 18.378157) (xy 217.144866 18.386069) (xy 217.060576 18.401825)
			(xy 216.9781 18.425292) (xy 216.898141 18.456268) (xy 216.821381 18.49449) (xy 216.748475 18.539631)
			(xy 216.680046 18.591307) (xy 216.616676 18.649076) (xy 216.558907 18.712446) (xy 216.507231 18.780875)
			(xy 216.46209 18.853781) (xy 216.423868 18.930541) (xy 216.392892 19.0105) (xy 216.369425 19.092976)
			(xy 216.353669 19.177266) (xy 216.345757 19.262649) (xy 211.850491 19.262649) (xy 211.842579 19.177266)
			(xy 211.826823 19.092976) (xy 211.803356 19.0105) (xy 211.77238 18.930541) (xy 211.734158 18.853781)
			(xy 211.689017 18.780875) (xy 211.637341 18.712446) (xy 211.579572 18.649076) (xy 211.516202 18.591307)
			(xy 211.447773 18.539631) (xy 211.374867 18.49449) (xy 211.298107 18.456268) (xy 211.218148 18.425292)
			(xy 211.135672 18.401825) (xy 211.051382 18.386069) (xy 210.965999 18.378157) (xy 210.880249 18.378157)
			(xy 210.794866 18.386069) (xy 210.710576 18.401825) (xy 210.6281 18.425292) (xy 210.548141 18.456268)
			(xy 210.471381 18.49449) (xy 210.398475 18.539631) (xy 210.330046 18.591307) (xy 210.266676 18.649076)
			(xy 210.208907 18.712446) (xy 210.157231 18.780875) (xy 210.11209 18.853781) (xy 210.073868 18.930541)
			(xy 210.042892 19.0105) (xy 210.019425 19.092976) (xy 210.003669 19.177266) (xy 209.995757 19.262649)
			(xy 158.621984 19.262649) (xy 158.621984 16.722649) (xy 209.995757 16.722649) (xy 209.995757 16.808399)
			(xy 210.003669 16.893782) (xy 210.019425 16.978072) (xy 210.042892 17.060548) (xy 210.073868 17.140507)
			(xy 210.11209 17.217267) (xy 210.157231 17.290173) (xy 210.208907 17.358602) (xy 210.266676 17.421972)
			(xy 210.330046 17.479741) (xy 210.398475 17.531417) (xy 210.471381 17.576558) (xy 210.548141 17.61478)
			(xy 210.6281 17.645756) (xy 210.710576 17.669223) (xy 210.794866 17.684979) (xy 210.880249 17.692891)
			(xy 210.965999 17.692891) (xy 211.051382 17.684979) (xy 211.135672 17.669223) (xy 211.218148 17.645756)
			(xy 211.298107 17.61478) (xy 211.374867 17.576558) (xy 211.447773 17.531417) (xy 211.516202 17.479741)
			(xy 211.579572 17.421972) (xy 211.637341 17.358602) (xy 211.689017 17.290173) (xy 211.734158 17.217267)
			(xy 211.77238 17.140507) (xy 211.803356 17.060548) (xy 211.826823 16.978072) (xy 211.842579 16.893782)
			(xy 211.850491 16.808399) (xy 211.850986 16.765524) (xy 211.850491 16.722649) (xy 216.345757 16.722649)
			(xy 216.345757 16.808399) (xy 216.353669 16.893782) (xy 216.369425 16.978072) (xy 216.392892 17.060548)
			(xy 216.423868 17.140507) (xy 216.46209 17.217267) (xy 216.507231 17.290173) (xy 216.558907 17.358602)
			(xy 216.616676 17.421972) (xy 216.680046 17.479741) (xy 216.748475 17.531417) (xy 216.821381 17.576558)
			(xy 216.898141 17.61478) (xy 216.9781 17.645756) (xy 217.060576 17.669223) (xy 217.144866 17.684979)
			(xy 217.230249 17.692891) (xy 217.315999 17.692891) (xy 217.401382 17.684979) (xy 217.485672 17.669223)
			(xy 217.568148 17.645756) (xy 217.648107 17.61478) (xy 217.724867 17.576558) (xy 217.797773 17.531417)
			(xy 217.866202 17.479741) (xy 217.929572 17.421972) (xy 217.987341 17.358602) (xy 218.039017 17.290173)
			(xy 218.084158 17.217267) (xy 218.12238 17.140507) (xy 218.153356 17.060548) (xy 218.176823 16.978072)
			(xy 218.192579 16.893782) (xy 218.200491 16.808399) (xy 218.200986 16.765524) (xy 218.200491 16.722649)
			(xy 218.199832 16.715537) (xy 244.026677 16.715537) (xy 244.026677 16.801287) (xy 244.034589 16.88667)
			(xy 244.050345 16.97096) (xy 244.073812 17.053436) (xy 244.104788 17.133395) (xy 244.14301 17.210155)
			(xy 244.188151 17.283061) (xy 244.239827 17.35149) (xy 244.297596 17.41486) (xy 244.360966 17.472629)
			(xy 244.429395 17.524305) (xy 244.502301 17.569446) (xy 244.579061 17.607668) (xy 244.65902 17.638644)
			(xy 244.741496 17.662111) (xy 244.825786 17.677867) (xy 244.911169 17.685779) (xy 244.996919 17.685779)
			(xy 245.082302 17.677867) (xy 245.166592 17.662111) (xy 245.249068 17.638644) (xy 245.329027 17.607668)
			(xy 245.405787 17.569446) (xy 245.478693 17.524305) (xy 245.547122 17.472629) (xy 245.610492 17.41486)
			(xy 245.668261 17.35149) (xy 245.719937 17.283061) (xy 245.765078 17.210155) (xy 245.8033 17.133395)
			(xy 245.834276 17.053436) (xy 245.857743 16.97096) (xy 245.873499 16.88667) (xy 245.881411 16.801287)
			(xy 245.881906 16.758412) (xy 245.881411 16.715537) (xy 250.376677 16.715537) (xy 250.376677 16.801287)
			(xy 250.384589 16.88667) (xy 250.400345 16.97096) (xy 250.423812 17.053436) (xy 250.454788 17.133395)
			(xy 250.49301 17.210155) (xy 250.538151 17.283061) (xy 250.589827 17.35149) (xy 250.647596 17.41486)
			(xy 250.710966 17.472629) (xy 250.779395 17.524305) (xy 250.852301 17.569446) (xy 250.929061 17.607668)
			(xy 251.00902 17.638644) (xy 251.091496 17.662111) (xy 251.175786 17.677867) (xy 251.261169 17.685779)
			(xy 251.346919 17.685779) (xy 251.432302 17.677867) (xy 251.516592 17.662111) (xy 251.599068 17.638644)
			(xy 251.679027 17.607668) (xy 251.755787 17.569446) (xy 251.828693 17.524305) (xy 251.897122 17.472629)
			(xy 251.960492 17.41486) (xy 252.018261 17.35149) (xy 252.069937 17.283061) (xy 252.115078 17.210155)
			(xy 252.1533 17.133395) (xy 252.184276 17.053436) (xy 252.207743 16.97096) (xy 252.223499 16.88667)
			(xy 252.231411 16.801287) (xy 252.231906 16.758412) (xy 252.231493 16.722649) (xy 269.304757 16.722649)
			(xy 269.304757 16.808399) (xy 269.312669 16.893782) (xy 269.328425 16.978072) (xy 269.351892 17.060548)
			(xy 269.382868 17.140507) (xy 269.42109 17.217267) (xy 269.466231 17.290173) (xy 269.517907 17.358602)
			(xy 269.575676 17.421972) (xy 269.639046 17.479741) (xy 269.707475 17.531417) (xy 269.780381 17.576558)
			(xy 269.857141 17.61478) (xy 269.9371 17.645756) (xy 270.019576 17.669223) (xy 270.103866 17.684979)
			(xy 270.189249 17.692891) (xy 270.274999 17.692891) (xy 270.360382 17.684979) (xy 270.444672 17.669223)
			(xy 270.527148 17.645756) (xy 270.607107 17.61478) (xy 270.62931 17.603724) (xy 274.239736 17.603724)
			(xy 274.239736 18.467324) (xy 274.240222 18.494593) (xy 274.247984 18.548577) (xy 274.263349 18.600907)
			(xy 274.286006 18.650517) (xy 274.315492 18.696398) (xy 274.351207 18.737615) (xy 274.392424 18.77333)
			(xy 274.438305 18.802816) (xy 274.487915 18.825473) (xy 274.540245 18.840838) (xy 274.594229 18.8486)
			(xy 274.648767 18.8486) (xy 274.702751 18.840838) (xy 274.755081 18.825473) (xy 274.804691 18.802816)
			(xy 274.850572 18.77333) (xy 274.891789 18.737615) (xy 274.927504 18.696398) (xy 274.95699 18.650517)
			(xy 274.979647 18.600907) (xy 274.995012 18.548577) (xy 275.002774 18.494593) (xy 275.00326 18.467324)
			(xy 275.00326 17.603724) (xy 275.002774 17.576455) (xy 274.995012 17.522471) (xy 274.979647 17.470141)
			(xy 274.95699 17.420531) (xy 274.927504 17.37465) (xy 274.891789 17.333433) (xy 274.850572 17.297718)
			(xy 274.804691 17.268232) (xy 274.755081 17.245575) (xy 274.702751 17.23021) (xy 274.648767 17.222448)
			(xy 274.594229 17.222448) (xy 274.540245 17.23021) (xy 274.487915 17.245575) (xy 274.438305 17.268232)
			(xy 274.392424 17.297718) (xy 274.351207 17.333433) (xy 274.315492 17.37465) (xy 274.286006 17.420531)
			(xy 274.263349 17.470141) (xy 274.247984 17.522471) (xy 274.240222 17.576455) (xy 274.239736 17.603724)
			(xy 270.62931 17.603724) (xy 270.683867 17.576558) (xy 270.756773 17.531417) (xy 270.825202 17.479741)
			(xy 270.888572 17.421972) (xy 270.946341 17.358602) (xy 270.998017 17.290173) (xy 271.043158 17.217267)
			(xy 271.08138 17.140507) (xy 271.112356 17.060548) (xy 271.135823 16.978072) (xy 271.151579 16.893782)
			(xy 271.159491 16.808399) (xy 271.159986 16.765524) (xy 271.159491 16.722649) (xy 275.654757 16.722649)
			(xy 275.654757 16.808399) (xy 275.662669 16.893782) (xy 275.678425 16.978072) (xy 275.701892 17.060548)
			(xy 275.732868 17.140507) (xy 275.77109 17.217267) (xy 275.816231 17.290173) (xy 275.867907 17.358602)
			(xy 275.925676 17.421972) (xy 275.989046 17.479741) (xy 276.057475 17.531417) (xy 276.130381 17.576558)
			(xy 276.207141 17.61478) (xy 276.2871 17.645756) (xy 276.369576 17.669223) (xy 276.453866 17.684979)
			(xy 276.539249 17.692891) (xy 276.624999 17.692891) (xy 276.710382 17.684979) (xy 276.794672 17.669223)
			(xy 276.877148 17.645756) (xy 276.957107 17.61478) (xy 277.033867 17.576558) (xy 277.106773 17.531417)
			(xy 277.175202 17.479741) (xy 277.238572 17.421972) (xy 277.296341 17.358602) (xy 277.348017 17.290173)
			(xy 277.393158 17.217267) (xy 277.43138 17.140507) (xy 277.462356 17.060548) (xy 277.485823 16.978072)
			(xy 277.501579 16.893782) (xy 277.509491 16.808399) (xy 277.509986 16.765524) (xy 277.509491 16.722649)
			(xy 277.508832 16.715537) (xy 308.364877 16.715537) (xy 308.364877 16.801287) (xy 308.372789 16.88667)
			(xy 308.388545 16.97096) (xy 308.412012 17.053436) (xy 308.442988 17.133395) (xy 308.48121 17.210155)
			(xy 308.526351 17.283061) (xy 308.578027 17.35149) (xy 308.635796 17.41486) (xy 308.699166 17.472629)
			(xy 308.767595 17.524305) (xy 308.840501 17.569446) (xy 308.917261 17.607668) (xy 308.99722 17.638644)
			(xy 309.079696 17.662111) (xy 309.163986 17.677867) (xy 309.249369 17.685779) (xy 309.335119 17.685779)
			(xy 309.420502 17.677867) (xy 309.504792 17.662111) (xy 309.587268 17.638644) (xy 309.667227 17.607668)
			(xy 309.68943 17.596612) (xy 310.871108 17.596612) (xy 310.871108 18.460212) (xy 310.871594 18.487481)
			(xy 310.879356 18.541465) (xy 310.894721 18.593795) (xy 310.917378 18.643405) (xy 310.946864 18.689286)
			(xy 310.982579 18.730503) (xy 311.023796 18.766218) (xy 311.069677 18.795704) (xy 311.119287 18.818361)
			(xy 311.171617 18.833726) (xy 311.225601 18.841488) (xy 311.280139 18.841488) (xy 311.334123 18.833726)
			(xy 311.386453 18.818361) (xy 311.436063 18.795704) (xy 311.481944 18.766218) (xy 311.523161 18.730503)
			(xy 311.558876 18.689286) (xy 311.588362 18.643405) (xy 311.611019 18.593795) (xy 311.626384 18.541465)
			(xy 311.634146 18.487481) (xy 311.634632 18.460212) (xy 311.634632 17.596612) (xy 311.634146 17.569343)
			(xy 311.626384 17.515359) (xy 311.611019 17.463029) (xy 311.588362 17.413419) (xy 311.558876 17.367538)
			(xy 311.523161 17.326321) (xy 311.481944 17.290606) (xy 311.436063 17.26112) (xy 311.386453 17.238463)
			(xy 311.334123 17.223098) (xy 311.280139 17.215336) (xy 311.225601 17.215336) (xy 311.171617 17.223098)
			(xy 311.119287 17.238463) (xy 311.069677 17.26112) (xy 311.023796 17.290606) (xy 310.982579 17.326321)
			(xy 310.946864 17.367538) (xy 310.917378 17.413419) (xy 310.894721 17.463029) (xy 310.879356 17.515359)
			(xy 310.871594 17.569343) (xy 310.871108 17.596612) (xy 309.68943 17.596612) (xy 309.743987 17.569446)
			(xy 309.816893 17.524305) (xy 309.885322 17.472629) (xy 309.948692 17.41486) (xy 310.006461 17.35149)
			(xy 310.058137 17.283061) (xy 310.103278 17.210155) (xy 310.1415 17.133395) (xy 310.172476 17.053436)
			(xy 310.195943 16.97096) (xy 310.211699 16.88667) (xy 310.219611 16.801287) (xy 310.220106 16.758412)
			(xy 310.219611 16.715537) (xy 314.714877 16.715537) (xy 314.714877 16.801287) (xy 314.722789 16.88667)
			(xy 314.738545 16.97096) (xy 314.762012 17.053436) (xy 314.792988 17.133395) (xy 314.83121 17.210155)
			(xy 314.876351 17.283061) (xy 314.928027 17.35149) (xy 314.985796 17.41486) (xy 315.049166 17.472629)
			(xy 315.117595 17.524305) (xy 315.190501 17.569446) (xy 315.267261 17.607668) (xy 315.34722 17.638644)
			(xy 315.429696 17.662111) (xy 315.513986 17.677867) (xy 315.599369 17.685779) (xy 315.685119 17.685779)
			(xy 315.770502 17.677867) (xy 315.854792 17.662111) (xy 315.937268 17.638644) (xy 316.017227 17.607668)
			(xy 316.093987 17.569446) (xy 316.166893 17.524305) (xy 316.235322 17.472629) (xy 316.298692 17.41486)
			(xy 316.356461 17.35149) (xy 316.408137 17.283061) (xy 316.453278 17.210155) (xy 316.4915 17.133395)
			(xy 316.522476 17.053436) (xy 316.545943 16.97096) (xy 316.561699 16.88667) (xy 316.569611 16.801287)
			(xy 316.570106 16.758412) (xy 316.569693 16.722649) (xy 334.455757 16.722649) (xy 334.455757 16.808399)
			(xy 334.463669 16.893782) (xy 334.479425 16.978072) (xy 334.502892 17.060548) (xy 334.533868 17.140507)
			(xy 334.57209 17.217267) (xy 334.617231 17.290173) (xy 334.668907 17.358602) (xy 334.726676 17.421972)
			(xy 334.790046 17.479741) (xy 334.858475 17.531417) (xy 334.931381 17.576558) (xy 335.008141 17.61478)
			(xy 335.0881 17.645756) (xy 335.170576 17.669223) (xy 335.254866 17.684979) (xy 335.340249 17.692891)
			(xy 335.425999 17.692891) (xy 335.511382 17.684979) (xy 335.595672 17.669223) (xy 335.678148 17.645756)
			(xy 335.758107 17.61478) (xy 335.78031 17.603724) (xy 339.390736 17.603724) (xy 339.390736 18.467324)
			(xy 339.391222 18.494593) (xy 339.398984 18.548577) (xy 339.414349 18.600907) (xy 339.437006 18.650517)
			(xy 339.466492 18.696398) (xy 339.502207 18.737615) (xy 339.543424 18.77333) (xy 339.589305 18.802816)
			(xy 339.638915 18.825473) (xy 339.691245 18.840838) (xy 339.745229 18.8486) (xy 339.799767 18.8486)
			(xy 339.853751 18.840838) (xy 339.906081 18.825473) (xy 339.955691 18.802816) (xy 340.001572 18.77333)
			(xy 340.042789 18.737615) (xy 340.078504 18.696398) (xy 340.10799 18.650517) (xy 340.130647 18.600907)
			(xy 340.146012 18.548577) (xy 340.153774 18.494593) (xy 340.15426 18.467324) (xy 340.15426 17.603724)
			(xy 340.153774 17.576455) (xy 340.146012 17.522471) (xy 340.130647 17.470141) (xy 340.10799 17.420531)
			(xy 340.078504 17.37465) (xy 340.042789 17.333433) (xy 340.001572 17.297718) (xy 339.955691 17.268232)
			(xy 339.906081 17.245575) (xy 339.853751 17.23021) (xy 339.799767 17.222448) (xy 339.745229 17.222448)
			(xy 339.691245 17.23021) (xy 339.638915 17.245575) (xy 339.589305 17.268232) (xy 339.543424 17.297718)
			(xy 339.502207 17.333433) (xy 339.466492 17.37465) (xy 339.437006 17.420531) (xy 339.414349 17.470141)
			(xy 339.398984 17.522471) (xy 339.391222 17.576455) (xy 339.390736 17.603724) (xy 335.78031 17.603724)
			(xy 335.834867 17.576558) (xy 335.907773 17.531417) (xy 335.976202 17.479741) (xy 336.039572 17.421972)
			(xy 336.097341 17.358602) (xy 336.149017 17.290173) (xy 336.194158 17.217267) (xy 336.23238 17.140507)
			(xy 336.263356 17.060548) (xy 336.286823 16.978072) (xy 336.302579 16.893782) (xy 336.310491 16.808399)
			(xy 336.310986 16.765524) (xy 336.310491 16.722649) (xy 340.805757 16.722649) (xy 340.805757 16.808399)
			(xy 340.813669 16.893782) (xy 340.829425 16.978072) (xy 340.852892 17.060548) (xy 340.883868 17.140507)
			(xy 340.92209 17.217267) (xy 340.967231 17.290173) (xy 341.018907 17.358602) (xy 341.076676 17.421972)
			(xy 341.140046 17.479741) (xy 341.208475 17.531417) (xy 341.281381 17.576558) (xy 341.358141 17.61478)
			(xy 341.4381 17.645756) (xy 341.520576 17.669223) (xy 341.604866 17.684979) (xy 341.690249 17.692891)
			(xy 341.775999 17.692891) (xy 341.861382 17.684979) (xy 341.945672 17.669223) (xy 342.028148 17.645756)
			(xy 342.108107 17.61478) (xy 342.184867 17.576558) (xy 342.257773 17.531417) (xy 342.326202 17.479741)
			(xy 342.389572 17.421972) (xy 342.447341 17.358602) (xy 342.499017 17.290173) (xy 342.544158 17.217267)
			(xy 342.58238 17.140507) (xy 342.613356 17.060548) (xy 342.636823 16.978072) (xy 342.652579 16.893782)
			(xy 342.660491 16.808399) (xy 342.660986 16.765524) (xy 342.660491 16.722649) (xy 342.659832 16.715537)
			(xy 373.515877 16.715537) (xy 373.515877 16.801287) (xy 373.523789 16.88667) (xy 373.539545 16.97096)
			(xy 373.563012 17.053436) (xy 373.593988 17.133395) (xy 373.63221 17.210155) (xy 373.677351 17.283061)
			(xy 373.729027 17.35149) (xy 373.786796 17.41486) (xy 373.850166 17.472629) (xy 373.918595 17.524305)
			(xy 373.991501 17.569446) (xy 374.068261 17.607668) (xy 374.14822 17.638644) (xy 374.230696 17.662111)
			(xy 374.314986 17.677867) (xy 374.400369 17.685779) (xy 374.486119 17.685779) (xy 374.571502 17.677867)
			(xy 374.655792 17.662111) (xy 374.738268 17.638644) (xy 374.818227 17.607668) (xy 374.84043 17.596612)
			(xy 376.022108 17.596612) (xy 376.022108 18.460212) (xy 376.022594 18.487481) (xy 376.030356 18.541465)
			(xy 376.045721 18.593795) (xy 376.068378 18.643405) (xy 376.097864 18.689286) (xy 376.133579 18.730503)
			(xy 376.174796 18.766218) (xy 376.220677 18.795704) (xy 376.270287 18.818361) (xy 376.322617 18.833726)
			(xy 376.376601 18.841488) (xy 376.431139 18.841488) (xy 376.485123 18.833726) (xy 376.537453 18.818361)
			(xy 376.587063 18.795704) (xy 376.632944 18.766218) (xy 376.674161 18.730503) (xy 376.709876 18.689286)
			(xy 376.739362 18.643405) (xy 376.762019 18.593795) (xy 376.777384 18.541465) (xy 376.785146 18.487481)
			(xy 376.785632 18.460212) (xy 376.785632 17.596612) (xy 376.785146 17.569343) (xy 376.777384 17.515359)
			(xy 376.762019 17.463029) (xy 376.739362 17.413419) (xy 376.709876 17.367538) (xy 376.674161 17.326321)
			(xy 376.632944 17.290606) (xy 376.587063 17.26112) (xy 376.537453 17.238463) (xy 376.485123 17.223098)
			(xy 376.431139 17.215336) (xy 376.376601 17.215336) (xy 376.322617 17.223098) (xy 376.270287 17.238463)
			(xy 376.220677 17.26112) (xy 376.174796 17.290606) (xy 376.133579 17.326321) (xy 376.097864 17.367538)
			(xy 376.068378 17.413419) (xy 376.045721 17.463029) (xy 376.030356 17.515359) (xy 376.022594 17.569343)
			(xy 376.022108 17.596612) (xy 374.84043 17.596612) (xy 374.894987 17.569446) (xy 374.967893 17.524305)
			(xy 375.036322 17.472629) (xy 375.099692 17.41486) (xy 375.157461 17.35149) (xy 375.209137 17.283061)
			(xy 375.254278 17.210155) (xy 375.2925 17.133395) (xy 375.323476 17.053436) (xy 375.346943 16.97096)
			(xy 375.362699 16.88667) (xy 375.370611 16.801287) (xy 375.371106 16.758412) (xy 375.370611 16.715537)
			(xy 379.865877 16.715537) (xy 379.865877 16.801287) (xy 379.873789 16.88667) (xy 379.889545 16.97096)
			(xy 379.913012 17.053436) (xy 379.943988 17.133395) (xy 379.98221 17.210155) (xy 380.027351 17.283061)
			(xy 380.079027 17.35149) (xy 380.136796 17.41486) (xy 380.200166 17.472629) (xy 380.268595 17.524305)
			(xy 380.341501 17.569446) (xy 380.418261 17.607668) (xy 380.49822 17.638644) (xy 380.580696 17.662111)
			(xy 380.664986 17.677867) (xy 380.750369 17.685779) (xy 380.836119 17.685779) (xy 380.921502 17.677867)
			(xy 381.005792 17.662111) (xy 381.088268 17.638644) (xy 381.168227 17.607668) (xy 381.244987 17.569446)
			(xy 381.317893 17.524305) (xy 381.386322 17.472629) (xy 381.449692 17.41486) (xy 381.507461 17.35149)
			(xy 381.559137 17.283061) (xy 381.604278 17.210155) (xy 381.6425 17.133395) (xy 381.673476 17.053436)
			(xy 381.696943 16.97096) (xy 381.712699 16.88667) (xy 381.720611 16.801287) (xy 381.721106 16.758412)
			(xy 381.720693 16.722649) (xy 399.098757 16.722649) (xy 399.098757 16.808399) (xy 399.106669 16.893782)
			(xy 399.122425 16.978072) (xy 399.145892 17.060548) (xy 399.176868 17.140507) (xy 399.21509 17.217267)
			(xy 399.260231 17.290173) (xy 399.311907 17.358602) (xy 399.369676 17.421972) (xy 399.433046 17.479741)
			(xy 399.501475 17.531417) (xy 399.574381 17.576558) (xy 399.651141 17.61478) (xy 399.7311 17.645756)
			(xy 399.813576 17.669223) (xy 399.897866 17.684979) (xy 399.983249 17.692891) (xy 400.068999 17.692891)
			(xy 400.154382 17.684979) (xy 400.238672 17.669223) (xy 400.321148 17.645756) (xy 400.401107 17.61478)
			(xy 400.42331 17.603724) (xy 404.033736 17.603724) (xy 404.033736 18.467324) (xy 404.034222 18.494593)
			(xy 404.041984 18.548577) (xy 404.057349 18.600907) (xy 404.080006 18.650517) (xy 404.109492 18.696398)
			(xy 404.145207 18.737615) (xy 404.186424 18.77333) (xy 404.232305 18.802816) (xy 404.281915 18.825473)
			(xy 404.334245 18.840838) (xy 404.388229 18.8486) (xy 404.442767 18.8486) (xy 404.496751 18.840838)
			(xy 404.549081 18.825473) (xy 404.598691 18.802816) (xy 404.644572 18.77333) (xy 404.685789 18.737615)
			(xy 404.721504 18.696398) (xy 404.75099 18.650517) (xy 404.773647 18.600907) (xy 404.789012 18.548577)
			(xy 404.796774 18.494593) (xy 404.79726 18.467324) (xy 404.79726 17.603724) (xy 404.796774 17.576455)
			(xy 404.789012 17.522471) (xy 404.773647 17.470141) (xy 404.75099 17.420531) (xy 404.721504 17.37465)
			(xy 404.685789 17.333433) (xy 404.644572 17.297718) (xy 404.598691 17.268232) (xy 404.549081 17.245575)
			(xy 404.496751 17.23021) (xy 404.442767 17.222448) (xy 404.388229 17.222448) (xy 404.334245 17.23021)
			(xy 404.281915 17.245575) (xy 404.232305 17.268232) (xy 404.186424 17.297718) (xy 404.145207 17.333433)
			(xy 404.109492 17.37465) (xy 404.080006 17.420531) (xy 404.057349 17.470141) (xy 404.041984 17.522471)
			(xy 404.034222 17.576455) (xy 404.033736 17.603724) (xy 400.42331 17.603724) (xy 400.477867 17.576558)
			(xy 400.550773 17.531417) (xy 400.619202 17.479741) (xy 400.682572 17.421972) (xy 400.740341 17.358602)
			(xy 400.792017 17.290173) (xy 400.837158 17.217267) (xy 400.87538 17.140507) (xy 400.906356 17.060548)
			(xy 400.929823 16.978072) (xy 400.945579 16.893782) (xy 400.953491 16.808399) (xy 400.953986 16.765524)
			(xy 400.953491 16.722649) (xy 405.448757 16.722649) (xy 405.448757 16.808399) (xy 405.456669 16.893782)
			(xy 405.472425 16.978072) (xy 405.495892 17.060548) (xy 405.526868 17.140507) (xy 405.56509 17.217267)
			(xy 405.610231 17.290173) (xy 405.661907 17.358602) (xy 405.719676 17.421972) (xy 405.783046 17.479741)
			(xy 405.851475 17.531417) (xy 405.924381 17.576558) (xy 406.001141 17.61478) (xy 406.0811 17.645756)
			(xy 406.163576 17.669223) (xy 406.247866 17.684979) (xy 406.333249 17.692891) (xy 406.418999 17.692891)
			(xy 406.504382 17.684979) (xy 406.588672 17.669223) (xy 406.671148 17.645756) (xy 406.751107 17.61478)
			(xy 406.827867 17.576558) (xy 406.900773 17.531417) (xy 406.969202 17.479741) (xy 407.032572 17.421972)
			(xy 407.090341 17.358602) (xy 407.142017 17.290173) (xy 407.187158 17.217267) (xy 407.22538 17.140507)
			(xy 407.256356 17.060548) (xy 407.279823 16.978072) (xy 407.295579 16.893782) (xy 407.303491 16.808399)
			(xy 407.303986 16.765524) (xy 407.303491 16.722649) (xy 407.302832 16.715537) (xy 438.158877 16.715537)
			(xy 438.158877 16.801287) (xy 438.166789 16.88667) (xy 438.182545 16.97096) (xy 438.206012 17.053436)
			(xy 438.236988 17.133395) (xy 438.27521 17.210155) (xy 438.320351 17.283061) (xy 438.372027 17.35149)
			(xy 438.429796 17.41486) (xy 438.493166 17.472629) (xy 438.561595 17.524305) (xy 438.634501 17.569446)
			(xy 438.711261 17.607668) (xy 438.79122 17.638644) (xy 438.873696 17.662111) (xy 438.957986 17.677867)
			(xy 439.043369 17.685779) (xy 439.129119 17.685779) (xy 439.214502 17.677867) (xy 439.298792 17.662111)
			(xy 439.381268 17.638644) (xy 439.461227 17.607668) (xy 439.48343 17.596612) (xy 440.665108 17.596612)
			(xy 440.665108 18.460212) (xy 440.665594 18.487481) (xy 440.673356 18.541465) (xy 440.688721 18.593795)
			(xy 440.711378 18.643405) (xy 440.740864 18.689286) (xy 440.776579 18.730503) (xy 440.817796 18.766218)
			(xy 440.863677 18.795704) (xy 440.913287 18.818361) (xy 440.965617 18.833726) (xy 441.019601 18.841488)
			(xy 441.074139 18.841488) (xy 441.128123 18.833726) (xy 441.180453 18.818361) (xy 441.230063 18.795704)
			(xy 441.275944 18.766218) (xy 441.317161 18.730503) (xy 441.352876 18.689286) (xy 441.382362 18.643405)
			(xy 441.405019 18.593795) (xy 441.420384 18.541465) (xy 441.428146 18.487481) (xy 441.428632 18.460212)
			(xy 441.428632 17.596612) (xy 441.428146 17.569343) (xy 441.420384 17.515359) (xy 441.405019 17.463029)
			(xy 441.382362 17.413419) (xy 441.352876 17.367538) (xy 441.317161 17.326321) (xy 441.275944 17.290606)
			(xy 441.230063 17.26112) (xy 441.180453 17.238463) (xy 441.128123 17.223098) (xy 441.074139 17.215336)
			(xy 441.019601 17.215336) (xy 440.965617 17.223098) (xy 440.913287 17.238463) (xy 440.863677 17.26112)
			(xy 440.817796 17.290606) (xy 440.776579 17.326321) (xy 440.740864 17.367538) (xy 440.711378 17.413419)
			(xy 440.688721 17.463029) (xy 440.673356 17.515359) (xy 440.665594 17.569343) (xy 440.665108 17.596612)
			(xy 439.48343 17.596612) (xy 439.537987 17.569446) (xy 439.610893 17.524305) (xy 439.679322 17.472629)
			(xy 439.742692 17.41486) (xy 439.800461 17.35149) (xy 439.852137 17.283061) (xy 439.897278 17.210155)
			(xy 439.9355 17.133395) (xy 439.966476 17.053436) (xy 439.989943 16.97096) (xy 440.005699 16.88667)
			(xy 440.013611 16.801287) (xy 440.014106 16.758412) (xy 440.013611 16.715537) (xy 444.508877 16.715537)
			(xy 444.508877 16.801287) (xy 444.516789 16.88667) (xy 444.532545 16.97096) (xy 444.556012 17.053436)
			(xy 444.586988 17.133395) (xy 444.62521 17.210155) (xy 444.670351 17.283061) (xy 444.722027 17.35149)
			(xy 444.779796 17.41486) (xy 444.843166 17.472629) (xy 444.911595 17.524305) (xy 444.984501 17.569446)
			(xy 445.061261 17.607668) (xy 445.14122 17.638644) (xy 445.223696 17.662111) (xy 445.307986 17.677867)
			(xy 445.393369 17.685779) (xy 445.479119 17.685779) (xy 445.564502 17.677867) (xy 445.648792 17.662111)
			(xy 445.731268 17.638644) (xy 445.811227 17.607668) (xy 445.887987 17.569446) (xy 445.960893 17.524305)
			(xy 446.029322 17.472629) (xy 446.092692 17.41486) (xy 446.150461 17.35149) (xy 446.202137 17.283061)
			(xy 446.247278 17.210155) (xy 446.2855 17.133395) (xy 446.316476 17.053436) (xy 446.339943 16.97096)
			(xy 446.355699 16.88667) (xy 446.363611 16.801287) (xy 446.364106 16.758412) (xy 446.363611 16.715537)
			(xy 446.355699 16.630154) (xy 446.339943 16.545864) (xy 446.316476 16.463388) (xy 446.2855 16.383429)
			(xy 446.247278 16.306669) (xy 446.202137 16.233763) (xy 446.150461 16.165334) (xy 446.092692 16.101964)
			(xy 446.029322 16.044195) (xy 445.960893 15.992519) (xy 445.887987 15.947378) (xy 445.811227 15.909156)
			(xy 445.731268 15.87818) (xy 445.648792 15.854713) (xy 445.564502 15.838957) (xy 445.479119 15.831045)
			(xy 445.393369 15.831045) (xy 445.307986 15.838957) (xy 445.223696 15.854713) (xy 445.14122 15.87818)
			(xy 445.061261 15.909156) (xy 444.984501 15.947378) (xy 444.911595 15.992519) (xy 444.843166 16.044195)
			(xy 444.779796 16.101964) (xy 444.722027 16.165334) (xy 444.670351 16.233763) (xy 444.62521 16.306669)
			(xy 444.586988 16.383429) (xy 444.556012 16.463388) (xy 444.532545 16.545864) (xy 444.516789 16.630154)
			(xy 444.508877 16.715537) (xy 440.013611 16.715537) (xy 440.005699 16.630154) (xy 439.989943 16.545864)
			(xy 439.966476 16.463388) (xy 439.9355 16.383429) (xy 439.897278 16.306669) (xy 439.852137 16.233763)
			(xy 439.800461 16.165334) (xy 439.742692 16.101964) (xy 439.679322 16.044195) (xy 439.610893 15.992519)
			(xy 439.537987 15.947378) (xy 439.461227 15.909156) (xy 439.381268 15.87818) (xy 439.298792 15.854713)
			(xy 439.214502 15.838957) (xy 439.129119 15.831045) (xy 439.043369 15.831045) (xy 438.957986 15.838957)
			(xy 438.873696 15.854713) (xy 438.79122 15.87818) (xy 438.711261 15.909156) (xy 438.634501 15.947378)
			(xy 438.561595 15.992519) (xy 438.493166 16.044195) (xy 438.429796 16.101964) (xy 438.372027 16.165334)
			(xy 438.320351 16.233763) (xy 438.27521 16.306669) (xy 438.236988 16.383429) (xy 438.206012 16.463388)
			(xy 438.182545 16.545864) (xy 438.166789 16.630154) (xy 438.158877 16.715537) (xy 407.302832 16.715537)
			(xy 407.295579 16.637266) (xy 407.279823 16.552976) (xy 407.256356 16.4705) (xy 407.22538 16.390541)
			(xy 407.187158 16.313781) (xy 407.142017 16.240875) (xy 407.090341 16.172446) (xy 407.032572 16.109076)
			(xy 406.969202 16.051307) (xy 406.900773 15.999631) (xy 406.827867 15.95449) (xy 406.751107 15.916268)
			(xy 406.671148 15.885292) (xy 406.588672 15.861825) (xy 406.504382 15.846069) (xy 406.418999 15.838157)
			(xy 406.333249 15.838157) (xy 406.247866 15.846069) (xy 406.163576 15.861825) (xy 406.0811 15.885292)
			(xy 406.001141 15.916268) (xy 405.924381 15.95449) (xy 405.851475 15.999631) (xy 405.783046 16.051307)
			(xy 405.719676 16.109076) (xy 405.661907 16.172446) (xy 405.610231 16.240875) (xy 405.56509 16.313781)
			(xy 405.526868 16.390541) (xy 405.495892 16.4705) (xy 405.472425 16.552976) (xy 405.456669 16.637266)
			(xy 405.448757 16.722649) (xy 400.953491 16.722649) (xy 400.945579 16.637266) (xy 400.929823 16.552976)
			(xy 400.906356 16.4705) (xy 400.87538 16.390541) (xy 400.837158 16.313781) (xy 400.792017 16.240875)
			(xy 400.740341 16.172446) (xy 400.682572 16.109076) (xy 400.619202 16.051307) (xy 400.550773 15.999631)
			(xy 400.477867 15.95449) (xy 400.401107 15.916268) (xy 400.321148 15.885292) (xy 400.238672 15.861825)
			(xy 400.154382 15.846069) (xy 400.068999 15.838157) (xy 399.983249 15.838157) (xy 399.897866 15.846069)
			(xy 399.813576 15.861825) (xy 399.7311 15.885292) (xy 399.651141 15.916268) (xy 399.574381 15.95449)
			(xy 399.501475 15.999631) (xy 399.433046 16.051307) (xy 399.369676 16.109076) (xy 399.311907 16.172446)
			(xy 399.260231 16.240875) (xy 399.21509 16.313781) (xy 399.176868 16.390541) (xy 399.145892 16.4705)
			(xy 399.122425 16.552976) (xy 399.106669 16.637266) (xy 399.098757 16.722649) (xy 381.720693 16.722649)
			(xy 381.720611 16.715537) (xy 381.712699 16.630154) (xy 381.696943 16.545864) (xy 381.673476 16.463388)
			(xy 381.6425 16.383429) (xy 381.604278 16.306669) (xy 381.559137 16.233763) (xy 381.507461 16.165334)
			(xy 381.449692 16.101964) (xy 381.386322 16.044195) (xy 381.317893 15.992519) (xy 381.244987 15.947378)
			(xy 381.168227 15.909156) (xy 381.088268 15.87818) (xy 381.005792 15.854713) (xy 380.921502 15.838957)
			(xy 380.836119 15.831045) (xy 380.750369 15.831045) (xy 380.664986 15.838957) (xy 380.580696 15.854713)
			(xy 380.49822 15.87818) (xy 380.418261 15.909156) (xy 380.341501 15.947378) (xy 380.268595 15.992519)
			(xy 380.200166 16.044195) (xy 380.136796 16.101964) (xy 380.079027 16.165334) (xy 380.027351 16.233763)
			(xy 379.98221 16.306669) (xy 379.943988 16.383429) (xy 379.913012 16.463388) (xy 379.889545 16.545864)
			(xy 379.873789 16.630154) (xy 379.865877 16.715537) (xy 375.370611 16.715537) (xy 375.362699 16.630154)
			(xy 375.346943 16.545864) (xy 375.323476 16.463388) (xy 375.2925 16.383429) (xy 375.254278 16.306669)
			(xy 375.209137 16.233763) (xy 375.157461 16.165334) (xy 375.099692 16.101964) (xy 375.036322 16.044195)
			(xy 374.967893 15.992519) (xy 374.894987 15.947378) (xy 374.818227 15.909156) (xy 374.738268 15.87818)
			(xy 374.655792 15.854713) (xy 374.571502 15.838957) (xy 374.486119 15.831045) (xy 374.400369 15.831045)
			(xy 374.314986 15.838957) (xy 374.230696 15.854713) (xy 374.14822 15.87818) (xy 374.068261 15.909156)
			(xy 373.991501 15.947378) (xy 373.918595 15.992519) (xy 373.850166 16.044195) (xy 373.786796 16.101964)
			(xy 373.729027 16.165334) (xy 373.677351 16.233763) (xy 373.63221 16.306669) (xy 373.593988 16.383429)
			(xy 373.563012 16.463388) (xy 373.539545 16.545864) (xy 373.523789 16.630154) (xy 373.515877 16.715537)
			(xy 342.659832 16.715537) (xy 342.652579 16.637266) (xy 342.636823 16.552976) (xy 342.613356 16.4705)
			(xy 342.58238 16.390541) (xy 342.544158 16.313781) (xy 342.499017 16.240875) (xy 342.447341 16.172446)
			(xy 342.389572 16.109076) (xy 342.326202 16.051307) (xy 342.257773 15.999631) (xy 342.184867 15.95449)
			(xy 342.108107 15.916268) (xy 342.028148 15.885292) (xy 341.945672 15.861825) (xy 341.861382 15.846069)
			(xy 341.775999 15.838157) (xy 341.690249 15.838157) (xy 341.604866 15.846069) (xy 341.520576 15.861825)
			(xy 341.4381 15.885292) (xy 341.358141 15.916268) (xy 341.281381 15.95449) (xy 341.208475 15.999631)
			(xy 341.140046 16.051307) (xy 341.076676 16.109076) (xy 341.018907 16.172446) (xy 340.967231 16.240875)
			(xy 340.92209 16.313781) (xy 340.883868 16.390541) (xy 340.852892 16.4705) (xy 340.829425 16.552976)
			(xy 340.813669 16.637266) (xy 340.805757 16.722649) (xy 336.310491 16.722649) (xy 336.302579 16.637266)
			(xy 336.286823 16.552976) (xy 336.263356 16.4705) (xy 336.23238 16.390541) (xy 336.194158 16.313781)
			(xy 336.149017 16.240875) (xy 336.097341 16.172446) (xy 336.039572 16.109076) (xy 335.976202 16.051307)
			(xy 335.907773 15.999631) (xy 335.834867 15.95449) (xy 335.758107 15.916268) (xy 335.678148 15.885292)
			(xy 335.595672 15.861825) (xy 335.511382 15.846069) (xy 335.425999 15.838157) (xy 335.340249 15.838157)
			(xy 335.254866 15.846069) (xy 335.170576 15.861825) (xy 335.0881 15.885292) (xy 335.008141 15.916268)
			(xy 334.931381 15.95449) (xy 334.858475 15.999631) (xy 334.790046 16.051307) (xy 334.726676 16.109076)
			(xy 334.668907 16.172446) (xy 334.617231 16.240875) (xy 334.57209 16.313781) (xy 334.533868 16.390541)
			(xy 334.502892 16.4705) (xy 334.479425 16.552976) (xy 334.463669 16.637266) (xy 334.455757 16.722649)
			(xy 316.569693 16.722649) (xy 316.569611 16.715537) (xy 316.561699 16.630154) (xy 316.545943 16.545864)
			(xy 316.522476 16.463388) (xy 316.4915 16.383429) (xy 316.453278 16.306669) (xy 316.408137 16.233763)
			(xy 316.356461 16.165334) (xy 316.298692 16.101964) (xy 316.235322 16.044195) (xy 316.166893 15.992519)
			(xy 316.093987 15.947378) (xy 316.017227 15.909156) (xy 315.937268 15.87818) (xy 315.854792 15.854713)
			(xy 315.770502 15.838957) (xy 315.685119 15.831045) (xy 315.599369 15.831045) (xy 315.513986 15.838957)
			(xy 315.429696 15.854713) (xy 315.34722 15.87818) (xy 315.267261 15.909156) (xy 315.190501 15.947378)
			(xy 315.117595 15.992519) (xy 315.049166 16.044195) (xy 314.985796 16.101964) (xy 314.928027 16.165334)
			(xy 314.876351 16.233763) (xy 314.83121 16.306669) (xy 314.792988 16.383429) (xy 314.762012 16.463388)
			(xy 314.738545 16.545864) (xy 314.722789 16.630154) (xy 314.714877 16.715537) (xy 310.219611 16.715537)
			(xy 310.211699 16.630154) (xy 310.195943 16.545864) (xy 310.172476 16.463388) (xy 310.1415 16.383429)
			(xy 310.103278 16.306669) (xy 310.058137 16.233763) (xy 310.006461 16.165334) (xy 309.948692 16.101964)
			(xy 309.885322 16.044195) (xy 309.816893 15.992519) (xy 309.743987 15.947378) (xy 309.667227 15.909156)
			(xy 309.587268 15.87818) (xy 309.504792 15.854713) (xy 309.420502 15.838957) (xy 309.335119 15.831045)
			(xy 309.249369 15.831045) (xy 309.163986 15.838957) (xy 309.079696 15.854713) (xy 308.99722 15.87818)
			(xy 308.917261 15.909156) (xy 308.840501 15.947378) (xy 308.767595 15.992519) (xy 308.699166 16.044195)
			(xy 308.635796 16.101964) (xy 308.578027 16.165334) (xy 308.526351 16.233763) (xy 308.48121 16.306669)
			(xy 308.442988 16.383429) (xy 308.412012 16.463388) (xy 308.388545 16.545864) (xy 308.372789 16.630154)
			(xy 308.364877 16.715537) (xy 277.508832 16.715537) (xy 277.501579 16.637266) (xy 277.485823 16.552976)
			(xy 277.462356 16.4705) (xy 277.43138 16.390541) (xy 277.393158 16.313781) (xy 277.348017 16.240875)
			(xy 277.296341 16.172446) (xy 277.238572 16.109076) (xy 277.175202 16.051307) (xy 277.106773 15.999631)
			(xy 277.033867 15.95449) (xy 276.957107 15.916268) (xy 276.877148 15.885292) (xy 276.794672 15.861825)
			(xy 276.710382 15.846069) (xy 276.624999 15.838157) (xy 276.539249 15.838157) (xy 276.453866 15.846069)
			(xy 276.369576 15.861825) (xy 276.2871 15.885292) (xy 276.207141 15.916268) (xy 276.130381 15.95449)
			(xy 276.057475 15.999631) (xy 275.989046 16.051307) (xy 275.925676 16.109076) (xy 275.867907 16.172446)
			(xy 275.816231 16.240875) (xy 275.77109 16.313781) (xy 275.732868 16.390541) (xy 275.701892 16.4705)
			(xy 275.678425 16.552976) (xy 275.662669 16.637266) (xy 275.654757 16.722649) (xy 271.159491 16.722649)
			(xy 271.151579 16.637266) (xy 271.135823 16.552976) (xy 271.112356 16.4705) (xy 271.08138 16.390541)
			(xy 271.043158 16.313781) (xy 270.998017 16.240875) (xy 270.946341 16.172446) (xy 270.888572 16.109076)
			(xy 270.825202 16.051307) (xy 270.756773 15.999631) (xy 270.683867 15.95449) (xy 270.607107 15.916268)
			(xy 270.527148 15.885292) (xy 270.444672 15.861825) (xy 270.360382 15.846069) (xy 270.274999 15.838157)
			(xy 270.189249 15.838157) (xy 270.103866 15.846069) (xy 270.019576 15.861825) (xy 269.9371 15.885292)
			(xy 269.857141 15.916268) (xy 269.780381 15.95449) (xy 269.707475 15.999631) (xy 269.639046 16.051307)
			(xy 269.575676 16.109076) (xy 269.517907 16.172446) (xy 269.466231 16.240875) (xy 269.42109 16.313781)
			(xy 269.382868 16.390541) (xy 269.351892 16.4705) (xy 269.328425 16.552976) (xy 269.312669 16.637266)
			(xy 269.304757 16.722649) (xy 252.231493 16.722649) (xy 252.231411 16.715537) (xy 252.223499 16.630154)
			(xy 252.207743 16.545864) (xy 252.184276 16.463388) (xy 252.1533 16.383429) (xy 252.115078 16.306669)
			(xy 252.069937 16.233763) (xy 252.018261 16.165334) (xy 251.960492 16.101964) (xy 251.897122 16.044195)
			(xy 251.828693 15.992519) (xy 251.755787 15.947378) (xy 251.679027 15.909156) (xy 251.599068 15.87818)
			(xy 251.516592 15.854713) (xy 251.432302 15.838957) (xy 251.346919 15.831045) (xy 251.261169 15.831045)
			(xy 251.175786 15.838957) (xy 251.091496 15.854713) (xy 251.00902 15.87818) (xy 250.929061 15.909156)
			(xy 250.852301 15.947378) (xy 250.779395 15.992519) (xy 250.710966 16.044195) (xy 250.647596 16.101964)
			(xy 250.589827 16.165334) (xy 250.538151 16.233763) (xy 250.49301 16.306669) (xy 250.454788 16.383429)
			(xy 250.423812 16.463388) (xy 250.400345 16.545864) (xy 250.384589 16.630154) (xy 250.376677 16.715537)
			(xy 245.881411 16.715537) (xy 245.873499 16.630154) (xy 245.857743 16.545864) (xy 245.834276 16.463388)
			(xy 245.8033 16.383429) (xy 245.765078 16.306669) (xy 245.719937 16.233763) (xy 245.668261 16.165334)
			(xy 245.610492 16.101964) (xy 245.547122 16.044195) (xy 245.478693 15.992519) (xy 245.405787 15.947378)
			(xy 245.329027 15.909156) (xy 245.249068 15.87818) (xy 245.166592 15.854713) (xy 245.082302 15.838957)
			(xy 244.996919 15.831045) (xy 244.911169 15.831045) (xy 244.825786 15.838957) (xy 244.741496 15.854713)
			(xy 244.65902 15.87818) (xy 244.579061 15.909156) (xy 244.502301 15.947378) (xy 244.429395 15.992519)
			(xy 244.360966 16.044195) (xy 244.297596 16.101964) (xy 244.239827 16.165334) (xy 244.188151 16.233763)
			(xy 244.14301 16.306669) (xy 244.104788 16.383429) (xy 244.073812 16.463388) (xy 244.050345 16.545864)
			(xy 244.034589 16.630154) (xy 244.026677 16.715537) (xy 218.199832 16.715537) (xy 218.192579 16.637266)
			(xy 218.176823 16.552976) (xy 218.153356 16.4705) (xy 218.12238 16.390541) (xy 218.084158 16.313781)
			(xy 218.039017 16.240875) (xy 217.987341 16.172446) (xy 217.929572 16.109076) (xy 217.866202 16.051307)
			(xy 217.797773 15.999631) (xy 217.724867 15.95449) (xy 217.648107 15.916268) (xy 217.568148 15.885292)
			(xy 217.485672 15.861825) (xy 217.401382 15.846069) (xy 217.315999 15.838157) (xy 217.230249 15.838157)
			(xy 217.144866 15.846069) (xy 217.060576 15.861825) (xy 216.9781 15.885292) (xy 216.898141 15.916268)
			(xy 216.821381 15.95449) (xy 216.748475 15.999631) (xy 216.680046 16.051307) (xy 216.616676 16.109076)
			(xy 216.558907 16.172446) (xy 216.507231 16.240875) (xy 216.46209 16.313781) (xy 216.423868 16.390541)
			(xy 216.392892 16.4705) (xy 216.369425 16.552976) (xy 216.353669 16.637266) (xy 216.345757 16.722649)
			(xy 211.850491 16.722649) (xy 211.842579 16.637266) (xy 211.826823 16.552976) (xy 211.803356 16.4705)
			(xy 211.77238 16.390541) (xy 211.734158 16.313781) (xy 211.689017 16.240875) (xy 211.637341 16.172446)
			(xy 211.579572 16.109076) (xy 211.516202 16.051307) (xy 211.447773 15.999631) (xy 211.374867 15.95449)
			(xy 211.298107 15.916268) (xy 211.218148 15.885292) (xy 211.135672 15.861825) (xy 211.051382 15.846069)
			(xy 210.965999 15.838157) (xy 210.880249 15.838157) (xy 210.794866 15.846069) (xy 210.710576 15.861825)
			(xy 210.6281 15.885292) (xy 210.548141 15.916268) (xy 210.471381 15.95449) (xy 210.398475 15.999631)
			(xy 210.330046 16.051307) (xy 210.266676 16.109076) (xy 210.208907 16.172446) (xy 210.157231 16.240875)
			(xy 210.11209 16.313781) (xy 210.073868 16.390541) (xy 210.042892 16.4705) (xy 210.019425 16.552976)
			(xy 210.003669 16.637266) (xy 209.995757 16.722649) (xy 158.621984 16.722649) (xy 158.621984 11.850929)
			(xy 251.524757 11.850929) (xy 251.524757 11.936679) (xy 251.532669 12.022062) (xy 251.548425 12.106352)
			(xy 251.571892 12.188828) (xy 251.602868 12.268787) (xy 251.64109 12.345547) (xy 251.686231 12.418453)
			(xy 251.737907 12.486882) (xy 251.795676 12.550252) (xy 251.859046 12.608021) (xy 251.927475 12.659697)
			(xy 252.000381 12.704838) (xy 252.077141 12.74306) (xy 252.1571 12.774036) (xy 252.239576 12.797503)
			(xy 252.323866 12.813259) (xy 252.409249 12.821171) (xy 252.494999 12.821171) (xy 252.580382 12.813259)
			(xy 252.664672 12.797503) (xy 252.747148 12.774036) (xy 252.827107 12.74306) (xy 252.903867 12.704838)
			(xy 252.976773 12.659697) (xy 253.045202 12.608021) (xy 253.108572 12.550252) (xy 253.166341 12.486882)
			(xy 253.218017 12.418453) (xy 253.263158 12.345547) (xy 253.30138 12.268787) (xy 253.332356 12.188828)
			(xy 253.355823 12.106352) (xy 253.371579 12.022062) (xy 253.379491 11.936679) (xy 253.379986 11.893804)
			(xy 253.379491 11.850929) (xy 257.874757 11.850929) (xy 257.874757 11.936679) (xy 257.882669 12.022062)
			(xy 257.898425 12.106352) (xy 257.921892 12.188828) (xy 257.952868 12.268787) (xy 257.99109 12.345547)
			(xy 258.036231 12.418453) (xy 258.087907 12.486882) (xy 258.145676 12.550252) (xy 258.209046 12.608021)
			(xy 258.277475 12.659697) (xy 258.350381 12.704838) (xy 258.427141 12.74306) (xy 258.5071 12.774036)
			(xy 258.589576 12.797503) (xy 258.673866 12.813259) (xy 258.759249 12.821171) (xy 258.844999 12.821171)
			(xy 258.930382 12.813259) (xy 259.014672 12.797503) (xy 259.097148 12.774036) (xy 259.177107 12.74306)
			(xy 259.253867 12.704838) (xy 259.326773 12.659697) (xy 259.395202 12.608021) (xy 259.458572 12.550252)
			(xy 259.516341 12.486882) (xy 259.568017 12.418453) (xy 259.613158 12.345547) (xy 259.65138 12.268787)
			(xy 259.682356 12.188828) (xy 259.705823 12.106352) (xy 259.721579 12.022062) (xy 259.729491 11.936679)
			(xy 259.729986 11.893804) (xy 259.72979 11.876837) (xy 309.725301 11.876837) (xy 309.725301 11.962587)
			(xy 309.733213 12.04797) (xy 309.748969 12.13226) (xy 309.772436 12.214736) (xy 309.803412 12.294695)
			(xy 309.841634 12.371455) (xy 309.886775 12.444361) (xy 309.938451 12.51279) (xy 309.99622 12.57616)
			(xy 310.05959 12.633929) (xy 310.128019 12.685605) (xy 310.200925 12.730746) (xy 310.277685 12.768968)
			(xy 310.357644 12.799944) (xy 310.44012 12.823411) (xy 310.52441 12.839167) (xy 310.609793 12.847079)
			(xy 310.695543 12.847079) (xy 310.780926 12.839167) (xy 310.865216 12.823411) (xy 310.947692 12.799944)
			(xy 311.027651 12.768968) (xy 311.104411 12.730746) (xy 311.177317 12.685605) (xy 311.245746 12.633929)
			(xy 311.309116 12.57616) (xy 311.366885 12.51279) (xy 311.418561 12.444361) (xy 311.463702 12.371455)
			(xy 311.501924 12.294695) (xy 311.5329 12.214736) (xy 311.556367 12.13226) (xy 311.572123 12.04797)
			(xy 311.580035 11.962587) (xy 311.58053 11.919712) (xy 311.580035 11.876837) (xy 316.075301 11.876837)
			(xy 316.075301 11.962587) (xy 316.083213 12.04797) (xy 316.098969 12.13226) (xy 316.122436 12.214736)
			(xy 316.153412 12.294695) (xy 316.191634 12.371455) (xy 316.236775 12.444361) (xy 316.288451 12.51279)
			(xy 316.34622 12.57616) (xy 316.40959 12.633929) (xy 316.478019 12.685605) (xy 316.550925 12.730746)
			(xy 316.627685 12.768968) (xy 316.707644 12.799944) (xy 316.79012 12.823411) (xy 316.87441 12.839167)
			(xy 316.959793 12.847079) (xy 317.045543 12.847079) (xy 317.130926 12.839167) (xy 317.215216 12.823411)
			(xy 317.297692 12.799944) (xy 317.377651 12.768968) (xy 317.454411 12.730746) (xy 317.527317 12.685605)
			(xy 317.595746 12.633929) (xy 317.659116 12.57616) (xy 317.716885 12.51279) (xy 317.768561 12.444361)
			(xy 317.813702 12.371455) (xy 317.851924 12.294695) (xy 317.8829 12.214736) (xy 317.906367 12.13226)
			(xy 317.922123 12.04797) (xy 317.930035 11.962587) (xy 317.93053 11.919712) (xy 317.930117 11.883949)
			(xy 324.295757 11.883949) (xy 324.295757 11.969699) (xy 324.303669 12.055082) (xy 324.319425 12.139372)
			(xy 324.342892 12.221848) (xy 324.373868 12.301807) (xy 324.41209 12.378567) (xy 324.457231 12.451473)
			(xy 324.508907 12.519902) (xy 324.566676 12.583272) (xy 324.630046 12.641041) (xy 324.698475 12.692717)
			(xy 324.771381 12.737858) (xy 324.848141 12.77608) (xy 324.9281 12.807056) (xy 325.010576 12.830523)
			(xy 325.094866 12.846279) (xy 325.180249 12.854191) (xy 325.265999 12.854191) (xy 325.351382 12.846279)
			(xy 325.435672 12.830523) (xy 325.518148 12.807056) (xy 325.598107 12.77608) (xy 325.674867 12.737858)
			(xy 325.747773 12.692717) (xy 325.816202 12.641041) (xy 325.879572 12.583272) (xy 325.937341 12.519902)
			(xy 325.989017 12.451473) (xy 326.034158 12.378567) (xy 326.07238 12.301807) (xy 326.103356 12.221848)
			(xy 326.126823 12.139372) (xy 326.142579 12.055082) (xy 326.150491 11.969699) (xy 326.150986 11.926824)
			(xy 326.150491 11.883949) (xy 330.645757 11.883949) (xy 330.645757 11.969699) (xy 330.653669 12.055082)
			(xy 330.669425 12.139372) (xy 330.692892 12.221848) (xy 330.723868 12.301807) (xy 330.76209 12.378567)
			(xy 330.807231 12.451473) (xy 330.858907 12.519902) (xy 330.916676 12.583272) (xy 330.980046 12.641041)
			(xy 331.048475 12.692717) (xy 331.121381 12.737858) (xy 331.198141 12.77608) (xy 331.2781 12.807056)
			(xy 331.360576 12.830523) (xy 331.444866 12.846279) (xy 331.530249 12.854191) (xy 331.615999 12.854191)
			(xy 331.701382 12.846279) (xy 331.785672 12.830523) (xy 331.868148 12.807056) (xy 331.948107 12.77608)
			(xy 332.024867 12.737858) (xy 332.097773 12.692717) (xy 332.166202 12.641041) (xy 332.229572 12.583272)
			(xy 332.287341 12.519902) (xy 332.339017 12.451473) (xy 332.384158 12.378567) (xy 332.42238 12.301807)
			(xy 332.453356 12.221848) (xy 332.476823 12.139372) (xy 332.492579 12.055082) (xy 332.500491 11.969699)
			(xy 332.500986 11.926824) (xy 332.50079 11.909857) (xy 382.496301 11.909857) (xy 382.496301 11.995607)
			(xy 382.504213 12.08099) (xy 382.519969 12.16528) (xy 382.543436 12.247756) (xy 382.574412 12.327715)
			(xy 382.612634 12.404475) (xy 382.657775 12.477381) (xy 382.709451 12.54581) (xy 382.76722 12.60918)
			(xy 382.83059 12.666949) (xy 382.899019 12.718625) (xy 382.971925 12.763766) (xy 383.048685 12.801988)
			(xy 383.128644 12.832964) (xy 383.21112 12.856431) (xy 383.29541 12.872187) (xy 383.380793 12.880099)
			(xy 383.466543 12.880099) (xy 383.551926 12.872187) (xy 383.636216 12.856431) (xy 383.718692 12.832964)
			(xy 383.798651 12.801988) (xy 383.875411 12.763766) (xy 383.948317 12.718625) (xy 384.016746 12.666949)
			(xy 384.080116 12.60918) (xy 384.137885 12.54581) (xy 384.189561 12.477381) (xy 384.234702 12.404475)
			(xy 384.272924 12.327715) (xy 384.3039 12.247756) (xy 384.327367 12.16528) (xy 384.343123 12.08099)
			(xy 384.351035 11.995607) (xy 384.35153 11.952732) (xy 384.351035 11.909857) (xy 388.846301 11.909857)
			(xy 388.846301 11.995607) (xy 388.854213 12.08099) (xy 388.869969 12.16528) (xy 388.893436 12.247756)
			(xy 388.924412 12.327715) (xy 388.962634 12.404475) (xy 389.007775 12.477381) (xy 389.059451 12.54581)
			(xy 389.11722 12.60918) (xy 389.18059 12.666949) (xy 389.249019 12.718625) (xy 389.321925 12.763766)
			(xy 389.398685 12.801988) (xy 389.478644 12.832964) (xy 389.56112 12.856431) (xy 389.64541 12.872187)
			(xy 389.730793 12.880099) (xy 389.816543 12.880099) (xy 389.901926 12.872187) (xy 389.986216 12.856431)
			(xy 390.068692 12.832964) (xy 390.148651 12.801988) (xy 390.225411 12.763766) (xy 390.298317 12.718625)
			(xy 390.366746 12.666949) (xy 390.430116 12.60918) (xy 390.487885 12.54581) (xy 390.539561 12.477381)
			(xy 390.584702 12.404475) (xy 390.622924 12.327715) (xy 390.6539 12.247756) (xy 390.677367 12.16528)
			(xy 390.693123 12.08099) (xy 390.701035 11.995607) (xy 390.70153 11.952732) (xy 390.701117 11.916969)
			(xy 396.558757 11.916969) (xy 396.558757 12.002719) (xy 396.566669 12.088102) (xy 396.582425 12.172392)
			(xy 396.605892 12.254868) (xy 396.636868 12.334827) (xy 396.67509 12.411587) (xy 396.720231 12.484493)
			(xy 396.771907 12.552922) (xy 396.829676 12.616292) (xy 396.893046 12.674061) (xy 396.961475 12.725737)
			(xy 397.034381 12.770878) (xy 397.111141 12.8091) (xy 397.1911 12.840076) (xy 397.273576 12.863543)
			(xy 397.357866 12.879299) (xy 397.443249 12.887211) (xy 397.528999 12.887211) (xy 397.614382 12.879299)
			(xy 397.698672 12.863543) (xy 397.781148 12.840076) (xy 397.861107 12.8091) (xy 397.937867 12.770878)
			(xy 398.010773 12.725737) (xy 398.079202 12.674061) (xy 398.142572 12.616292) (xy 398.200341 12.552922)
			(xy 398.252017 12.484493) (xy 398.297158 12.411587) (xy 398.33538 12.334827) (xy 398.366356 12.254868)
			(xy 398.389823 12.172392) (xy 398.405579 12.088102) (xy 398.413491 12.002719) (xy 398.413986 11.959844)
			(xy 398.413491 11.916969) (xy 402.908757 11.916969) (xy 402.908757 12.002719) (xy 402.916669 12.088102)
			(xy 402.932425 12.172392) (xy 402.955892 12.254868) (xy 402.986868 12.334827) (xy 403.02509 12.411587)
			(xy 403.070231 12.484493) (xy 403.121907 12.552922) (xy 403.179676 12.616292) (xy 403.243046 12.674061)
			(xy 403.311475 12.725737) (xy 403.384381 12.770878) (xy 403.461141 12.8091) (xy 403.5411 12.840076)
			(xy 403.623576 12.863543) (xy 403.707866 12.879299) (xy 403.793249 12.887211) (xy 403.878999 12.887211)
			(xy 403.964382 12.879299) (xy 404.048672 12.863543) (xy 404.131148 12.840076) (xy 404.211107 12.8091)
			(xy 404.287867 12.770878) (xy 404.360773 12.725737) (xy 404.429202 12.674061) (xy 404.492572 12.616292)
			(xy 404.550341 12.552922) (xy 404.602017 12.484493) (xy 404.647158 12.411587) (xy 404.68538 12.334827)
			(xy 404.716356 12.254868) (xy 404.739823 12.172392) (xy 404.755579 12.088102) (xy 404.763491 12.002719)
			(xy 404.763986 11.959844) (xy 404.76379 11.942877) (xy 454.759301 11.942877) (xy 454.759301 12.028627)
			(xy 454.767213 12.11401) (xy 454.782969 12.1983) (xy 454.806436 12.280776) (xy 454.837412 12.360735)
			(xy 454.875634 12.437495) (xy 454.920775 12.510401) (xy 454.972451 12.57883) (xy 455.03022 12.6422)
			(xy 455.09359 12.699969) (xy 455.162019 12.751645) (xy 455.234925 12.796786) (xy 455.311685 12.835008)
			(xy 455.391644 12.865984) (xy 455.47412 12.889451) (xy 455.55841 12.905207) (xy 455.643793 12.913119)
			(xy 455.729543 12.913119) (xy 455.814926 12.905207) (xy 455.899216 12.889451) (xy 455.981692 12.865984)
			(xy 456.061651 12.835008) (xy 456.138411 12.796786) (xy 456.211317 12.751645) (xy 456.279746 12.699969)
			(xy 456.343116 12.6422) (xy 456.400885 12.57883) (xy 456.452561 12.510401) (xy 456.497702 12.437495)
			(xy 456.535924 12.360735) (xy 456.5669 12.280776) (xy 456.590367 12.1983) (xy 456.606123 12.11401)
			(xy 456.614035 12.028627) (xy 456.61453 11.985752) (xy 456.614035 11.942877) (xy 461.109301 11.942877)
			(xy 461.109301 12.028627) (xy 461.117213 12.11401) (xy 461.132969 12.1983) (xy 461.156436 12.280776)
			(xy 461.187412 12.360735) (xy 461.225634 12.437495) (xy 461.270775 12.510401) (xy 461.322451 12.57883)
			(xy 461.38022 12.6422) (xy 461.44359 12.699969) (xy 461.512019 12.751645) (xy 461.584925 12.796786)
			(xy 461.661685 12.835008) (xy 461.741644 12.865984) (xy 461.82412 12.889451) (xy 461.90841 12.905207)
			(xy 461.993793 12.913119) (xy 462.079543 12.913119) (xy 462.164926 12.905207) (xy 462.249216 12.889451)
			(xy 462.331692 12.865984) (xy 462.411651 12.835008) (xy 462.488411 12.796786) (xy 462.561317 12.751645)
			(xy 462.629746 12.699969) (xy 462.693116 12.6422) (xy 462.750885 12.57883) (xy 462.802561 12.510401)
			(xy 462.847702 12.437495) (xy 462.885924 12.360735) (xy 462.9169 12.280776) (xy 462.940367 12.1983)
			(xy 462.956123 12.11401) (xy 462.964035 12.028627) (xy 462.96453 11.985752) (xy 462.964035 11.942877)
			(xy 462.956123 11.857494) (xy 462.940367 11.773204) (xy 462.9169 11.690728) (xy 462.885924 11.610769)
			(xy 462.847702 11.534009) (xy 462.802561 11.461103) (xy 462.750885 11.392674) (xy 462.693116 11.329304)
			(xy 462.629746 11.271535) (xy 462.561317 11.219859) (xy 462.488411 11.174718) (xy 462.411651 11.136496)
			(xy 462.331692 11.10552) (xy 462.249216 11.082053) (xy 462.164926 11.066297) (xy 462.079543 11.058385)
			(xy 461.993793 11.058385) (xy 461.90841 11.066297) (xy 461.82412 11.082053) (xy 461.741644 11.10552)
			(xy 461.661685 11.136496) (xy 461.584925 11.174718) (xy 461.512019 11.219859) (xy 461.44359 11.271535)
			(xy 461.38022 11.329304) (xy 461.322451 11.392674) (xy 461.270775 11.461103) (xy 461.225634 11.534009)
			(xy 461.187412 11.610769) (xy 461.156436 11.690728) (xy 461.132969 11.773204) (xy 461.117213 11.857494)
			(xy 461.109301 11.942877) (xy 456.614035 11.942877) (xy 456.606123 11.857494) (xy 456.590367 11.773204)
			(xy 456.5669 11.690728) (xy 456.535924 11.610769) (xy 456.497702 11.534009) (xy 456.452561 11.461103)
			(xy 456.400885 11.392674) (xy 456.343116 11.329304) (xy 456.279746 11.271535) (xy 456.211317 11.219859)
			(xy 456.138411 11.174718) (xy 456.061651 11.136496) (xy 455.981692 11.10552) (xy 455.899216 11.082053)
			(xy 455.814926 11.066297) (xy 455.729543 11.058385) (xy 455.643793 11.058385) (xy 455.55841 11.066297)
			(xy 455.47412 11.082053) (xy 455.391644 11.10552) (xy 455.311685 11.136496) (xy 455.234925 11.174718)
			(xy 455.162019 11.219859) (xy 455.09359 11.271535) (xy 455.03022 11.329304) (xy 454.972451 11.392674)
			(xy 454.920775 11.461103) (xy 454.875634 11.534009) (xy 454.837412 11.610769) (xy 454.806436 11.690728)
			(xy 454.782969 11.773204) (xy 454.767213 11.857494) (xy 454.759301 11.942877) (xy 404.76379 11.942877)
			(xy 404.763491 11.916969) (xy 404.755579 11.831586) (xy 404.739823 11.747296) (xy 404.716356 11.66482)
			(xy 404.68538 11.584861) (xy 404.647158 11.508101) (xy 404.602017 11.435195) (xy 404.550341 11.366766)
			(xy 404.492572 11.303396) (xy 404.429202 11.245627) (xy 404.360773 11.193951) (xy 404.287867 11.14881)
			(xy 404.211107 11.110588) (xy 404.131148 11.079612) (xy 404.048672 11.056145) (xy 403.964382 11.040389)
			(xy 403.878999 11.032477) (xy 403.793249 11.032477) (xy 403.707866 11.040389) (xy 403.623576 11.056145)
			(xy 403.5411 11.079612) (xy 403.461141 11.110588) (xy 403.384381 11.14881) (xy 403.311475 11.193951)
			(xy 403.243046 11.245627) (xy 403.179676 11.303396) (xy 403.121907 11.366766) (xy 403.070231 11.435195)
			(xy 403.02509 11.508101) (xy 402.986868 11.584861) (xy 402.955892 11.66482) (xy 402.932425 11.747296)
			(xy 402.916669 11.831586) (xy 402.908757 11.916969) (xy 398.413491 11.916969) (xy 398.405579 11.831586)
			(xy 398.389823 11.747296) (xy 398.366356 11.66482) (xy 398.33538 11.584861) (xy 398.297158 11.508101)
			(xy 398.252017 11.435195) (xy 398.200341 11.366766) (xy 398.142572 11.303396) (xy 398.079202 11.245627)
			(xy 398.010773 11.193951) (xy 397.937867 11.14881) (xy 397.861107 11.110588) (xy 397.781148 11.079612)
			(xy 397.698672 11.056145) (xy 397.614382 11.040389) (xy 397.528999 11.032477) (xy 397.443249 11.032477)
			(xy 397.357866 11.040389) (xy 397.273576 11.056145) (xy 397.1911 11.079612) (xy 397.111141 11.110588)
			(xy 397.034381 11.14881) (xy 396.961475 11.193951) (xy 396.893046 11.245627) (xy 396.829676 11.303396)
			(xy 396.771907 11.366766) (xy 396.720231 11.435195) (xy 396.67509 11.508101) (xy 396.636868 11.584861)
			(xy 396.605892 11.66482) (xy 396.582425 11.747296) (xy 396.566669 11.831586) (xy 396.558757 11.916969)
			(xy 390.701117 11.916969) (xy 390.701035 11.909857) (xy 390.693123 11.824474) (xy 390.677367 11.740184)
			(xy 390.6539 11.657708) (xy 390.622924 11.577749) (xy 390.584702 11.500989) (xy 390.539561 11.428083)
			(xy 390.487885 11.359654) (xy 390.430116 11.296284) (xy 390.366746 11.238515) (xy 390.298317 11.186839)
			(xy 390.225411 11.141698) (xy 390.148651 11.103476) (xy 390.068692 11.0725) (xy 389.986216 11.049033)
			(xy 389.901926 11.033277) (xy 389.816543 11.025365) (xy 389.730793 11.025365) (xy 389.64541 11.033277)
			(xy 389.56112 11.049033) (xy 389.478644 11.0725) (xy 389.398685 11.103476) (xy 389.321925 11.141698)
			(xy 389.249019 11.186839) (xy 389.18059 11.238515) (xy 389.11722 11.296284) (xy 389.059451 11.359654)
			(xy 389.007775 11.428083) (xy 388.962634 11.500989) (xy 388.924412 11.577749) (xy 388.893436 11.657708)
			(xy 388.869969 11.740184) (xy 388.854213 11.824474) (xy 388.846301 11.909857) (xy 384.351035 11.909857)
			(xy 384.343123 11.824474) (xy 384.327367 11.740184) (xy 384.3039 11.657708) (xy 384.272924 11.577749)
			(xy 384.234702 11.500989) (xy 384.189561 11.428083) (xy 384.137885 11.359654) (xy 384.080116 11.296284)
			(xy 384.016746 11.238515) (xy 383.948317 11.186839) (xy 383.875411 11.141698) (xy 383.798651 11.103476)
			(xy 383.718692 11.0725) (xy 383.636216 11.049033) (xy 383.551926 11.033277) (xy 383.466543 11.025365)
			(xy 383.380793 11.025365) (xy 383.29541 11.033277) (xy 383.21112 11.049033) (xy 383.128644 11.0725)
			(xy 383.048685 11.103476) (xy 382.971925 11.141698) (xy 382.899019 11.186839) (xy 382.83059 11.238515)
			(xy 382.76722 11.296284) (xy 382.709451 11.359654) (xy 382.657775 11.428083) (xy 382.612634 11.500989)
			(xy 382.574412 11.577749) (xy 382.543436 11.657708) (xy 382.519969 11.740184) (xy 382.504213 11.824474)
			(xy 382.496301 11.909857) (xy 332.50079 11.909857) (xy 332.500491 11.883949) (xy 332.492579 11.798566)
			(xy 332.476823 11.714276) (xy 332.453356 11.6318) (xy 332.42238 11.551841) (xy 332.384158 11.475081)
			(xy 332.339017 11.402175) (xy 332.287341 11.333746) (xy 332.229572 11.270376) (xy 332.166202 11.212607)
			(xy 332.097773 11.160931) (xy 332.024867 11.11579) (xy 331.948107 11.077568) (xy 331.868148 11.046592)
			(xy 331.785672 11.023125) (xy 331.701382 11.007369) (xy 331.615999 10.999457) (xy 331.530249 10.999457)
			(xy 331.444866 11.007369) (xy 331.360576 11.023125) (xy 331.2781 11.046592) (xy 331.198141 11.077568)
			(xy 331.121381 11.11579) (xy 331.048475 11.160931) (xy 330.980046 11.212607) (xy 330.916676 11.270376)
			(xy 330.858907 11.333746) (xy 330.807231 11.402175) (xy 330.76209 11.475081) (xy 330.723868 11.551841)
			(xy 330.692892 11.6318) (xy 330.669425 11.714276) (xy 330.653669 11.798566) (xy 330.645757 11.883949)
			(xy 326.150491 11.883949) (xy 326.142579 11.798566) (xy 326.126823 11.714276) (xy 326.103356 11.6318)
			(xy 326.07238 11.551841) (xy 326.034158 11.475081) (xy 325.989017 11.402175) (xy 325.937341 11.333746)
			(xy 325.879572 11.270376) (xy 325.816202 11.212607) (xy 325.747773 11.160931) (xy 325.674867 11.11579)
			(xy 325.598107 11.077568) (xy 325.518148 11.046592) (xy 325.435672 11.023125) (xy 325.351382 11.007369)
			(xy 325.265999 10.999457) (xy 325.180249 10.999457) (xy 325.094866 11.007369) (xy 325.010576 11.023125)
			(xy 324.9281 11.046592) (xy 324.848141 11.077568) (xy 324.771381 11.11579) (xy 324.698475 11.160931)
			(xy 324.630046 11.212607) (xy 324.566676 11.270376) (xy 324.508907 11.333746) (xy 324.457231 11.402175)
			(xy 324.41209 11.475081) (xy 324.373868 11.551841) (xy 324.342892 11.6318) (xy 324.319425 11.714276)
			(xy 324.303669 11.798566) (xy 324.295757 11.883949) (xy 317.930117 11.883949) (xy 317.930035 11.876837)
			(xy 317.922123 11.791454) (xy 317.906367 11.707164) (xy 317.8829 11.624688) (xy 317.851924 11.544729)
			(xy 317.813702 11.467969) (xy 317.768561 11.395063) (xy 317.716885 11.326634) (xy 317.659116 11.263264)
			(xy 317.595746 11.205495) (xy 317.527317 11.153819) (xy 317.454411 11.108678) (xy 317.377651 11.070456)
			(xy 317.297692 11.03948) (xy 317.215216 11.016013) (xy 317.130926 11.000257) (xy 317.045543 10.992345)
			(xy 316.959793 10.992345) (xy 316.87441 11.000257) (xy 316.79012 11.016013) (xy 316.707644 11.03948)
			(xy 316.627685 11.070456) (xy 316.550925 11.108678) (xy 316.478019 11.153819) (xy 316.40959 11.205495)
			(xy 316.34622 11.263264) (xy 316.288451 11.326634) (xy 316.236775 11.395063) (xy 316.191634 11.467969)
			(xy 316.153412 11.544729) (xy 316.122436 11.624688) (xy 316.098969 11.707164) (xy 316.083213 11.791454)
			(xy 316.075301 11.876837) (xy 311.580035 11.876837) (xy 311.572123 11.791454) (xy 311.556367 11.707164)
			(xy 311.5329 11.624688) (xy 311.501924 11.544729) (xy 311.463702 11.467969) (xy 311.418561 11.395063)
			(xy 311.366885 11.326634) (xy 311.309116 11.263264) (xy 311.245746 11.205495) (xy 311.177317 11.153819)
			(xy 311.104411 11.108678) (xy 311.027651 11.070456) (xy 310.947692 11.03948) (xy 310.865216 11.016013)
			(xy 310.780926 11.000257) (xy 310.695543 10.992345) (xy 310.609793 10.992345) (xy 310.52441 11.000257)
			(xy 310.44012 11.016013) (xy 310.357644 11.03948) (xy 310.277685 11.070456) (xy 310.200925 11.108678)
			(xy 310.128019 11.153819) (xy 310.05959 11.205495) (xy 309.99622 11.263264) (xy 309.938451 11.326634)
			(xy 309.886775 11.395063) (xy 309.841634 11.467969) (xy 309.803412 11.544729) (xy 309.772436 11.624688)
			(xy 309.748969 11.707164) (xy 309.733213 11.791454) (xy 309.725301 11.876837) (xy 259.72979 11.876837)
			(xy 259.729491 11.850929) (xy 259.721579 11.765546) (xy 259.705823 11.681256) (xy 259.682356 11.59878)
			(xy 259.65138 11.518821) (xy 259.613158 11.442061) (xy 259.568017 11.369155) (xy 259.516341 11.300726)
			(xy 259.458572 11.237356) (xy 259.395202 11.179587) (xy 259.326773 11.127911) (xy 259.253867 11.08277)
			(xy 259.177107 11.044548) (xy 259.097148 11.013572) (xy 259.014672 10.990105) (xy 258.930382 10.974349)
			(xy 258.844999 10.966437) (xy 258.759249 10.966437) (xy 258.673866 10.974349) (xy 258.589576 10.990105)
			(xy 258.5071 11.013572) (xy 258.427141 11.044548) (xy 258.350381 11.08277) (xy 258.277475 11.127911)
			(xy 258.209046 11.179587) (xy 258.145676 11.237356) (xy 258.087907 11.300726) (xy 258.036231 11.369155)
			(xy 257.99109 11.442061) (xy 257.952868 11.518821) (xy 257.921892 11.59878) (xy 257.898425 11.681256)
			(xy 257.882669 11.765546) (xy 257.874757 11.850929) (xy 253.379491 11.850929) (xy 253.371579 11.765546)
			(xy 253.355823 11.681256) (xy 253.332356 11.59878) (xy 253.30138 11.518821) (xy 253.263158 11.442061)
			(xy 253.218017 11.369155) (xy 253.166341 11.300726) (xy 253.108572 11.237356) (xy 253.045202 11.179587)
			(xy 252.976773 11.127911) (xy 252.903867 11.08277) (xy 252.827107 11.044548) (xy 252.747148 11.013572)
			(xy 252.664672 10.990105) (xy 252.580382 10.974349) (xy 252.494999 10.966437) (xy 252.409249 10.966437)
			(xy 252.323866 10.974349) (xy 252.239576 10.990105) (xy 252.1571 11.013572) (xy 252.077141 11.044548)
			(xy 252.000381 11.08277) (xy 251.927475 11.127911) (xy 251.859046 11.179587) (xy 251.795676 11.237356)
			(xy 251.737907 11.300726) (xy 251.686231 11.369155) (xy 251.64109 11.442061) (xy 251.602868 11.518821)
			(xy 251.571892 11.59878) (xy 251.548425 11.681256) (xy 251.532669 11.765546) (xy 251.524757 11.850929)
			(xy 158.621984 11.850929) (xy 158.621984 9.310929) (xy 179.515757 9.310929) (xy 179.515757 9.396679)
			(xy 179.523669 9.482062) (xy 179.539425 9.566352) (xy 179.562892 9.648828) (xy 179.593868 9.728787)
			(xy 179.63209 9.805547) (xy 179.677231 9.878453) (xy 179.728907 9.946882) (xy 179.786676 10.010252)
			(xy 179.850046 10.068021) (xy 179.918475 10.119697) (xy 179.991381 10.164838) (xy 180.068141 10.20306)
			(xy 180.1481 10.234036) (xy 180.230576 10.257503) (xy 180.314866 10.273259) (xy 180.400249 10.281171)
			(xy 180.485999 10.281171) (xy 180.571382 10.273259) (xy 180.655672 10.257503) (xy 180.738148 10.234036)
			(xy 180.818107 10.20306) (xy 180.894867 10.164838) (xy 180.967773 10.119697) (xy 181.036202 10.068021)
			(xy 181.099572 10.010252) (xy 181.157341 9.946882) (xy 181.209017 9.878453) (xy 181.254158 9.805547)
			(xy 181.29238 9.728787) (xy 181.323356 9.648828) (xy 181.346823 9.566352) (xy 181.362579 9.482062)
			(xy 181.370491 9.396679) (xy 181.370986 9.353804) (xy 181.370491 9.310929) (xy 185.865757 9.310929)
			(xy 185.865757 9.396679) (xy 185.873669 9.482062) (xy 185.889425 9.566352) (xy 185.912892 9.648828)
			(xy 185.943868 9.728787) (xy 185.98209 9.805547) (xy 186.027231 9.878453) (xy 186.078907 9.946882)
			(xy 186.136676 10.010252) (xy 186.200046 10.068021) (xy 186.268475 10.119697) (xy 186.341381 10.164838)
			(xy 186.418141 10.20306) (xy 186.4981 10.234036) (xy 186.580576 10.257503) (xy 186.664866 10.273259)
			(xy 186.750249 10.281171) (xy 186.835999 10.281171) (xy 186.921382 10.273259) (xy 187.005672 10.257503)
			(xy 187.088148 10.234036) (xy 187.168107 10.20306) (xy 187.244867 10.164838) (xy 187.317773 10.119697)
			(xy 187.386202 10.068021) (xy 187.449572 10.010252) (xy 187.507341 9.946882) (xy 187.559017 9.878453)
			(xy 187.604158 9.805547) (xy 187.64238 9.728787) (xy 187.673356 9.648828) (xy 187.696823 9.566352)
			(xy 187.712579 9.482062) (xy 187.720491 9.396679) (xy 187.720986 9.353804) (xy 187.720491 9.310929)
			(xy 187.719832 9.303817) (xy 237.716301 9.303817) (xy 237.716301 9.389567) (xy 237.724213 9.47495)
			(xy 237.739969 9.55924) (xy 237.763436 9.641716) (xy 237.794412 9.721675) (xy 237.832634 9.798435)
			(xy 237.877775 9.871341) (xy 237.929451 9.93977) (xy 237.98722 10.00314) (xy 238.05059 10.060909)
			(xy 238.119019 10.112585) (xy 238.191925 10.157726) (xy 238.268685 10.195948) (xy 238.348644 10.226924)
			(xy 238.43112 10.250391) (xy 238.51541 10.266147) (xy 238.600793 10.274059) (xy 238.686543 10.274059)
			(xy 238.771926 10.266147) (xy 238.856216 10.250391) (xy 238.938692 10.226924) (xy 239.018651 10.195948)
			(xy 239.095411 10.157726) (xy 239.168317 10.112585) (xy 239.236746 10.060909) (xy 239.300116 10.00314)
			(xy 239.357885 9.93977) (xy 239.409561 9.871341) (xy 239.454702 9.798435) (xy 239.492924 9.721675)
			(xy 239.5239 9.641716) (xy 239.547367 9.55924) (xy 239.563123 9.47495) (xy 239.571035 9.389567) (xy 239.57153 9.346692)
			(xy 239.571035 9.303817) (xy 244.066301 9.303817) (xy 244.066301 9.389567) (xy 244.074213 9.47495)
			(xy 244.089969 9.55924) (xy 244.113436 9.641716) (xy 244.144412 9.721675) (xy 244.182634 9.798435)
			(xy 244.227775 9.871341) (xy 244.279451 9.93977) (xy 244.33722 10.00314) (xy 244.40059 10.060909)
			(xy 244.469019 10.112585) (xy 244.541925 10.157726) (xy 244.618685 10.195948) (xy 244.698644 10.226924)
			(xy 244.78112 10.250391) (xy 244.86541 10.266147) (xy 244.950793 10.274059) (xy 245.036543 10.274059)
			(xy 245.121926 10.266147) (xy 245.206216 10.250391) (xy 245.288692 10.226924) (xy 245.368651 10.195948)
			(xy 245.445411 10.157726) (xy 245.518317 10.112585) (xy 245.586746 10.060909) (xy 245.650116 10.00314)
			(xy 245.707885 9.93977) (xy 245.759561 9.871341) (xy 245.804702 9.798435) (xy 245.842924 9.721675)
			(xy 245.8739 9.641716) (xy 245.897367 9.55924) (xy 245.913123 9.47495) (xy 245.921035 9.389567) (xy 245.92153 9.346692)
			(xy 245.921117 9.310929) (xy 251.524757 9.310929) (xy 251.524757 9.396679) (xy 251.532669 9.482062)
			(xy 251.548425 9.566352) (xy 251.571892 9.648828) (xy 251.602868 9.728787) (xy 251.64109 9.805547)
			(xy 251.686231 9.878453) (xy 251.737907 9.946882) (xy 251.795676 10.010252) (xy 251.859046 10.068021)
			(xy 251.927475 10.119697) (xy 252.000381 10.164838) (xy 252.077141 10.20306) (xy 252.1571 10.234036)
			(xy 252.239576 10.257503) (xy 252.323866 10.273259) (xy 252.409249 10.281171) (xy 252.494999 10.281171)
			(xy 252.580382 10.273259) (xy 252.664672 10.257503) (xy 252.747148 10.234036) (xy 252.827107 10.20306)
			(xy 252.84931 10.192004) (xy 256.459736 10.192004) (xy 256.459736 11.055604) (xy 256.460222 11.082873)
			(xy 256.467984 11.136857) (xy 256.483349 11.189187) (xy 256.506006 11.238797) (xy 256.535492 11.284678)
			(xy 256.571207 11.325895) (xy 256.612424 11.36161) (xy 256.658305 11.391096) (xy 256.707915 11.413753)
			(xy 256.760245 11.429118) (xy 256.814229 11.43688) (xy 256.868767 11.43688) (xy 256.922751 11.429118)
			(xy 256.975081 11.413753) (xy 257.024691 11.391096) (xy 257.070572 11.36161) (xy 257.111789 11.325895)
			(xy 257.147504 11.284678) (xy 257.17699 11.238797) (xy 257.199647 11.189187) (xy 257.215012 11.136857)
			(xy 257.222774 11.082873) (xy 257.22326 11.055604) (xy 257.22326 10.192004) (xy 257.222774 10.164735)
			(xy 257.215012 10.110751) (xy 257.199647 10.058421) (xy 257.17699 10.008811) (xy 257.147504 9.96293)
			(xy 257.111789 9.921713) (xy 257.070572 9.885998) (xy 257.024691 9.856512) (xy 256.975081 9.833855)
			(xy 256.922751 9.81849) (xy 256.868767 9.810728) (xy 256.814229 9.810728) (xy 256.760245 9.81849)
			(xy 256.707915 9.833855) (xy 256.658305 9.856512) (xy 256.612424 9.885998) (xy 256.571207 9.921713)
			(xy 256.535492 9.96293) (xy 256.506006 10.008811) (xy 256.483349 10.058421) (xy 256.467984 10.110751)
			(xy 256.460222 10.164735) (xy 256.459736 10.192004) (xy 252.84931 10.192004) (xy 252.903867 10.164838)
			(xy 252.976773 10.119697) (xy 253.045202 10.068021) (xy 253.108572 10.010252) (xy 253.166341 9.946882)
			(xy 253.218017 9.878453) (xy 253.263158 9.805547) (xy 253.30138 9.728787) (xy 253.332356 9.648828)
			(xy 253.355823 9.566352) (xy 253.371579 9.482062) (xy 253.379491 9.396679) (xy 253.379986 9.353804)
			(xy 253.379491 9.310929) (xy 257.874757 9.310929) (xy 257.874757 9.396679) (xy 257.882669 9.482062)
			(xy 257.898425 9.566352) (xy 257.921892 9.648828) (xy 257.952868 9.728787) (xy 257.99109 9.805547)
			(xy 258.036231 9.878453) (xy 258.087907 9.946882) (xy 258.145676 10.010252) (xy 258.209046 10.068021)
			(xy 258.277475 10.119697) (xy 258.350381 10.164838) (xy 258.427141 10.20306) (xy 258.5071 10.234036)
			(xy 258.589576 10.257503) (xy 258.673866 10.273259) (xy 258.759249 10.281171) (xy 258.844999 10.281171)
			(xy 258.930382 10.273259) (xy 259.014672 10.257503) (xy 259.097148 10.234036) (xy 259.177107 10.20306)
			(xy 259.253867 10.164838) (xy 259.326773 10.119697) (xy 259.395202 10.068021) (xy 259.458572 10.010252)
			(xy 259.516341 9.946882) (xy 259.568017 9.878453) (xy 259.613158 9.805547) (xy 259.65138 9.728787)
			(xy 259.682356 9.648828) (xy 259.705823 9.566352) (xy 259.721579 9.482062) (xy 259.729491 9.396679)
			(xy 259.729986 9.353804) (xy 259.72979 9.336837) (xy 309.725301 9.336837) (xy 309.725301 9.422587)
			(xy 309.733213 9.50797) (xy 309.748969 9.59226) (xy 309.772436 9.674736) (xy 309.803412 9.754695)
			(xy 309.841634 9.831455) (xy 309.886775 9.904361) (xy 309.938451 9.97279) (xy 309.99622 10.03616)
			(xy 310.05959 10.093929) (xy 310.128019 10.145605) (xy 310.200925 10.190746) (xy 310.277685 10.228968)
			(xy 310.357644 10.259944) (xy 310.44012 10.283411) (xy 310.52441 10.299167) (xy 310.609793 10.307079)
			(xy 310.695543 10.307079) (xy 310.780926 10.299167) (xy 310.865216 10.283411) (xy 310.947692 10.259944)
			(xy 311.027651 10.228968) (xy 311.049854 10.217912) (xy 312.231532 10.217912) (xy 312.231532 11.081512)
			(xy 312.232018 11.108781) (xy 312.23978 11.162765) (xy 312.255145 11.215095) (xy 312.277802 11.264705)
			(xy 312.307288 11.310586) (xy 312.343003 11.351803) (xy 312.38422 11.387518) (xy 312.430101 11.417004)
			(xy 312.479711 11.439661) (xy 312.532041 11.455026) (xy 312.586025 11.462788) (xy 312.640563 11.462788)
			(xy 312.694547 11.455026) (xy 312.746877 11.439661) (xy 312.796487 11.417004) (xy 312.842368 11.387518)
			(xy 312.883585 11.351803) (xy 312.9193 11.310586) (xy 312.948786 11.264705) (xy 312.971443 11.215095)
			(xy 312.986808 11.162765) (xy 312.99457 11.108781) (xy 312.995056 11.081512) (xy 312.995056 10.217912)
			(xy 312.99457 10.190643) (xy 312.986808 10.136659) (xy 312.971443 10.084329) (xy 312.948786 10.034719)
			(xy 312.9193 9.988838) (xy 312.883585 9.947621) (xy 312.842368 9.911906) (xy 312.796487 9.88242)
			(xy 312.746877 9.859763) (xy 312.694547 9.844398) (xy 312.640563 9.836636) (xy 312.586025 9.836636)
			(xy 312.532041 9.844398) (xy 312.479711 9.859763) (xy 312.430101 9.88242) (xy 312.38422 9.911906)
			(xy 312.343003 9.947621) (xy 312.307288 9.988838) (xy 312.277802 10.034719) (xy 312.255145 10.084329)
			(xy 312.23978 10.136659) (xy 312.232018 10.190643) (xy 312.231532 10.217912) (xy 311.049854 10.217912)
			(xy 311.104411 10.190746) (xy 311.177317 10.145605) (xy 311.245746 10.093929) (xy 311.309116 10.03616)
			(xy 311.366885 9.97279) (xy 311.418561 9.904361) (xy 311.463702 9.831455) (xy 311.501924 9.754695)
			(xy 311.5329 9.674736) (xy 311.556367 9.59226) (xy 311.572123 9.50797) (xy 311.580035 9.422587) (xy 311.58053 9.379712)
			(xy 311.580035 9.336837) (xy 316.075301 9.336837) (xy 316.075301 9.422587) (xy 316.083213 9.50797)
			(xy 316.098969 9.59226) (xy 316.122436 9.674736) (xy 316.153412 9.754695) (xy 316.191634 9.831455)
			(xy 316.236775 9.904361) (xy 316.288451 9.97279) (xy 316.34622 10.03616) (xy 316.40959 10.093929)
			(xy 316.478019 10.145605) (xy 316.550925 10.190746) (xy 316.627685 10.228968) (xy 316.707644 10.259944)
			(xy 316.79012 10.283411) (xy 316.87441 10.299167) (xy 316.959793 10.307079) (xy 317.045543 10.307079)
			(xy 317.130926 10.299167) (xy 317.215216 10.283411) (xy 317.297692 10.259944) (xy 317.377651 10.228968)
			(xy 317.454411 10.190746) (xy 317.527317 10.145605) (xy 317.595746 10.093929) (xy 317.659116 10.03616)
			(xy 317.716885 9.97279) (xy 317.768561 9.904361) (xy 317.813702 9.831455) (xy 317.851924 9.754695)
			(xy 317.8829 9.674736) (xy 317.906367 9.59226) (xy 317.922123 9.50797) (xy 317.930035 9.422587) (xy 317.93053 9.379712)
			(xy 317.930117 9.343949) (xy 324.295757 9.343949) (xy 324.295757 9.429699) (xy 324.303669 9.515082)
			(xy 324.319425 9.599372) (xy 324.342892 9.681848) (xy 324.373868 9.761807) (xy 324.41209 9.838567)
			(xy 324.457231 9.911473) (xy 324.508907 9.979902) (xy 324.566676 10.043272) (xy 324.630046 10.101041)
			(xy 324.698475 10.152717) (xy 324.771381 10.197858) (xy 324.848141 10.23608) (xy 324.9281 10.267056)
			(xy 325.010576 10.290523) (xy 325.094866 10.306279) (xy 325.180249 10.314191) (xy 325.265999 10.314191)
			(xy 325.351382 10.306279) (xy 325.435672 10.290523) (xy 325.518148 10.267056) (xy 325.598107 10.23608)
			(xy 325.62031 10.225024) (xy 329.230736 10.225024) (xy 329.230736 11.088624) (xy 329.231222 11.115893)
			(xy 329.238984 11.169877) (xy 329.254349 11.222207) (xy 329.277006 11.271817) (xy 329.306492 11.317698)
			(xy 329.342207 11.358915) (xy 329.383424 11.39463) (xy 329.429305 11.424116) (xy 329.478915 11.446773)
			(xy 329.531245 11.462138) (xy 329.585229 11.4699) (xy 329.639767 11.4699) (xy 329.693751 11.462138)
			(xy 329.746081 11.446773) (xy 329.795691 11.424116) (xy 329.841572 11.39463) (xy 329.882789 11.358915)
			(xy 329.918504 11.317698) (xy 329.94799 11.271817) (xy 329.970647 11.222207) (xy 329.986012 11.169877)
			(xy 329.993774 11.115893) (xy 329.99426 11.088624) (xy 329.99426 10.225024) (xy 329.993774 10.197755)
			(xy 329.986012 10.143771) (xy 329.970647 10.091441) (xy 329.94799 10.041831) (xy 329.918504 9.99595)
			(xy 329.882789 9.954733) (xy 329.841572 9.919018) (xy 329.795691 9.889532) (xy 329.746081 9.866875)
			(xy 329.693751 9.85151) (xy 329.639767 9.843748) (xy 329.585229 9.843748) (xy 329.531245 9.85151)
			(xy 329.478915 9.866875) (xy 329.429305 9.889532) (xy 329.383424 9.919018) (xy 329.342207 9.954733)
			(xy 329.306492 9.99595) (xy 329.277006 10.041831) (xy 329.254349 10.091441) (xy 329.238984 10.143771)
			(xy 329.231222 10.197755) (xy 329.230736 10.225024) (xy 325.62031 10.225024) (xy 325.674867 10.197858)
			(xy 325.747773 10.152717) (xy 325.816202 10.101041) (xy 325.879572 10.043272) (xy 325.937341 9.979902)
			(xy 325.989017 9.911473) (xy 326.034158 9.838567) (xy 326.07238 9.761807) (xy 326.103356 9.681848)
			(xy 326.126823 9.599372) (xy 326.142579 9.515082) (xy 326.150491 9.429699) (xy 326.150986 9.386824)
			(xy 326.150491 9.343949) (xy 330.645757 9.343949) (xy 330.645757 9.429699) (xy 330.653669 9.515082)
			(xy 330.669425 9.599372) (xy 330.692892 9.681848) (xy 330.723868 9.761807) (xy 330.76209 9.838567)
			(xy 330.807231 9.911473) (xy 330.858907 9.979902) (xy 330.916676 10.043272) (xy 330.980046 10.101041)
			(xy 331.048475 10.152717) (xy 331.121381 10.197858) (xy 331.198141 10.23608) (xy 331.2781 10.267056)
			(xy 331.360576 10.290523) (xy 331.444866 10.306279) (xy 331.530249 10.314191) (xy 331.615999 10.314191)
			(xy 331.701382 10.306279) (xy 331.785672 10.290523) (xy 331.868148 10.267056) (xy 331.948107 10.23608)
			(xy 332.024867 10.197858) (xy 332.097773 10.152717) (xy 332.166202 10.101041) (xy 332.229572 10.043272)
			(xy 332.287341 9.979902) (xy 332.339017 9.911473) (xy 332.384158 9.838567) (xy 332.42238 9.761807)
			(xy 332.453356 9.681848) (xy 332.476823 9.599372) (xy 332.492579 9.515082) (xy 332.500491 9.429699)
			(xy 332.500986 9.386824) (xy 332.50079 9.369857) (xy 382.496301 9.369857) (xy 382.496301 9.455607)
			(xy 382.504213 9.54099) (xy 382.519969 9.62528) (xy 382.543436 9.707756) (xy 382.574412 9.787715)
			(xy 382.612634 9.864475) (xy 382.657775 9.937381) (xy 382.709451 10.00581) (xy 382.76722 10.06918)
			(xy 382.83059 10.126949) (xy 382.899019 10.178625) (xy 382.971925 10.223766) (xy 383.048685 10.261988)
			(xy 383.128644 10.292964) (xy 383.21112 10.316431) (xy 383.29541 10.332187) (xy 383.380793 10.340099)
			(xy 383.466543 10.340099) (xy 383.551926 10.332187) (xy 383.636216 10.316431) (xy 383.718692 10.292964)
			(xy 383.798651 10.261988) (xy 383.820854 10.250932) (xy 385.002532 10.250932) (xy 385.002532 11.114532)
			(xy 385.003018 11.141801) (xy 385.01078 11.195785) (xy 385.026145 11.248115) (xy 385.048802 11.297725)
			(xy 385.078288 11.343606) (xy 385.114003 11.384823) (xy 385.15522 11.420538) (xy 385.201101 11.450024)
			(xy 385.250711 11.472681) (xy 385.303041 11.488046) (xy 385.357025 11.495808) (xy 385.411563 11.495808)
			(xy 385.465547 11.488046) (xy 385.517877 11.472681) (xy 385.567487 11.450024) (xy 385.613368 11.420538)
			(xy 385.654585 11.384823) (xy 385.6903 11.343606) (xy 385.719786 11.297725) (xy 385.742443 11.248115)
			(xy 385.757808 11.195785) (xy 385.76557 11.141801) (xy 385.766056 11.114532) (xy 385.766056 10.250932)
			(xy 385.76557 10.223663) (xy 385.757808 10.169679) (xy 385.742443 10.117349) (xy 385.719786 10.067739)
			(xy 385.6903 10.021858) (xy 385.654585 9.980641) (xy 385.613368 9.944926) (xy 385.567487 9.91544)
			(xy 385.517877 9.892783) (xy 385.465547 9.877418) (xy 385.411563 9.869656) (xy 385.357025 9.869656)
			(xy 385.303041 9.877418) (xy 385.250711 9.892783) (xy 385.201101 9.91544) (xy 385.15522 9.944926)
			(xy 385.114003 9.980641) (xy 385.078288 10.021858) (xy 385.048802 10.067739) (xy 385.026145 10.117349)
			(xy 385.01078 10.169679) (xy 385.003018 10.223663) (xy 385.002532 10.250932) (xy 383.820854 10.250932)
			(xy 383.875411 10.223766) (xy 383.948317 10.178625) (xy 384.016746 10.126949) (xy 384.080116 10.06918)
			(xy 384.137885 10.00581) (xy 384.189561 9.937381) (xy 384.234702 9.864475) (xy 384.272924 9.787715)
			(xy 384.3039 9.707756) (xy 384.327367 9.62528) (xy 384.343123 9.54099) (xy 384.351035 9.455607) (xy 384.35153 9.412732)
			(xy 384.351035 9.369857) (xy 388.846301 9.369857) (xy 388.846301 9.455607) (xy 388.854213 9.54099)
			(xy 388.869969 9.62528) (xy 388.893436 9.707756) (xy 388.924412 9.787715) (xy 388.962634 9.864475)
			(xy 389.007775 9.937381) (xy 389.059451 10.00581) (xy 389.11722 10.06918) (xy 389.18059 10.126949)
			(xy 389.249019 10.178625) (xy 389.321925 10.223766) (xy 389.398685 10.261988) (xy 389.478644 10.292964)
			(xy 389.56112 10.316431) (xy 389.64541 10.332187) (xy 389.730793 10.340099) (xy 389.816543 10.340099)
			(xy 389.901926 10.332187) (xy 389.986216 10.316431) (xy 390.068692 10.292964) (xy 390.148651 10.261988)
			(xy 390.225411 10.223766) (xy 390.298317 10.178625) (xy 390.366746 10.126949) (xy 390.430116 10.06918)
			(xy 390.487885 10.00581) (xy 390.539561 9.937381) (xy 390.584702 9.864475) (xy 390.622924 9.787715)
			(xy 390.6539 9.707756) (xy 390.677367 9.62528) (xy 390.693123 9.54099) (xy 390.701035 9.455607) (xy 390.70153 9.412732)
			(xy 390.701117 9.376969) (xy 396.558757 9.376969) (xy 396.558757 9.462719) (xy 396.566669 9.548102)
			(xy 396.582425 9.632392) (xy 396.605892 9.714868) (xy 396.636868 9.794827) (xy 396.67509 9.871587)
			(xy 396.720231 9.944493) (xy 396.771907 10.012922) (xy 396.829676 10.076292) (xy 396.893046 10.134061)
			(xy 396.961475 10.185737) (xy 397.034381 10.230878) (xy 397.111141 10.2691) (xy 397.1911 10.300076)
			(xy 397.273576 10.323543) (xy 397.357866 10.339299) (xy 397.443249 10.347211) (xy 397.528999 10.347211)
			(xy 397.614382 10.339299) (xy 397.698672 10.323543) (xy 397.781148 10.300076) (xy 397.861107 10.2691)
			(xy 397.88331 10.258044) (xy 401.493736 10.258044) (xy 401.493736 11.121644) (xy 401.494222 11.148913)
			(xy 401.501984 11.202897) (xy 401.517349 11.255227) (xy 401.540006 11.304837) (xy 401.569492 11.350718)
			(xy 401.605207 11.391935) (xy 401.646424 11.42765) (xy 401.692305 11.457136) (xy 401.741915 11.479793)
			(xy 401.794245 11.495158) (xy 401.848229 11.50292) (xy 401.902767 11.50292) (xy 401.956751 11.495158)
			(xy 402.009081 11.479793) (xy 402.058691 11.457136) (xy 402.104572 11.42765) (xy 402.145789 11.391935)
			(xy 402.181504 11.350718) (xy 402.21099 11.304837) (xy 402.233647 11.255227) (xy 402.249012 11.202897)
			(xy 402.256774 11.148913) (xy 402.25726 11.121644) (xy 402.25726 10.258044) (xy 402.256774 10.230775)
			(xy 402.249012 10.176791) (xy 402.233647 10.124461) (xy 402.21099 10.074851) (xy 402.181504 10.02897)
			(xy 402.145789 9.987753) (xy 402.104572 9.952038) (xy 402.058691 9.922552) (xy 402.009081 9.899895)
			(xy 401.956751 9.88453) (xy 401.902767 9.876768) (xy 401.848229 9.876768) (xy 401.794245 9.88453)
			(xy 401.741915 9.899895) (xy 401.692305 9.922552) (xy 401.646424 9.952038) (xy 401.605207 9.987753)
			(xy 401.569492 10.02897) (xy 401.540006 10.074851) (xy 401.517349 10.124461) (xy 401.501984 10.176791)
			(xy 401.494222 10.230775) (xy 401.493736 10.258044) (xy 397.88331 10.258044) (xy 397.937867 10.230878)
			(xy 398.010773 10.185737) (xy 398.079202 10.134061) (xy 398.142572 10.076292) (xy 398.200341 10.012922)
			(xy 398.252017 9.944493) (xy 398.297158 9.871587) (xy 398.33538 9.794827) (xy 398.366356 9.714868)
			(xy 398.389823 9.632392) (xy 398.405579 9.548102) (xy 398.413491 9.462719) (xy 398.413986 9.419844)
			(xy 398.413491 9.376969) (xy 402.908757 9.376969) (xy 402.908757 9.462719) (xy 402.916669 9.548102)
			(xy 402.932425 9.632392) (xy 402.955892 9.714868) (xy 402.986868 9.794827) (xy 403.02509 9.871587)
			(xy 403.070231 9.944493) (xy 403.121907 10.012922) (xy 403.179676 10.076292) (xy 403.243046 10.134061)
			(xy 403.311475 10.185737) (xy 403.384381 10.230878) (xy 403.461141 10.2691) (xy 403.5411 10.300076)
			(xy 403.623576 10.323543) (xy 403.707866 10.339299) (xy 403.793249 10.347211) (xy 403.878999 10.347211)
			(xy 403.964382 10.339299) (xy 404.048672 10.323543) (xy 404.131148 10.300076) (xy 404.211107 10.2691)
			(xy 404.287867 10.230878) (xy 404.360773 10.185737) (xy 404.429202 10.134061) (xy 404.492572 10.076292)
			(xy 404.550341 10.012922) (xy 404.602017 9.944493) (xy 404.647158 9.871587) (xy 404.68538 9.794827)
			(xy 404.716356 9.714868) (xy 404.739823 9.632392) (xy 404.755579 9.548102) (xy 404.763491 9.462719)
			(xy 404.763986 9.419844) (xy 404.76379 9.402877) (xy 454.759301 9.402877) (xy 454.759301 9.488627)
			(xy 454.767213 9.57401) (xy 454.782969 9.6583) (xy 454.806436 9.740776) (xy 454.837412 9.820735)
			(xy 454.875634 9.897495) (xy 454.920775 9.970401) (xy 454.972451 10.03883) (xy 455.03022 10.1022)
			(xy 455.09359 10.159969) (xy 455.162019 10.211645) (xy 455.234925 10.256786) (xy 455.311685 10.295008)
			(xy 455.391644 10.325984) (xy 455.47412 10.349451) (xy 455.55841 10.365207) (xy 455.643793 10.373119)
			(xy 455.729543 10.373119) (xy 455.814926 10.365207) (xy 455.899216 10.349451) (xy 455.981692 10.325984)
			(xy 456.061651 10.295008) (xy 456.083854 10.283952) (xy 457.265532 10.283952) (xy 457.265532 11.147552)
			(xy 457.266018 11.174821) (xy 457.27378 11.228805) (xy 457.289145 11.281135) (xy 457.311802 11.330745)
			(xy 457.341288 11.376626) (xy 457.377003 11.417843) (xy 457.41822 11.453558) (xy 457.464101 11.483044)
			(xy 457.513711 11.505701) (xy 457.566041 11.521066) (xy 457.620025 11.528828) (xy 457.674563 11.528828)
			(xy 457.728547 11.521066) (xy 457.780877 11.505701) (xy 457.830487 11.483044) (xy 457.876368 11.453558)
			(xy 457.917585 11.417843) (xy 457.9533 11.376626) (xy 457.982786 11.330745) (xy 458.005443 11.281135)
			(xy 458.020808 11.228805) (xy 458.02857 11.174821) (xy 458.029056 11.147552) (xy 458.029056 10.283952)
			(xy 458.02857 10.256683) (xy 458.020808 10.202699) (xy 458.005443 10.150369) (xy 457.982786 10.100759)
			(xy 457.9533 10.054878) (xy 457.917585 10.013661) (xy 457.876368 9.977946) (xy 457.830487 9.94846)
			(xy 457.780877 9.925803) (xy 457.728547 9.910438) (xy 457.674563 9.902676) (xy 457.620025 9.902676)
			(xy 457.566041 9.910438) (xy 457.513711 9.925803) (xy 457.464101 9.94846) (xy 457.41822 9.977946)
			(xy 457.377003 10.013661) (xy 457.341288 10.054878) (xy 457.311802 10.100759) (xy 457.289145 10.150369)
			(xy 457.27378 10.202699) (xy 457.266018 10.256683) (xy 457.265532 10.283952) (xy 456.083854 10.283952)
			(xy 456.138411 10.256786) (xy 456.211317 10.211645) (xy 456.279746 10.159969) (xy 456.343116 10.1022)
			(xy 456.400885 10.03883) (xy 456.452561 9.970401) (xy 456.497702 9.897495) (xy 456.535924 9.820735)
			(xy 456.5669 9.740776) (xy 456.590367 9.6583) (xy 456.606123 9.57401) (xy 456.614035 9.488627) (xy 456.61453 9.445752)
			(xy 456.614035 9.402877) (xy 461.109301 9.402877) (xy 461.109301 9.488627) (xy 461.117213 9.57401)
			(xy 461.132969 9.6583) (xy 461.156436 9.740776) (xy 461.187412 9.820735) (xy 461.225634 9.897495)
			(xy 461.270775 9.970401) (xy 461.322451 10.03883) (xy 461.38022 10.1022) (xy 461.44359 10.159969)
			(xy 461.512019 10.211645) (xy 461.584925 10.256786) (xy 461.661685 10.295008) (xy 461.741644 10.325984)
			(xy 461.82412 10.349451) (xy 461.90841 10.365207) (xy 461.993793 10.373119) (xy 462.079543 10.373119)
			(xy 462.164926 10.365207) (xy 462.249216 10.349451) (xy 462.331692 10.325984) (xy 462.411651 10.295008)
			(xy 462.488411 10.256786) (xy 462.561317 10.211645) (xy 462.629746 10.159969) (xy 462.693116 10.1022)
			(xy 462.750885 10.03883) (xy 462.802561 9.970401) (xy 462.847702 9.897495) (xy 462.885924 9.820735)
			(xy 462.9169 9.740776) (xy 462.940367 9.6583) (xy 462.956123 9.57401) (xy 462.964035 9.488627) (xy 462.96453 9.445752)
			(xy 462.964035 9.402877) (xy 462.956123 9.317494) (xy 462.940367 9.233204) (xy 462.9169 9.150728)
			(xy 462.885924 9.070769) (xy 462.847702 8.994009) (xy 462.802561 8.921103) (xy 462.750885 8.852674)
			(xy 462.693116 8.789304) (xy 462.629746 8.731535) (xy 462.561317 8.679859) (xy 462.488411 8.634718)
			(xy 462.411651 8.596496) (xy 462.331692 8.56552) (xy 462.249216 8.542053) (xy 462.164926 8.526297)
			(xy 462.079543 8.518385) (xy 461.993793 8.518385) (xy 461.90841 8.526297) (xy 461.82412 8.542053)
			(xy 461.741644 8.56552) (xy 461.661685 8.596496) (xy 461.584925 8.634718) (xy 461.512019 8.679859)
			(xy 461.44359 8.731535) (xy 461.38022 8.789304) (xy 461.322451 8.852674) (xy 461.270775 8.921103)
			(xy 461.225634 8.994009) (xy 461.187412 9.070769) (xy 461.156436 9.150728) (xy 461.132969 9.233204)
			(xy 461.117213 9.317494) (xy 461.109301 9.402877) (xy 456.614035 9.402877) (xy 456.606123 9.317494)
			(xy 456.590367 9.233204) (xy 456.5669 9.150728) (xy 456.535924 9.070769) (xy 456.497702 8.994009)
			(xy 456.452561 8.921103) (xy 456.400885 8.852674) (xy 456.343116 8.789304) (xy 456.279746 8.731535)
			(xy 456.211317 8.679859) (xy 456.138411 8.634718) (xy 456.061651 8.596496) (xy 455.981692 8.56552)
			(xy 455.899216 8.542053) (xy 455.814926 8.526297) (xy 455.729543 8.518385) (xy 455.643793 8.518385)
			(xy 455.55841 8.526297) (xy 455.47412 8.542053) (xy 455.391644 8.56552) (xy 455.311685 8.596496)
			(xy 455.234925 8.634718) (xy 455.162019 8.679859) (xy 455.09359 8.731535) (xy 455.03022 8.789304)
			(xy 454.972451 8.852674) (xy 454.920775 8.921103) (xy 454.875634 8.994009) (xy 454.837412 9.070769)
			(xy 454.806436 9.150728) (xy 454.782969 9.233204) (xy 454.767213 9.317494) (xy 454.759301 9.402877)
			(xy 404.76379 9.402877) (xy 404.763491 9.376969) (xy 404.755579 9.291586) (xy 404.739823 9.207296)
			(xy 404.716356 9.12482) (xy 404.68538 9.044861) (xy 404.647158 8.968101) (xy 404.602017 8.895195)
			(xy 404.550341 8.826766) (xy 404.492572 8.763396) (xy 404.429202 8.705627) (xy 404.360773 8.653951)
			(xy 404.287867 8.60881) (xy 404.211107 8.570588) (xy 404.131148 8.539612) (xy 404.048672 8.516145)
			(xy 403.964382 8.500389) (xy 403.878999 8.492477) (xy 403.793249 8.492477) (xy 403.707866 8.500389)
			(xy 403.623576 8.516145) (xy 403.5411 8.539612) (xy 403.461141 8.570588) (xy 403.384381 8.60881)
			(xy 403.311475 8.653951) (xy 403.243046 8.705627) (xy 403.179676 8.763396) (xy 403.121907 8.826766)
			(xy 403.070231 8.895195) (xy 403.02509 8.968101) (xy 402.986868 9.044861) (xy 402.955892 9.12482)
			(xy 402.932425 9.207296) (xy 402.916669 9.291586) (xy 402.908757 9.376969) (xy 398.413491 9.376969)
			(xy 398.405579 9.291586) (xy 398.389823 9.207296) (xy 398.366356 9.12482) (xy 398.33538 9.044861)
			(xy 398.297158 8.968101) (xy 398.252017 8.895195) (xy 398.200341 8.826766) (xy 398.142572 8.763396)
			(xy 398.079202 8.705627) (xy 398.010773 8.653951) (xy 397.937867 8.60881) (xy 397.861107 8.570588)
			(xy 397.781148 8.539612) (xy 397.698672 8.516145) (xy 397.614382 8.500389) (xy 397.528999 8.492477)
			(xy 397.443249 8.492477) (xy 397.357866 8.500389) (xy 397.273576 8.516145) (xy 397.1911 8.539612)
			(xy 397.111141 8.570588) (xy 397.034381 8.60881) (xy 396.961475 8.653951) (xy 396.893046 8.705627)
			(xy 396.829676 8.763396) (xy 396.771907 8.826766) (xy 396.720231 8.895195) (xy 396.67509 8.968101)
			(xy 396.636868 9.044861) (xy 396.605892 9.12482) (xy 396.582425 9.207296) (xy 396.566669 9.291586)
			(xy 396.558757 9.376969) (xy 390.701117 9.376969) (xy 390.701035 9.369857) (xy 390.693123 9.284474)
			(xy 390.677367 9.200184) (xy 390.6539 9.117708) (xy 390.622924 9.037749) (xy 390.584702 8.960989)
			(xy 390.539561 8.888083) (xy 390.487885 8.819654) (xy 390.430116 8.756284) (xy 390.366746 8.698515)
			(xy 390.298317 8.646839) (xy 390.225411 8.601698) (xy 390.148651 8.563476) (xy 390.068692 8.5325)
			(xy 389.986216 8.509033) (xy 389.901926 8.493277) (xy 389.816543 8.485365) (xy 389.730793 8.485365)
			(xy 389.64541 8.493277) (xy 389.56112 8.509033) (xy 389.478644 8.5325) (xy 389.398685 8.563476) (xy 389.321925 8.601698)
			(xy 389.249019 8.646839) (xy 389.18059 8.698515) (xy 389.11722 8.756284) (xy 389.059451 8.819654)
			(xy 389.007775 8.888083) (xy 388.962634 8.960989) (xy 388.924412 9.037749) (xy 388.893436 9.117708)
			(xy 388.869969 9.200184) (xy 388.854213 9.284474) (xy 388.846301 9.369857) (xy 384.351035 9.369857)
			(xy 384.343123 9.284474) (xy 384.327367 9.200184) (xy 384.3039 9.117708) (xy 384.272924 9.037749)
			(xy 384.234702 8.960989) (xy 384.189561 8.888083) (xy 384.137885 8.819654) (xy 384.080116 8.756284)
			(xy 384.016746 8.698515) (xy 383.948317 8.646839) (xy 383.875411 8.601698) (xy 383.798651 8.563476)
			(xy 383.718692 8.5325) (xy 383.636216 8.509033) (xy 383.551926 8.493277) (xy 383.466543 8.485365)
			(xy 383.380793 8.485365) (xy 383.29541 8.493277) (xy 383.21112 8.509033) (xy 383.128644 8.5325) (xy 383.048685 8.563476)
			(xy 382.971925 8.601698) (xy 382.899019 8.646839) (xy 382.83059 8.698515) (xy 382.76722 8.756284)
			(xy 382.709451 8.819654) (xy 382.657775 8.888083) (xy 382.612634 8.960989) (xy 382.574412 9.037749)
			(xy 382.543436 9.117708) (xy 382.519969 9.200184) (xy 382.504213 9.284474) (xy 382.496301 9.369857)
			(xy 332.50079 9.369857) (xy 332.500491 9.343949) (xy 332.492579 9.258566) (xy 332.476823 9.174276)
			(xy 332.453356 9.0918) (xy 332.42238 9.011841) (xy 332.384158 8.935081) (xy 332.339017 8.862175)
			(xy 332.287341 8.793746) (xy 332.229572 8.730376) (xy 332.166202 8.672607) (xy 332.097773 8.620931)
			(xy 332.024867 8.57579) (xy 331.948107 8.537568) (xy 331.868148 8.506592) (xy 331.785672 8.483125)
			(xy 331.701382 8.467369) (xy 331.615999 8.459457) (xy 331.530249 8.459457) (xy 331.444866 8.467369)
			(xy 331.360576 8.483125) (xy 331.2781 8.506592) (xy 331.198141 8.537568) (xy 331.121381 8.57579)
			(xy 331.048475 8.620931) (xy 330.980046 8.672607) (xy 330.916676 8.730376) (xy 330.858907 8.793746)
			(xy 330.807231 8.862175) (xy 330.76209 8.935081) (xy 330.723868 9.011841) (xy 330.692892 9.0918)
			(xy 330.669425 9.174276) (xy 330.653669 9.258566) (xy 330.645757 9.343949) (xy 326.150491 9.343949)
			(xy 326.142579 9.258566) (xy 326.126823 9.174276) (xy 326.103356 9.0918) (xy 326.07238 9.011841)
			(xy 326.034158 8.935081) (xy 325.989017 8.862175) (xy 325.937341 8.793746) (xy 325.879572 8.730376)
			(xy 325.816202 8.672607) (xy 325.747773 8.620931) (xy 325.674867 8.57579) (xy 325.598107 8.537568)
			(xy 325.518148 8.506592) (xy 325.435672 8.483125) (xy 325.351382 8.467369) (xy 325.265999 8.459457)
			(xy 325.180249 8.459457) (xy 325.094866 8.467369) (xy 325.010576 8.483125) (xy 324.9281 8.506592)
			(xy 324.848141 8.537568) (xy 324.771381 8.57579) (xy 324.698475 8.620931) (xy 324.630046 8.672607)
			(xy 324.566676 8.730376) (xy 324.508907 8.793746) (xy 324.457231 8.862175) (xy 324.41209 8.935081)
			(xy 324.373868 9.011841) (xy 324.342892 9.0918) (xy 324.319425 9.174276) (xy 324.303669 9.258566)
			(xy 324.295757 9.343949) (xy 317.930117 9.343949) (xy 317.930035 9.336837) (xy 317.922123 9.251454)
			(xy 317.906367 9.167164) (xy 317.8829 9.084688) (xy 317.851924 9.004729) (xy 317.813702 8.927969)
			(xy 317.768561 8.855063) (xy 317.716885 8.786634) (xy 317.659116 8.723264) (xy 317.595746 8.665495)
			(xy 317.527317 8.613819) (xy 317.454411 8.568678) (xy 317.377651 8.530456) (xy 317.297692 8.49948)
			(xy 317.215216 8.476013) (xy 317.130926 8.460257) (xy 317.045543 8.452345) (xy 316.959793 8.452345)
			(xy 316.87441 8.460257) (xy 316.79012 8.476013) (xy 316.707644 8.49948) (xy 316.627685 8.530456)
			(xy 316.550925 8.568678) (xy 316.478019 8.613819) (xy 316.40959 8.665495) (xy 316.34622 8.723264)
			(xy 316.288451 8.786634) (xy 316.236775 8.855063) (xy 316.191634 8.927969) (xy 316.153412 9.004729)
			(xy 316.122436 9.084688) (xy 316.098969 9.167164) (xy 316.083213 9.251454) (xy 316.075301 9.336837)
			(xy 311.580035 9.336837) (xy 311.572123 9.251454) (xy 311.556367 9.167164) (xy 311.5329 9.084688)
			(xy 311.501924 9.004729) (xy 311.463702 8.927969) (xy 311.418561 8.855063) (xy 311.366885 8.786634)
			(xy 311.309116 8.723264) (xy 311.245746 8.665495) (xy 311.177317 8.613819) (xy 311.104411 8.568678)
			(xy 311.027651 8.530456) (xy 310.947692 8.49948) (xy 310.865216 8.476013) (xy 310.780926 8.460257)
			(xy 310.695543 8.452345) (xy 310.609793 8.452345) (xy 310.52441 8.460257) (xy 310.44012 8.476013)
			(xy 310.357644 8.49948) (xy 310.277685 8.530456) (xy 310.200925 8.568678) (xy 310.128019 8.613819)
			(xy 310.05959 8.665495) (xy 309.99622 8.723264) (xy 309.938451 8.786634) (xy 309.886775 8.855063)
			(xy 309.841634 8.927969) (xy 309.803412 9.004729) (xy 309.772436 9.084688) (xy 309.748969 9.167164)
			(xy 309.733213 9.251454) (xy 309.725301 9.336837) (xy 259.72979 9.336837) (xy 259.729491 9.310929)
			(xy 259.721579 9.225546) (xy 259.705823 9.141256) (xy 259.682356 9.05878) (xy 259.65138 8.978821)
			(xy 259.613158 8.902061) (xy 259.568017 8.829155) (xy 259.516341 8.760726) (xy 259.458572 8.697356)
			(xy 259.395202 8.639587) (xy 259.326773 8.587911) (xy 259.253867 8.54277) (xy 259.177107 8.504548)
			(xy 259.097148 8.473572) (xy 259.014672 8.450105) (xy 258.930382 8.434349) (xy 258.844999 8.426437)
			(xy 258.759249 8.426437) (xy 258.673866 8.434349) (xy 258.589576 8.450105) (xy 258.5071 8.473572)
			(xy 258.427141 8.504548) (xy 258.350381 8.54277) (xy 258.277475 8.587911) (xy 258.209046 8.639587)
			(xy 258.145676 8.697356) (xy 258.087907 8.760726) (xy 258.036231 8.829155) (xy 257.99109 8.902061)
			(xy 257.952868 8.978821) (xy 257.921892 9.05878) (xy 257.898425 9.141256) (xy 257.882669 9.225546)
			(xy 257.874757 9.310929) (xy 253.379491 9.310929) (xy 253.371579 9.225546) (xy 253.355823 9.141256)
			(xy 253.332356 9.05878) (xy 253.30138 8.978821) (xy 253.263158 8.902061) (xy 253.218017 8.829155)
			(xy 253.166341 8.760726) (xy 253.108572 8.697356) (xy 253.045202 8.639587) (xy 252.976773 8.587911)
			(xy 252.903867 8.54277) (xy 252.827107 8.504548) (xy 252.747148 8.473572) (xy 252.664672 8.450105)
			(xy 252.580382 8.434349) (xy 252.494999 8.426437) (xy 252.409249 8.426437) (xy 252.323866 8.434349)
			(xy 252.239576 8.450105) (xy 252.1571 8.473572) (xy 252.077141 8.504548) (xy 252.000381 8.54277)
			(xy 251.927475 8.587911) (xy 251.859046 8.639587) (xy 251.795676 8.697356) (xy 251.737907 8.760726)
			(xy 251.686231 8.829155) (xy 251.64109 8.902061) (xy 251.602868 8.978821) (xy 251.571892 9.05878)
			(xy 251.548425 9.141256) (xy 251.532669 9.225546) (xy 251.524757 9.310929) (xy 245.921117 9.310929)
			(xy 245.921035 9.303817) (xy 245.913123 9.218434) (xy 245.897367 9.134144) (xy 245.8739 9.051668)
			(xy 245.842924 8.971709) (xy 245.804702 8.894949) (xy 245.759561 8.822043) (xy 245.707885 8.753614)
			(xy 245.650116 8.690244) (xy 245.586746 8.632475) (xy 245.518317 8.580799) (xy 245.445411 8.535658)
			(xy 245.368651 8.497436) (xy 245.288692 8.46646) (xy 245.206216 8.442993) (xy 245.121926 8.427237)
			(xy 245.036543 8.419325) (xy 244.950793 8.419325) (xy 244.86541 8.427237) (xy 244.78112 8.442993)
			(xy 244.698644 8.46646) (xy 244.618685 8.497436) (xy 244.541925 8.535658) (xy 244.469019 8.580799)
			(xy 244.40059 8.632475) (xy 244.33722 8.690244) (xy 244.279451 8.753614) (xy 244.227775 8.822043)
			(xy 244.182634 8.894949) (xy 244.144412 8.971709) (xy 244.113436 9.051668) (xy 244.089969 9.134144)
			(xy 244.074213 9.218434) (xy 244.066301 9.303817) (xy 239.571035 9.303817) (xy 239.563123 9.218434)
			(xy 239.547367 9.134144) (xy 239.5239 9.051668) (xy 239.492924 8.971709) (xy 239.454702 8.894949)
			(xy 239.409561 8.822043) (xy 239.357885 8.753614) (xy 239.300116 8.690244) (xy 239.236746 8.632475)
			(xy 239.168317 8.580799) (xy 239.095411 8.535658) (xy 239.018651 8.497436) (xy 238.938692 8.46646)
			(xy 238.856216 8.442993) (xy 238.771926 8.427237) (xy 238.686543 8.419325) (xy 238.600793 8.419325)
			(xy 238.51541 8.427237) (xy 238.43112 8.442993) (xy 238.348644 8.46646) (xy 238.268685 8.497436)
			(xy 238.191925 8.535658) (xy 238.119019 8.580799) (xy 238.05059 8.632475) (xy 237.98722 8.690244)
			(xy 237.929451 8.753614) (xy 237.877775 8.822043) (xy 237.832634 8.894949) (xy 237.794412 8.971709)
			(xy 237.763436 9.051668) (xy 237.739969 9.134144) (xy 237.724213 9.218434) (xy 237.716301 9.303817)
			(xy 187.719832 9.303817) (xy 187.712579 9.225546) (xy 187.696823 9.141256) (xy 187.673356 9.05878)
			(xy 187.64238 8.978821) (xy 187.604158 8.902061) (xy 187.559017 8.829155) (xy 187.507341 8.760726)
			(xy 187.449572 8.697356) (xy 187.386202 8.639587) (xy 187.317773 8.587911) (xy 187.244867 8.54277)
			(xy 187.168107 8.504548) (xy 187.088148 8.473572) (xy 187.005672 8.450105) (xy 186.921382 8.434349)
			(xy 186.835999 8.426437) (xy 186.750249 8.426437) (xy 186.664866 8.434349) (xy 186.580576 8.450105)
			(xy 186.4981 8.473572) (xy 186.418141 8.504548) (xy 186.341381 8.54277) (xy 186.268475 8.587911)
			(xy 186.200046 8.639587) (xy 186.136676 8.697356) (xy 186.078907 8.760726) (xy 186.027231 8.829155)
			(xy 185.98209 8.902061) (xy 185.943868 8.978821) (xy 185.912892 9.05878) (xy 185.889425 9.141256)
			(xy 185.873669 9.225546) (xy 185.865757 9.310929) (xy 181.370491 9.310929) (xy 181.362579 9.225546)
			(xy 181.346823 9.141256) (xy 181.323356 9.05878) (xy 181.29238 8.978821) (xy 181.254158 8.902061)
			(xy 181.209017 8.829155) (xy 181.157341 8.760726) (xy 181.099572 8.697356) (xy 181.036202 8.639587)
			(xy 180.967773 8.587911) (xy 180.894867 8.54277) (xy 180.818107 8.504548) (xy 180.738148 8.473572)
			(xy 180.655672 8.450105) (xy 180.571382 8.434349) (xy 180.485999 8.426437) (xy 180.400249 8.426437)
			(xy 180.314866 8.434349) (xy 180.230576 8.450105) (xy 180.1481 8.473572) (xy 180.068141 8.504548)
			(xy 179.991381 8.54277) (xy 179.918475 8.587911) (xy 179.850046 8.639587) (xy 179.786676 8.697356)
			(xy 179.728907 8.760726) (xy 179.677231 8.829155) (xy 179.63209 8.902061) (xy 179.593868 8.978821)
			(xy 179.562892 9.05878) (xy 179.539425 9.141256) (xy 179.523669 9.225546) (xy 179.515757 9.310929)
			(xy 158.621984 9.310929) (xy 158.621984 8.377682) (xy 158.62149 8.307329) (xy 158.6136 8.166844)
			(xy 158.597845 8.027022) (xy 158.574274 7.888303) (xy 158.542963 7.751125) (xy 158.50401 7.615918)
			(xy 158.457537 7.483107) (xy 158.40369 7.353112) (xy 158.342638 7.22634) (xy 158.274575 7.103191)
			(xy 158.199714 6.984051) (xy 158.11829 6.869297) (xy 158.039844 6.770929) (xy 179.515757 6.770929)
			(xy 179.515757 6.856679) (xy 179.523669 6.942062) (xy 179.539425 7.026352) (xy 179.562892 7.108828)
			(xy 179.593868 7.188787) (xy 179.63209 7.265547) (xy 179.677231 7.338453) (xy 179.728907 7.406882)
			(xy 179.786676 7.470252) (xy 179.850046 7.528021) (xy 179.918475 7.579697) (xy 179.991381 7.624838)
			(xy 180.068141 7.66306) (xy 180.1481 7.694036) (xy 180.230576 7.717503) (xy 180.314866 7.733259)
			(xy 180.400249 7.741171) (xy 180.485999 7.741171) (xy 180.571382 7.733259) (xy 180.655672 7.717503)
			(xy 180.738148 7.694036) (xy 180.818107 7.66306) (xy 180.894867 7.624838) (xy 180.967773 7.579697)
			(xy 181.036202 7.528021) (xy 181.099572 7.470252) (xy 181.157341 7.406882) (xy 181.209017 7.338453)
			(xy 181.254158 7.265547) (xy 181.29238 7.188787) (xy 181.323356 7.108828) (xy 181.346823 7.026352)
			(xy 181.362579 6.942062) (xy 181.370491 6.856679) (xy 181.370986 6.813804) (xy 181.370491 6.770929)
			(xy 185.865757 6.770929) (xy 185.865757 6.856679) (xy 185.873669 6.942062) (xy 185.889425 7.026352)
			(xy 185.912892 7.108828) (xy 185.943868 7.188787) (xy 185.98209 7.265547) (xy 186.027231 7.338453)
			(xy 186.078907 7.406882) (xy 186.136676 7.470252) (xy 186.200046 7.528021) (xy 186.268475 7.579697)
			(xy 186.341381 7.624838) (xy 186.418141 7.66306) (xy 186.4981 7.694036) (xy 186.580576 7.717503)
			(xy 186.664866 7.733259) (xy 186.750249 7.741171) (xy 186.835999 7.741171) (xy 186.921382 7.733259)
			(xy 187.005672 7.717503) (xy 187.088148 7.694036) (xy 187.168107 7.66306) (xy 187.244867 7.624838)
			(xy 187.317773 7.579697) (xy 187.386202 7.528021) (xy 187.449572 7.470252) (xy 187.507341 7.406882)
			(xy 187.559017 7.338453) (xy 187.604158 7.265547) (xy 187.64238 7.188787) (xy 187.673356 7.108828)
			(xy 187.696823 7.026352) (xy 187.712579 6.942062) (xy 187.720491 6.856679) (xy 187.720986 6.813804)
			(xy 187.720491 6.770929) (xy 187.719832 6.763817) (xy 237.716301 6.763817) (xy 237.716301 6.849567)
			(xy 237.724213 6.93495) (xy 237.739969 7.01924) (xy 237.763436 7.101716) (xy 237.794412 7.181675)
			(xy 237.832634 7.258435) (xy 237.877775 7.331341) (xy 237.929451 7.39977) (xy 237.98722 7.46314)
			(xy 238.05059 7.520909) (xy 238.119019 7.572585) (xy 238.191925 7.617726) (xy 238.268685 7.655948)
			(xy 238.348644 7.686924) (xy 238.43112 7.710391) (xy 238.51541 7.726147) (xy 238.600793 7.734059)
			(xy 238.686543 7.734059) (xy 238.771926 7.726147) (xy 238.856216 7.710391) (xy 238.938692 7.686924)
			(xy 239.018651 7.655948) (xy 239.095411 7.617726) (xy 239.168317 7.572585) (xy 239.236746 7.520909)
			(xy 239.300116 7.46314) (xy 239.357885 7.39977) (xy 239.409561 7.331341) (xy 239.454702 7.258435)
			(xy 239.492924 7.181675) (xy 239.5239 7.101716) (xy 239.547367 7.01924) (xy 239.563123 6.93495) (xy 239.571035 6.849567)
			(xy 239.57153 6.806692) (xy 239.571035 6.763817) (xy 244.066301 6.763817) (xy 244.066301 6.849567)
			(xy 244.074213 6.93495) (xy 244.089969 7.01924) (xy 244.113436 7.101716) (xy 244.144412 7.181675)
			(xy 244.182634 7.258435) (xy 244.227775 7.331341) (xy 244.279451 7.39977) (xy 244.33722 7.46314)
			(xy 244.40059 7.520909) (xy 244.469019 7.572585) (xy 244.541925 7.617726) (xy 244.618685 7.655948)
			(xy 244.698644 7.686924) (xy 244.78112 7.710391) (xy 244.86541 7.726147) (xy 244.950793 7.734059)
			(xy 245.036543 7.734059) (xy 245.121926 7.726147) (xy 245.206216 7.710391) (xy 245.288692 7.686924)
			(xy 245.368651 7.655948) (xy 245.445411 7.617726) (xy 245.518317 7.572585) (xy 245.586746 7.520909)
			(xy 245.650116 7.46314) (xy 245.707885 7.39977) (xy 245.759561 7.331341) (xy 245.804702 7.258435)
			(xy 245.842924 7.181675) (xy 245.8739 7.101716) (xy 245.897367 7.01924) (xy 245.913123 6.93495) (xy 245.921035 6.849567)
			(xy 245.92153 6.806692) (xy 245.921117 6.770929) (xy 251.524757 6.770929) (xy 251.524757 6.856679)
			(xy 251.532669 6.942062) (xy 251.548425 7.026352) (xy 251.571892 7.108828) (xy 251.602868 7.188787)
			(xy 251.64109 7.265547) (xy 251.686231 7.338453) (xy 251.737907 7.406882) (xy 251.795676 7.470252)
			(xy 251.859046 7.528021) (xy 251.927475 7.579697) (xy 252.000381 7.624838) (xy 252.077141 7.66306)
			(xy 252.1571 7.694036) (xy 252.239576 7.717503) (xy 252.323866 7.733259) (xy 252.409249 7.741171)
			(xy 252.494999 7.741171) (xy 252.580382 7.733259) (xy 252.664672 7.717503) (xy 252.747148 7.694036)
			(xy 252.827107 7.66306) (xy 252.84931 7.652004) (xy 256.459736 7.652004) (xy 256.459736 8.515604)
			(xy 256.460222 8.542873) (xy 256.467984 8.596857) (xy 256.483349 8.649187) (xy 256.506006 8.698797)
			(xy 256.535492 8.744678) (xy 256.571207 8.785895) (xy 256.612424 8.82161) (xy 256.658305 8.851096)
			(xy 256.707915 8.873753) (xy 256.760245 8.889118) (xy 256.814229 8.89688) (xy 256.868767 8.89688)
			(xy 256.922751 8.889118) (xy 256.975081 8.873753) (xy 257.024691 8.851096) (xy 257.070572 8.82161)
			(xy 257.111789 8.785895) (xy 257.147504 8.744678) (xy 257.17699 8.698797) (xy 257.199647 8.649187)
			(xy 257.215012 8.596857) (xy 257.222774 8.542873) (xy 257.22326 8.515604) (xy 257.22326 7.652004)
			(xy 257.222774 7.624735) (xy 257.215012 7.570751) (xy 257.199647 7.518421) (xy 257.17699 7.468811)
			(xy 257.147504 7.42293) (xy 257.111789 7.381713) (xy 257.070572 7.345998) (xy 257.024691 7.316512)
			(xy 256.975081 7.293855) (xy 256.922751 7.27849) (xy 256.868767 7.270728) (xy 256.814229 7.270728)
			(xy 256.760245 7.27849) (xy 256.707915 7.293855) (xy 256.658305 7.316512) (xy 256.612424 7.345998)
			(xy 256.571207 7.381713) (xy 256.535492 7.42293) (xy 256.506006 7.468811) (xy 256.483349 7.518421)
			(xy 256.467984 7.570751) (xy 256.460222 7.624735) (xy 256.459736 7.652004) (xy 252.84931 7.652004)
			(xy 252.903867 7.624838) (xy 252.976773 7.579697) (xy 253.045202 7.528021) (xy 253.108572 7.470252)
			(xy 253.166341 7.406882) (xy 253.218017 7.338453) (xy 253.263158 7.265547) (xy 253.30138 7.188787)
			(xy 253.332356 7.108828) (xy 253.355823 7.026352) (xy 253.371579 6.942062) (xy 253.379491 6.856679)
			(xy 253.379986 6.813804) (xy 253.379491 6.770929) (xy 257.874757 6.770929) (xy 257.874757 6.856679)
			(xy 257.882669 6.942062) (xy 257.898425 7.026352) (xy 257.921892 7.108828) (xy 257.952868 7.188787)
			(xy 257.99109 7.265547) (xy 258.036231 7.338453) (xy 258.087907 7.406882) (xy 258.145676 7.470252)
			(xy 258.209046 7.528021) (xy 258.277475 7.579697) (xy 258.350381 7.624838) (xy 258.427141 7.66306)
			(xy 258.5071 7.694036) (xy 258.589576 7.717503) (xy 258.673866 7.733259) (xy 258.759249 7.741171)
			(xy 258.844999 7.741171) (xy 258.930382 7.733259) (xy 259.014672 7.717503) (xy 259.097148 7.694036)
			(xy 259.177107 7.66306) (xy 259.253867 7.624838) (xy 259.326773 7.579697) (xy 259.395202 7.528021)
			(xy 259.458572 7.470252) (xy 259.516341 7.406882) (xy 259.568017 7.338453) (xy 259.613158 7.265547)
			(xy 259.65138 7.188787) (xy 259.682356 7.108828) (xy 259.705823 7.026352) (xy 259.721579 6.942062)
			(xy 259.729491 6.856679) (xy 259.729986 6.813804) (xy 259.72979 6.796837) (xy 309.725301 6.796837)
			(xy 309.725301 6.882587) (xy 309.733213 6.96797) (xy 309.748969 7.05226) (xy 309.772436 7.134736)
			(xy 309.803412 7.214695) (xy 309.841634 7.291455) (xy 309.886775 7.364361) (xy 309.938451 7.43279)
			(xy 309.99622 7.49616) (xy 310.05959 7.553929) (xy 310.128019 7.605605) (xy 310.200925 7.650746)
			(xy 310.277685 7.688968) (xy 310.357644 7.719944) (xy 310.44012 7.743411) (xy 310.52441 7.759167)
			(xy 310.609793 7.767079) (xy 310.695543 7.767079) (xy 310.780926 7.759167) (xy 310.865216 7.743411)
			(xy 310.947692 7.719944) (xy 311.027651 7.688968) (xy 311.049854 7.677912) (xy 312.231532 7.677912)
			(xy 312.231532 8.541512) (xy 312.232018 8.568781) (xy 312.23978 8.622765) (xy 312.255145 8.675095)
			(xy 312.277802 8.724705) (xy 312.307288 8.770586) (xy 312.343003 8.811803) (xy 312.38422 8.847518)
			(xy 312.430101 8.877004) (xy 312.479711 8.899661) (xy 312.532041 8.915026) (xy 312.586025 8.922788)
			(xy 312.640563 8.922788) (xy 312.694547 8.915026) (xy 312.746877 8.899661) (xy 312.796487 8.877004)
			(xy 312.842368 8.847518) (xy 312.883585 8.811803) (xy 312.9193 8.770586) (xy 312.948786 8.724705)
			(xy 312.971443 8.675095) (xy 312.986808 8.622765) (xy 312.99457 8.568781) (xy 312.995056 8.541512)
			(xy 312.995056 7.677912) (xy 312.99457 7.650643) (xy 312.986808 7.596659) (xy 312.971443 7.544329)
			(xy 312.948786 7.494719) (xy 312.9193 7.448838) (xy 312.883585 7.407621) (xy 312.842368 7.371906)
			(xy 312.796487 7.34242) (xy 312.746877 7.319763) (xy 312.694547 7.304398) (xy 312.640563 7.296636)
			(xy 312.586025 7.296636) (xy 312.532041 7.304398) (xy 312.479711 7.319763) (xy 312.430101 7.34242)
			(xy 312.38422 7.371906) (xy 312.343003 7.407621) (xy 312.307288 7.448838) (xy 312.277802 7.494719)
			(xy 312.255145 7.544329) (xy 312.23978 7.596659) (xy 312.232018 7.650643) (xy 312.231532 7.677912)
			(xy 311.049854 7.677912) (xy 311.104411 7.650746) (xy 311.177317 7.605605) (xy 311.245746 7.553929)
			(xy 311.309116 7.49616) (xy 311.366885 7.43279) (xy 311.418561 7.364361) (xy 311.463702 7.291455)
			(xy 311.501924 7.214695) (xy 311.5329 7.134736) (xy 311.556367 7.05226) (xy 311.572123 6.96797) (xy 311.580035 6.882587)
			(xy 311.58053 6.839712) (xy 311.580035 6.796837) (xy 316.075301 6.796837) (xy 316.075301 6.882587)
			(xy 316.083213 6.96797) (xy 316.098969 7.05226) (xy 316.122436 7.134736) (xy 316.153412 7.214695)
			(xy 316.191634 7.291455) (xy 316.236775 7.364361) (xy 316.288451 7.43279) (xy 316.34622 7.49616)
			(xy 316.40959 7.553929) (xy 316.478019 7.605605) (xy 316.550925 7.650746) (xy 316.627685 7.688968)
			(xy 316.707644 7.719944) (xy 316.79012 7.743411) (xy 316.87441 7.759167) (xy 316.959793 7.767079)
			(xy 317.045543 7.767079) (xy 317.130926 7.759167) (xy 317.215216 7.743411) (xy 317.297692 7.719944)
			(xy 317.377651 7.688968) (xy 317.454411 7.650746) (xy 317.527317 7.605605) (xy 317.595746 7.553929)
			(xy 317.659116 7.49616) (xy 317.716885 7.43279) (xy 317.768561 7.364361) (xy 317.813702 7.291455)
			(xy 317.851924 7.214695) (xy 317.8829 7.134736) (xy 317.906367 7.05226) (xy 317.922123 6.96797) (xy 317.930035 6.882587)
			(xy 317.93053 6.839712) (xy 317.930117 6.803949) (xy 324.295757 6.803949) (xy 324.295757 6.889699)
			(xy 324.303669 6.975082) (xy 324.319425 7.059372) (xy 324.342892 7.141848) (xy 324.373868 7.221807)
			(xy 324.41209 7.298567) (xy 324.457231 7.371473) (xy 324.508907 7.439902) (xy 324.566676 7.503272)
			(xy 324.630046 7.561041) (xy 324.698475 7.612717) (xy 324.771381 7.657858) (xy 324.848141 7.69608)
			(xy 324.9281 7.727056) (xy 325.010576 7.750523) (xy 325.094866 7.766279) (xy 325.180249 7.774191)
			(xy 325.265999 7.774191) (xy 325.351382 7.766279) (xy 325.435672 7.750523) (xy 325.518148 7.727056)
			(xy 325.598107 7.69608) (xy 325.62031 7.685024) (xy 329.230736 7.685024) (xy 329.230736 8.548624)
			(xy 329.231222 8.575893) (xy 329.238984 8.629877) (xy 329.254349 8.682207) (xy 329.277006 8.731817)
			(xy 329.306492 8.777698) (xy 329.342207 8.818915) (xy 329.383424 8.85463) (xy 329.429305 8.884116)
			(xy 329.478915 8.906773) (xy 329.531245 8.922138) (xy 329.585229 8.9299) (xy 329.639767 8.9299) (xy 329.693751 8.922138)
			(xy 329.746081 8.906773) (xy 329.795691 8.884116) (xy 329.841572 8.85463) (xy 329.882789 8.818915)
			(xy 329.918504 8.777698) (xy 329.94799 8.731817) (xy 329.970647 8.682207) (xy 329.986012 8.629877)
			(xy 329.993774 8.575893) (xy 329.99426 8.548624) (xy 329.99426 7.685024) (xy 329.993774 7.657755)
			(xy 329.986012 7.603771) (xy 329.970647 7.551441) (xy 329.94799 7.501831) (xy 329.918504 7.45595)
			(xy 329.882789 7.414733) (xy 329.841572 7.379018) (xy 329.795691 7.349532) (xy 329.746081 7.326875)
			(xy 329.693751 7.31151) (xy 329.639767 7.303748) (xy 329.585229 7.303748) (xy 329.531245 7.31151)
			(xy 329.478915 7.326875) (xy 329.429305 7.349532) (xy 329.383424 7.379018) (xy 329.342207 7.414733)
			(xy 329.306492 7.45595) (xy 329.277006 7.501831) (xy 329.254349 7.551441) (xy 329.238984 7.603771)
			(xy 329.231222 7.657755) (xy 329.230736 7.685024) (xy 325.62031 7.685024) (xy 325.674867 7.657858)
			(xy 325.747773 7.612717) (xy 325.816202 7.561041) (xy 325.879572 7.503272) (xy 325.937341 7.439902)
			(xy 325.989017 7.371473) (xy 326.034158 7.298567) (xy 326.07238 7.221807) (xy 326.103356 7.141848)
			(xy 326.126823 7.059372) (xy 326.142579 6.975082) (xy 326.150491 6.889699) (xy 326.150986 6.846824)
			(xy 326.150491 6.803949) (xy 330.645757 6.803949) (xy 330.645757 6.889699) (xy 330.653669 6.975082)
			(xy 330.669425 7.059372) (xy 330.692892 7.141848) (xy 330.723868 7.221807) (xy 330.76209 7.298567)
			(xy 330.807231 7.371473) (xy 330.858907 7.439902) (xy 330.916676 7.503272) (xy 330.980046 7.561041)
			(xy 331.048475 7.612717) (xy 331.121381 7.657858) (xy 331.198141 7.69608) (xy 331.2781 7.727056)
			(xy 331.360576 7.750523) (xy 331.444866 7.766279) (xy 331.530249 7.774191) (xy 331.615999 7.774191)
			(xy 331.701382 7.766279) (xy 331.785672 7.750523) (xy 331.868148 7.727056) (xy 331.948107 7.69608)
			(xy 332.024867 7.657858) (xy 332.097773 7.612717) (xy 332.166202 7.561041) (xy 332.229572 7.503272)
			(xy 332.287341 7.439902) (xy 332.339017 7.371473) (xy 332.384158 7.298567) (xy 332.42238 7.221807)
			(xy 332.453356 7.141848) (xy 332.476823 7.059372) (xy 332.492579 6.975082) (xy 332.500491 6.889699)
			(xy 332.500986 6.846824) (xy 332.50079 6.829857) (xy 382.496301 6.829857) (xy 382.496301 6.915607)
			(xy 382.504213 7.00099) (xy 382.519969 7.08528) (xy 382.543436 7.167756) (xy 382.574412 7.247715)
			(xy 382.612634 7.324475) (xy 382.657775 7.397381) (xy 382.709451 7.46581) (xy 382.76722 7.52918)
			(xy 382.83059 7.586949) (xy 382.899019 7.638625) (xy 382.971925 7.683766) (xy 383.048685 7.721988)
			(xy 383.128644 7.752964) (xy 383.21112 7.776431) (xy 383.29541 7.792187) (xy 383.380793 7.800099)
			(xy 383.466543 7.800099) (xy 383.551926 7.792187) (xy 383.636216 7.776431) (xy 383.718692 7.752964)
			(xy 383.798651 7.721988) (xy 383.820854 7.710932) (xy 385.002532 7.710932) (xy 385.002532 8.574532)
			(xy 385.003018 8.601801) (xy 385.01078 8.655785) (xy 385.026145 8.708115) (xy 385.048802 8.757725)
			(xy 385.078288 8.803606) (xy 385.114003 8.844823) (xy 385.15522 8.880538) (xy 385.201101 8.910024)
			(xy 385.250711 8.932681) (xy 385.303041 8.948046) (xy 385.357025 8.955808) (xy 385.411563 8.955808)
			(xy 385.465547 8.948046) (xy 385.517877 8.932681) (xy 385.567487 8.910024) (xy 385.613368 8.880538)
			(xy 385.654585 8.844823) (xy 385.6903 8.803606) (xy 385.719786 8.757725) (xy 385.742443 8.708115)
			(xy 385.757808 8.655785) (xy 385.76557 8.601801) (xy 385.766056 8.574532) (xy 385.766056 7.710932)
			(xy 385.76557 7.683663) (xy 385.757808 7.629679) (xy 385.742443 7.577349) (xy 385.719786 7.527739)
			(xy 385.6903 7.481858) (xy 385.654585 7.440641) (xy 385.613368 7.404926) (xy 385.567487 7.37544)
			(xy 385.517877 7.352783) (xy 385.465547 7.337418) (xy 385.411563 7.329656) (xy 385.357025 7.329656)
			(xy 385.303041 7.337418) (xy 385.250711 7.352783) (xy 385.201101 7.37544) (xy 385.15522 7.404926)
			(xy 385.114003 7.440641) (xy 385.078288 7.481858) (xy 385.048802 7.527739) (xy 385.026145 7.577349)
			(xy 385.01078 7.629679) (xy 385.003018 7.683663) (xy 385.002532 7.710932) (xy 383.820854 7.710932)
			(xy 383.875411 7.683766) (xy 383.948317 7.638625) (xy 384.016746 7.586949) (xy 384.080116 7.52918)
			(xy 384.137885 7.46581) (xy 384.189561 7.397381) (xy 384.234702 7.324475) (xy 384.272924 7.247715)
			(xy 384.3039 7.167756) (xy 384.327367 7.08528) (xy 384.343123 7.00099) (xy 384.351035 6.915607) (xy 384.35153 6.872732)
			(xy 384.351035 6.829857) (xy 388.846301 6.829857) (xy 388.846301 6.915607) (xy 388.854213 7.00099)
			(xy 388.869969 7.08528) (xy 388.893436 7.167756) (xy 388.924412 7.247715) (xy 388.962634 7.324475)
			(xy 389.007775 7.397381) (xy 389.059451 7.46581) (xy 389.11722 7.52918) (xy 389.18059 7.586949) (xy 389.249019 7.638625)
			(xy 389.321925 7.683766) (xy 389.398685 7.721988) (xy 389.478644 7.752964) (xy 389.56112 7.776431)
			(xy 389.64541 7.792187) (xy 389.730793 7.800099) (xy 389.816543 7.800099) (xy 389.901926 7.792187)
			(xy 389.986216 7.776431) (xy 390.068692 7.752964) (xy 390.148651 7.721988) (xy 390.225411 7.683766)
			(xy 390.298317 7.638625) (xy 390.366746 7.586949) (xy 390.430116 7.52918) (xy 390.487885 7.46581)
			(xy 390.539561 7.397381) (xy 390.584702 7.324475) (xy 390.622924 7.247715) (xy 390.6539 7.167756)
			(xy 390.677367 7.08528) (xy 390.693123 7.00099) (xy 390.701035 6.915607) (xy 390.70153 6.872732)
			(xy 390.701117 6.836969) (xy 396.558757 6.836969) (xy 396.558757 6.922719) (xy 396.566669 7.008102)
			(xy 396.582425 7.092392) (xy 396.605892 7.174868) (xy 396.636868 7.254827) (xy 396.67509 7.331587)
			(xy 396.720231 7.404493) (xy 396.771907 7.472922) (xy 396.829676 7.536292) (xy 396.893046 7.594061)
			(xy 396.961475 7.645737) (xy 397.034381 7.690878) (xy 397.111141 7.7291) (xy 397.1911 7.760076) (xy 397.273576 7.783543)
			(xy 397.357866 7.799299) (xy 397.443249 7.807211) (xy 397.528999 7.807211) (xy 397.614382 7.799299)
			(xy 397.698672 7.783543) (xy 397.781148 7.760076) (xy 397.861107 7.7291) (xy 397.88331 7.718044)
			(xy 401.493736 7.718044) (xy 401.493736 8.581644) (xy 401.494222 8.608913) (xy 401.501984 8.662897)
			(xy 401.517349 8.715227) (xy 401.540006 8.764837) (xy 401.569492 8.810718) (xy 401.605207 8.851935)
			(xy 401.646424 8.88765) (xy 401.692305 8.917136) (xy 401.741915 8.939793) (xy 401.794245 8.955158)
			(xy 401.848229 8.96292) (xy 401.902767 8.96292) (xy 401.956751 8.955158) (xy 402.009081 8.939793)
			(xy 402.058691 8.917136) (xy 402.104572 8.88765) (xy 402.145789 8.851935) (xy 402.181504 8.810718)
			(xy 402.21099 8.764837) (xy 402.233647 8.715227) (xy 402.249012 8.662897) (xy 402.256774 8.608913)
			(xy 402.25726 8.581644) (xy 402.25726 7.718044) (xy 402.256774 7.690775) (xy 402.249012 7.636791)
			(xy 402.233647 7.584461) (xy 402.21099 7.534851) (xy 402.181504 7.48897) (xy 402.145789 7.447753)
			(xy 402.104572 7.412038) (xy 402.058691 7.382552) (xy 402.009081 7.359895) (xy 401.956751 7.34453)
			(xy 401.902767 7.336768) (xy 401.848229 7.336768) (xy 401.794245 7.34453) (xy 401.741915 7.359895)
			(xy 401.692305 7.382552) (xy 401.646424 7.412038) (xy 401.605207 7.447753) (xy 401.569492 7.48897)
			(xy 401.540006 7.534851) (xy 401.517349 7.584461) (xy 401.501984 7.636791) (xy 401.494222 7.690775)
			(xy 401.493736 7.718044) (xy 397.88331 7.718044) (xy 397.937867 7.690878) (xy 398.010773 7.645737)
			(xy 398.079202 7.594061) (xy 398.142572 7.536292) (xy 398.200341 7.472922) (xy 398.252017 7.404493)
			(xy 398.297158 7.331587) (xy 398.33538 7.254827) (xy 398.366356 7.174868) (xy 398.389823 7.092392)
			(xy 398.405579 7.008102) (xy 398.413491 6.922719) (xy 398.413986 6.879844) (xy 398.413491 6.836969)
			(xy 402.908757 6.836969) (xy 402.908757 6.922719) (xy 402.916669 7.008102) (xy 402.932425 7.092392)
			(xy 402.955892 7.174868) (xy 402.986868 7.254827) (xy 403.02509 7.331587) (xy 403.070231 7.404493)
			(xy 403.121907 7.472922) (xy 403.179676 7.536292) (xy 403.243046 7.594061) (xy 403.311475 7.645737)
			(xy 403.384381 7.690878) (xy 403.461141 7.7291) (xy 403.5411 7.760076) (xy 403.623576 7.783543) (xy 403.707866 7.799299)
			(xy 403.793249 7.807211) (xy 403.878999 7.807211) (xy 403.964382 7.799299) (xy 404.048672 7.783543)
			(xy 404.131148 7.760076) (xy 404.211107 7.7291) (xy 404.287867 7.690878) (xy 404.360773 7.645737)
			(xy 404.429202 7.594061) (xy 404.492572 7.536292) (xy 404.550341 7.472922) (xy 404.602017 7.404493)
			(xy 404.647158 7.331587) (xy 404.68538 7.254827) (xy 404.716356 7.174868) (xy 404.739823 7.092392)
			(xy 404.755579 7.008102) (xy 404.763491 6.922719) (xy 404.763986 6.879844) (xy 404.76379 6.862877)
			(xy 454.759301 6.862877) (xy 454.759301 6.948627) (xy 454.767213 7.03401) (xy 454.782969 7.1183)
			(xy 454.806436 7.200776) (xy 454.837412 7.280735) (xy 454.875634 7.357495) (xy 454.920775 7.430401)
			(xy 454.972451 7.49883) (xy 455.03022 7.5622) (xy 455.09359 7.619969) (xy 455.162019 7.671645) (xy 455.234925 7.716786)
			(xy 455.311685 7.755008) (xy 455.391644 7.785984) (xy 455.47412 7.809451) (xy 455.55841 7.825207)
			(xy 455.643793 7.833119) (xy 455.729543 7.833119) (xy 455.814926 7.825207) (xy 455.899216 7.809451)
			(xy 455.981692 7.785984) (xy 456.061651 7.755008) (xy 456.083854 7.743952) (xy 457.265532 7.743952)
			(xy 457.265532 8.607552) (xy 457.266018 8.634821) (xy 457.27378 8.688805) (xy 457.289145 8.741135)
			(xy 457.311802 8.790745) (xy 457.341288 8.836626) (xy 457.377003 8.877843) (xy 457.41822 8.913558)
			(xy 457.464101 8.943044) (xy 457.513711 8.965701) (xy 457.566041 8.981066) (xy 457.620025 8.988828)
			(xy 457.674563 8.988828) (xy 457.728547 8.981066) (xy 457.780877 8.965701) (xy 457.830487 8.943044)
			(xy 457.876368 8.913558) (xy 457.917585 8.877843) (xy 457.9533 8.836626) (xy 457.982786 8.790745)
			(xy 458.005443 8.741135) (xy 458.020808 8.688805) (xy 458.02857 8.634821) (xy 458.029056 8.607552)
			(xy 458.029056 7.743952) (xy 458.02857 7.716683) (xy 458.020808 7.662699) (xy 458.005443 7.610369)
			(xy 457.982786 7.560759) (xy 457.9533 7.514878) (xy 457.917585 7.473661) (xy 457.876368 7.437946)
			(xy 457.830487 7.40846) (xy 457.780877 7.385803) (xy 457.728547 7.370438) (xy 457.674563 7.362676)
			(xy 457.620025 7.362676) (xy 457.566041 7.370438) (xy 457.513711 7.385803) (xy 457.464101 7.40846)
			(xy 457.41822 7.437946) (xy 457.377003 7.473661) (xy 457.341288 7.514878) (xy 457.311802 7.560759)
			(xy 457.289145 7.610369) (xy 457.27378 7.662699) (xy 457.266018 7.716683) (xy 457.265532 7.743952)
			(xy 456.083854 7.743952) (xy 456.138411 7.716786) (xy 456.211317 7.671645) (xy 456.279746 7.619969)
			(xy 456.343116 7.5622) (xy 456.400885 7.49883) (xy 456.452561 7.430401) (xy 456.497702 7.357495)
			(xy 456.535924 7.280735) (xy 456.5669 7.200776) (xy 456.590367 7.1183) (xy 456.606123 7.03401) (xy 456.614035 6.948627)
			(xy 456.61453 6.905752) (xy 456.614035 6.862877) (xy 461.109301 6.862877) (xy 461.109301 6.948627)
			(xy 461.117213 7.03401) (xy 461.132969 7.1183) (xy 461.156436 7.200776) (xy 461.187412 7.280735)
			(xy 461.225634 7.357495) (xy 461.270775 7.430401) (xy 461.322451 7.49883) (xy 461.38022 7.5622) (xy 461.44359 7.619969)
			(xy 461.512019 7.671645) (xy 461.584925 7.716786) (xy 461.661685 7.755008) (xy 461.741644 7.785984)
			(xy 461.82412 7.809451) (xy 461.90841 7.825207) (xy 461.993793 7.833119) (xy 462.079543 7.833119)
			(xy 462.164926 7.825207) (xy 462.249216 7.809451) (xy 462.331692 7.785984) (xy 462.411651 7.755008)
			(xy 462.488411 7.716786) (xy 462.561317 7.671645) (xy 462.629746 7.619969) (xy 462.693116 7.5622)
			(xy 462.750885 7.49883) (xy 462.802561 7.430401) (xy 462.847702 7.357495) (xy 462.885924 7.280735)
			(xy 462.9169 7.200776) (xy 462.940367 7.1183) (xy 462.956123 7.03401) (xy 462.964035 6.948627) (xy 462.96453 6.905752)
			(xy 462.964035 6.862877) (xy 462.956123 6.777494) (xy 462.940367 6.693204) (xy 462.9169 6.610728)
			(xy 462.885924 6.530769) (xy 462.847702 6.454009) (xy 462.802561 6.381103) (xy 462.750885 6.312674)
			(xy 462.693116 6.249304) (xy 462.629746 6.191535) (xy 462.561317 6.139859) (xy 462.488411 6.094718)
			(xy 462.411651 6.056496) (xy 462.331692 6.02552) (xy 462.249216 6.002053) (xy 462.164926 5.986297)
			(xy 462.079543 5.978385) (xy 461.993793 5.978385) (xy 461.90841 5.986297) (xy 461.82412 6.002053)
			(xy 461.741644 6.02552) (xy 461.661685 6.056496) (xy 461.584925 6.094718) (xy 461.512019 6.139859)
			(xy 461.44359 6.191535) (xy 461.38022 6.249304) (xy 461.322451 6.312674) (xy 461.270775 6.381103)
			(xy 461.225634 6.454009) (xy 461.187412 6.530769) (xy 461.156436 6.610728) (xy 461.132969 6.693204)
			(xy 461.117213 6.777494) (xy 461.109301 6.862877) (xy 456.614035 6.862877) (xy 456.606123 6.777494)
			(xy 456.590367 6.693204) (xy 456.5669 6.610728) (xy 456.535924 6.530769) (xy 456.497702 6.454009)
			(xy 456.452561 6.381103) (xy 456.400885 6.312674) (xy 456.343116 6.249304) (xy 456.279746 6.191535)
			(xy 456.211317 6.139859) (xy 456.138411 6.094718) (xy 456.061651 6.056496) (xy 455.981692 6.02552)
			(xy 455.899216 6.002053) (xy 455.814926 5.986297) (xy 455.729543 5.978385) (xy 455.643793 5.978385)
			(xy 455.55841 5.986297) (xy 455.47412 6.002053) (xy 455.391644 6.02552) (xy 455.311685 6.056496)
			(xy 455.234925 6.094718) (xy 455.162019 6.139859) (xy 455.09359 6.191535) (xy 455.03022 6.249304)
			(xy 454.972451 6.312674) (xy 454.920775 6.381103) (xy 454.875634 6.454009) (xy 454.837412 6.530769)
			(xy 454.806436 6.610728) (xy 454.782969 6.693204) (xy 454.767213 6.777494) (xy 454.759301 6.862877)
			(xy 404.76379 6.862877) (xy 404.763491 6.836969) (xy 404.755579 6.751586) (xy 404.739823 6.667296)
			(xy 404.716356 6.58482) (xy 404.68538 6.504861) (xy 404.647158 6.428101) (xy 404.602017 6.355195)
			(xy 404.550341 6.286766) (xy 404.492572 6.223396) (xy 404.429202 6.165627) (xy 404.360773 6.113951)
			(xy 404.287867 6.06881) (xy 404.211107 6.030588) (xy 404.131148 5.999612) (xy 404.048672 5.976145)
			(xy 403.964382 5.960389) (xy 403.878999 5.952477) (xy 403.793249 5.952477) (xy 403.707866 5.960389)
			(xy 403.623576 5.976145) (xy 403.5411 5.999612) (xy 403.461141 6.030588) (xy 403.384381 6.06881)
			(xy 403.311475 6.113951) (xy 403.243046 6.165627) (xy 403.179676 6.223396) (xy 403.121907 6.286766)
			(xy 403.070231 6.355195) (xy 403.02509 6.428101) (xy 402.986868 6.504861) (xy 402.955892 6.58482)
			(xy 402.932425 6.667296) (xy 402.916669 6.751586) (xy 402.908757 6.836969) (xy 398.413491 6.836969)
			(xy 398.405579 6.751586) (xy 398.389823 6.667296) (xy 398.366356 6.58482) (xy 398.33538 6.504861)
			(xy 398.297158 6.428101) (xy 398.252017 6.355195) (xy 398.200341 6.286766) (xy 398.142572 6.223396)
			(xy 398.079202 6.165627) (xy 398.010773 6.113951) (xy 397.937867 6.06881) (xy 397.861107 6.030588)
			(xy 397.781148 5.999612) (xy 397.698672 5.976145) (xy 397.614382 5.960389) (xy 397.528999 5.952477)
			(xy 397.443249 5.952477) (xy 397.357866 5.960389) (xy 397.273576 5.976145) (xy 397.1911 5.999612)
			(xy 397.111141 6.030588) (xy 397.034381 6.06881) (xy 396.961475 6.113951) (xy 396.893046 6.165627)
			(xy 396.829676 6.223396) (xy 396.771907 6.286766) (xy 396.720231 6.355195) (xy 396.67509 6.428101)
			(xy 396.636868 6.504861) (xy 396.605892 6.58482) (xy 396.582425 6.667296) (xy 396.566669 6.751586)
			(xy 396.558757 6.836969) (xy 390.701117 6.836969) (xy 390.701035 6.829857) (xy 390.693123 6.744474)
			(xy 390.677367 6.660184) (xy 390.6539 6.577708) (xy 390.622924 6.497749) (xy 390.584702 6.420989)
			(xy 390.539561 6.348083) (xy 390.487885 6.279654) (xy 390.430116 6.216284) (xy 390.366746 6.158515)
			(xy 390.298317 6.106839) (xy 390.225411 6.061698) (xy 390.148651 6.023476) (xy 390.068692 5.9925)
			(xy 389.986216 5.969033) (xy 389.901926 5.953277) (xy 389.816543 5.945365) (xy 389.730793 5.945365)
			(xy 389.64541 5.953277) (xy 389.56112 5.969033) (xy 389.478644 5.9925) (xy 389.398685 6.023476) (xy 389.321925 6.061698)
			(xy 389.249019 6.106839) (xy 389.18059 6.158515) (xy 389.11722 6.216284) (xy 389.059451 6.279654)
			(xy 389.007775 6.348083) (xy 388.962634 6.420989) (xy 388.924412 6.497749) (xy 388.893436 6.577708)
			(xy 388.869969 6.660184) (xy 388.854213 6.744474) (xy 388.846301 6.829857) (xy 384.351035 6.829857)
			(xy 384.343123 6.744474) (xy 384.327367 6.660184) (xy 384.3039 6.577708) (xy 384.272924 6.497749)
			(xy 384.234702 6.420989) (xy 384.189561 6.348083) (xy 384.137885 6.279654) (xy 384.080116 6.216284)
			(xy 384.016746 6.158515) (xy 383.948317 6.106839) (xy 383.875411 6.061698) (xy 383.798651 6.023476)
			(xy 383.718692 5.9925) (xy 383.636216 5.969033) (xy 383.551926 5.953277) (xy 383.466543 5.945365)
			(xy 383.380793 5.945365) (xy 383.29541 5.953277) (xy 383.21112 5.969033) (xy 383.128644 5.9925) (xy 383.048685 6.023476)
			(xy 382.971925 6.061698) (xy 382.899019 6.106839) (xy 382.83059 6.158515) (xy 382.76722 6.216284)
			(xy 382.709451 6.279654) (xy 382.657775 6.348083) (xy 382.612634 6.420989) (xy 382.574412 6.497749)
			(xy 382.543436 6.577708) (xy 382.519969 6.660184) (xy 382.504213 6.744474) (xy 382.496301 6.829857)
			(xy 332.50079 6.829857) (xy 332.500491 6.803949) (xy 332.492579 6.718566) (xy 332.476823 6.634276)
			(xy 332.453356 6.5518) (xy 332.42238 6.471841) (xy 332.384158 6.395081) (xy 332.339017 6.322175)
			(xy 332.287341 6.253746) (xy 332.229572 6.190376) (xy 332.166202 6.132607) (xy 332.097773 6.080931)
			(xy 332.024867 6.03579) (xy 331.948107 5.997568) (xy 331.868148 5.966592) (xy 331.785672 5.943125)
			(xy 331.701382 5.927369) (xy 331.615999 5.919457) (xy 331.530249 5.919457) (xy 331.444866 5.927369)
			(xy 331.360576 5.943125) (xy 331.2781 5.966592) (xy 331.198141 5.997568) (xy 331.121381 6.03579)
			(xy 331.048475 6.080931) (xy 330.980046 6.132607) (xy 330.916676 6.190376) (xy 330.858907 6.253746)
			(xy 330.807231 6.322175) (xy 330.76209 6.395081) (xy 330.723868 6.471841) (xy 330.692892 6.5518)
			(xy 330.669425 6.634276) (xy 330.653669 6.718566) (xy 330.645757 6.803949) (xy 326.150491 6.803949)
			(xy 326.142579 6.718566) (xy 326.126823 6.634276) (xy 326.103356 6.5518) (xy 326.07238 6.471841)
			(xy 326.034158 6.395081) (xy 325.989017 6.322175) (xy 325.937341 6.253746) (xy 325.879572 6.190376)
			(xy 325.816202 6.132607) (xy 325.747773 6.080931) (xy 325.674867 6.03579) (xy 325.598107 5.997568)
			(xy 325.518148 5.966592) (xy 325.435672 5.943125) (xy 325.351382 5.927369) (xy 325.265999 5.919457)
			(xy 325.180249 5.919457) (xy 325.094866 5.927369) (xy 325.010576 5.943125) (xy 324.9281 5.966592)
			(xy 324.848141 5.997568) (xy 324.771381 6.03579) (xy 324.698475 6.080931) (xy 324.630046 6.132607)
			(xy 324.566676 6.190376) (xy 324.508907 6.253746) (xy 324.457231 6.322175) (xy 324.41209 6.395081)
			(xy 324.373868 6.471841) (xy 324.342892 6.5518) (xy 324.319425 6.634276) (xy 324.303669 6.718566)
			(xy 324.295757 6.803949) (xy 317.930117 6.803949) (xy 317.930035 6.796837) (xy 317.922123 6.711454)
			(xy 317.906367 6.627164) (xy 317.8829 6.544688) (xy 317.851924 6.464729) (xy 317.813702 6.387969)
			(xy 317.768561 6.315063) (xy 317.716885 6.246634) (xy 317.659116 6.183264) (xy 317.595746 6.125495)
			(xy 317.527317 6.073819) (xy 317.454411 6.028678) (xy 317.377651 5.990456) (xy 317.297692 5.95948)
			(xy 317.215216 5.936013) (xy 317.130926 5.920257) (xy 317.045543 5.912345) (xy 316.959793 5.912345)
			(xy 316.87441 5.920257) (xy 316.79012 5.936013) (xy 316.707644 5.95948) (xy 316.627685 5.990456)
			(xy 316.550925 6.028678) (xy 316.478019 6.073819) (xy 316.40959 6.125495) (xy 316.34622 6.183264)
			(xy 316.288451 6.246634) (xy 316.236775 6.315063) (xy 316.191634 6.387969) (xy 316.153412 6.464729)
			(xy 316.122436 6.544688) (xy 316.098969 6.627164) (xy 316.083213 6.711454) (xy 316.075301 6.796837)
			(xy 311.580035 6.796837) (xy 311.572123 6.711454) (xy 311.556367 6.627164) (xy 311.5329 6.544688)
			(xy 311.501924 6.464729) (xy 311.463702 6.387969) (xy 311.418561 6.315063) (xy 311.366885 6.246634)
			(xy 311.309116 6.183264) (xy 311.245746 6.125495) (xy 311.177317 6.073819) (xy 311.104411 6.028678)
			(xy 311.027651 5.990456) (xy 310.947692 5.95948) (xy 310.865216 5.936013) (xy 310.780926 5.920257)
			(xy 310.695543 5.912345) (xy 310.609793 5.912345) (xy 310.52441 5.920257) (xy 310.44012 5.936013)
			(xy 310.357644 5.95948) (xy 310.277685 5.990456) (xy 310.200925 6.028678) (xy 310.128019 6.073819)
			(xy 310.05959 6.125495) (xy 309.99622 6.183264) (xy 309.938451 6.246634) (xy 309.886775 6.315063)
			(xy 309.841634 6.387969) (xy 309.803412 6.464729) (xy 309.772436 6.544688) (xy 309.748969 6.627164)
			(xy 309.733213 6.711454) (xy 309.725301 6.796837) (xy 259.72979 6.796837) (xy 259.729491 6.770929)
			(xy 259.721579 6.685546) (xy 259.705823 6.601256) (xy 259.682356 6.51878) (xy 259.65138 6.438821)
			(xy 259.613158 6.362061) (xy 259.568017 6.289155) (xy 259.516341 6.220726) (xy 259.458572 6.157356)
			(xy 259.395202 6.099587) (xy 259.326773 6.047911) (xy 259.253867 6.00277) (xy 259.177107 5.964548)
			(xy 259.097148 5.933572) (xy 259.014672 5.910105) (xy 258.930382 5.894349) (xy 258.844999 5.886437)
			(xy 258.759249 5.886437) (xy 258.673866 5.894349) (xy 258.589576 5.910105) (xy 258.5071 5.933572)
			(xy 258.427141 5.964548) (xy 258.350381 6.00277) (xy 258.277475 6.047911) (xy 258.209046 6.099587)
			(xy 258.145676 6.157356) (xy 258.087907 6.220726) (xy 258.036231 6.289155) (xy 257.99109 6.362061)
			(xy 257.952868 6.438821) (xy 257.921892 6.51878) (xy 257.898425 6.601256) (xy 257.882669 6.685546)
			(xy 257.874757 6.770929) (xy 253.379491 6.770929) (xy 253.371579 6.685546) (xy 253.355823 6.601256)
			(xy 253.332356 6.51878) (xy 253.30138 6.438821) (xy 253.263158 6.362061) (xy 253.218017 6.289155)
			(xy 253.166341 6.220726) (xy 253.108572 6.157356) (xy 253.045202 6.099587) (xy 252.976773 6.047911)
			(xy 252.903867 6.00277) (xy 252.827107 5.964548) (xy 252.747148 5.933572) (xy 252.664672 5.910105)
			(xy 252.580382 5.894349) (xy 252.494999 5.886437) (xy 252.409249 5.886437) (xy 252.323866 5.894349)
			(xy 252.239576 5.910105) (xy 252.1571 5.933572) (xy 252.077141 5.964548) (xy 252.000381 6.00277)
			(xy 251.927475 6.047911) (xy 251.859046 6.099587) (xy 251.795676 6.157356) (xy 251.737907 6.220726)
			(xy 251.686231 6.289155) (xy 251.64109 6.362061) (xy 251.602868 6.438821) (xy 251.571892 6.51878)
			(xy 251.548425 6.601256) (xy 251.532669 6.685546) (xy 251.524757 6.770929) (xy 245.921117 6.770929)
			(xy 245.921035 6.763817) (xy 245.913123 6.678434) (xy 245.897367 6.594144) (xy 245.8739 6.511668)
			(xy 245.842924 6.431709) (xy 245.804702 6.354949) (xy 245.759561 6.282043) (xy 245.707885 6.213614)
			(xy 245.650116 6.150244) (xy 245.586746 6.092475) (xy 245.518317 6.040799) (xy 245.445411 5.995658)
			(xy 245.368651 5.957436) (xy 245.288692 5.92646) (xy 245.206216 5.902993) (xy 245.121926 5.887237)
			(xy 245.036543 5.879325) (xy 244.950793 5.879325) (xy 244.86541 5.887237) (xy 244.78112 5.902993)
			(xy 244.698644 5.92646) (xy 244.618685 5.957436) (xy 244.541925 5.995658) (xy 244.469019 6.040799)
			(xy 244.40059 6.092475) (xy 244.33722 6.150244) (xy 244.279451 6.213614) (xy 244.227775 6.282043)
			(xy 244.182634 6.354949) (xy 244.144412 6.431709) (xy 244.113436 6.511668) (xy 244.089969 6.594144)
			(xy 244.074213 6.678434) (xy 244.066301 6.763817) (xy 239.571035 6.763817) (xy 239.563123 6.678434)
			(xy 239.547367 6.594144) (xy 239.5239 6.511668) (xy 239.492924 6.431709) (xy 239.454702 6.354949)
			(xy 239.409561 6.282043) (xy 239.357885 6.213614) (xy 239.300116 6.150244) (xy 239.236746 6.092475)
			(xy 239.168317 6.040799) (xy 239.095411 5.995658) (xy 239.018651 5.957436) (xy 238.938692 5.92646)
			(xy 238.856216 5.902993) (xy 238.771926 5.887237) (xy 238.686543 5.879325) (xy 238.600793 5.879325)
			(xy 238.51541 5.887237) (xy 238.43112 5.902993) (xy 238.348644 5.92646) (xy 238.268685 5.957436)
			(xy 238.191925 5.995658) (xy 238.119019 6.040799) (xy 238.05059 6.092475) (xy 237.98722 6.150244)
			(xy 237.929451 6.213614) (xy 237.877775 6.282043) (xy 237.832634 6.354949) (xy 237.794412 6.431709)
			(xy 237.763436 6.511668) (xy 237.739969 6.594144) (xy 237.724213 6.678434) (xy 237.716301 6.763817)
			(xy 187.719832 6.763817) (xy 187.712579 6.685546) (xy 187.696823 6.601256) (xy 187.673356 6.51878)
			(xy 187.64238 6.438821) (xy 187.604158 6.362061) (xy 187.559017 6.289155) (xy 187.507341 6.220726)
			(xy 187.449572 6.157356) (xy 187.386202 6.099587) (xy 187.317773 6.047911) (xy 187.244867 6.00277)
			(xy 187.168107 5.964548) (xy 187.088148 5.933572) (xy 187.005672 5.910105) (xy 186.921382 5.894349)
			(xy 186.835999 5.886437) (xy 186.750249 5.886437) (xy 186.664866 5.894349) (xy 186.580576 5.910105)
			(xy 186.4981 5.933572) (xy 186.418141 5.964548) (xy 186.341381 6.00277) (xy 186.268475 6.047911)
			(xy 186.200046 6.099587) (xy 186.136676 6.157356) (xy 186.078907 6.220726) (xy 186.027231 6.289155)
			(xy 185.98209 6.362061) (xy 185.943868 6.438821) (xy 185.912892 6.51878) (xy 185.889425 6.601256)
			(xy 185.873669 6.685546) (xy 185.865757 6.770929) (xy 181.370491 6.770929) (xy 181.362579 6.685546)
			(xy 181.346823 6.601256) (xy 181.323356 6.51878) (xy 181.29238 6.438821) (xy 181.254158 6.362061)
			(xy 181.209017 6.289155) (xy 181.157341 6.220726) (xy 181.099572 6.157356) (xy 181.036202 6.099587)
			(xy 180.967773 6.047911) (xy 180.894867 6.00277) (xy 180.818107 5.964548) (xy 180.738148 5.933572)
			(xy 180.655672 5.910105) (xy 180.571382 5.894349) (xy 180.485999 5.886437) (xy 180.400249 5.886437)
			(xy 180.314866 5.894349) (xy 180.230576 5.910105) (xy 180.1481 5.933572) (xy 180.068141 5.964548)
			(xy 179.991381 6.00277) (xy 179.918475 6.047911) (xy 179.850046 6.099587) (xy 179.786676 6.157356)
			(xy 179.728907 6.220726) (xy 179.677231 6.289155) (xy 179.63209 6.362061) (xy 179.593868 6.438821)
			(xy 179.562892 6.51878) (xy 179.539425 6.601256) (xy 179.523669 6.685546) (xy 179.515757 6.770929)
			(xy 158.039844 6.770929) (xy 158.030561 6.759289) (xy 157.936801 6.654373) (xy 157.837306 6.554879)
			(xy 157.732388 6.46112) (xy 157.622379 6.373391) (xy 157.507624 6.291969) (xy 157.388483 6.21711)
			(xy 157.265333 6.149048) (xy 157.138561 6.087998) (xy 157.008565 6.034153) (xy 156.875754 5.987681)
			(xy 156.740546 5.948729) (xy 156.603367 5.91742) (xy 156.464649 5.893851) (xy 156.324827 5.878098)
			(xy 156.184341 5.870209) (xy 156.113988 5.869686) (xy 17.493996 5.869686) (xy 17.423642 5.870179)
			(xy 17.283156 5.878069) (xy 17.143333 5.893824) (xy 17.004613 5.917393) (xy 16.867433 5.948703) (xy 16.732225 5.987656)
			(xy 16.599413 6.034129) (xy 16.469416 6.087976) (xy 16.342643 6.149026) (xy 16.219492 6.217089) (xy 16.100351 6.29195)
			(xy 15.985596 6.373373) (xy 15.875586 6.461103) (xy 15.770668 6.554863) (xy 15.671172 6.654358) (xy 15.577412 6.759275)
			(xy 15.489682 6.869284) (xy 15.408258 6.98404) (xy 15.333396 7.10318) (xy 15.265333 7.22633) (xy 15.204281 7.353103)
			(xy 15.150434 7.4831) (xy 15.103961 7.615912) (xy 15.065007 7.75112) (xy 15.033696 7.8883) (xy 15.010125 8.027019)
			(xy 14.99437 8.166842) (xy 14.98648 8.307328) (xy 14.986 8.377682) (xy 14.986 24.157686) (xy 14.985478 24.213493)
			(xy 14.977137 24.324795) (xy 14.960501 24.435162) (xy 14.935664 24.543977) (xy 14.902765 24.650632)
			(xy 14.861988 24.754531) (xy 14.81356 24.855091) (xy 14.757753 24.951752) (xy 14.694879 25.043971)
			(xy 14.625289 25.131234) (xy 14.549372 25.213053) (xy 14.467553 25.28897) (xy 14.38029 25.35856)
			(xy 14.28807 25.421434) (xy 14.19141 25.477241) (xy 14.090849 25.525669) (xy 13.986951 25.566446)
			(xy 13.880295 25.599345) (xy 13.77148 25.624182) (xy 13.661113 25.640817) (xy 13.549811 25.649158)
			(xy 13.494004 25.649682) (xy 1.999996 25.649682) (xy 1.944189 25.64916) (xy 1.832887 25.640819) (xy 1.72252 25.624184)
			(xy 1.613704 25.599347) (xy 1.507049 25.566448) (xy 1.40315 25.525671) (xy 1.30259 25.477243) (xy 1.205929 25.421436)
			(xy 1.113709 25.358562) (xy 1.026446 25.288971) (xy 0.944627 25.213055) (xy 0.86871 25.131236) (xy 0.79912 25.043972)
			(xy 0.736245 24.951753) (xy 0.680438 24.855092) (xy 0.63201 24.754532) (xy 0.591233 24.650633) (xy 0.558334 24.543978)
			(xy 0.533497 24.435162) (xy 0.516861 24.324795) (xy 0.50852 24.213493) (xy 0.508 24.157686) (xy 0.508 21.093122)
			(xy 2.904225 21.093122) (xy 2.904225 21.222262) (xy 2.912175 21.351157) (xy 2.928045 21.479317) (xy 2.951774 21.606258)
			(xy 2.983273 21.731497) (xy 3.022422 21.85456) (xy 3.069073 21.974979) (xy 3.123048 22.092298) (xy 3.184143 22.206072)
			(xy 3.252126 22.315869) (xy 3.32674 22.421272) (xy 3.407701 22.521882) (xy 3.494701 22.617317) (xy 3.587412 22.707216)
			(xy 3.685482 22.791237) (xy 3.788537 22.869061) (xy 3.896188 22.940393) (xy 4.008027 23.004963) (xy 4.123628 23.062525)
			(xy 4.242553 23.112862) (xy 4.364352 23.155782) (xy 4.488562 23.191123) (xy 4.614711 23.21875) (xy 4.742323 23.238559)
			(xy 4.870912 23.250475) (xy 4.99999 23.254452) (xy 5.129068 23.250475) (xy 5.257657 23.238559) (xy 5.385269 23.21875)
			(xy 5.511418 23.191123) (xy 5.635628 23.155782) (xy 5.757427 23.112862) (xy 5.876352 23.062525) (xy 5.991953 23.004963)
			(xy 6.103792 22.940393) (xy 6.211443 22.869061) (xy 6.314498 22.791237) (xy 6.412568 22.707216) (xy 6.505279 22.617317)
			(xy 6.592279 22.521882) (xy 6.67324 22.421272) (xy 6.747854 22.315869) (xy 6.815837 22.206072) (xy 6.876932 22.092298)
			(xy 6.930907 21.974979) (xy 6.977558 21.85456) (xy 7.016707 21.731497) (xy 7.048206 21.606258) (xy 7.071935 21.479317)
			(xy 7.087805 21.351157) (xy 7.095755 21.222262) (xy 7.096252 21.157692) (xy 7.095755 21.093122) (xy 7.087805 20.964227)
			(xy 7.071935 20.836067) (xy 7.048206 20.709126) (xy 7.016707 20.583887) (xy 6.977558 20.460824) (xy 6.930907 20.340405)
			(xy 6.876932 20.223086) (xy 6.815837 20.109312) (xy 6.747854 19.999515) (xy 6.67324 19.894112) (xy 6.592279 19.793502)
			(xy 6.505279 19.698067) (xy 6.412568 19.608168) (xy 6.314498 19.524147) (xy 6.211443 19.446323) (xy 6.103792 19.374991)
			(xy 5.991953 19.310421) (xy 5.876352 19.252859) (xy 5.757427 19.202522) (xy 5.635628 19.159602) (xy 5.511418 19.124261)
			(xy 5.385269 19.096634) (xy 5.257657 19.076825) (xy 5.129068 19.064909) (xy 4.99999 19.060933) (xy 4.870912 19.064909)
			(xy 4.742323 19.076825) (xy 4.614711 19.096634) (xy 4.488562 19.124261) (xy 4.364352 19.159602) (xy 4.242553 19.202522)
			(xy 4.123628 19.252859) (xy 4.008027 19.310421) (xy 3.896188 19.374991) (xy 3.788537 19.446323) (xy 3.685482 19.524147)
			(xy 3.587412 19.608168) (xy 3.494701 19.698067) (xy 3.407701 19.793502) (xy 3.32674 19.894112) (xy 3.252126 19.999515)
			(xy 3.184143 20.109312) (xy 3.123048 20.223086) (xy 3.069073 20.340405) (xy 3.022422 20.460824) (xy 2.983273 20.583887)
			(xy 2.951774 20.709126) (xy 2.928045 20.836067) (xy 2.912175 20.964227) (xy 2.904225 21.093122) (xy 0.508 21.093122)
			(xy 0.508 3.999992) (xy 0.508522 3.944185) (xy 0.516863 3.832883) (xy 0.533498 3.722516) (xy 0.558335 3.6137)
			(xy 0.591234 3.507045) (xy 0.632011 3.403146) (xy 0.680438 3.302586) (xy 0.736246 3.205925) (xy 0.79912 3.113705)
			(xy 0.86871 3.026442) (xy 0.944627 2.944623) (xy 1.026446 2.868706) (xy 1.113709 2.799116) (xy 1.205929 2.736242)
			(xy 1.30259 2.680434) (xy 1.40315 2.632007) (xy 1.507049 2.59123) (xy 1.613704 2.558331) (xy 1.72252 2.533494)
			(xy 1.832887 2.516859) (xy 1.944189 2.508518) (xy 1.999996 2.507996) (xy 7.964932 2.507996) (xy 8.035286 2.507503)
			(xy 8.175772 2.499613) (xy 8.315594 2.483859) (xy 8.454314 2.460289) (xy 8.591493 2.428979) (xy 8.726701 2.390026)
			(xy 8.859513 2.343553) (xy 8.989509 2.289707) (xy 9.116282 2.228656) (xy 9.239433 2.160593) (xy 9.358573 2.085732)
			(xy 9.473329 2.004309) (xy 9.583338 1.916579) (xy 9.688255 1.822819) (xy 9.78775 1.723324) (xy 9.88151 1.618406)
			(xy 9.96924 1.508397) (xy 10.050663 1.393641) (xy 10.125524 1.274501) (xy 10.193587 1.151351) (xy 10.254637 1.024578)
			(xy 10.308484 0.894581) (xy 10.354957 0.76177) (xy 10.393909 0.626561) (xy 10.42522 0.489382) (xy 10.448789 0.350662)
			(xy 10.464543 0.21084) (xy 10.472433 0.070354) (xy 10.472928 0) (xy 10.472928 -8.850122) (xy 10.47345 -8.905929)
			(xy 10.481791 -9.017231) (xy 10.498426 -9.127599) (xy 10.523263 -9.236414) (xy 10.556162 -9.34307)
			(xy 10.596939 -9.446968) (xy 10.645366 -9.547529) (xy 10.701173 -9.64419) (xy 10.764048 -9.73641)
			(xy 10.833638 -9.823673) (xy 10.909555 -9.905492) (xy 10.991374 -9.981409) (xy 11.078637 -10.051)
			(xy 11.170857 -10.113875) (xy 11.267517 -10.169682) (xy 11.368078 -10.21811) (xy 11.471977 -10.258887)
			(xy 11.578632 -10.291786) (xy 11.687448 -10.316623) (xy 11.797815 -10.333259) (xy 11.909117 -10.3416)
			(xy 11.964924 -10.342118)
		)
		(stroke
			(width 0)
			(type solid)
		)
		(fill yes)
		(layer "In3.Cu")
		(net "COUPON_GND2")
	)
	(gr_poly
		(pts
			(xy 462.778602 -243.13769) (xy 462.787788 -243.137354) (xy 462.805014 -243.130976) (xy 462.818882 -243.118932)
			(xy 462.82356 -243.11102) (xy 462.872582 -243.01958) (xy 462.871312 -242.99164) (xy 462.863438 -242.979956)
			(xy 462.816319 -242.907995) (xy 462.728325 -242.760176) (xy 462.647649 -242.60824) (xy 462.574481 -242.452549)
			(xy 462.508997 -242.293473) (xy 462.451353 -242.131391) (xy 462.401685 -241.96669) (xy 462.360113 -241.799762)
			(xy 462.326735 -241.631004) (xy 462.301631 -241.460819) (xy 462.28486 -241.289611) (xy 462.276463 -241.117789)
			(xy 462.275936 -241.031776) (xy 462.275936 -87.58809) (xy 462.276456 -87.501606) (xy 462.28494 -87.328845)
			(xy 462.30189 -87.15671) (xy 462.327267 -86.985613) (xy 462.36101 -86.815968) (xy 462.403036 -86.648182)
			(xy 462.453245 -86.482662) (xy 462.511516 -86.319804) (xy 462.577708 -86.160002) (xy 462.651662 -86.003641)
			(xy 462.7332 -85.851097) (xy 462.822125 -85.702738) (xy 462.918223 -85.558921) (xy 463.021263 -85.419993)
			(xy 463.130996 -85.286289) (xy 463.247157 -85.158131) (xy 463.307938 -85.096604) (xy 465.936584 -82.467958)
			(xy 465.958275 -82.445601) (xy 465.996222 -82.396201) (xy 466.027395 -82.342269) (xy 466.051259 -82.284728)
			(xy 466.067406 -82.224565) (xy 466.075561 -82.162808) (xy 466.07603 -82.131662) (xy 466.07603 -1.999996)
			(xy 466.07552 -1.96883) (xy 466.067384 -1.907032) (xy 466.051252 -1.846825) (xy 466.027399 -1.789238)
			(xy 465.996235 -1.735257) (xy 465.958291 -1.685805) (xy 465.914217 -1.641729) (xy 465.864768 -1.603782)
			(xy 465.810789 -1.572614) (xy 465.753204 -1.548758) (xy 465.692997 -1.532622) (xy 465.6312 -1.524482)
			(xy 465.600034 -1.524) (xy 459.989174 -1.524) (xy 459.979558 -1.524417) (xy 459.961681 -1.531509)
			(xy 459.947672 -1.544686) (xy 459.9432 -1.55321) (xy 459.897734 -1.64973) (xy 459.901544 -1.67894)
			(xy 459.910942 -1.69037) (xy 459.974368 -1.76736) (xy 460.095946 -1.925536) (xy 460.211337 -2.088279)
			(xy 460.320371 -2.255349) (xy 460.422885 -2.426496) (xy 460.518728 -2.601467) (xy 460.607756 -2.780001)
			(xy 460.689837 -2.961834) (xy 460.76485 -3.146695) (xy 460.832683 -3.33431) (xy 460.893236 -3.5244)
			(xy 460.946417 -3.716681) (xy 460.992149 -3.91087) (xy 461.030364 -4.106677) (xy 461.061003 -4.30381)
			(xy 461.084023 -4.501979) (xy 461.099389 -4.700887) (xy 461.107078 -4.90024) (xy 461.107536 -4.99999)
			(xy 461.107282 -5.057394) (xy 461.107282 -5.059934) (xy 461.108044 -5.06984) (xy 461.108552 -5.071872)
			(xy 461.124558 -5.16361) (xy 461.150865 -5.347988) (xy 461.170629 -5.533182) (xy 461.183824 -5.718959)
			(xy 461.190435 -5.905087) (xy 461.190848 -5.99821) (xy 461.190848 -5.999988) (xy 461.190354 -6.101963)
			(xy 461.182445 -6.30576) (xy 461.166641 -6.509097) (xy 461.142964 -6.711669) (xy 461.111449 -6.913169)
			(xy 461.072146 -7.113297) (xy 461.025112 -7.31175) (xy 460.970418 -7.50823) (xy 460.908146 -7.702441)
			(xy 460.838391 -7.894092) (xy 460.761257 -8.082893) (xy 460.67686 -8.268562) (xy 460.585328 -8.450819)
			(xy 460.486797 -8.629389) (xy 460.381416 -8.804005) (xy 460.269343 -8.974403) (xy 460.150747 -9.140327)
			(xy 460.025807 -9.301528) (xy 459.894711 -9.457763) (xy 459.757654 -9.608797) (xy 459.614845 -9.754403)
			(xy 459.466497 -9.894363) (xy 459.312833 -10.028464) (xy 459.154085 -10.156507) (xy 458.990492 -10.278298)
			(xy 458.822299 -10.393653) (xy 458.64976 -10.502401) (xy 458.473134 -10.604376) (xy 458.292686 -10.699426)
			(xy 458.108689 -10.787407) (xy 457.921418 -10.868188) (xy 457.731156 -10.941646) (xy 457.538189 -11.007672)
			(xy 457.342807 -11.066165) (xy 457.145303 -11.117039) (xy 456.945976 -11.160216) (xy 456.745124 -11.195631)
			(xy 456.54305 -11.223232) (xy 456.340057 -11.242977) (xy 456.136452 -11.254836) (xy 455.93254 -11.258791)
			(xy 455.728628 -11.254836) (xy 455.525023 -11.242977) (xy 455.32203 -11.223232) (xy 455.119956 -11.195631)
			(xy 454.919104 -11.160216) (xy 454.719777 -11.117039) (xy 454.522273 -11.066165) (xy 454.326891 -11.007672)
			(xy 454.133924 -10.941646) (xy 453.943662 -10.868188) (xy 453.756391 -10.787407) (xy 453.572394 -10.699426)
			(xy 453.391946 -10.604376) (xy 453.21532 -10.502401) (xy 453.042781 -10.393653) (xy 452.874588 -10.278298)
			(xy 452.710995 -10.156507) (xy 452.552247 -10.028464) (xy 452.398583 -9.894363) (xy 452.250235 -9.754403)
			(xy 452.107426 -9.608797) (xy 451.970369 -9.457763) (xy 451.839273 -9.301528) (xy 451.714333 -9.140327)
			(xy 451.595737 -8.974403) (xy 451.483664 -8.804005) (xy 451.378283 -8.629389) (xy 451.279752 -8.450819)
			(xy 451.18822 -8.268562) (xy 451.103823 -8.082893) (xy 451.026689 -7.894092) (xy 450.956934 -7.702441)
			(xy 450.894662 -7.50823) (xy 450.839968 -7.31175) (xy 450.792934 -7.113297) (xy 450.753631 -6.913169)
			(xy 450.722116 -6.711669) (xy 450.698439 -6.509097) (xy 450.682635 -6.30576) (xy 450.674726 -6.101963)
			(xy 450.674232 -5.999988) (xy 450.674232 -5.997956) (xy 450.67465 -5.904859) (xy 450.681259 -5.718781)
			(xy 450.694454 -5.533054) (xy 450.714217 -5.347911) (xy 450.740524 -5.163584) (xy 450.756528 -5.071872)
			(xy 450.757036 -5.06984) (xy 450.757798 -5.059934) (xy 450.757798 -5.057394) (xy 450.757544 -4.99999)
			(xy 450.758023 -4.900314) (xy 450.7657 -4.701111) (xy 450.781042 -4.502351) (xy 450.804026 -4.304329)
			(xy 450.834617 -4.107339) (xy 450.872772 -3.911673) (xy 450.918432 -3.717621) (xy 450.971531 -3.525472)
			(xy 451.03199 -3.335509) (xy 451.099718 -3.148016) (xy 451.174616 -2.96327) (xy 451.256573 -2.781544)
			(xy 451.345466 -2.60311) (xy 451.441164 -2.42823) (xy 451.543525 -2.257165) (xy 451.652397 -2.090169)
			(xy 451.767619 -1.927489) (xy 451.88902 -1.769366) (xy 451.95236 -1.692402) (xy 451.962266 -1.682496)
			(xy 451.967854 -1.651) (xy 451.92188 -1.55321) (xy 451.917419 -1.54468) (xy 451.903405 -1.531504)
			(xy 451.885523 -1.524417) (xy 451.875906 -1.524) (xy 446.265046 -1.524) (xy 446.233877 -1.524485)
			(xy 446.172073 -1.532616) (xy 446.111859 -1.548745) (xy 446.054265 -1.572596) (xy 446.000278 -1.603761)
			(xy 445.95082 -1.641706) (xy 445.906739 -1.685783) (xy 445.868789 -1.735236) (xy 445.837618 -1.78922)
			(xy 445.813761 -1.846812) (xy 445.797626 -1.907024) (xy 445.789488 -1.968828) (xy 445.78905 -1.999996)
			(xy 445.78905 -11.850116) (xy 445.788562 -11.920918) (xy 445.780621 -12.062299) (xy 445.764766 -12.203013)
			(xy 445.741045 -12.342616) (xy 445.709534 -12.48067) (xy 445.670332 -12.61674) (xy 445.623562 -12.750397)
			(xy 445.569371 -12.881222) (xy 445.50793 -13.008802) (xy 445.439432 -13.132737) (xy 445.364092 -13.252636)
			(xy 445.282149 -13.368122) (xy 445.193859 -13.478831) (xy 445.0995 -13.584416) (xy 444.999369 -13.684544)
			(xy 444.893782 -13.7789) (xy 444.78307 -13.867187) (xy 444.667582 -13.949128) (xy 444.547682 -14.024464)
			(xy 444.423745 -14.092959) (xy 444.296163 -14.154397) (xy 444.165337 -14.208584) (xy 444.031679 -14.255351)
			(xy 443.895608 -14.29455) (xy 443.757554 -14.326057) (xy 443.61795 -14.349774) (xy 443.477236 -14.365627)
			(xy 443.335854 -14.373564) (xy 443.265052 -14.374114) (xy 435.265068 -14.374114) (xy 435.194266 -14.373617)
			(xy 435.052884 -14.365675) (xy 434.91217 -14.349819) (xy 434.772567 -14.326098) (xy 434.634513 -14.294586)
			(xy 434.498443 -14.255384) (xy 434.364786 -14.208614) (xy 434.233961 -14.154423) (xy 434.10638 -14.092982)
			(xy 433.982445 -14.024485) (xy 433.862545 -13.949146) (xy 433.747059 -13.867203) (xy 433.636348 -13.778914)
			(xy 433.530763 -13.684556) (xy 433.430633 -13.584426) (xy 433.336276 -13.478839) (xy 433.247987 -13.368128)
			(xy 433.166045 -13.252641) (xy 433.090707 -13.132741) (xy 433.02221 -13.008806) (xy 432.96077 -12.881225)
			(xy 432.90658 -12.750399) (xy 432.859811 -12.616741) (xy 432.82061 -12.480671) (xy 432.789099 -12.342617)
			(xy 432.765379 -12.203014) (xy 432.749524 -12.0623) (xy 432.741583 -11.920918) (xy 432.74107 -11.850116)
			(xy 432.74107 -1.999996) (xy 432.740582 -1.96883) (xy 432.732445 -1.907032) (xy 432.716312 -1.846825)
			(xy 432.692457 -1.789239) (xy 432.661291 -1.735259) (xy 432.623344 -1.685809) (xy 432.579268 -1.641736)
			(xy 432.529816 -1.603793) (xy 432.475834 -1.572629) (xy 432.418246 -1.548779) (xy 432.358038 -1.532649)
			(xy 432.29624 -1.524516) (xy 432.265074 -1.524) (xy 420.265098 -1.524) (xy 420.233933 -1.52451) (xy 420.172136 -1.532646)
			(xy 420.11193 -1.548778) (xy 420.054345 -1.572631) (xy 420.000365 -1.603796) (xy 419.950915 -1.64174)
			(xy 419.906841 -1.685814) (xy 419.868897 -1.735263) (xy 419.837732 -1.789243) (xy 419.813879 -1.846828)
			(xy 419.797746 -1.907034) (xy 419.78961 -1.968831) (xy 419.789102 -1.999996) (xy 419.789102 -11.850116)
			(xy 419.788605 -11.920918) (xy 419.780664 -12.0623) (xy 419.764809 -12.203015) (xy 419.741088 -12.342618)
			(xy 419.709578 -12.480673) (xy 419.670376 -12.616743) (xy 419.623606 -12.750401) (xy 419.569416 -12.881227)
			(xy 419.507975 -13.008808) (xy 419.439478 -13.132743) (xy 419.364139 -13.252643) (xy 419.282196 -13.36813)
			(xy 419.193907 -13.478841) (xy 419.099549 -13.584427) (xy 418.999419 -13.684557) (xy 418.893832 -13.778914)
			(xy 418.783121 -13.867203) (xy 418.667633 -13.949146) (xy 418.547733 -14.024484) (xy 418.423797 -14.092981)
			(xy 418.296216 -14.154421) (xy 418.16539 -14.20861) (xy 418.031732 -14.255379) (xy 417.895661 -14.294581)
			(xy 417.757607 -14.326091) (xy 417.618003 -14.34981) (xy 417.477288 -14.365665) (xy 417.335906 -14.373605)
			(xy 417.265104 -14.374114) (xy 409.26512 -14.374114) (xy 409.194317 -14.373627) (xy 409.052933 -14.365688)
			(xy 408.912216 -14.349834) (xy 408.77261 -14.326115) (xy 408.634553 -14.294606) (xy 408.49848 -14.255405)
			(xy 408.36482 -14.208636) (xy 408.233992 -14.154447) (xy 408.106408 -14.093007) (xy 407.98247 -14.02451)
			(xy 407.862567 -13.949172) (xy 407.747078 -13.867229) (xy 407.636365 -13.778939) (xy 407.530776 -13.684581)
			(xy 407.430644 -13.58445) (xy 407.336284 -13.478863) (xy 407.247993 -13.368151) (xy 407.166048 -13.252662)
			(xy 407.090708 -13.132761) (xy 407.02221 -13.008824) (xy 406.960768 -12.881241) (xy 406.906576 -12.750414)
			(xy 406.859806 -12.616754) (xy 406.820603 -12.480682) (xy 406.789092 -12.342626) (xy 406.765371 -12.20302)
			(xy 406.749515 -12.062303) (xy 406.741574 -11.920919) (xy 406.741122 -11.850116) (xy 406.741122 -1.999996)
			(xy 406.740612 -1.968831) (xy 406.732476 -1.907033) (xy 406.716344 -1.846826) (xy 406.692491 -1.789239)
			(xy 406.661326 -1.735259) (xy 406.623383 -1.685808) (xy 406.579309 -1.641732) (xy 406.52986 -1.603786)
			(xy 406.47588 -1.572619) (xy 406.418295 -1.548763) (xy 406.358089 -1.532628) (xy 406.296291 -1.524489)
			(xy 406.265126 -1.524) (xy 404.321518 -1.524) (xy 404.311897 -1.524409) (xy 404.294007 -1.531492)
			(xy 404.279985 -1.544667) (xy 404.275544 -1.55321) (xy 404.230078 -1.64973) (xy 404.233888 -1.67894)
			(xy 404.243286 -1.69037) (xy 404.306713 -1.76736) (xy 404.428292 -1.925535) (xy 404.543684 -2.088278)
			(xy 404.652719 -2.255347) (xy 404.755234 -2.426494) (xy 404.851078 -2.601465) (xy 404.940107 -2.779999)
			(xy 405.022189 -2.961832) (xy 405.097203 -3.146693) (xy 405.165037 -3.334308) (xy 405.22559 -3.524398)
			(xy 405.278772 -3.71668) (xy 405.324505 -3.910868) (xy 405.36272 -4.106675) (xy 405.39336 -4.303809)
			(xy 405.41638 -4.501978) (xy 405.431746 -4.700886) (xy 405.439435 -4.900239) (xy 405.43988 -4.99999)
			(xy 405.439626 -5.057394) (xy 405.439626 -5.059934) (xy 405.440388 -5.06984) (xy 405.440896 -5.071872)
			(xy 405.456901 -5.16361) (xy 405.483209 -5.347988) (xy 405.502972 -5.533182) (xy 405.516167 -5.718959)
			(xy 405.522778 -5.905087) (xy 405.523192 -5.99821) (xy 405.523192 -5.999988) (xy 405.522698 -6.101963)
			(xy 405.514789 -6.30576) (xy 405.498985 -6.509097) (xy 405.475308 -6.711669) (xy 405.443793 -6.913169)
			(xy 405.40449 -7.113297) (xy 405.357456 -7.31175) (xy 405.302762 -7.50823) (xy 405.24049 -7.702441)
			(xy 405.170735 -7.894092) (xy 405.093601 -8.082893) (xy 405.009204 -8.268562) (xy 404.917672 -8.450819)
			(xy 404.819141 -8.629389) (xy 404.71376 -8.804005) (xy 404.601687 -8.974403) (xy 404.483091 -9.140327)
			(xy 404.358151 -9.301528) (xy 404.227055 -9.457763) (xy 404.089998 -9.608797) (xy 403.947189 -9.754403)
			(xy 403.798841 -9.894363) (xy 403.645177 -10.028464) (xy 403.486429 -10.156507) (xy 403.322836 -10.278298)
			(xy 403.154643 -10.393653) (xy 402.982104 -10.502401) (xy 402.805478 -10.604376) (xy 402.62503 -10.699426)
			(xy 402.441033 -10.787407) (xy 402.253762 -10.868188) (xy 402.0635 -10.941646) (xy 401.870533 -11.007672)
			(xy 401.675151 -11.066165) (xy 401.477647 -11.117039) (xy 401.27832 -11.160216) (xy 401.077468 -11.195631)
			(xy 400.875394 -11.223232) (xy 400.672401 -11.242977) (xy 400.468796 -11.254836) (xy 400.264884 -11.258791)
			(xy 400.060972 -11.254836) (xy 399.857367 -11.242977) (xy 399.654374 -11.223232) (xy 399.4523 -11.195631)
			(xy 399.251448 -11.160216) (xy 399.052121 -11.117039) (xy 398.854617 -11.066165) (xy 398.659235 -11.007672)
			(xy 398.466268 -10.941646) (xy 398.276006 -10.868188) (xy 398.088735 -10.787407) (xy 397.904738 -10.699426)
			(xy 397.72429 -10.604376) (xy 397.547664 -10.502401) (xy 397.375125 -10.393653) (xy 397.206932 -10.278298)
			(xy 397.043339 -10.156507) (xy 396.884591 -10.028464) (xy 396.730927 -9.894363) (xy 396.582579 -9.754403)
			(xy 396.43977 -9.608797) (xy 396.302713 -9.457763) (xy 396.171617 -9.301528) (xy 396.046677 -9.140327)
			(xy 395.928081 -8.974403) (xy 395.816008 -8.804005) (xy 395.710627 -8.629389) (xy 395.612096 -8.450819)
			(xy 395.520564 -8.268562) (xy 395.436167 -8.082893) (xy 395.359033 -7.894092) (xy 395.289278 -7.702441)
			(xy 395.227006 -7.50823) (xy 395.172312 -7.31175) (xy 395.125278 -7.113297) (xy 395.085975 -6.913169)
			(xy 395.05446 -6.711669) (xy 395.030783 -6.509097) (xy 395.014979 -6.30576) (xy 395.00707 -6.101963)
			(xy 395.006576 -5.999988) (xy 395.006576 -5.997956) (xy 395.006994 -5.904859) (xy 395.013603 -5.718781)
			(xy 395.026798 -5.533054) (xy 395.04656 -5.347911) (xy 395.072867 -5.163584) (xy 395.088872 -5.071872)
			(xy 395.08938 -5.06984) (xy 395.090142 -5.059934) (xy 395.090142 -5.057394) (xy 395.089888 -4.99999)
			(xy 395.090368 -4.900314) (xy 395.098044 -4.701111) (xy 395.113386 -4.502351) (xy 395.13637 -4.304329)
			(xy 395.166962 -4.10734) (xy 395.205117 -3.911674) (xy 395.250778 -3.717622) (xy 395.303877 -3.525473)
			(xy 395.364336 -3.335511) (xy 395.432065 -3.148018) (xy 395.506963 -2.963272) (xy 395.58892 -2.781547)
			(xy 395.677814 -2.603113) (xy 395.773513 -2.428234) (xy 395.875874 -2.257169) (xy 395.984747 -2.090174)
			(xy 396.09997 -1.927494) (xy 396.221371 -1.769372) (xy 396.284704 -1.692402) (xy 396.29461 -1.682496)
			(xy 396.300198 -1.651) (xy 396.254224 -1.55321) (xy 396.249765 -1.544675) (xy 396.235754 -1.531487)
			(xy 396.217871 -1.524385) (xy 396.20825 -1.524) (xy 394.264896 -1.524) (xy 394.233731 -1.52451) (xy 394.171934 -1.532646)
			(xy 394.111729 -1.548779) (xy 394.054143 -1.572631) (xy 394.000164 -1.603797) (xy 393.950715 -1.641741)
			(xy 393.906641 -1.685815) (xy 393.868697 -1.735264) (xy 393.837531 -1.789243) (xy 393.813679 -1.846829)
			(xy 393.797546 -1.907034) (xy 393.78941 -1.968831) (xy 393.7889 -1.999996) (xy 393.7889 -11.850116)
			(xy 393.788403 -11.920918) (xy 393.780462 -12.0623) (xy 393.764607 -12.203014) (xy 393.740886 -12.342618)
			(xy 393.709376 -12.480673) (xy 393.670174 -12.616743) (xy 393.623404 -12.750401) (xy 393.569214 -12.881226)
			(xy 393.507773 -13.008807) (xy 393.439276 -13.132743) (xy 393.363937 -13.252643) (xy 393.281994 -13.36813)
			(xy 393.193705 -13.478841) (xy 393.099346 -13.584427) (xy 392.999216 -13.684556) (xy 392.89363 -13.778914)
			(xy 392.782919 -13.867202) (xy 392.667431 -13.949145) (xy 392.547531 -14.024483) (xy 392.423595 -14.092979)
			(xy 392.296014 -14.154419) (xy 392.165188 -14.208609) (xy 392.031529 -14.255378) (xy 391.895459 -14.294579)
			(xy 391.757405 -14.326089) (xy 391.617801 -14.349809) (xy 391.477086 -14.365663) (xy 391.335704 -14.373603)
			(xy 391.264902 -14.374114) (xy 383.264918 -14.374114) (xy 383.194115 -14.373627) (xy 383.052731 -14.365688)
			(xy 382.912014 -14.349834) (xy 382.772408 -14.326115) (xy 382.634352 -14.294606) (xy 382.498279 -14.255405)
			(xy 382.364618 -14.208636) (xy 382.23379 -14.154446) (xy 382.106207 -14.093006) (xy 381.982269 -14.024509)
			(xy 381.862366 -13.949171) (xy 381.746877 -13.867228) (xy 381.636164 -13.778938) (xy 381.530575 -13.68458)
			(xy 381.430444 -13.584449) (xy 381.336084 -13.478862) (xy 381.247793 -13.36815) (xy 381.165848 -13.252662)
			(xy 381.090508 -13.13276) (xy 381.022009 -13.008823) (xy 380.960568 -12.881241) (xy 380.906376 -12.750413)
			(xy 380.859606 -12.616753) (xy 380.820403 -12.480681) (xy 380.788892 -12.342625) (xy 380.765171 -12.203019)
			(xy 380.749315 -12.062303) (xy 380.741374 -11.920919) (xy 380.74092 -11.850116) (xy 380.74092 -1.999996)
			(xy 380.74041 -1.968831) (xy 380.732274 -1.907033) (xy 380.716142 -1.846826) (xy 380.692289 -1.78924)
			(xy 380.661124 -1.735259) (xy 380.62318 -1.685808) (xy 380.579107 -1.641733) (xy 380.529657 -1.603787)
			(xy 380.475678 -1.57262) (xy 380.418093 -1.548765) (xy 380.357887 -1.53263) (xy 380.296089 -1.524491)
			(xy 380.264924 -1.524) (xy 368.264948 -1.524) (xy 368.233779 -1.524485) (xy 368.171975 -1.532616)
			(xy 368.11176 -1.548745) (xy 368.054167 -1.572595) (xy 368.000179 -1.60376) (xy 367.950721 -1.641706)
			(xy 367.90664 -1.685782) (xy 367.868689 -1.735236) (xy 367.837518 -1.78922) (xy 367.813661 -1.846811)
			(xy 367.797526 -1.907024) (xy 367.789388 -1.968827) (xy 367.788952 -1.999996) (xy 367.788952 -11.850116)
			(xy 367.788464 -11.920918) (xy 367.780523 -12.0623) (xy 367.764668 -12.203013) (xy 367.740947 -12.342617)
			(xy 367.709436 -12.48067) (xy 367.670234 -12.61674) (xy 367.623464 -12.750397) (xy 367.569273 -12.881222)
			(xy 367.507832 -13.008803) (xy 367.439334 -13.132737) (xy 367.363995 -13.252636) (xy 367.282051 -13.368122)
			(xy 367.193761 -13.478832) (xy 367.099402 -13.584417) (xy 366.999272 -13.684545) (xy 366.893684 -13.778901)
			(xy 366.782973 -13.867188) (xy 366.667485 -13.949129) (xy 366.547584 -14.024465) (xy 366.423647 -14.09296)
			(xy 366.296066 -14.154398) (xy 366.165239 -14.208586) (xy 366.031581 -14.255352) (xy 365.89551 -14.294551)
			(xy 365.757456 -14.326059) (xy 365.617852 -14.349776) (xy 365.477138 -14.365628) (xy 365.335756 -14.373566)
			(xy 365.264954 -14.374114) (xy 357.26497 -14.374114) (xy 357.194168 -14.373617) (xy 357.052786 -14.365675)
			(xy 356.912072 -14.349819) (xy 356.772469 -14.326098) (xy 356.634415 -14.294587) (xy 356.498345 -14.255384)
			(xy 356.364687 -14.208614) (xy 356.233862 -14.154424) (xy 356.106281 -14.092983) (xy 355.982346 -14.024485)
			(xy 355.862447 -13.949147) (xy 355.74696 -13.867204) (xy 355.636249 -13.778914) (xy 355.530663 -13.684556)
			(xy 355.430534 -13.584426) (xy 355.336177 -13.47884) (xy 355.247888 -13.368129) (xy 355.165946 -13.252642)
			(xy 355.090607 -13.132742) (xy 355.022111 -13.008806) (xy 354.960671 -12.881225) (xy 354.906481 -12.7504)
			(xy 354.859711 -12.616742) (xy 354.82051 -12.480672) (xy 354.788999 -12.342618) (xy 354.765279 -12.203014)
			(xy 354.749424 -12.0623) (xy 354.741483 -11.920918) (xy 354.740972 -11.850116) (xy 354.740972 -1.999996)
			(xy 354.740484 -1.96883) (xy 354.732347 -1.907032) (xy 354.716214 -1.846825) (xy 354.69236 -1.789239)
			(xy 354.661193 -1.735259) (xy 354.623246 -1.685809) (xy 354.57917 -1.641735) (xy 354.529718 -1.603792)
			(xy 354.475736 -1.572628) (xy 354.418149 -1.548777) (xy 354.35794 -1.532647) (xy 354.296142 -1.524514)
			(xy 354.264976 -1.524) (xy 330.164948 -1.524) (xy 330.133779 -1.524485) (xy 330.071975 -1.532616)
			(xy 330.01176 -1.548745) (xy 329.954167 -1.572595) (xy 329.900179 -1.60376) (xy 329.850721 -1.641706)
			(xy 329.80664 -1.685782) (xy 329.768689 -1.735236) (xy 329.737518 -1.78922) (xy 329.713661 -1.846811)
			(xy 329.697526 -1.907024) (xy 329.689388 -1.968827) (xy 329.688952 -1.999996) (xy 329.688952 -7.35711)
			(xy 329.689546 -7.368369) (xy 329.699157 -7.388732) (xy 329.716537 -7.403049) (xy 329.727306 -7.406386)
			(xy 329.728068 -7.406386) (xy 329.755361 -7.413587) (xy 329.807615 -7.434931) (xy 329.856153 -7.463741)
			(xy 329.899918 -7.499388) (xy 329.937953 -7.541094) (xy 329.969429 -7.587948) (xy 329.993658 -7.638928)
			(xy 330.010113 -7.692921) (xy 330.018433 -7.74875) (xy 330.018898 -7.776972) (xy 330.018353 -7.806696)
			(xy 330.009173 -7.86543) (xy 329.990985 -7.922026) (xy 329.964229 -7.975111) (xy 329.929555 -8.023398)
			(xy 329.887804 -8.065715) (xy 329.864212 -8.083804) (xy 329.85837 -8.08863) (xy 329.853544 -8.093456)
			(xy 329.850853 -8.096179) (xy 329.84626 -8.102303) (xy 329.8444 -8.105648) (xy 329.834748 -8.12419)
			(xy 329.832056 -8.129722) (xy 329.829106 -8.141663) (xy 329.828906 -8.147812) (xy 329.828906 -8.206232)
			(xy 329.829071 -8.212386) (xy 329.832015 -8.224338) (xy 329.834748 -8.229854) (xy 329.845416 -8.250174)
			(xy 329.848226 -8.255167) (xy 329.855659 -8.263885) (xy 329.860148 -8.267446) (xy 329.860656 -8.2677)
			(xy 329.86091 -8.267954) (xy 329.881527 -8.28339) (xy 329.918819 -8.318915) (xy 329.950994 -8.359133)
			(xy 329.977469 -8.403312) (xy 329.997762 -8.450649) (xy 330.011505 -8.500286) (xy 330.018448 -8.55132)
			(xy 330.018898 -8.577072) (xy 330.01839 -8.605305) (xy 330.010068 -8.661155) (xy 329.993604 -8.715167)
			(xy 329.969355 -8.766162) (xy 329.937853 -8.813024) (xy 329.899786 -8.85473) (xy 329.855987 -8.890367)
			(xy 329.807411 -8.919157) (xy 329.755122 -8.94047) (xy 329.727814 -8.947658) (xy 329.710542 -8.951976)
			(xy 329.688952 -8.979408) (xy 329.688952 -11.850116) (xy 329.688464 -11.920918) (xy 329.680523 -12.0623)
			(xy 329.664668 -12.203013) (xy 329.640947 -12.342617) (xy 329.609436 -12.48067) (xy 329.570234 -12.61674)
			(xy 329.523464 -12.750397) (xy 329.469273 -12.881222) (xy 329.407832 -13.008803) (xy 329.339334 -13.132737)
			(xy 329.263995 -13.252636) (xy 329.182051 -13.368122) (xy 329.093761 -13.478832) (xy 328.999402 -13.584417)
			(xy 328.899272 -13.684545) (xy 328.793684 -13.778901) (xy 328.682973 -13.867188) (xy 328.567485 -13.949129)
			(xy 328.447584 -14.024465) (xy 328.323647 -14.09296) (xy 328.196066 -14.154398) (xy 328.065239 -14.208586)
			(xy 327.931581 -14.255352) (xy 327.79551 -14.294551) (xy 327.657456 -14.326059) (xy 327.517852 -14.349776)
			(xy 327.377138 -14.365628) (xy 327.235756 -14.373566) (xy 327.164954 -14.374114) (xy 319.16497 -14.374114)
			(xy 319.094168 -14.373617) (xy 318.952786 -14.365675) (xy 318.812072 -14.349819) (xy 318.672469 -14.326098)
			(xy 318.534415 -14.294587) (xy 318.398345 -14.255384) (xy 318.264687 -14.208614) (xy 318.133862 -14.154424)
			(xy 318.006281 -14.092983) (xy 317.882346 -14.024485) (xy 317.762447 -13.949147) (xy 317.64696 -13.867204)
			(xy 317.536249 -13.778914) (xy 317.430663 -13.684556) (xy 317.330534 -13.584426) (xy 317.236177 -13.47884)
			(xy 317.147888 -13.368129) (xy 317.065946 -13.252642) (xy 316.990607 -13.132742) (xy 316.922111 -13.008806)
			(xy 316.860671 -12.881225) (xy 316.806481 -12.7504) (xy 316.759711 -12.616742) (xy 316.72051 -12.480672)
			(xy 316.688999 -12.342618) (xy 316.665279 -12.203014) (xy 316.649424 -12.0623) (xy 316.641483 -11.920918)
			(xy 316.640972 -11.850116) (xy 316.640972 -1.999996) (xy 316.640484 -1.96883) (xy 316.632347 -1.907032)
			(xy 316.616214 -1.846825) (xy 316.59236 -1.789239) (xy 316.561193 -1.735259) (xy 316.523246 -1.685809)
			(xy 316.47917 -1.641735) (xy 316.429718 -1.603792) (xy 316.375736 -1.572628) (xy 316.318149 -1.548777)
			(xy 316.25794 -1.532647) (xy 316.196142 -1.524514) (xy 316.164976 -1.524) (xy 304.165 -1.524) (xy 304.133835 -1.52451)
			(xy 304.072038 -1.532645) (xy 304.011832 -1.548778) (xy 303.954246 -1.57263) (xy 303.900266 -1.603795)
			(xy 303.850816 -1.641739) (xy 303.806742 -1.685813) (xy 303.768797 -1.735263) (xy 303.737632 -1.789242)
			(xy 303.713779 -1.846828) (xy 303.697646 -1.907034) (xy 303.68951 -1.968831) (xy 303.689004 -1.999996)
			(xy 303.689004 -11.850116) (xy 303.688507 -11.920918) (xy 303.680566 -12.0623) (xy 303.664711 -12.203015)
			(xy 303.64099 -12.342619) (xy 303.60948 -12.480673) (xy 303.570278 -12.616743) (xy 303.523508 -12.750401)
			(xy 303.469318 -12.881227) (xy 303.407877 -13.008808) (xy 303.33938 -13.132744) (xy 303.264041 -13.252644)
			(xy 303.182098 -13.368131) (xy 303.093809 -13.478842) (xy 302.999451 -13.584428) (xy 302.899321 -13.684558)
			(xy 302.793734 -13.778915) (xy 302.683023 -13.867204) (xy 302.567535 -13.949147) (xy 302.447635 -14.024485)
			(xy 302.323699 -14.092982) (xy 302.196118 -14.154422) (xy 302.065292 -14.208612) (xy 301.931634 -14.255381)
			(xy 301.795563 -14.294582) (xy 301.657509 -14.326092) (xy 301.517905 -14.349812) (xy 301.37719 -14.365667)
			(xy 301.235808 -14.373607) (xy 301.165006 -14.374114) (xy 293.165022 -14.374114) (xy 293.094219 -14.373627)
			(xy 292.952834 -14.365688) (xy 292.812118 -14.349835) (xy 292.672512 -14.326116) (xy 292.534455 -14.294606)
			(xy 292.398382 -14.255406) (xy 292.264721 -14.208637) (xy 292.133893 -14.154447) (xy 292.006309 -14.093008)
			(xy 291.882371 -14.024511) (xy 291.762469 -13.949172) (xy 291.646979 -13.867229) (xy 291.536266 -13.77894)
			(xy 291.430677 -13.684581) (xy 291.330545 -13.584451) (xy 291.236185 -13.478864) (xy 291.147894 -13.368151)
			(xy 291.065949 -13.252663) (xy 290.990609 -13.132762) (xy 290.92211 -13.008825) (xy 290.860668 -12.881242)
			(xy 290.806477 -12.750414) (xy 290.759706 -12.616754) (xy 290.720503 -12.480682) (xy 290.688992 -12.342626)
			(xy 290.665271 -12.20302) (xy 290.649415 -12.062303) (xy 290.641474 -11.920919) (xy 290.641024 -11.850116)
			(xy 290.641024 -1.999996) (xy 290.640514 -1.96883) (xy 290.632378 -1.907033) (xy 290.616246 -1.846826)
			(xy 290.592393 -1.789239) (xy 290.561228 -1.735258) (xy 290.523285 -1.685807) (xy 290.479211 -1.641731)
			(xy 290.429762 -1.603785) (xy 290.375783 -1.572617) (xy 290.318197 -1.548762) (xy 290.257991 -1.532627)
			(xy 290.196193 -1.524488) (xy 290.165028 -1.524) (xy 288.206688 -1.524) (xy 288.18205 -1.539748)
			(xy 288.1757 -1.55321) (xy 288.130234 -1.64973) (xy 288.134044 -1.67894) (xy 288.143442 -1.69037)
			(xy 288.206868 -1.76736) (xy 288.328446 -1.925536) (xy 288.443837 -2.088279) (xy 288.552871 -2.255349)
			(xy 288.655385 -2.426496) (xy 288.751228 -2.601467) (xy 288.840256 -2.780001) (xy 288.922337 -2.961834)
			(xy 288.99735 -3.146695) (xy 289.065183 -3.33431) (xy 289.125736 -3.5244) (xy 289.178917 -3.716681)
			(xy 289.224649 -3.91087) (xy 289.262864 -4.106677) (xy 289.293503 -4.30381) (xy 289.316523 -4.501979)
			(xy 289.331889 -4.700887) (xy 289.339578 -4.90024) (xy 289.340036 -4.99999) (xy 289.339782 -5.057394)
			(xy 289.339782 -5.059934) (xy 289.340544 -5.06984) (xy 289.341052 -5.071872) (xy 289.357058 -5.16361)
			(xy 289.383365 -5.347988) (xy 289.403129 -5.533182) (xy 289.416324 -5.718959) (xy 289.422935 -5.905087)
			(xy 289.423348 -5.99821) (xy 289.423348 -5.999988) (xy 289.422854 -6.101963) (xy 289.414945 -6.30576)
			(xy 289.399141 -6.509097) (xy 289.375464 -6.711669) (xy 289.343949 -6.913169) (xy 289.304646 -7.113297)
			(xy 289.257612 -7.31175) (xy 289.202918 -7.50823) (xy 289.140646 -7.702441) (xy 289.070891 -7.894092)
			(xy 288.993757 -8.082893) (xy 288.90936 -8.268562) (xy 288.817828 -8.450819) (xy 288.719297 -8.629389)
			(xy 288.613916 -8.804005) (xy 288.501843 -8.974403) (xy 288.383247 -9.140327) (xy 288.258307 -9.301528)
			(xy 288.127211 -9.457763) (xy 287.990154 -9.608797) (xy 287.847345 -9.754403) (xy 287.698997 -9.894363)
			(xy 287.545333 -10.028464) (xy 287.386585 -10.156507) (xy 287.222992 -10.278298) (xy 287.054799 -10.393653)
			(xy 286.88226 -10.502401) (xy 286.705634 -10.604376) (xy 286.525186 -10.699426) (xy 286.341189 -10.787407)
			(xy 286.153918 -10.868188) (xy 285.963656 -10.941646) (xy 285.770689 -11.007672) (xy 285.575307 -11.066165)
			(xy 285.377803 -11.117039) (xy 285.178476 -11.160216) (xy 284.977624 -11.195631) (xy 284.77555 -11.223232)
			(xy 284.572557 -11.242977) (xy 284.368952 -11.254836) (xy 284.16504 -11.258791) (xy 283.961128 -11.254836)
			(xy 283.757523 -11.242977) (xy 283.55453 -11.223232) (xy 283.352456 -11.195631) (xy 283.151604 -11.160216)
			(xy 282.952277 -11.117039) (xy 282.754773 -11.066165) (xy 282.559391 -11.007672) (xy 282.366424 -10.941646)
			(xy 282.176162 -10.868188) (xy 281.988891 -10.787407) (xy 281.804894 -10.699426) (xy 281.624446 -10.604376)
			(xy 281.44782 -10.502401) (xy 281.275281 -10.393653) (xy 281.107088 -10.278298) (xy 280.943495 -10.156507)
			(xy 280.784747 -10.028464) (xy 280.631083 -9.894363) (xy 280.482735 -9.754403) (xy 280.339926 -9.608797)
			(xy 280.202869 -9.457763) (xy 280.071773 -9.301528) (xy 279.946833 -9.140327) (xy 279.828237 -8.974403)
			(xy 279.716164 -8.804005) (xy 279.610783 -8.629389) (xy 279.512252 -8.450819) (xy 279.42072 -8.268562)
			(xy 279.336323 -8.082893) (xy 279.259189 -7.894092) (xy 279.189434 -7.702441) (xy 279.127162 -7.50823)
			(xy 279.072468 -7.31175) (xy 279.025434 -7.113297) (xy 278.986131 -6.913169) (xy 278.954616 -6.711669)
			(xy 278.930939 -6.509097) (xy 278.915135 -6.30576) (xy 278.907226 -6.101963) (xy 278.906732 -5.999988)
			(xy 278.906732 -5.997956) (xy 278.90715 -5.904859) (xy 278.913759 -5.718781) (xy 278.926954 -5.533054)
			(xy 278.946717 -5.347911) (xy 278.973024 -5.163584) (xy 278.989028 -5.071872) (xy 278.989536 -5.06984)
			(xy 278.990298 -5.059934) (xy 278.990298 -5.057394) (xy 278.990044 -4.99999) (xy 278.990523 -4.900314)
			(xy 278.9982 -4.701111) (xy 279.013542 -4.502351) (xy 279.036526 -4.304329) (xy 279.067117 -4.107339)
			(xy 279.105272 -3.911673) (xy 279.150932 -3.717621) (xy 279.204031 -3.525472) (xy 279.26449 -3.335509)
			(xy 279.332218 -3.148016) (xy 279.407116 -2.96327) (xy 279.489073 -2.781544) (xy 279.577966 -2.60311)
			(xy 279.673664 -2.42823) (xy 279.776025 -2.257165) (xy 279.884897 -2.090169) (xy 280.000119 -1.927489)
			(xy 280.12152 -1.769366) (xy 280.18486 -1.692402) (xy 280.194766 -1.682496) (xy 280.200354 -1.651)
			(xy 280.15438 -1.55321) (xy 280.149919 -1.54468) (xy 280.135905 -1.531504) (xy 280.118023 -1.524417)
			(xy 280.108406 -1.524) (xy 278.165052 -1.524) (xy 278.133889 -1.524513) (xy 278.072097 -1.532654)
			(xy 278.011895 -1.54879) (xy 277.954315 -1.572645) (xy 277.900341 -1.603812) (xy 277.850897 -1.641756)
			(xy 277.806827 -1.68583) (xy 277.768887 -1.735278) (xy 277.737726 -1.789255) (xy 277.713876 -1.846837)
			(xy 277.697745 -1.90704) (xy 277.68961 -1.968833) (xy 277.689056 -1.999996) (xy 277.689056 -11.850116)
			(xy 277.688568 -11.920918) (xy 277.680627 -12.0623) (xy 277.664772 -12.203013) (xy 277.641051 -12.342617)
			(xy 277.60954 -12.480671) (xy 277.570338 -12.61674) (xy 277.523568 -12.750398) (xy 277.469377 -12.881223)
			(xy 277.407936 -13.008803) (xy 277.339438 -13.132738) (xy 277.264099 -13.252637) (xy 277.182155 -13.368123)
			(xy 277.093865 -13.478833) (xy 276.999506 -13.584418) (xy 276.899376 -13.684546) (xy 276.793789 -13.778903)
			(xy 276.683077 -13.86719) (xy 276.567589 -13.949131) (xy 276.447688 -14.024467) (xy 276.323752 -14.092962)
			(xy 276.19617 -14.154401) (xy 276.065344 -14.208588) (xy 275.931685 -14.255355) (xy 275.795614 -14.294554)
			(xy 275.65756 -14.326062) (xy 275.517956 -14.34978) (xy 275.377242 -14.365632) (xy 275.23586 -14.37357)
			(xy 275.165058 -14.374114) (xy 267.165074 -14.374114) (xy 267.094272 -14.373617) (xy 266.95289 -14.365676)
			(xy 266.812176 -14.34982) (xy 266.672572 -14.326099) (xy 266.534518 -14.294588) (xy 266.398448 -14.255385)
			(xy 266.26479 -14.208615) (xy 266.133965 -14.154425) (xy 266.006384 -14.092984) (xy 265.882448 -14.024487)
			(xy 265.762549 -13.949148) (xy 265.647062 -13.867205) (xy 265.536351 -13.778916) (xy 265.430765 -13.684558)
			(xy 265.330635 -13.584428) (xy 265.236278 -13.478841) (xy 265.147989 -13.36813) (xy 265.066046 -13.252643)
			(xy 264.990708 -13.132743) (xy 264.922211 -13.008807) (xy 264.860771 -12.881226) (xy 264.806581 -12.750401)
			(xy 264.759812 -12.616743) (xy 264.72061 -12.480672) (xy 264.689099 -12.342618) (xy 264.665379 -12.203014)
			(xy 264.649524 -12.0623) (xy 264.641583 -11.920918) (xy 264.641076 -11.850116) (xy 264.641076 -1.999996)
			(xy 264.640588 -1.96883) (xy 264.632451 -1.907032) (xy 264.616318 -1.846824) (xy 264.592464 -1.789238)
			(xy 264.561297 -1.735258) (xy 264.523351 -1.685808) (xy 264.479274 -1.641734) (xy 264.429822 -1.60379)
			(xy 264.375841 -1.572626) (xy 264.318253 -1.548774) (xy 264.258045 -1.532644) (xy 264.196246 -1.52451)
			(xy 264.16508 -1.524) (xy 252.165104 -1.524) (xy 252.133939 -1.524509) (xy 252.072141 -1.532645)
			(xy 252.011935 -1.548777) (xy 251.954348 -1.572629) (xy 251.900368 -1.603794) (xy 251.850918 -1.641738)
			(xy 251.806843 -1.685812) (xy 251.768898 -1.735262) (xy 251.737732 -1.789241) (xy 251.713879 -1.846827)
			(xy 251.697746 -1.907033) (xy 251.68961 -1.968831) (xy 251.689108 -1.999996) (xy 251.689108 -11.850116)
			(xy 251.688611 -11.920918) (xy 251.68067 -12.0623) (xy 251.664815 -12.203015) (xy 251.641094 -12.342619)
			(xy 251.609584 -12.480673) (xy 251.570382 -12.616744) (xy 251.523612 -12.750402) (xy 251.469422 -12.881228)
			(xy 251.407981 -13.008809) (xy 251.339484 -13.132745) (xy 251.264145 -13.252645) (xy 251.182202 -13.368132)
			(xy 251.093913 -13.478843) (xy 250.999555 -13.584429) (xy 250.899425 -13.684559) (xy 250.793838 -13.778917)
			(xy 250.683127 -13.867206) (xy 250.56764 -13.949149) (xy 250.44774 -14.024487) (xy 250.323804 -14.092984)
			(xy 250.196222 -14.154424) (xy 250.065396 -14.208614) (xy 249.931738 -14.255384) (xy 249.795667 -14.294585)
			(xy 249.657613 -14.326096) (xy 249.518009 -14.349816) (xy 249.377295 -14.365671) (xy 249.235912 -14.373611)
			(xy 249.16511 -14.374114) (xy 241.164872 -14.374114) (xy 241.094072 -14.373631) (xy 240.952696 -14.365701)
			(xy 240.811986 -14.349856) (xy 240.672386 -14.326146) (xy 240.534335 -14.294646) (xy 240.398268 -14.255455)
			(xy 240.264612 -14.208696) (xy 240.133788 -14.154516) (xy 240.006208 -14.093085) (xy 239.882274 -14.024598)
			(xy 239.762374 -13.949269) (xy 239.646888 -13.867336) (xy 239.536176 -13.779056) (xy 239.43059 -13.684707)
			(xy 239.330459 -13.584586) (xy 239.2361 -13.479009) (xy 239.14781 -13.368306) (xy 239.065865 -13.252827)
			(xy 238.990525 -13.132935) (xy 238.922026 -13.009007) (xy 238.860583 -12.881433) (xy 238.806391 -12.750614)
			(xy 238.759619 -12.616963) (xy 238.720414 -12.480899) (xy 238.688901 -12.342851) (xy 238.665178 -12.203254)
			(xy 238.649319 -12.062546) (xy 238.641376 -11.92117) (xy 238.640874 -11.85037) (xy 238.640874 -1.999996)
			(xy 238.640386 -1.96883) (xy 238.632249 -1.907032) (xy 238.616116 -1.846825) (xy 238.592262 -1.789238)
			(xy 238.561095 -1.735258) (xy 238.523148 -1.685808) (xy 238.479072 -1.641734) (xy 238.42962 -1.603791)
			(xy 238.375638 -1.572627) (xy 238.318051 -1.548776) (xy 238.257842 -1.532646) (xy 238.196044 -1.524512)
			(xy 238.164878 -1.524) (xy 230.171752 -1.524) (xy 230.162128 -1.524403) (xy 230.144228 -1.531479)
			(xy 230.130196 -1.544653) (xy 230.125778 -1.55321) (xy 230.080312 -1.64973) (xy 230.084122 -1.67894)
			(xy 230.09352 -1.69037) (xy 230.156947 -1.76736) (xy 230.278525 -1.925535) (xy 230.393916 -2.088278)
			(xy 230.502951 -2.255348) (xy 230.605465 -2.426495) (xy 230.701308 -2.601466) (xy 230.790336 -2.780001)
			(xy 230.872418 -2.961833) (xy 230.947432 -3.146695) (xy 231.015265 -3.334309) (xy 231.075818 -3.524399)
			(xy 231.129 -3.716681) (xy 231.174732 -3.910869) (xy 231.212946 -4.106676) (xy 231.243586 -4.30381)
			(xy 231.266606 -4.501978) (xy 231.281972 -4.700887) (xy 231.289661 -4.90024) (xy 231.290114 -4.99999)
			(xy 231.28986 -5.057394) (xy 231.28986 -5.059934) (xy 231.290622 -5.06857) (xy 231.290876 -5.070856)
			(xy 231.29113 -5.072634) (xy 231.291384 -5.073396) (xy 231.307392 -5.165159) (xy 231.333704 -5.349588)
			(xy 231.353469 -5.534833) (xy 231.366663 -5.720661) (xy 231.37327 -5.90684) (xy 231.37368 -5.999988)
			(xy 231.373186 -6.101968) (xy 231.365277 -6.305775) (xy 231.349472 -6.509122) (xy 231.325793 -6.711703)
			(xy 231.294278 -6.913214) (xy 231.254972 -7.113351) (xy 231.207936 -7.311813) (xy 231.153239 -7.508302)
			(xy 231.090965 -7.702523) (xy 231.021206 -7.894183) (xy 230.944068 -8.082994) (xy 230.859667 -8.268672)
			(xy 230.76813 -8.450937) (xy 230.669595 -8.629516) (xy 230.564208 -8.80414) (xy 230.45213 -8.974547)
			(xy 230.333529 -9.140479) (xy 230.208583 -9.301687) (xy 230.07748 -9.45793) (xy 229.940417 -9.608972)
			(xy 229.797601 -9.754585) (xy 229.649245 -9.894551) (xy 229.495574 -10.028659) (xy 229.336819 -10.156708)
			(xy 229.173218 -10.278504) (xy 229.005017 -10.393866) (xy 228.832469 -10.502618) (xy 228.655834 -10.604598)
			(xy 228.475378 -10.699653) (xy 228.291372 -10.787638) (xy 228.104092 -10.868423) (xy 227.913821 -10.941885)
			(xy 227.720845 -11.007913) (xy 227.525453 -11.06641) (xy 227.32794 -11.117286) (xy 227.128603 -11.160465)
			(xy 226.927741 -11.195882) (xy 226.725657 -11.223485) (xy 226.522655 -11.24323) (xy 226.31904 -11.255089)
			(xy 226.115118 -11.259045) (xy 225.911196 -11.255089) (xy 225.707581 -11.24323) (xy 225.504579 -11.223485)
			(xy 225.302495 -11.195882) (xy 225.101633 -11.160465) (xy 224.902296 -11.117286) (xy 224.704783 -11.06641)
			(xy 224.509391 -11.007913) (xy 224.316415 -10.941885) (xy 224.126144 -10.868423) (xy 223.938864 -10.787638)
			(xy 223.754858 -10.699653) (xy 223.574402 -10.604598) (xy 223.397767 -10.502618) (xy 223.225219 -10.393866)
			(xy 223.057018 -10.278504) (xy 222.893417 -10.156708) (xy 222.734662 -10.028659) (xy 222.580991 -9.894551)
			(xy 222.432635 -9.754585) (xy 222.289819 -9.608972) (xy 222.152756 -9.45793) (xy 222.021653 -9.301687)
			(xy 221.896707 -9.140479) (xy 221.778106 -8.974547) (xy 221.666028 -8.80414) (xy 221.560641 -8.629516)
			(xy 221.462106 -8.450937) (xy 221.370569 -8.268672) (xy 221.286168 -8.082994) (xy 221.20903 -7.894183)
			(xy 221.139271 -7.702523) (xy 221.076997 -7.508302) (xy 221.0223 -7.311813) (xy 220.975264 -7.113351)
			(xy 220.935958 -6.913214) (xy 220.904443 -6.711703) (xy 220.880764 -6.509122) (xy 220.864959 -6.305775)
			(xy 220.85705 -6.101968) (xy 220.856556 -5.999988) (xy 220.856966 -5.90684) (xy 220.863564 -5.72066)
			(xy 220.876754 -5.534831) (xy 220.896521 -5.349587) (xy 220.92284 -5.165159) (xy 220.938852 -5.073396)
			(xy 220.939106 -5.072634) (xy 220.93936 -5.070856) (xy 220.939614 -5.06857) (xy 220.940376 -5.059934)
			(xy 220.940376 -5.057394) (xy 220.940122 -4.99999) (xy 220.940601 -4.900314) (xy 220.948278 -4.701111)
			(xy 220.96362 -4.502351) (xy 220.986603 -4.304329) (xy 221.017195 -4.107339) (xy 221.055349 -3.911673)
			(xy 221.10101 -3.717621) (xy 221.154109 -3.525471) (xy 221.214567 -3.335509) (xy 221.282295 -3.148015)
			(xy 221.357193 -2.963268) (xy 221.439149 -2.781543) (xy 221.528042 -2.603108) (xy 221.62374 -2.428228)
			(xy 221.7261 -2.257163) (xy 221.834972 -2.090167) (xy 221.950194 -1.927486) (xy 222.071594 -1.769363)
			(xy 222.134938 -1.692402) (xy 222.144844 -1.682496) (xy 222.150432 -1.651) (xy 222.104458 -1.55321)
			(xy 222.099996 -1.544682) (xy 222.085981 -1.531512) (xy 222.0681 -1.524433) (xy 222.058484 -1.524)
			(xy 214.065104 -1.524) (xy 214.033939 -1.524509) (xy 213.972141 -1.532645) (xy 213.911935 -1.548777)
			(xy 213.854348 -1.572629) (xy 213.800368 -1.603794) (xy 213.750918 -1.641738) (xy 213.706843 -1.685812)
			(xy 213.668898 -1.735262) (xy 213.637732 -1.789241) (xy 213.613879 -1.846827) (xy 213.597746 -1.907033)
			(xy 213.58961 -1.968831) (xy 213.589108 -1.999996) (xy 213.589108 -11.850116) (xy 213.588611 -11.920918)
			(xy 213.58067 -12.0623) (xy 213.564815 -12.203015) (xy 213.541094 -12.342619) (xy 213.509584 -12.480673)
			(xy 213.470382 -12.616744) (xy 213.423612 -12.750402) (xy 213.369422 -12.881228) (xy 213.307981 -13.008809)
			(xy 213.239484 -13.132745) (xy 213.164145 -13.252645) (xy 213.082202 -13.368132) (xy 212.993913 -13.478843)
			(xy 212.899555 -13.584429) (xy 212.799425 -13.684559) (xy 212.693838 -13.778917) (xy 212.583127 -13.867206)
			(xy 212.46764 -13.949149) (xy 212.34774 -14.024487) (xy 212.223804 -14.092984) (xy 212.096222 -14.154424)
			(xy 211.965396 -14.208614) (xy 211.831738 -14.255384) (xy 211.695667 -14.294585) (xy 211.557613 -14.326096)
			(xy 211.418009 -14.349816) (xy 211.277295 -14.365671) (xy 211.135912 -14.373611) (xy 211.06511 -14.374114)
			(xy 203.064872 -14.374114) (xy 202.994072 -14.373631) (xy 202.852696 -14.365701) (xy 202.711986 -14.349856)
			(xy 202.572386 -14.326146) (xy 202.434335 -14.294646) (xy 202.298268 -14.255455) (xy 202.164612 -14.208696)
			(xy 202.033788 -14.154516) (xy 201.906208 -14.093085) (xy 201.782274 -14.024598) (xy 201.662374 -13.949269)
			(xy 201.546888 -13.867336) (xy 201.436176 -13.779056) (xy 201.33059 -13.684707) (xy 201.230459 -13.584586)
			(xy 201.1361 -13.479009) (xy 201.04781 -13.368306) (xy 200.965865 -13.252827) (xy 200.890525 -13.132935)
			(xy 200.822026 -13.009007) (xy 200.760583 -12.881433) (xy 200.706391 -12.750614) (xy 200.659619 -12.616963)
			(xy 200.620414 -12.480899) (xy 200.588901 -12.342851) (xy 200.565178 -12.203254) (xy 200.549319 -12.062546)
			(xy 200.541376 -11.92117) (xy 200.540874 -11.85037) (xy 200.540874 -1.999996) (xy 200.540386 -1.96883)
			(xy 200.532249 -1.907032) (xy 200.516116 -1.846825) (xy 200.492262 -1.789238) (xy 200.461095 -1.735258)
			(xy 200.423148 -1.685808) (xy 200.379072 -1.641734) (xy 200.32962 -1.603791) (xy 200.275638 -1.572627)
			(xy 200.218051 -1.548776) (xy 200.157842 -1.532646) (xy 200.096044 -1.524512) (xy 200.064878 -1.524)
			(xy 188.064902 -1.524) (xy 188.033737 -1.52451) (xy 187.97194 -1.532645) (xy 187.911733 -1.548777)
			(xy 187.854147 -1.57263) (xy 187.800167 -1.603794) (xy 187.750717 -1.641739) (xy 187.706642 -1.685812)
			(xy 187.668698 -1.735262) (xy 187.637532 -1.789242) (xy 187.613679 -1.846827) (xy 187.597546 -1.907034)
			(xy 187.58941 -1.968831) (xy 187.588906 -1.999996) (xy 187.588906 -11.850116) (xy 187.588409 -11.920918)
			(xy 187.580468 -12.0623) (xy 187.564613 -12.203015) (xy 187.540892 -12.342619) (xy 187.509382 -12.480673)
			(xy 187.47018 -12.616743) (xy 187.42341 -12.750402) (xy 187.36922 -12.881227) (xy 187.307779 -13.008809)
			(xy 187.239282 -13.132744) (xy 187.163943 -13.252644) (xy 187.082 -13.368131) (xy 186.993711 -13.478842)
			(xy 186.899353 -13.584429) (xy 186.799223 -13.684558) (xy 186.693636 -13.778916) (xy 186.582925 -13.867205)
			(xy 186.467438 -13.949148) (xy 186.347537 -14.024486) (xy 186.223601 -14.092983) (xy 186.09602 -14.154423)
			(xy 185.965194 -14.208613) (xy 185.831536 -14.255382) (xy 185.695465 -14.294584) (xy 185.557411 -14.326094)
			(xy 185.417807 -14.349814) (xy 185.277092 -14.365669) (xy 185.13571 -14.373609) (xy 185.064908 -14.374114)
			(xy 177.064924 -14.374114) (xy 176.994121 -14.373627) (xy 176.852736 -14.365688) (xy 176.71202 -14.349835)
			(xy 176.572413 -14.326116) (xy 176.434356 -14.294607) (xy 176.298284 -14.255406) (xy 176.164623 -14.208638)
			(xy 176.033794 -14.154448) (xy 175.906211 -14.093008) (xy 175.782272 -14.024511) (xy 175.66237 -13.949173)
			(xy 175.54688 -13.86723) (xy 175.436166 -13.77894) (xy 175.330578 -13.684582) (xy 175.230445 -13.584452)
			(xy 175.136085 -13.478864) (xy 175.047794 -13.368152) (xy 174.965849 -13.252664) (xy 174.890509 -13.132762)
			(xy 174.82201 -13.008825) (xy 174.760568 -12.881242) (xy 174.706377 -12.750415) (xy 174.659606 -12.616755)
			(xy 174.620403 -12.480682) (xy 174.588892 -12.342626) (xy 174.565171 -12.20302) (xy 174.549315 -12.062304)
			(xy 174.541374 -11.920919) (xy 174.540926 -11.850116) (xy 174.540926 -1.999996) (xy 174.540416 -1.96883)
			(xy 174.53228 -1.907033) (xy 174.516148 -1.846825) (xy 174.492295 -1.789239) (xy 174.46113 -1.735258)
			(xy 174.423187 -1.685806) (xy 174.379113 -1.64173) (xy 174.329664 -1.603784) (xy 174.275685 -1.572616)
			(xy 174.218099 -1.548761) (xy 174.157893 -1.532625) (xy 174.096096 -1.524486) (xy 174.06493 -1.524)
			(xy 172.121576 -1.524) (xy 172.11196 -1.524416) (xy 172.094082 -1.531508) (xy 172.080072 -1.544685)
			(xy 172.075602 -1.55321) (xy 172.030136 -1.64973) (xy 172.033946 -1.67894) (xy 172.043344 -1.69037)
			(xy 172.10677 -1.76736) (xy 172.228348 -1.925536) (xy 172.343739 -2.088279) (xy 172.452773 -2.255349)
			(xy 172.555287 -2.426496) (xy 172.651129 -2.601467) (xy 172.740157 -2.780001) (xy 172.822239 -2.961834)
			(xy 172.897252 -3.146696) (xy 172.965085 -3.33431) (xy 173.025637 -3.5244) (xy 173.078819 -3.716681)
			(xy 173.124551 -3.91087) (xy 173.162765 -4.106677) (xy 173.193405 -4.30381) (xy 173.216425 -4.501979)
			(xy 173.231791 -4.700887) (xy 173.239479 -4.90024) (xy 173.239938 -4.99999) (xy 173.239938 -5.00507)
			(xy 173.239684 -5.05587) (xy 173.239684 -5.05841) (xy 173.240446 -5.067046) (xy 173.2407 -5.069332)
			(xy 173.240954 -5.07111) (xy 173.241208 -5.071872) (xy 173.25721 -5.163585) (xy 173.283512 -5.347912)
			(xy 173.303274 -5.533055) (xy 173.316471 -5.718782) (xy 173.323087 -5.904859) (xy 173.323504 -5.997956)
			(xy 173.323504 -5.999988) (xy 173.32301 -6.101963) (xy 173.315101 -6.30576) (xy 173.299297 -6.509097)
			(xy 173.27562 -6.711669) (xy 173.244105 -6.913169) (xy 173.204802 -7.113297) (xy 173.157768 -7.31175)
			(xy 173.103074 -7.50823) (xy 173.040802 -7.702441) (xy 172.971047 -7.894092) (xy 172.893913 -8.082893)
			(xy 172.809516 -8.268562) (xy 172.717984 -8.450819) (xy 172.619453 -8.629389) (xy 172.514072 -8.804005)
			(xy 172.401999 -8.974403) (xy 172.283403 -9.140327) (xy 172.158463 -9.301528) (xy 172.027367 -9.457763)
			(xy 171.89031 -9.608797) (xy 171.747501 -9.754403) (xy 171.599153 -9.894363) (xy 171.445489 -10.028464)
			(xy 171.286741 -10.156507) (xy 171.123148 -10.278298) (xy 170.954955 -10.393653) (xy 170.782416 -10.502401)
			(xy 170.60579 -10.604376) (xy 170.425342 -10.699426) (xy 170.241345 -10.787407) (xy 170.054074 -10.868188)
			(xy 169.863812 -10.941646) (xy 169.670845 -11.007672) (xy 169.475463 -11.066165) (xy 169.277959 -11.117039)
			(xy 169.078632 -11.160216) (xy 168.87778 -11.195631) (xy 168.675706 -11.223232) (xy 168.472713 -11.242977)
			(xy 168.269108 -11.254836) (xy 168.065196 -11.258791) (xy 167.861284 -11.254836) (xy 167.657679 -11.242977)
			(xy 167.454686 -11.223232) (xy 167.252612 -11.195631) (xy 167.05176 -11.160216) (xy 166.852433 -11.117039)
			(xy 166.654929 -11.066165) (xy 166.459547 -11.007672) (xy 166.26658 -10.941646) (xy 166.076318 -10.868188)
			(xy 165.889047 -10.787407) (xy 165.70505 -10.699426) (xy 165.524602 -10.604376) (xy 165.347976 -10.502401)
			(xy 165.175437 -10.393653) (xy 165.007244 -10.278298) (xy 164.843651 -10.156507) (xy 164.684903 -10.028464)
			(xy 164.531239 -9.894363) (xy 164.382891 -9.754403) (xy 164.240082 -9.608797) (xy 164.103025 -9.457763)
			(xy 163.971929 -9.301528) (xy 163.846989 -9.140327) (xy 163.728393 -8.974403) (xy 163.61632 -8.804005)
			(xy 163.510939 -8.629389) (xy 163.412408 -8.450819) (xy 163.320876 -8.268562) (xy 163.236479 -8.082893)
			(xy 163.159345 -7.894092) (xy 163.08959 -7.702441) (xy 163.027318 -7.50823) (xy 162.972624 -7.31175)
			(xy 162.92559 -7.113297) (xy 162.886287 -6.913169) (xy 162.854772 -6.711669) (xy 162.831095 -6.509097)
			(xy 162.815291 -6.30576) (xy 162.807382 -6.101963) (xy 162.806888 -5.999988) (xy 162.806888 -5.997956)
			(xy 162.807305 -5.904988) (xy 162.813895 -5.719169) (xy 162.827049 -5.533698) (xy 162.846749 -5.348809)
			(xy 162.872971 -5.164731) (xy 162.88893 -5.073142) (xy 162.889438 -5.07111) (xy 162.8902 -5.061204)
			(xy 162.8902 -5.058664) (xy 162.889946 -4.99999) (xy 162.890425 -4.900314) (xy 162.898102 -4.701111)
			(xy 162.913444 -4.502351) (xy 162.936428 -4.304329) (xy 162.967019 -4.107339) (xy 163.005174 -3.911673)
			(xy 163.050834 -3.717621) (xy 163.103933 -3.525472) (xy 163.164392 -3.335509) (xy 163.232121 -3.148016)
			(xy 163.307018 -2.96327) (xy 163.388975 -2.781544) (xy 163.477868 -2.60311) (xy 163.573566 -2.42823)
			(xy 163.675927 -2.257166) (xy 163.784799 -2.090169) (xy 163.900021 -1.927489) (xy 164.021422 -1.769366)
			(xy 164.084762 -1.692402) (xy 164.094668 -1.682496) (xy 164.100256 -1.651) (xy 164.054282 -1.55321)
			(xy 164.047932 -1.539748) (xy 164.023294 -1.524) (xy 162.064954 -1.524) (xy 162.033791 -1.524513)
			(xy 161.971998 -1.532653) (xy 161.911797 -1.548789) (xy 161.854217 -1.572645) (xy 161.800242 -1.603811)
			(xy 161.750797 -1.641756) (xy 161.706728 -1.685829) (xy 161.668788 -1.735277) (xy 161.637626 -1.789254)
			(xy 161.613776 -1.846837) (xy 161.597645 -1.90704) (xy 161.58951 -1.968833) (xy 161.588958 -1.999996)
			(xy 161.588958 -11.850116) (xy 161.58847 -11.920918) (xy 161.580529 -12.0623) (xy 161.564674 -12.203014)
			(xy 161.540953 -12.342617) (xy 161.509442 -12.480671) (xy 161.47024 -12.616741) (xy 161.42347 -12.750398)
			(xy 161.369279 -12.881223) (xy 161.307838 -13.008804) (xy 161.23934 -13.132738) (xy 161.164001 -13.252638)
			(xy 161.082057 -13.368124) (xy 160.993767 -13.478834) (xy 160.899409 -13.584419) (xy 160.799278 -13.684547)
			(xy 160.693691 -13.778903) (xy 160.582979 -13.867191) (xy 160.467491 -13.949132) (xy 160.34759 -14.024468)
			(xy 160.223654 -14.092964) (xy 160.096072 -14.154402) (xy 159.965246 -14.20859) (xy 159.831587 -14.255357)
			(xy 159.695517 -14.294556) (xy 159.557462 -14.326064) (xy 159.417858 -14.349781) (xy 159.277144 -14.365634)
			(xy 159.135762 -14.373572) (xy 159.06496 -14.374114) (xy 151.064976 -14.374114) (xy 150.994174 -14.373617)
			(xy 150.852792 -14.365676) (xy 150.712078 -14.34982) (xy 150.572474 -14.326099) (xy 150.43442 -14.294588)
			(xy 150.298349 -14.255386) (xy 150.164691 -14.208616) (xy 150.033866 -14.154426) (xy 149.906285 -14.092985)
			(xy 149.782349 -14.024487) (xy 149.66245 -13.949149) (xy 149.546963 -13.867206) (xy 149.436252 -13.778916)
			(xy 149.330666 -13.684558) (xy 149.230536 -13.584429) (xy 149.136178 -13.478842) (xy 149.047889 -13.368131)
			(xy 148.965947 -13.252644) (xy 148.890608 -13.132744) (xy 148.822111 -13.008808) (xy 148.760671 -12.881227)
			(xy 148.706481 -12.750401) (xy 148.659712 -12.616743) (xy 148.62051 -12.480673) (xy 148.588999 -12.342618)
			(xy 148.565279 -12.203014) (xy 148.549424 -12.0623) (xy 148.541483 -11.920918) (xy 148.540978 -11.850116)
			(xy 148.540978 -1.999996) (xy 148.54049 -1.96883) (xy 148.532353 -1.907032) (xy 148.51622 -1.846824)
			(xy 148.492366 -1.789238) (xy 148.461199 -1.735257) (xy 148.423253 -1.685807) (xy 148.379176 -1.641733)
			(xy 148.329724 -1.603789) (xy 148.275743 -1.572625) (xy 148.218155 -1.548773) (xy 148.157947 -1.532642)
			(xy 148.096148 -1.524509) (xy 148.064982 -1.524) (xy 136.065006 -1.524) (xy 136.033839 -1.524487)
			(xy 135.972039 -1.532623) (xy 135.911829 -1.548755) (xy 135.85424 -1.572609) (xy 135.800257 -1.603775)
			(xy 135.750804 -1.641721) (xy 135.706727 -1.685797) (xy 135.66878 -1.735249) (xy 135.637613 -1.789231)
			(xy 135.613758 -1.846819) (xy 135.597625 -1.907029) (xy 135.589488 -1.968829) (xy 135.58901 -1.999996)
			(xy 135.58901 -11.850116) (xy 135.588513 -11.920918) (xy 135.580572 -12.062301) (xy 135.564717 -12.203015)
			(xy 135.540996 -12.342619) (xy 135.509486 -12.480673) (xy 135.470284 -12.616744) (xy 135.423514 -12.750402)
			(xy 135.369324 -12.881228) (xy 135.307883 -13.008809) (xy 135.239386 -13.132745) (xy 135.164047 -13.252645)
			(xy 135.082104 -13.368133) (xy 134.993815 -13.478844) (xy 134.899457 -13.58443) (xy 134.799327 -13.68456)
			(xy 134.69374 -13.778918) (xy 134.583029 -13.867207) (xy 134.467542 -13.94915) (xy 134.347642 -14.024488)
			(xy 134.223706 -14.092985) (xy 134.096124 -14.154425) (xy 133.965299 -14.208616) (xy 133.83164 -14.255385)
			(xy 133.69557 -14.294587) (xy 133.557515 -14.326097) (xy 133.417911 -14.349817) (xy 133.277197 -14.365673)
			(xy 133.135814 -14.373613) (xy 133.065012 -14.374114) (xy 125.065028 -14.374114) (xy 124.994224 -14.373627)
			(xy 124.85284 -14.365689) (xy 124.712123 -14.349835) (xy 124.572517 -14.326117) (xy 124.43446 -14.294608)
			(xy 124.298387 -14.255407) (xy 124.164726 -14.208639) (xy 124.033897 -14.154449) (xy 123.906313 -14.09301)
			(xy 123.782374 -14.024513) (xy 123.662472 -13.949174) (xy 123.546982 -13.867231) (xy 123.436268 -13.778942)
			(xy 123.330679 -13.684583) (xy 123.230547 -13.584453) (xy 123.136187 -13.478866) (xy 123.047895 -13.368153)
			(xy 122.96595 -13.252665) (xy 122.89061 -13.132763) (xy 122.822111 -13.008826) (xy 122.760669 -12.881243)
			(xy 122.706477 -12.750416) (xy 122.659706 -12.616755) (xy 122.620503 -12.480683) (xy 122.588992 -12.342626)
			(xy 122.565271 -12.20302) (xy 122.549415 -12.062304) (xy 122.541474 -11.92092) (xy 122.54103 -11.850116)
			(xy 122.54103 -1.999996) (xy 122.54052 -1.96883) (xy 122.532384 -1.907032) (xy 122.516252 -1.846825)
			(xy 122.492399 -1.789238) (xy 122.461235 -1.735257) (xy 122.423291 -1.685805) (xy 122.379217 -1.641729)
			(xy 122.329768 -1.603782) (xy 122.275789 -1.572614) (xy 122.218204 -1.548758) (xy 122.157997 -1.532622)
			(xy 122.0962 -1.524482) (xy 122.065034 -1.524) (xy 97.965006 -1.524) (xy 97.933839 -1.524487) (xy 97.872039 -1.532623)
			(xy 97.811829 -1.548755) (xy 97.75424 -1.572609) (xy 97.700257 -1.603775) (xy 97.650804 -1.641721)
			(xy 97.606727 -1.685797) (xy 97.56878 -1.735249) (xy 97.537613 -1.789231) (xy 97.513758 -1.846819)
			(xy 97.497625 -1.907029) (xy 97.489488 -1.968829) (xy 97.48901 -1.999996) (xy 97.48901 -7.35711)
			(xy 97.489603 -7.368371) (xy 97.499211 -7.388742) (xy 97.516587 -7.403071) (xy 97.527364 -7.406386)
			(xy 97.528126 -7.406386) (xy 97.555421 -7.413584) (xy 97.60768 -7.434925) (xy 97.656224 -7.463733)
			(xy 97.699993 -7.499378) (xy 97.738033 -7.541084) (xy 97.769512 -7.587939) (xy 97.793745 -7.638921)
			(xy 97.810201 -7.692917) (xy 97.818523 -7.748748) (xy 97.818956 -7.776972) (xy 97.818411 -7.806695)
			(xy 97.809231 -7.865428) (xy 97.791041 -7.922023) (xy 97.764283 -7.975106) (xy 97.729606 -8.02339)
			(xy 97.687853 -8.065704) (xy 97.66427 -8.083804) (xy 97.658428 -8.08863) (xy 97.653602 -8.093456)
			(xy 97.650909 -8.096177) (xy 97.646311 -8.102298) (xy 97.644458 -8.105648) (xy 97.634806 -8.12419)
			(xy 97.632111 -8.129721) (xy 97.629158 -8.141662) (xy 97.628964 -8.147812) (xy 97.628964 -8.212328)
			(xy 97.632012 -8.224266) (xy 97.634806 -8.229854) (xy 97.645474 -8.250174) (xy 97.648287 -8.255165)
			(xy 97.655724 -8.263876) (xy 97.660206 -8.267446) (xy 97.660714 -8.2677) (xy 97.660968 -8.267954)
			(xy 97.681587 -8.283389) (xy 97.718882 -8.318912) (xy 97.751061 -8.359129) (xy 97.777539 -8.403308)
			(xy 97.797835 -8.450646) (xy 97.811579 -8.500284) (xy 97.818523 -8.551319) (xy 97.818956 -8.577072)
			(xy 97.818448 -8.605304) (xy 97.810126 -8.661152) (xy 97.79366 -8.715163) (xy 97.769411 -8.766155)
			(xy 97.737908 -8.813014) (xy 97.69984 -8.854716) (xy 97.656038 -8.890349) (xy 97.607462 -8.919134)
			(xy 97.555172 -8.940442) (xy 97.527872 -8.947658) (xy 97.5106 -8.951976) (xy 97.48901 -8.979408)
			(xy 97.48901 -11.850116) (xy 97.488513 -11.920918) (xy 97.480572 -12.062301) (xy 97.464717 -12.203015)
			(xy 97.440996 -12.342619) (xy 97.409486 -12.480673) (xy 97.370284 -12.616744) (xy 97.323514 -12.750402)
			(xy 97.269324 -12.881228) (xy 97.207883 -13.008809) (xy 97.139386 -13.132745) (xy 97.064047 -13.252645)
			(xy 96.982104 -13.368133) (xy 96.893815 -13.478844) (xy 96.799457 -13.58443) (xy 96.699327 -13.68456)
			(xy 96.59374 -13.778918) (xy 96.483029 -13.867207) (xy 96.367542 -13.94915) (xy 96.247642 -14.024488)
			(xy 96.123706 -14.092985) (xy 95.996124 -14.154425) (xy 95.865299 -14.208616) (xy 95.73164 -14.255385)
			(xy 95.59557 -14.294587) (xy 95.457515 -14.326097) (xy 95.317911 -14.349817) (xy 95.177197 -14.365673)
			(xy 95.035814 -14.373613) (xy 94.965012 -14.374114) (xy 86.965028 -14.374114) (xy 86.894224 -14.373627)
			(xy 86.75284 -14.365689) (xy 86.612123 -14.349835) (xy 86.472517 -14.326117) (xy 86.33446 -14.294608)
			(xy 86.198387 -14.255407) (xy 86.064726 -14.208639) (xy 85.933897 -14.154449) (xy 85.806313 -14.09301)
			(xy 85.682374 -14.024513) (xy 85.562472 -13.949174) (xy 85.446982 -13.867231) (xy 85.336268 -13.778942)
			(xy 85.230679 -13.684583) (xy 85.130547 -13.584453) (xy 85.036187 -13.478866) (xy 84.947895 -13.368153)
			(xy 84.86595 -13.252665) (xy 84.79061 -13.132763) (xy 84.722111 -13.008826) (xy 84.660669 -12.881243)
			(xy 84.606477 -12.750416) (xy 84.559706 -12.616755) (xy 84.520503 -12.480683) (xy 84.488992 -12.342626)
			(xy 84.465271 -12.20302) (xy 84.449415 -12.062304) (xy 84.441474 -11.92092) (xy 84.44103 -11.850116)
			(xy 84.44103 -1.999996) (xy 84.44052 -1.96883) (xy 84.432384 -1.907032) (xy 84.416252 -1.846825)
			(xy 84.392399 -1.789238) (xy 84.361235 -1.735257) (xy 84.323291 -1.685805) (xy 84.279217 -1.641729)
			(xy 84.229768 -1.603782) (xy 84.175789 -1.572614) (xy 84.118204 -1.548758) (xy 84.057997 -1.532622)
			(xy 83.9962 -1.524482) (xy 83.965034 -1.524) (xy 71.965058 -1.524) (xy 71.933895 -1.524512) (xy 71.872102 -1.532653)
			(xy 71.8119 -1.548788) (xy 71.754319 -1.572643) (xy 71.700344 -1.60381) (xy 71.650899 -1.641754)
			(xy 71.606829 -1.685828) (xy 71.568889 -1.735276) (xy 71.537727 -1.789253) (xy 71.513876 -1.846836)
			(xy 71.497745 -1.907039) (xy 71.48961 -1.968833) (xy 71.489062 -1.999996) (xy 71.489062 -11.850116)
			(xy 71.488574 -11.920918) (xy 71.480633 -12.0623) (xy 71.464778 -12.203014) (xy 71.441057 -12.342617)
			(xy 71.409546 -12.480671) (xy 71.370344 -12.616741) (xy 71.323574 -12.750399) (xy 71.269383 -12.881224)
			(xy 71.207942 -13.008804) (xy 71.139444 -13.132739) (xy 71.064105 -13.252639) (xy 70.982161 -13.368125)
			(xy 70.893871 -13.478835) (xy 70.799513 -13.58442) (xy 70.699382 -13.684548) (xy 70.593795 -13.778905)
			(xy 70.483083 -13.867193) (xy 70.367595 -13.949134) (xy 70.247695 -14.024471) (xy 70.123758 -14.092966)
			(xy 69.996176 -14.154404) (xy 69.86535 -14.208592) (xy 69.731692 -14.25536) (xy 69.595621 -14.294559)
			(xy 69.457566 -14.326067) (xy 69.317962 -14.349785) (xy 69.177248 -14.365638) (xy 69.035866 -14.373575)
			(xy 68.965064 -14.374114) (xy 60.96508 -14.374114) (xy 60.894278 -14.373617) (xy 60.752896 -14.365676)
			(xy 60.612181 -14.34982) (xy 60.472577 -14.3261) (xy 60.334523 -14.294589) (xy 60.198453 -14.255387)
			(xy 60.064794 -14.208617) (xy 59.933969 -14.154427) (xy 59.806387 -14.092986) (xy 59.682452 -14.024489)
			(xy 59.562552 -13.94915) (xy 59.447065 -13.867207) (xy 59.336354 -13.778918) (xy 59.230767 -13.68456)
			(xy 59.130637 -13.58443) (xy 59.03628 -13.478843) (xy 58.94799 -13.368132) (xy 58.866048 -13.252645)
			(xy 58.790709 -13.132745) (xy 58.722212 -13.008809) (xy 58.660772 -12.881228) (xy 58.606581 -12.750402)
			(xy 58.559812 -12.616744) (xy 58.52061 -12.480673) (xy 58.4891 -12.342619) (xy 58.465379 -12.203015)
			(xy 58.449524 -12.0623) (xy 58.441583 -11.920918) (xy 58.441082 -11.850116) (xy 58.441082 -1.999996)
			(xy 58.440594 -1.96883) (xy 58.432457 -1.907031) (xy 58.416324 -1.846824) (xy 58.39247 -1.789237)
			(xy 58.361303 -1.735256) (xy 58.323357 -1.685806) (xy 58.279281 -1.641731) (xy 58.229829 -1.603787)
			(xy 58.175847 -1.572622) (xy 58.118259 -1.54877) (xy 58.058051 -1.532639) (xy 57.996252 -1.524505)
			(xy 57.965086 -1.524) (xy 45.96511 -1.524) (xy 45.933943 -1.524487) (xy 45.872142 -1.532622) (xy 45.811932 -1.548754)
			(xy 45.754342 -1.572607) (xy 45.700359 -1.603773) (xy 45.650906 -1.641719) (xy 45.606828 -1.685795)
			(xy 45.568881 -1.735248) (xy 45.537714 -1.78923) (xy 45.513859 -1.846819) (xy 45.497725 -1.907028)
			(xy 45.489588 -1.968829) (xy 45.489114 -1.999996) (xy 45.489114 -11.850116) (xy 45.488617 -11.920918)
			(xy 45.480676 -12.062301) (xy 45.464821 -12.203015) (xy 45.4411 -12.342619) (xy 45.40959 -12.480674)
			(xy 45.370388 -12.616744) (xy 45.323618 -12.750403) (xy 45.269428 -12.881229) (xy 45.207987 -13.00881)
			(xy 45.13949 -13.132746) (xy 45.064152 -13.252646) (xy 44.982209 -13.368134) (xy 44.893919 -13.478845)
			(xy 44.799561 -13.584431) (xy 44.699431 -13.684561) (xy 44.593845 -13.778919) (xy 44.483134 -13.867209)
			(xy 44.367646 -13.949152) (xy 44.247746 -14.02449) (xy 44.12381 -14.092987) (xy 43.996229 -14.154428)
			(xy 43.865403 -14.208618) (xy 43.731744 -14.255388) (xy 43.595674 -14.29459) (xy 43.457619 -14.3261)
			(xy 43.318015 -14.349821) (xy 43.177301 -14.365676) (xy 43.035918 -14.373617) (xy 42.965116 -14.374114)
			(xy 34.964878 -14.374114) (xy 34.894076 -14.373617) (xy 34.752694 -14.365676) (xy 34.611979 -14.34982)
			(xy 34.472376 -14.326099) (xy 34.334321 -14.294588) (xy 34.198251 -14.255386) (xy 34.064593 -14.208617)
			(xy 33.933767 -14.154426) (xy 33.806186 -14.092986) (xy 33.682251 -14.024488) (xy 33.562351 -13.949149)
			(xy 33.446864 -13.867207) (xy 33.336153 -13.778917) (xy 33.230566 -13.684559) (xy 33.130437 -13.584429)
			(xy 33.036079 -13.478843) (xy 32.94779 -13.368132) (xy 32.865847 -13.252644) (xy 32.790509 -13.132744)
			(xy 32.722012 -13.008809) (xy 32.660571 -12.881227) (xy 32.606381 -12.750402) (xy 32.559612 -12.616743)
			(xy 32.52041 -12.480673) (xy 32.488899 -12.342619) (xy 32.465179 -12.203015) (xy 32.449324 -12.0623)
			(xy 32.441383 -11.920918) (xy 32.44088 -11.850116) (xy 32.44088 -1.999996) (xy 32.440392 -1.96883)
			(xy 32.432255 -1.907032) (xy 32.416122 -1.846824) (xy 32.392268 -1.789237) (xy 32.361101 -1.735257)
			(xy 32.323155 -1.685806) (xy 32.279079 -1.641732) (xy 32.229627 -1.603788) (xy 32.175645 -1.572623)
			(xy 32.118057 -1.548772) (xy 32.057849 -1.532641) (xy 31.99605 -1.524507) (xy 31.964884 -1.524) (xy 19.964908 -1.524)
			(xy 19.933741 -1.524487) (xy 19.87194 -1.532622) (xy 19.81173 -1.548755) (xy 19.754141 -1.572608)
			(xy 19.700158 -1.603774) (xy 19.650705 -1.64172) (xy 19.606628 -1.685796) (xy 19.568681 -1.735248)
			(xy 19.537513 -1.78923) (xy 19.513659 -1.846819) (xy 19.497525 -1.907029) (xy 19.489388 -1.968829)
			(xy 19.488912 -1.999996) (xy 19.488912 -11.850116) (xy 19.488416 -11.920919) (xy 19.480476 -12.062301)
			(xy 19.464621 -12.203017) (xy 19.440902 -12.342621) (xy 19.409392 -12.480676) (xy 19.370191 -12.616748)
			(xy 19.323421 -12.750407) (xy 19.269232 -12.881233) (xy 19.207792 -13.008815) (xy 19.139294 -13.132752)
			(xy 19.063956 -13.252653) (xy 18.982013 -13.368141) (xy 18.893724 -13.478853) (xy 18.799366 -13.58444)
			(xy 18.699236 -13.68457) (xy 18.593649 -13.778929) (xy 18.482937 -13.867218) (xy 18.36745 -13.949162)
			(xy 18.247549 -14.0245) (xy 18.123613 -14.092998) (xy 17.996031 -14.154438) (xy 17.865204 -14.208629)
			(xy 17.731545 -14.255398) (xy 17.595474 -14.2946) (xy 17.457419 -14.32611) (xy 17.317814 -14.34983)
			(xy 17.177099 -14.365685) (xy 17.035717 -14.373625) (xy 16.964914 -14.374114) (xy 8.96493 -14.374114)
			(xy 8.894127 -14.373626) (xy 8.752744 -14.365687) (xy 8.612029 -14.349832) (xy 8.472424 -14.326112)
			(xy 8.334369 -14.294602) (xy 8.198297 -14.2554) (xy 8.064638 -14.208631) (xy 7.933812 -14.15444)
			(xy 7.806229 -14.093) (xy 7.682293 -14.024503) (xy 7.562392 -13.949164) (xy 7.446904 -13.867221)
			(xy 7.336192 -13.778931) (xy 7.230605 -13.684572) (xy 7.130475 -13.584442) (xy 7.036117 -13.478855)
			(xy 6.947827 -13.368143) (xy 6.865884 -13.252655) (xy 6.790545 -13.132754) (xy 6.722048 -13.008817)
			(xy 6.660608 -12.881235) (xy 6.606418 -12.750408) (xy 6.559649 -12.616749) (xy 6.520447 -12.480677)
			(xy 6.488937 -12.342622) (xy 6.465218 -12.203017) (xy 6.449363 -12.062302) (xy 6.441423 -11.920919)
			(xy 6.440932 -11.850116) (xy 6.440932 -1.999996) (xy 6.440422 -1.96883) (xy 6.432286 -1.907032) (xy 6.416154 -1.846825)
			(xy 6.392301 -1.789238) (xy 6.361137 -1.735256) (xy 6.323193 -1.685804) (xy 6.27912 -1.641728) (xy 6.22967 -1.603781)
			(xy 6.175691 -1.572613) (xy 6.118106 -1.548756) (xy 6.057899 -1.53262) (xy 5.996102 -1.52448) (xy 5.964936 -1.524)
			(xy 1.999996 -1.524) (xy 1.968831 -1.52451) (xy 1.907034 -1.532646) (xy 1.846829 -1.548779) (xy 1.789243 -1.572631)
			(xy 1.735264 -1.603797) (xy 1.685815 -1.641741) (xy 1.641741 -1.685815) (xy 1.603797 -1.735264) (xy 1.572631 -1.789243)
			(xy 1.548779 -1.846829) (xy 1.532646 -1.907034) (xy 1.52451 -1.968831) (xy 1.524 -1.999996) (xy 1.524 -16.969994)
			(xy 13.748519 -16.969994) (xy 13.752523 -16.882109) (xy 13.764503 -16.794952) (xy 13.784358 -16.709245)
			(xy 13.811925 -16.6257) (xy 13.846975 -16.545007) (xy 13.889217 -16.467835) (xy 13.938302 -16.394825)
			(xy 13.993823 -16.326581) (xy 14.05532 -16.263668) (xy 14.122282 -16.206608) (xy 14.194156 -16.155874)
			(xy 14.270346 -16.111886) (xy 14.35022 -16.075008) (xy 14.433117 -16.045547) (xy 14.518349 -16.023745)
			(xy 14.605211 -16.009785) (xy 14.692982 -16.003781) (xy 14.780936 -16.005784) (xy 14.868343 -16.015776)
			(xy 14.954479 -16.033676) (xy 15.038631 -16.059334) (xy 15.120101 -16.092538) (xy 15.198214 -16.133012)
			(xy 15.272322 -16.180423) (xy 15.341813 -16.234376) (xy 15.406109 -16.294424) (xy 15.464678 -16.360071)
			(xy 15.517035 -16.430771) (xy 15.562747 -16.50594) (xy 15.601433 -16.584954) (xy 15.632774 -16.667159)
			(xy 15.656509 -16.751873) (xy 15.672443 -16.838394) (xy 15.680443 -16.926006) (xy 15.680944 -16.969994)
			(xy 15.680443 -17.013982) (xy 15.672443 -17.101594) (xy 15.656509 -17.188115) (xy 15.632774 -17.272829)
			(xy 15.601433 -17.355034) (xy 15.562747 -17.434048) (xy 15.517035 -17.509217) (xy 15.464678 -17.579917)
			(xy 15.406109 -17.645564) (xy 15.341813 -17.705612) (xy 15.272322 -17.759565) (xy 15.198214 -17.806976)
			(xy 15.120101 -17.84745) (xy 15.038631 -17.880654) (xy 14.954479 -17.906312) (xy 14.868343 -17.924212)
			(xy 14.780936 -17.934204) (xy 14.692982 -17.936207) (xy 14.605211 -17.930203) (xy 14.518349 -17.916243)
			(xy 14.433117 -17.894441) (xy 14.35022 -17.86498) (xy 14.270346 -17.828102) (xy 14.194156 -17.784114)
			(xy 14.122282 -17.73338) (xy 14.05532 -17.67632) (xy 13.993823 -17.613407) (xy 13.938302 -17.545163)
			(xy 13.889217 -17.472153) (xy 13.846975 -17.394981) (xy 13.811925 -17.314288) (xy 13.784358 -17.230743)
			(xy 13.764503 -17.145036) (xy 13.752523 -17.057879) (xy 13.748519 -16.969994) (xy 1.524 -16.969994)
			(xy 1.524 -17.999964) (xy 20.705834 -17.999964) (xy 20.709838 -17.794776) (xy 20.721845 -17.5899)
			(xy 20.741836 -17.385649) (xy 20.769781 -17.182334) (xy 20.805637 -16.980263) (xy 20.849351 -16.779745)
			(xy 20.900854 -16.581086) (xy 20.960069 -16.384587) (xy 21.026905 -16.190548) (xy 21.101261 -15.999265)
			(xy 21.183024 -15.811028) (xy 21.272069 -15.626125) (xy 21.36826 -15.444837) (xy 21.471451 -15.26744)
			(xy 21.581485 -15.094203) (xy 21.698194 -14.925392) (xy 21.8214 -14.761263) (xy 21.950917 -14.602066)
			(xy 22.086546 -14.448044) (xy 22.228081 -14.29943) (xy 22.375306 -14.156452) (xy 22.527998 -14.019327)
			(xy 22.685924 -13.888263) (xy 22.848843 -13.763461) (xy 23.016508 -13.645111) (xy 23.188662 -13.533392)
			(xy 23.365044 -13.428475) (xy 23.545385 -13.33052) (xy 23.729411 -13.239676) (xy 23.916841 -13.15608)
			(xy 24.10739 -13.079861) (xy 24.300767 -13.011135) (xy 24.496679 -12.950006) (xy 24.694826 -12.896567)
			(xy 24.894908 -12.8509) (xy 25.096619 -12.813073) (xy 25.299652 -12.783146) (xy 25.503699 -12.761163)
			(xy 25.708448 -12.747158) (xy 25.913587 -12.741152) (xy 26.118804 -12.743154) (xy 26.323787 -12.753162)
			(xy 26.528224 -12.771159) (xy 26.731802 -12.797119) (xy 26.934213 -12.831002) (xy 27.135147 -12.872757)
			(xy 27.3343 -12.92232) (xy 27.531367 -12.979615) (xy 27.726049 -13.044555) (xy 27.918049 -13.117041)
			(xy 28.107074 -13.196964) (xy 28.292837 -13.2842) (xy 28.475055 -13.378618) (xy 28.653451 -13.480073)
			(xy 28.827752 -13.588412) (xy 28.997694 -13.703468) (xy 29.163017 -13.825068) (xy 29.32347 -13.953025)
			(xy 29.478809 -14.087144) (xy 29.628796 -14.227223) (xy 29.773204 -14.373047) (xy 29.911812 -14.524393)
			(xy 30.04441 -14.681033) (xy 30.170796 -14.842727) (xy 30.290776 -15.009229) (xy 30.404169 -15.180285)
			(xy 30.510802 -15.355635) (xy 30.610512 -15.535012) (xy 30.703148 -15.718142) (xy 30.788568 -15.904748)
			(xy 30.866642 -16.094544) (xy 30.937252 -16.287242) (xy 31.000289 -16.482548) (xy 31.055659 -16.680164)
			(xy 31.103276 -16.879791) (xy 31.121104 -16.969994) (xy 39.748467 -16.969994) (xy 39.752471 -16.882109)
			(xy 39.764451 -16.794952) (xy 39.784306 -16.709245) (xy 39.811873 -16.6257) (xy 39.846923 -16.545007)
			(xy 39.889165 -16.467835) (xy 39.93825 -16.394825) (xy 39.993771 -16.326581) (xy 40.055268 -16.263668)
			(xy 40.12223 -16.206608) (xy 40.194104 -16.155874) (xy 40.270294 -16.111886) (xy 40.350168 -16.075008)
			(xy 40.433065 -16.045547) (xy 40.518297 -16.023745) (xy 40.605159 -16.009785) (xy 40.69293 -16.003781)
			(xy 40.780884 -16.005784) (xy 40.868291 -16.015776) (xy 40.954427 -16.033676) (xy 41.038579 -16.059334)
			(xy 41.120049 -16.092538) (xy 41.198162 -16.133012) (xy 41.27227 -16.180423) (xy 41.341761 -16.234376)
			(xy 41.406057 -16.294424) (xy 41.464626 -16.360071) (xy 41.516983 -16.430771) (xy 41.562695 -16.50594)
			(xy 41.601381 -16.584954) (xy 41.632722 -16.667159) (xy 41.656457 -16.751873) (xy 41.672391 -16.838394)
			(xy 41.680391 -16.926006) (xy 41.680892 -16.969994) (xy 65.748415 -16.969994) (xy 65.752419 -16.882109)
			(xy 65.764399 -16.794952) (xy 65.784254 -16.709245) (xy 65.811821 -16.6257) (xy 65.846871 -16.545007)
			(xy 65.889113 -16.467835) (xy 65.938198 -16.394825) (xy 65.993719 -16.326581) (xy 66.055216 -16.263668)
			(xy 66.122178 -16.206608) (xy 66.194052 -16.155874) (xy 66.270242 -16.111886) (xy 66.350116 -16.075008)
			(xy 66.433013 -16.045547) (xy 66.518245 -16.023745) (xy 66.605107 -16.009785) (xy 66.692878 -16.003781)
			(xy 66.780832 -16.005784) (xy 66.868239 -16.015776) (xy 66.954375 -16.033676) (xy 67.038527 -16.059334)
			(xy 67.119997 -16.092538) (xy 67.19811 -16.133012) (xy 67.272218 -16.180423) (xy 67.341709 -16.234376)
			(xy 67.406005 -16.294424) (xy 67.464574 -16.360071) (xy 67.516931 -16.430771) (xy 67.562643 -16.50594)
			(xy 67.601329 -16.584954) (xy 67.63267 -16.667159) (xy 67.656405 -16.751873) (xy 67.672339 -16.838394)
			(xy 67.680339 -16.926006) (xy 67.68084 -16.969994) (xy 91.748363 -16.969994) (xy 91.752367 -16.882109)
			(xy 91.764347 -16.794952) (xy 91.784202 -16.709245) (xy 91.811769 -16.6257) (xy 91.846819 -16.545007)
			(xy 91.889061 -16.467835) (xy 91.938146 -16.394825) (xy 91.993667 -16.326581) (xy 92.055164 -16.263668)
			(xy 92.122126 -16.206608) (xy 92.194 -16.155874) (xy 92.27019 -16.111886) (xy 92.350064 -16.075008)
			(xy 92.432961 -16.045547) (xy 92.518193 -16.023745) (xy 92.605055 -16.009785) (xy 92.692826 -16.003781)
			(xy 92.78078 -16.005784) (xy 92.868187 -16.015776) (xy 92.954323 -16.033676) (xy 93.038475 -16.059334)
			(xy 93.119945 -16.092538) (xy 93.198058 -16.133012) (xy 93.272166 -16.180423) (xy 93.341657 -16.234376)
			(xy 93.405953 -16.294424) (xy 93.464522 -16.360071) (xy 93.516879 -16.430771) (xy 93.562591 -16.50594)
			(xy 93.601277 -16.584954) (xy 93.632618 -16.667159) (xy 93.656353 -16.751873) (xy 93.672287 -16.838394)
			(xy 93.680287 -16.926006) (xy 93.680788 -16.969994) (xy 93.680287 -17.013982) (xy 93.672287 -17.101594)
			(xy 93.656353 -17.188115) (xy 93.632618 -17.272829) (xy 93.601277 -17.355034) (xy 93.562591 -17.434048)
			(xy 93.516879 -17.509217) (xy 93.464522 -17.579917) (xy 93.405953 -17.645564) (xy 93.341657 -17.705612)
			(xy 93.272166 -17.759565) (xy 93.198058 -17.806976) (xy 93.119945 -17.84745) (xy 93.038475 -17.880654)
			(xy 92.954323 -17.906312) (xy 92.868187 -17.924212) (xy 92.78078 -17.934204) (xy 92.692826 -17.936207)
			(xy 92.605055 -17.930203) (xy 92.518193 -17.916243) (xy 92.432961 -17.894441) (xy 92.350064 -17.86498)
			(xy 92.27019 -17.828102) (xy 92.194 -17.784114) (xy 92.122126 -17.73338) (xy 92.055164 -17.67632)
			(xy 91.993667 -17.613407) (xy 91.938146 -17.545163) (xy 91.889061 -17.472153) (xy 91.846819 -17.394981)
			(xy 91.811769 -17.314288) (xy 91.784202 -17.230743) (xy 91.764347 -17.145036) (xy 91.752367 -17.057879)
			(xy 91.748363 -16.969994) (xy 67.68084 -16.969994) (xy 67.680339 -17.013982) (xy 67.672339 -17.101594)
			(xy 67.656405 -17.188115) (xy 67.63267 -17.272829) (xy 67.601329 -17.355034) (xy 67.562643 -17.434048)
			(xy 67.516931 -17.509217) (xy 67.464574 -17.579917) (xy 67.406005 -17.645564) (xy 67.341709 -17.705612)
			(xy 67.272218 -17.759565) (xy 67.19811 -17.806976) (xy 67.119997 -17.84745) (xy 67.038527 -17.880654)
			(xy 66.954375 -17.906312) (xy 66.868239 -17.924212) (xy 66.780832 -17.934204) (xy 66.692878 -17.936207)
			(xy 66.605107 -17.930203) (xy 66.518245 -17.916243) (xy 66.433013 -17.894441) (xy 66.350116 -17.86498)
			(xy 66.270242 -17.828102) (xy 66.194052 -17.784114) (xy 66.122178 -17.73338) (xy 66.055216 -17.67632)
			(xy 65.993719 -17.613407) (xy 65.938198 -17.545163) (xy 65.889113 -17.472153) (xy 65.846871 -17.394981)
			(xy 65.811821 -17.314288) (xy 65.784254 -17.230743) (xy 65.764399 -17.145036) (xy 65.752419 -17.057879)
			(xy 65.748415 -16.969994) (xy 41.680892 -16.969994) (xy 41.680391 -17.013982) (xy 41.672391 -17.101594)
			(xy 41.656457 -17.188115) (xy 41.632722 -17.272829) (xy 41.601381 -17.355034) (xy 41.562695 -17.434048)
			(xy 41.516983 -17.509217) (xy 41.464626 -17.579917) (xy 41.406057 -17.645564) (xy 41.341761 -17.705612)
			(xy 41.27227 -17.759565) (xy 41.198162 -17.806976) (xy 41.120049 -17.84745) (xy 41.038579 -17.880654)
			(xy 40.954427 -17.906312) (xy 40.868291 -17.924212) (xy 40.780884 -17.934204) (xy 40.69293 -17.936207)
			(xy 40.605159 -17.930203) (xy 40.518297 -17.916243) (xy 40.433065 -17.894441) (xy 40.350168 -17.86498)
			(xy 40.270294 -17.828102) (xy 40.194104 -17.784114) (xy 40.12223 -17.73338) (xy 40.055268 -17.67632)
			(xy 39.993771 -17.613407) (xy 39.93825 -17.545163) (xy 39.889165 -17.472153) (xy 39.846923 -17.394981)
			(xy 39.811873 -17.314288) (xy 39.784306 -17.230743) (xy 39.764451 -17.145036) (xy 39.752471 -17.057879)
			(xy 39.748467 -16.969994) (xy 31.121104 -16.969994) (xy 31.143068 -17.081123) (xy 31.174975 -17.283855)
			(xy 31.198948 -17.487677) (xy 31.21495 -17.69228) (xy 31.222957 -17.89735) (xy 31.223458 -17.999964)
			(xy 104.755958 -17.999964) (xy 104.759962 -17.794776) (xy 104.771969 -17.5899) (xy 104.79196 -17.385649)
			(xy 104.819905 -17.182334) (xy 104.855761 -16.980263) (xy 104.899475 -16.779745) (xy 104.950978 -16.581086)
			(xy 105.010193 -16.384587) (xy 105.077029 -16.190548) (xy 105.151385 -15.999265) (xy 105.233148 -15.811028)
			(xy 105.322193 -15.626125) (xy 105.418384 -15.444837) (xy 105.521575 -15.26744) (xy 105.631609 -15.094203)
			(xy 105.748318 -14.925392) (xy 105.871524 -14.761263) (xy 106.001041 -14.602066) (xy 106.13667 -14.448044)
			(xy 106.278205 -14.29943) (xy 106.42543 -14.156452) (xy 106.578122 -14.019327) (xy 106.736048 -13.888263)
			(xy 106.898967 -13.763461) (xy 107.066632 -13.645111) (xy 107.238786 -13.533392) (xy 107.415168 -13.428475)
			(xy 107.595509 -13.33052) (xy 107.779535 -13.239676) (xy 107.966965 -13.15608) (xy 108.157514 -13.079861)
			(xy 108.350891 -13.011135) (xy 108.546803 -12.950006) (xy 108.74495 -12.896567) (xy 108.945032 -12.8509)
			(xy 109.146743 -12.813073) (xy 109.349776 -12.783146) (xy 109.553823 -12.761163) (xy 109.758572 -12.747158)
			(xy 109.963711 -12.741152) (xy 110.168928 -12.743154) (xy 110.373911 -12.753162) (xy 110.578348 -12.771159)
			(xy 110.781926 -12.797119) (xy 110.984337 -12.831002) (xy 111.185271 -12.872757) (xy 111.384424 -12.92232)
			(xy 111.581491 -12.979615) (xy 111.776173 -13.044555) (xy 111.968173 -13.117041) (xy 112.157198 -13.196964)
			(xy 112.342961 -13.2842) (xy 112.525179 -13.378618) (xy 112.703575 -13.480073) (xy 112.877876 -13.588412)
			(xy 113.047818 -13.703468) (xy 113.213141 -13.825068) (xy 113.373594 -13.953025) (xy 113.528933 -14.087144)
			(xy 113.67892 -14.227223) (xy 113.823328 -14.373047) (xy 113.961936 -14.524393) (xy 114.094534 -14.681033)
			(xy 114.22092 -14.842727) (xy 114.3409 -15.009229) (xy 114.454293 -15.180285) (xy 114.560926 -15.355635)
			(xy 114.660636 -15.535012) (xy 114.753272 -15.718142) (xy 114.838692 -15.904748) (xy 114.916766 -16.094544)
			(xy 114.987376 -16.287242) (xy 115.050413 -16.482548) (xy 115.105783 -16.680164) (xy 115.1534 -16.879791)
			(xy 115.171228 -16.969994) (xy 129.848617 -16.969994) (xy 129.852621 -16.882109) (xy 129.864601 -16.794952)
			(xy 129.884456 -16.709245) (xy 129.912023 -16.6257) (xy 129.947073 -16.545007) (xy 129.989315 -16.467835)
			(xy 130.0384 -16.394825) (xy 130.093921 -16.326581) (xy 130.155418 -16.263668) (xy 130.22238 -16.206608)
			(xy 130.294254 -16.155874) (xy 130.370444 -16.111886) (xy 130.450318 -16.075008) (xy 130.533215 -16.045547)
			(xy 130.618447 -16.023745) (xy 130.705309 -16.009785) (xy 130.79308 -16.003781) (xy 130.881034 -16.005784)
			(xy 130.968441 -16.015776) (xy 131.054577 -16.033676) (xy 131.138729 -16.059334) (xy 131.220199 -16.092538)
			(xy 131.298312 -16.133012) (xy 131.37242 -16.180423) (xy 131.441911 -16.234376) (xy 131.506207 -16.294424)
			(xy 131.564776 -16.360071) (xy 131.617133 -16.430771) (xy 131.662845 -16.50594) (xy 131.701531 -16.584954)
			(xy 131.732872 -16.667159) (xy 131.756607 -16.751873) (xy 131.772541 -16.838394) (xy 131.780541 -16.926006)
			(xy 131.781042 -16.969994) (xy 155.848565 -16.969994) (xy 155.852569 -16.882109) (xy 155.864549 -16.794952)
			(xy 155.884404 -16.709245) (xy 155.911971 -16.6257) (xy 155.947021 -16.545007) (xy 155.989263 -16.467835)
			(xy 156.038348 -16.394825) (xy 156.093869 -16.326581) (xy 156.155366 -16.263668) (xy 156.222328 -16.206608)
			(xy 156.294202 -16.155874) (xy 156.370392 -16.111886) (xy 156.450266 -16.075008) (xy 156.533163 -16.045547)
			(xy 156.618395 -16.023745) (xy 156.705257 -16.009785) (xy 156.793028 -16.003781) (xy 156.880982 -16.005784)
			(xy 156.968389 -16.015776) (xy 157.054525 -16.033676) (xy 157.138677 -16.059334) (xy 157.220147 -16.092538)
			(xy 157.29826 -16.133012) (xy 157.372368 -16.180423) (xy 157.441859 -16.234376) (xy 157.506155 -16.294424)
			(xy 157.564724 -16.360071) (xy 157.617081 -16.430771) (xy 157.662793 -16.50594) (xy 157.701479 -16.584954)
			(xy 157.73282 -16.667159) (xy 157.756555 -16.751873) (xy 157.772489 -16.838394) (xy 157.780489 -16.926006)
			(xy 157.78099 -16.969994) (xy 181.848513 -16.969994) (xy 181.852517 -16.882109) (xy 181.864497 -16.794952)
			(xy 181.884352 -16.709245) (xy 181.911919 -16.6257) (xy 181.946969 -16.545007) (xy 181.989211 -16.467835)
			(xy 182.038296 -16.394825) (xy 182.093817 -16.326581) (xy 182.155314 -16.263668) (xy 182.222276 -16.206608)
			(xy 182.29415 -16.155874) (xy 182.37034 -16.111886) (xy 182.450214 -16.075008) (xy 182.533111 -16.045547)
			(xy 182.618343 -16.023745) (xy 182.705205 -16.009785) (xy 182.792976 -16.003781) (xy 182.88093 -16.005784)
			(xy 182.968337 -16.015776) (xy 183.054473 -16.033676) (xy 183.138625 -16.059334) (xy 183.220095 -16.092538)
			(xy 183.298208 -16.133012) (xy 183.372316 -16.180423) (xy 183.441807 -16.234376) (xy 183.506103 -16.294424)
			(xy 183.564672 -16.360071) (xy 183.617029 -16.430771) (xy 183.662741 -16.50594) (xy 183.701427 -16.584954)
			(xy 183.732768 -16.667159) (xy 183.756503 -16.751873) (xy 183.772437 -16.838394) (xy 183.780437 -16.926006)
			(xy 183.780938 -16.969994) (xy 207.848461 -16.969994) (xy 207.852465 -16.882109) (xy 207.864445 -16.794952)
			(xy 207.8843 -16.709245) (xy 207.911867 -16.6257) (xy 207.946917 -16.545007) (xy 207.989159 -16.467835)
			(xy 208.038244 -16.394825) (xy 208.093765 -16.326581) (xy 208.155262 -16.263668) (xy 208.222224 -16.206608)
			(xy 208.294098 -16.155874) (xy 208.370288 -16.111886) (xy 208.450162 -16.075008) (xy 208.533059 -16.045547)
			(xy 208.618291 -16.023745) (xy 208.705153 -16.009785) (xy 208.792924 -16.003781) (xy 208.880878 -16.005784)
			(xy 208.968285 -16.015776) (xy 209.054421 -16.033676) (xy 209.138573 -16.059334) (xy 209.220043 -16.092538)
			(xy 209.298156 -16.133012) (xy 209.372264 -16.180423) (xy 209.441755 -16.234376) (xy 209.506051 -16.294424)
			(xy 209.56462 -16.360071) (xy 209.616977 -16.430771) (xy 209.662689 -16.50594) (xy 209.701375 -16.584954)
			(xy 209.732716 -16.667159) (xy 209.756451 -16.751873) (xy 209.772385 -16.838394) (xy 209.780385 -16.926006)
			(xy 209.780886 -16.969994) (xy 245.948461 -16.969994) (xy 245.952465 -16.882109) (xy 245.964445 -16.794952)
			(xy 245.9843 -16.709245) (xy 246.011867 -16.6257) (xy 246.046917 -16.545007) (xy 246.089159 -16.467835)
			(xy 246.138244 -16.394825) (xy 246.193765 -16.326581) (xy 246.255262 -16.263668) (xy 246.322224 -16.206608)
			(xy 246.394098 -16.155874) (xy 246.470288 -16.111886) (xy 246.550162 -16.075008) (xy 246.633059 -16.045547)
			(xy 246.718291 -16.023745) (xy 246.805153 -16.009785) (xy 246.892924 -16.003781) (xy 246.980878 -16.005784)
			(xy 247.068285 -16.015776) (xy 247.154421 -16.033676) (xy 247.238573 -16.059334) (xy 247.320043 -16.092538)
			(xy 247.398156 -16.133012) (xy 247.472264 -16.180423) (xy 247.541755 -16.234376) (xy 247.606051 -16.294424)
			(xy 247.66462 -16.360071) (xy 247.716977 -16.430771) (xy 247.762689 -16.50594) (xy 247.801375 -16.584954)
			(xy 247.832716 -16.667159) (xy 247.856451 -16.751873) (xy 247.872385 -16.838394) (xy 247.880385 -16.926006)
			(xy 247.880886 -16.969994) (xy 271.948409 -16.969994) (xy 271.952413 -16.882109) (xy 271.964393 -16.794952)
			(xy 271.984248 -16.709245) (xy 272.011815 -16.6257) (xy 272.046865 -16.545007) (xy 272.089107 -16.467835)
			(xy 272.138192 -16.394825) (xy 272.193713 -16.326581) (xy 272.25521 -16.263668) (xy 272.322172 -16.206608)
			(xy 272.394046 -16.155874) (xy 272.470236 -16.111886) (xy 272.55011 -16.075008) (xy 272.633007 -16.045547)
			(xy 272.718239 -16.023745) (xy 272.805101 -16.009785) (xy 272.892872 -16.003781) (xy 272.980826 -16.005784)
			(xy 273.068233 -16.015776) (xy 273.154369 -16.033676) (xy 273.238521 -16.059334) (xy 273.319991 -16.092538)
			(xy 273.398104 -16.133012) (xy 273.472212 -16.180423) (xy 273.541703 -16.234376) (xy 273.605999 -16.294424)
			(xy 273.664568 -16.360071) (xy 273.716925 -16.430771) (xy 273.762637 -16.50594) (xy 273.801323 -16.584954)
			(xy 273.832664 -16.667159) (xy 273.856399 -16.751873) (xy 273.872333 -16.838394) (xy 273.880333 -16.926006)
			(xy 273.880834 -16.969994) (xy 297.948357 -16.969994) (xy 297.952361 -16.882109) (xy 297.964341 -16.794952)
			(xy 297.984196 -16.709245) (xy 298.011763 -16.6257) (xy 298.046813 -16.545007) (xy 298.089055 -16.467835)
			(xy 298.13814 -16.394825) (xy 298.193661 -16.326581) (xy 298.255158 -16.263668) (xy 298.32212 -16.206608)
			(xy 298.393994 -16.155874) (xy 298.470184 -16.111886) (xy 298.550058 -16.075008) (xy 298.632955 -16.045547)
			(xy 298.718187 -16.023745) (xy 298.805049 -16.009785) (xy 298.89282 -16.003781) (xy 298.980774 -16.005784)
			(xy 299.068181 -16.015776) (xy 299.154317 -16.033676) (xy 299.238469 -16.059334) (xy 299.319939 -16.092538)
			(xy 299.398052 -16.133012) (xy 299.47216 -16.180423) (xy 299.541651 -16.234376) (xy 299.605947 -16.294424)
			(xy 299.664516 -16.360071) (xy 299.716873 -16.430771) (xy 299.762585 -16.50594) (xy 299.801271 -16.584954)
			(xy 299.832612 -16.667159) (xy 299.856347 -16.751873) (xy 299.872281 -16.838394) (xy 299.880281 -16.926006)
			(xy 299.880782 -16.969994) (xy 323.948305 -16.969994) (xy 323.952309 -16.882109) (xy 323.964289 -16.794952)
			(xy 323.984144 -16.709245) (xy 324.011711 -16.6257) (xy 324.046761 -16.545007) (xy 324.089003 -16.467835)
			(xy 324.138088 -16.394825) (xy 324.193609 -16.326581) (xy 324.255106 -16.263668) (xy 324.322068 -16.206608)
			(xy 324.393942 -16.155874) (xy 324.470132 -16.111886) (xy 324.550006 -16.075008) (xy 324.632903 -16.045547)
			(xy 324.718135 -16.023745) (xy 324.804997 -16.009785) (xy 324.892768 -16.003781) (xy 324.980722 -16.005784)
			(xy 325.068129 -16.015776) (xy 325.154265 -16.033676) (xy 325.238417 -16.059334) (xy 325.319887 -16.092538)
			(xy 325.398 -16.133012) (xy 325.472108 -16.180423) (xy 325.541599 -16.234376) (xy 325.605895 -16.294424)
			(xy 325.664464 -16.360071) (xy 325.716821 -16.430771) (xy 325.762533 -16.50594) (xy 325.801219 -16.584954)
			(xy 325.83256 -16.667159) (xy 325.856295 -16.751873) (xy 325.872229 -16.838394) (xy 325.880229 -16.926006)
			(xy 325.88073 -16.969994) (xy 325.880229 -17.013982) (xy 325.872229 -17.101594) (xy 325.856295 -17.188115)
			(xy 325.83256 -17.272829) (xy 325.801219 -17.355034) (xy 325.762533 -17.434048) (xy 325.716821 -17.509217)
			(xy 325.664464 -17.579917) (xy 325.605895 -17.645564) (xy 325.541599 -17.705612) (xy 325.472108 -17.759565)
			(xy 325.398 -17.806976) (xy 325.319887 -17.84745) (xy 325.238417 -17.880654) (xy 325.154265 -17.906312)
			(xy 325.068129 -17.924212) (xy 324.980722 -17.934204) (xy 324.892768 -17.936207) (xy 324.804997 -17.930203)
			(xy 324.718135 -17.916243) (xy 324.632903 -17.894441) (xy 324.550006 -17.86498) (xy 324.470132 -17.828102)
			(xy 324.393942 -17.784114) (xy 324.322068 -17.73338) (xy 324.255106 -17.67632) (xy 324.193609 -17.613407)
			(xy 324.138088 -17.545163) (xy 324.089003 -17.472153) (xy 324.046761 -17.394981) (xy 324.011711 -17.314288)
			(xy 323.984144 -17.230743) (xy 323.964289 -17.145036) (xy 323.952309 -17.057879) (xy 323.948305 -16.969994)
			(xy 299.880782 -16.969994) (xy 299.880281 -17.013982) (xy 299.872281 -17.101594) (xy 299.856347 -17.188115)
			(xy 299.832612 -17.272829) (xy 299.801271 -17.355034) (xy 299.762585 -17.434048) (xy 299.716873 -17.509217)
			(xy 299.664516 -17.579917) (xy 299.605947 -17.645564) (xy 299.541651 -17.705612) (xy 299.47216 -17.759565)
			(xy 299.398052 -17.806976) (xy 299.319939 -17.84745) (xy 299.238469 -17.880654) (xy 299.154317 -17.906312)
			(xy 299.068181 -17.924212) (xy 298.980774 -17.934204) (xy 298.89282 -17.936207) (xy 298.805049 -17.930203)
			(xy 298.718187 -17.916243) (xy 298.632955 -17.894441) (xy 298.550058 -17.86498) (xy 298.470184 -17.828102)
			(xy 298.393994 -17.784114) (xy 298.32212 -17.73338) (xy 298.255158 -17.67632) (xy 298.193661 -17.613407)
			(xy 298.13814 -17.545163) (xy 298.089055 -17.472153) (xy 298.046813 -17.394981) (xy 298.011763 -17.314288)
			(xy 297.984196 -17.230743) (xy 297.964341 -17.145036) (xy 297.952361 -17.057879) (xy 297.948357 -16.969994)
			(xy 273.880834 -16.969994) (xy 273.880333 -17.013982) (xy 273.872333 -17.101594) (xy 273.856399 -17.188115)
			(xy 273.832664 -17.272829) (xy 273.801323 -17.355034) (xy 273.762637 -17.434048) (xy 273.716925 -17.509217)
			(xy 273.664568 -17.579917) (xy 273.605999 -17.645564) (xy 273.541703 -17.705612) (xy 273.472212 -17.759565)
			(xy 273.398104 -17.806976) (xy 273.319991 -17.84745) (xy 273.238521 -17.880654) (xy 273.154369 -17.906312)
			(xy 273.068233 -17.924212) (xy 272.980826 -17.934204) (xy 272.892872 -17.936207) (xy 272.805101 -17.930203)
			(xy 272.718239 -17.916243) (xy 272.633007 -17.894441) (xy 272.55011 -17.86498) (xy 272.470236 -17.828102)
			(xy 272.394046 -17.784114) (xy 272.322172 -17.73338) (xy 272.25521 -17.67632) (xy 272.193713 -17.613407)
			(xy 272.138192 -17.545163) (xy 272.089107 -17.472153) (xy 272.046865 -17.394981) (xy 272.011815 -17.314288)
			(xy 271.984248 -17.230743) (xy 271.964393 -17.145036) (xy 271.952413 -17.057879) (xy 271.948409 -16.969994)
			(xy 247.880886 -16.969994) (xy 247.880385 -17.013982) (xy 247.872385 -17.101594) (xy 247.856451 -17.188115)
			(xy 247.832716 -17.272829) (xy 247.801375 -17.355034) (xy 247.762689 -17.434048) (xy 247.716977 -17.509217)
			(xy 247.66462 -17.579917) (xy 247.606051 -17.645564) (xy 247.541755 -17.705612) (xy 247.472264 -17.759565)
			(xy 247.398156 -17.806976) (xy 247.320043 -17.84745) (xy 247.238573 -17.880654) (xy 247.154421 -17.906312)
			(xy 247.068285 -17.924212) (xy 246.980878 -17.934204) (xy 246.892924 -17.936207) (xy 246.805153 -17.930203)
			(xy 246.718291 -17.916243) (xy 246.633059 -17.894441) (xy 246.550162 -17.86498) (xy 246.470288 -17.828102)
			(xy 246.394098 -17.784114) (xy 246.322224 -17.73338) (xy 246.255262 -17.67632) (xy 246.193765 -17.613407)
			(xy 246.138244 -17.545163) (xy 246.089159 -17.472153) (xy 246.046917 -17.394981) (xy 246.011867 -17.314288)
			(xy 245.9843 -17.230743) (xy 245.964445 -17.145036) (xy 245.952465 -17.057879) (xy 245.948461 -16.969994)
			(xy 209.780886 -16.969994) (xy 209.780385 -17.013982) (xy 209.772385 -17.101594) (xy 209.756451 -17.188115)
			(xy 209.732716 -17.272829) (xy 209.701375 -17.355034) (xy 209.662689 -17.434048) (xy 209.616977 -17.509217)
			(xy 209.56462 -17.579917) (xy 209.506051 -17.645564) (xy 209.441755 -17.705612) (xy 209.372264 -17.759565)
			(xy 209.298156 -17.806976) (xy 209.220043 -17.84745) (xy 209.138573 -17.880654) (xy 209.054421 -17.906312)
			(xy 208.968285 -17.924212) (xy 208.880878 -17.934204) (xy 208.792924 -17.936207) (xy 208.705153 -17.930203)
			(xy 208.618291 -17.916243) (xy 208.533059 -17.894441) (xy 208.450162 -17.86498) (xy 208.370288 -17.828102)
			(xy 208.294098 -17.784114) (xy 208.222224 -17.73338) (xy 208.155262 -17.67632) (xy 208.093765 -17.613407)
			(xy 208.038244 -17.545163) (xy 207.989159 -17.472153) (xy 207.946917 -17.394981) (xy 207.911867 -17.314288)
			(xy 207.8843 -17.230743) (xy 207.864445 -17.145036) (xy 207.852465 -17.057879) (xy 207.848461 -16.969994)
			(xy 183.780938 -16.969994) (xy 183.780437 -17.013982) (xy 183.772437 -17.101594) (xy 183.756503 -17.188115)
			(xy 183.732768 -17.272829) (xy 183.701427 -17.355034) (xy 183.662741 -17.434048) (xy 183.617029 -17.509217)
			(xy 183.564672 -17.579917) (xy 183.506103 -17.645564) (xy 183.441807 -17.705612) (xy 183.372316 -17.759565)
			(xy 183.298208 -17.806976) (xy 183.220095 -17.84745) (xy 183.138625 -17.880654) (xy 183.054473 -17.906312)
			(xy 182.968337 -17.924212) (xy 182.88093 -17.934204) (xy 182.792976 -17.936207) (xy 182.705205 -17.930203)
			(xy 182.618343 -17.916243) (xy 182.533111 -17.894441) (xy 182.450214 -17.86498) (xy 182.37034 -17.828102)
			(xy 182.29415 -17.784114) (xy 182.222276 -17.73338) (xy 182.155314 -17.67632) (xy 182.093817 -17.613407)
			(xy 182.038296 -17.545163) (xy 181.989211 -17.472153) (xy 181.946969 -17.394981) (xy 181.911919 -17.314288)
			(xy 181.884352 -17.230743) (xy 181.864497 -17.145036) (xy 181.852517 -17.057879) (xy 181.848513 -16.969994)
			(xy 157.78099 -16.969994) (xy 157.780489 -17.013982) (xy 157.772489 -17.101594) (xy 157.756555 -17.188115)
			(xy 157.73282 -17.272829) (xy 157.701479 -17.355034) (xy 157.662793 -17.434048) (xy 157.617081 -17.509217)
			(xy 157.564724 -17.579917) (xy 157.506155 -17.645564) (xy 157.441859 -17.705612) (xy 157.372368 -17.759565)
			(xy 157.29826 -17.806976) (xy 157.220147 -17.84745) (xy 157.138677 -17.880654) (xy 157.054525 -17.906312)
			(xy 156.968389 -17.924212) (xy 156.880982 -17.934204) (xy 156.793028 -17.936207) (xy 156.705257 -17.930203)
			(xy 156.618395 -17.916243) (xy 156.533163 -17.894441) (xy 156.450266 -17.86498) (xy 156.370392 -17.828102)
			(xy 156.294202 -17.784114) (xy 156.222328 -17.73338) (xy 156.155366 -17.67632) (xy 156.093869 -17.613407)
			(xy 156.038348 -17.545163) (xy 155.989263 -17.472153) (xy 155.947021 -17.394981) (xy 155.911971 -17.314288)
			(xy 155.884404 -17.230743) (xy 155.864549 -17.145036) (xy 155.852569 -17.057879) (xy 155.848565 -16.969994)
			(xy 131.781042 -16.969994) (xy 131.780541 -17.013982) (xy 131.772541 -17.101594) (xy 131.756607 -17.188115)
			(xy 131.732872 -17.272829) (xy 131.701531 -17.355034) (xy 131.662845 -17.434048) (xy 131.617133 -17.509217)
			(xy 131.564776 -17.579917) (xy 131.506207 -17.645564) (xy 131.441911 -17.705612) (xy 131.37242 -17.759565)
			(xy 131.298312 -17.806976) (xy 131.220199 -17.84745) (xy 131.138729 -17.880654) (xy 131.054577 -17.906312)
			(xy 130.968441 -17.924212) (xy 130.881034 -17.934204) (xy 130.79308 -17.936207) (xy 130.705309 -17.930203)
			(xy 130.618447 -17.916243) (xy 130.533215 -17.894441) (xy 130.450318 -17.86498) (xy 130.370444 -17.828102)
			(xy 130.294254 -17.784114) (xy 130.22238 -17.73338) (xy 130.155418 -17.67632) (xy 130.093921 -17.613407)
			(xy 130.0384 -17.545163) (xy 129.989315 -17.472153) (xy 129.947073 -17.394981) (xy 129.912023 -17.314288)
			(xy 129.884456 -17.230743) (xy 129.864601 -17.145036) (xy 129.852621 -17.057879) (xy 129.848617 -16.969994)
			(xy 115.171228 -16.969994) (xy 115.193192 -17.081123) (xy 115.225099 -17.283855) (xy 115.249072 -17.487677)
			(xy 115.265074 -17.69228) (xy 115.273081 -17.89735) (xy 115.273582 -17.999964) (xy 336.9559 -17.999964)
			(xy 336.959904 -17.794776) (xy 336.971911 -17.5899) (xy 336.991902 -17.385649) (xy 337.019847 -17.182334)
			(xy 337.055703 -16.980263) (xy 337.099417 -16.779745) (xy 337.15092 -16.581086) (xy 337.210135 -16.384587)
			(xy 337.276971 -16.190548) (xy 337.351327 -15.999265) (xy 337.43309 -15.811028) (xy 337.522135 -15.626125)
			(xy 337.618326 -15.444837) (xy 337.721517 -15.26744) (xy 337.831551 -15.094203) (xy 337.94826 -14.925392)
			(xy 338.071466 -14.761263) (xy 338.200983 -14.602066) (xy 338.336612 -14.448044) (xy 338.478147 -14.29943)
			(xy 338.625372 -14.156452) (xy 338.778064 -14.019327) (xy 338.93599 -13.888263) (xy 339.098909 -13.763461)
			(xy 339.266574 -13.645111) (xy 339.438728 -13.533392) (xy 339.61511 -13.428475) (xy 339.795451 -13.33052)
			(xy 339.979477 -13.239676) (xy 340.166907 -13.15608) (xy 340.357456 -13.079861) (xy 340.550833 -13.011135)
			(xy 340.746745 -12.950006) (xy 340.944892 -12.896567) (xy 341.144974 -12.8509) (xy 341.346685 -12.813073)
			(xy 341.549718 -12.783146) (xy 341.753765 -12.761163) (xy 341.958514 -12.747158) (xy 342.163653 -12.741152)
			(xy 342.36887 -12.743154) (xy 342.573853 -12.753162) (xy 342.77829 -12.771159) (xy 342.981868 -12.797119)
			(xy 343.184279 -12.831002) (xy 343.385213 -12.872757) (xy 343.584366 -12.92232) (xy 343.781433 -12.979615)
			(xy 343.976115 -13.044555) (xy 344.168115 -13.117041) (xy 344.35714 -13.196964) (xy 344.542903 -13.2842)
			(xy 344.725121 -13.378618) (xy 344.903517 -13.480073) (xy 345.077818 -13.588412) (xy 345.24776 -13.703468)
			(xy 345.413083 -13.825068) (xy 345.573536 -13.953025) (xy 345.728875 -14.087144) (xy 345.878862 -14.227223)
			(xy 346.02327 -14.373047) (xy 346.161878 -14.524393) (xy 346.294476 -14.681033) (xy 346.420862 -14.842727)
			(xy 346.540842 -15.009229) (xy 346.654235 -15.180285) (xy 346.666298 -15.200122) (xy 459.541372 -15.200122)
			(xy 459.541372 -13.599922) (xy 459.54188 -13.535242) (xy 459.550003 -13.406136) (xy 459.566216 -13.277796)
			(xy 459.590456 -13.150726) (xy 459.622626 -13.02543) (xy 459.662601 -12.9024) (xy 459.710222 -12.782124)
			(xy 459.765301 -12.665075) (xy 459.827621 -12.551715) (xy 459.896936 -12.442492) (xy 459.972972 -12.337837)
			(xy 460.05543 -12.238163) (xy 460.143983 -12.143863) (xy 460.238283 -12.05531) (xy 460.337957 -11.972852)
			(xy 460.442612 -11.896816) (xy 460.551835 -11.827501) (xy 460.665195 -11.765181) (xy 460.782244 -11.710102)
			(xy 460.90252 -11.662481) (xy 461.02555 -11.622506) (xy 461.150846 -11.590336) (xy 461.277916 -11.566096)
			(xy 461.406256 -11.549883) (xy 461.535362 -11.54176) (xy 461.664722 -11.54176) (xy 461.793828 -11.549883)
			(xy 461.922168 -11.566096) (xy 462.049238 -11.590336) (xy 462.174534 -11.622506) (xy 462.297564 -11.662481)
			(xy 462.41784 -11.710102) (xy 462.534889 -11.765181) (xy 462.648249 -11.827501) (xy 462.757472 -11.896816)
			(xy 462.862127 -11.972852) (xy 462.961801 -12.05531) (xy 463.056101 -12.143863) (xy 463.144654 -12.238163)
			(xy 463.227112 -12.337837) (xy 463.303148 -12.442492) (xy 463.372463 -12.551715) (xy 463.434783 -12.665075)
			(xy 463.489862 -12.782124) (xy 463.537483 -12.9024) (xy 463.577458 -13.02543) (xy 463.609628 -13.150726)
			(xy 463.633868 -13.277796) (xy 463.650081 -13.406136) (xy 463.658204 -13.535242) (xy 463.658712 -13.599922)
			(xy 463.658712 -15.200122) (xy 463.658204 -15.264802) (xy 463.650081 -15.393908) (xy 463.633868 -15.522248)
			(xy 463.609628 -15.649318) (xy 463.577458 -15.774614) (xy 463.537483 -15.897644) (xy 463.489862 -16.01792)
			(xy 463.434783 -16.134969) (xy 463.372463 -16.248329) (xy 463.303148 -16.357552) (xy 463.227112 -16.462207)
			(xy 463.144654 -16.561881) (xy 463.056101 -16.656181) (xy 462.961801 -16.744734) (xy 462.862127 -16.827192)
			(xy 462.757472 -16.903228) (xy 462.648249 -16.972543) (xy 462.534889 -17.034863) (xy 462.41784 -17.089942)
			(xy 462.297564 -17.137563) (xy 462.174534 -17.177538) (xy 462.049238 -17.209708) (xy 461.922168 -17.233948)
			(xy 461.793828 -17.250161) (xy 461.664722 -17.258284) (xy 461.535362 -17.258284) (xy 461.406256 -17.250161)
			(xy 461.277916 -17.233948) (xy 461.150846 -17.209708) (xy 461.02555 -17.177538) (xy 460.90252 -17.137563)
			(xy 460.782244 -17.089942) (xy 460.665195 -17.034863) (xy 460.551835 -16.972543) (xy 460.442612 -16.903228)
			(xy 460.337957 -16.827192) (xy 460.238283 -16.744734) (xy 460.143983 -16.656181) (xy 460.05543 -16.561881)
			(xy 459.972972 -16.462207) (xy 459.896936 -16.357552) (xy 459.827621 -16.248329) (xy 459.765301 -16.134969)
			(xy 459.710222 -16.01792) (xy 459.662601 -15.897644) (xy 459.622626 -15.774614) (xy 459.590456 -15.649318)
			(xy 459.566216 -15.522248) (xy 459.550003 -15.393908) (xy 459.54188 -15.264802) (xy 459.541372 -15.200122)
			(xy 346.666298 -15.200122) (xy 346.760868 -15.355635) (xy 346.860578 -15.535012) (xy 346.953214 -15.718142)
			(xy 347.038634 -15.904748) (xy 347.116708 -16.094544) (xy 347.187318 -16.287242) (xy 347.250355 -16.482548)
			(xy 347.305725 -16.680164) (xy 347.353342 -16.879791) (xy 347.37117 -16.969994) (xy 362.048559 -16.969994)
			(xy 362.052563 -16.882109) (xy 362.064543 -16.794952) (xy 362.084398 -16.709245) (xy 362.111965 -16.6257)
			(xy 362.147015 -16.545007) (xy 362.189257 -16.467835) (xy 362.238342 -16.394825) (xy 362.293863 -16.326581)
			(xy 362.35536 -16.263668) (xy 362.422322 -16.206608) (xy 362.494196 -16.155874) (xy 362.570386 -16.111886)
			(xy 362.65026 -16.075008) (xy 362.733157 -16.045547) (xy 362.818389 -16.023745) (xy 362.905251 -16.009785)
			(xy 362.993022 -16.003781) (xy 363.080976 -16.005784) (xy 363.168383 -16.015776) (xy 363.254519 -16.033676)
			(xy 363.338671 -16.059334) (xy 363.420141 -16.092538) (xy 363.498254 -16.133012) (xy 363.572362 -16.180423)
			(xy 363.641853 -16.234376) (xy 363.706149 -16.294424) (xy 363.764718 -16.360071) (xy 363.817075 -16.430771)
			(xy 363.862787 -16.50594) (xy 363.901473 -16.584954) (xy 363.932814 -16.667159) (xy 363.956549 -16.751873)
			(xy 363.972483 -16.838394) (xy 363.980483 -16.926006) (xy 363.980984 -16.969994) (xy 388.048507 -16.969994)
			(xy 388.052511 -16.882109) (xy 388.064491 -16.794952) (xy 388.084346 -16.709245) (xy 388.111913 -16.6257)
			(xy 388.146963 -16.545007) (xy 388.189205 -16.467835) (xy 388.23829 -16.394825) (xy 388.293811 -16.326581)
			(xy 388.355308 -16.263668) (xy 388.42227 -16.206608) (xy 388.494144 -16.155874) (xy 388.570334 -16.111886)
			(xy 388.650208 -16.075008) (xy 388.733105 -16.045547) (xy 388.818337 -16.023745) (xy 388.905199 -16.009785)
			(xy 388.99297 -16.003781) (xy 389.080924 -16.005784) (xy 389.168331 -16.015776) (xy 389.254467 -16.033676)
			(xy 389.338619 -16.059334) (xy 389.420089 -16.092538) (xy 389.498202 -16.133012) (xy 389.57231 -16.180423)
			(xy 389.641801 -16.234376) (xy 389.706097 -16.294424) (xy 389.764666 -16.360071) (xy 389.817023 -16.430771)
			(xy 389.862735 -16.50594) (xy 389.901421 -16.584954) (xy 389.932762 -16.667159) (xy 389.956497 -16.751873)
			(xy 389.972431 -16.838394) (xy 389.980431 -16.926006) (xy 389.980932 -16.969994) (xy 414.048455 -16.969994)
			(xy 414.052459 -16.882109) (xy 414.064439 -16.794952) (xy 414.084294 -16.709245) (xy 414.111861 -16.6257)
			(xy 414.146911 -16.545007) (xy 414.189153 -16.467835) (xy 414.238238 -16.394825) (xy 414.293759 -16.326581)
			(xy 414.355256 -16.263668) (xy 414.422218 -16.206608) (xy 414.494092 -16.155874) (xy 414.570282 -16.111886)
			(xy 414.650156 -16.075008) (xy 414.733053 -16.045547) (xy 414.818285 -16.023745) (xy 414.905147 -16.009785)
			(xy 414.992918 -16.003781) (xy 415.080872 -16.005784) (xy 415.168279 -16.015776) (xy 415.254415 -16.033676)
			(xy 415.338567 -16.059334) (xy 415.420037 -16.092538) (xy 415.49815 -16.133012) (xy 415.572258 -16.180423)
			(xy 415.641749 -16.234376) (xy 415.706045 -16.294424) (xy 415.764614 -16.360071) (xy 415.816971 -16.430771)
			(xy 415.862683 -16.50594) (xy 415.901369 -16.584954) (xy 415.93271 -16.667159) (xy 415.956445 -16.751873)
			(xy 415.972379 -16.838394) (xy 415.980379 -16.926006) (xy 415.98088 -16.969994) (xy 440.048403 -16.969994)
			(xy 440.052407 -16.882109) (xy 440.064387 -16.794952) (xy 440.084242 -16.709245) (xy 440.111809 -16.6257)
			(xy 440.146859 -16.545007) (xy 440.189101 -16.467835) (xy 440.238186 -16.394825) (xy 440.293707 -16.326581)
			(xy 440.355204 -16.263668) (xy 440.422166 -16.206608) (xy 440.49404 -16.155874) (xy 440.57023 -16.111886)
			(xy 440.650104 -16.075008) (xy 440.733001 -16.045547) (xy 440.818233 -16.023745) (xy 440.905095 -16.009785)
			(xy 440.992866 -16.003781) (xy 441.08082 -16.005784) (xy 441.168227 -16.015776) (xy 441.254363 -16.033676)
			(xy 441.338515 -16.059334) (xy 441.419985 -16.092538) (xy 441.498098 -16.133012) (xy 441.572206 -16.180423)
			(xy 441.641697 -16.234376) (xy 441.705993 -16.294424) (xy 441.764562 -16.360071) (xy 441.816919 -16.430771)
			(xy 441.862631 -16.50594) (xy 441.901317 -16.584954) (xy 441.932658 -16.667159) (xy 441.956393 -16.751873)
			(xy 441.972327 -16.838394) (xy 441.980327 -16.926006) (xy 441.980828 -16.969994) (xy 441.980327 -17.013982)
			(xy 441.972327 -17.101594) (xy 441.956393 -17.188115) (xy 441.932658 -17.272829) (xy 441.901317 -17.355034)
			(xy 441.862631 -17.434048) (xy 441.816919 -17.509217) (xy 441.764562 -17.579917) (xy 441.705993 -17.645564)
			(xy 441.641697 -17.705612) (xy 441.572206 -17.759565) (xy 441.498098 -17.806976) (xy 441.419985 -17.84745)
			(xy 441.338515 -17.880654) (xy 441.254363 -17.906312) (xy 441.168227 -17.924212) (xy 441.08082 -17.934204)
			(xy 440.992866 -17.936207) (xy 440.905095 -17.930203) (xy 440.818233 -17.916243) (xy 440.733001 -17.894441)
			(xy 440.650104 -17.86498) (xy 440.57023 -17.828102) (xy 440.49404 -17.784114) (xy 440.422166 -17.73338)
			(xy 440.355204 -17.67632) (xy 440.293707 -17.613407) (xy 440.238186 -17.545163) (xy 440.189101 -17.472153)
			(xy 440.146859 -17.394981) (xy 440.111809 -17.314288) (xy 440.084242 -17.230743) (xy 440.064387 -17.145036)
			(xy 440.052407 -17.057879) (xy 440.048403 -16.969994) (xy 415.98088 -16.969994) (xy 415.980379 -17.013982)
			(xy 415.972379 -17.101594) (xy 415.956445 -17.188115) (xy 415.93271 -17.272829) (xy 415.901369 -17.355034)
			(xy 415.862683 -17.434048) (xy 415.816971 -17.509217) (xy 415.764614 -17.579917) (xy 415.706045 -17.645564)
			(xy 415.641749 -17.705612) (xy 415.572258 -17.759565) (xy 415.49815 -17.806976) (xy 415.420037 -17.84745)
			(xy 415.338567 -17.880654) (xy 415.254415 -17.906312) (xy 415.168279 -17.924212) (xy 415.080872 -17.934204)
			(xy 414.992918 -17.936207) (xy 414.905147 -17.930203) (xy 414.818285 -17.916243) (xy 414.733053 -17.894441)
			(xy 414.650156 -17.86498) (xy 414.570282 -17.828102) (xy 414.494092 -17.784114) (xy 414.422218 -17.73338)
			(xy 414.355256 -17.67632) (xy 414.293759 -17.613407) (xy 414.238238 -17.545163) (xy 414.189153 -17.472153)
			(xy 414.146911 -17.394981) (xy 414.111861 -17.314288) (xy 414.084294 -17.230743) (xy 414.064439 -17.145036)
			(xy 414.052459 -17.057879) (xy 414.048455 -16.969994) (xy 389.980932 -16.969994) (xy 389.980431 -17.013982)
			(xy 389.972431 -17.101594) (xy 389.956497 -17.188115) (xy 389.932762 -17.272829) (xy 389.901421 -17.355034)
			(xy 389.862735 -17.434048) (xy 389.817023 -17.509217) (xy 389.764666 -17.579917) (xy 389.706097 -17.645564)
			(xy 389.641801 -17.705612) (xy 389.57231 -17.759565) (xy 389.498202 -17.806976) (xy 389.420089 -17.84745)
			(xy 389.338619 -17.880654) (xy 389.254467 -17.906312) (xy 389.168331 -17.924212) (xy 389.080924 -17.934204)
			(xy 388.99297 -17.936207) (xy 388.905199 -17.930203) (xy 388.818337 -17.916243) (xy 388.733105 -17.894441)
			(xy 388.650208 -17.86498) (xy 388.570334 -17.828102) (xy 388.494144 -17.784114) (xy 388.42227 -17.73338)
			(xy 388.355308 -17.67632) (xy 388.293811 -17.613407) (xy 388.23829 -17.545163) (xy 388.189205 -17.472153)
			(xy 388.146963 -17.394981) (xy 388.111913 -17.314288) (xy 388.084346 -17.230743) (xy 388.064491 -17.145036)
			(xy 388.052511 -17.057879) (xy 388.048507 -16.969994) (xy 363.980984 -16.969994) (xy 363.980483 -17.013982)
			(xy 363.972483 -17.101594) (xy 363.956549 -17.188115) (xy 363.932814 -17.272829) (xy 363.901473 -17.355034)
			(xy 363.862787 -17.434048) (xy 363.817075 -17.509217) (xy 363.764718 -17.579917) (xy 363.706149 -17.645564)
			(xy 363.641853 -17.705612) (xy 363.572362 -17.759565) (xy 363.498254 -17.806976) (xy 363.420141 -17.84745)
			(xy 363.338671 -17.880654) (xy 363.254519 -17.906312) (xy 363.168383 -17.924212) (xy 363.080976 -17.934204)
			(xy 362.993022 -17.936207) (xy 362.905251 -17.930203) (xy 362.818389 -17.916243) (xy 362.733157 -17.894441)
			(xy 362.65026 -17.86498) (xy 362.570386 -17.828102) (xy 362.494196 -17.784114) (xy 362.422322 -17.73338)
			(xy 362.35536 -17.67632) (xy 362.293863 -17.613407) (xy 362.238342 -17.545163) (xy 362.189257 -17.472153)
			(xy 362.147015 -17.394981) (xy 362.111965 -17.314288) (xy 362.084398 -17.230743) (xy 362.064543 -17.145036)
			(xy 362.052563 -17.057879) (xy 362.048559 -16.969994) (xy 347.37117 -16.969994) (xy 347.393134 -17.081123)
			(xy 347.425041 -17.283855) (xy 347.449014 -17.487677) (xy 347.465016 -17.69228) (xy 347.473023 -17.89735)
			(xy 347.473524 -17.999964) (xy 347.473023 -18.102578) (xy 347.465016 -18.307648) (xy 347.449014 -18.512251)
			(xy 347.425041 -18.716073) (xy 347.393134 -18.918805) (xy 347.353342 -19.120137) (xy 347.305725 -19.319764)
			(xy 347.250355 -19.51738) (xy 347.187318 -19.712686) (xy 347.116708 -19.905384) (xy 347.038634 -20.09518)
			(xy 346.953214 -20.281786) (xy 346.860578 -20.464916) (xy 346.760868 -20.644293) (xy 346.654235 -20.819643)
			(xy 346.540842 -20.990699) (xy 346.420862 -21.157201) (xy 346.294476 -21.318895) (xy 346.161878 -21.475535)
			(xy 346.02327 -21.626881) (xy 345.878862 -21.772705) (xy 345.728875 -21.912784) (xy 345.573536 -22.046903)
			(xy 345.413083 -22.17486) (xy 345.24776 -22.29646) (xy 345.077818 -22.411516) (xy 344.903517 -22.519855)
			(xy 344.725121 -22.62131) (xy 344.542903 -22.715728) (xy 344.35714 -22.802964) (xy 344.168115 -22.882887)
			(xy 343.976115 -22.955373) (xy 343.781433 -23.020313) (xy 343.584366 -23.077608) (xy 343.385213 -23.127171)
			(xy 343.184279 -23.168926) (xy 342.981868 -23.202809) (xy 342.77829 -23.228769) (xy 342.573853 -23.246766)
			(xy 342.36887 -23.256774) (xy 342.163653 -23.258776) (xy 341.958514 -23.25277) (xy 341.753765 -23.238765)
			(xy 341.549718 -23.216782) (xy 341.346685 -23.186855) (xy 341.144974 -23.149028) (xy 340.944892 -23.103361)
			(xy 340.746745 -23.049922) (xy 340.550833 -22.988793) (xy 340.357456 -22.920067) (xy 340.166907 -22.843848)
			(xy 339.979477 -22.760252) (xy 339.795451 -22.669408) (xy 339.61511 -22.571453) (xy 339.438728 -22.466536)
			(xy 339.266574 -22.354817) (xy 339.098909 -22.236467) (xy 338.93599 -22.111665) (xy 338.778064 -21.980601)
			(xy 338.625372 -21.843476) (xy 338.478147 -21.700498) (xy 338.336612 -21.551884) (xy 338.200983 -21.397862)
			(xy 338.071466 -21.238665) (xy 337.94826 -21.074536) (xy 337.831551 -20.905725) (xy 337.721517 -20.732488)
			(xy 337.618326 -20.555091) (xy 337.522135 -20.373803) (xy 337.43309 -20.1889) (xy 337.351327 -20.000663)
			(xy 337.276971 -19.80938) (xy 337.210135 -19.615341) (xy 337.15092 -19.418842) (xy 337.099417 -19.220183)
			(xy 337.055703 -19.019665) (xy 337.019847 -18.817594) (xy 336.991902 -18.614279) (xy 336.971911 -18.410028)
			(xy 336.959904 -18.205152) (xy 336.9559 -17.999964) (xy 115.273582 -17.999964) (xy 115.273081 -18.102578)
			(xy 115.265074 -18.307648) (xy 115.249072 -18.512251) (xy 115.225099 -18.716073) (xy 115.193192 -18.918805)
			(xy 115.1534 -19.120137) (xy 115.105783 -19.319764) (xy 115.050413 -19.51738) (xy 114.987376 -19.712686)
			(xy 114.916766 -19.905384) (xy 114.838692 -20.09518) (xy 114.753272 -20.281786) (xy 114.660636 -20.464916)
			(xy 114.560926 -20.644293) (xy 114.454293 -20.819643) (xy 114.3409 -20.990699) (xy 114.22092 -21.157201)
			(xy 114.094534 -21.318895) (xy 113.961936 -21.475535) (xy 113.823328 -21.626881) (xy 113.67892 -21.772705)
			(xy 113.528933 -21.912784) (xy 113.373594 -22.046903) (xy 113.213141 -22.17486) (xy 113.047818 -22.29646)
			(xy 112.877876 -22.411516) (xy 112.703575 -22.519855) (xy 112.525179 -22.62131) (xy 112.342961 -22.715728)
			(xy 112.157198 -22.802964) (xy 111.968173 -22.882887) (xy 111.776173 -22.955373) (xy 111.581491 -23.020313)
			(xy 111.384424 -23.077608) (xy 111.185271 -23.127171) (xy 110.984337 -23.168926) (xy 110.781926 -23.202809)
			(xy 110.578348 -23.228769) (xy 110.373911 -23.246766) (xy 110.168928 -23.256774) (xy 109.963711 -23.258776)
			(xy 109.758572 -23.25277) (xy 109.553823 -23.238765) (xy 109.349776 -23.216782) (xy 109.146743 -23.186855)
			(xy 108.945032 -23.149028) (xy 108.74495 -23.103361) (xy 108.546803 -23.049922) (xy 108.350891 -22.988793)
			(xy 108.157514 -22.920067) (xy 107.966965 -22.843848) (xy 107.779535 -22.760252) (xy 107.595509 -22.669408)
			(xy 107.415168 -22.571453) (xy 107.238786 -22.466536) (xy 107.066632 -22.354817) (xy 106.898967 -22.236467)
			(xy 106.736048 -22.111665) (xy 106.578122 -21.980601) (xy 106.42543 -21.843476) (xy 106.278205 -21.700498)
			(xy 106.13667 -21.551884) (xy 106.001041 -21.397862) (xy 105.871524 -21.238665) (xy 105.748318 -21.074536)
			(xy 105.631609 -20.905725) (xy 105.521575 -20.732488) (xy 105.418384 -20.555091) (xy 105.322193 -20.373803)
			(xy 105.233148 -20.1889) (xy 105.151385 -20.000663) (xy 105.077029 -19.80938) (xy 105.010193 -19.615341)
			(xy 104.950978 -19.418842) (xy 104.899475 -19.220183) (xy 104.855761 -19.019665) (xy 104.819905 -18.817594)
			(xy 104.79196 -18.614279) (xy 104.771969 -18.410028) (xy 104.759962 -18.205152) (xy 104.755958 -17.999964)
			(xy 31.223458 -17.999964) (xy 31.222957 -18.102578) (xy 31.21495 -18.307648) (xy 31.198948 -18.512251)
			(xy 31.174975 -18.716073) (xy 31.143068 -18.918805) (xy 31.103276 -19.120137) (xy 31.055659 -19.319764)
			(xy 31.000289 -19.51738) (xy 30.937252 -19.712686) (xy 30.866642 -19.905384) (xy 30.788568 -20.09518)
			(xy 30.703148 -20.281786) (xy 30.610512 -20.464916) (xy 30.510802 -20.644293) (xy 30.404169 -20.819643)
			(xy 30.290776 -20.990699) (xy 30.170796 -21.157201) (xy 30.04441 -21.318895) (xy 29.911812 -21.475535)
			(xy 29.773204 -21.626881) (xy 29.628796 -21.772705) (xy 29.478809 -21.912784) (xy 29.32347 -22.046903)
			(xy 29.163017 -22.17486) (xy 28.997694 -22.29646) (xy 28.827752 -22.411516) (xy 28.653451 -22.519855)
			(xy 28.475055 -22.62131) (xy 28.292837 -22.715728) (xy 28.107074 -22.802964) (xy 27.918049 -22.882887)
			(xy 27.726049 -22.955373) (xy 27.531367 -23.020313) (xy 27.3343 -23.077608) (xy 27.135147 -23.127171)
			(xy 26.934213 -23.168926) (xy 26.731802 -23.202809) (xy 26.528224 -23.228769) (xy 26.323787 -23.246766)
			(xy 26.118804 -23.256774) (xy 25.913587 -23.258776) (xy 25.708448 -23.25277) (xy 25.503699 -23.238765)
			(xy 25.299652 -23.216782) (xy 25.096619 -23.186855) (xy 24.894908 -23.149028) (xy 24.694826 -23.103361)
			(xy 24.496679 -23.049922) (xy 24.300767 -22.988793) (xy 24.10739 -22.920067) (xy 23.916841 -22.843848)
			(xy 23.729411 -22.760252) (xy 23.545385 -22.669408) (xy 23.365044 -22.571453) (xy 23.188662 -22.466536)
			(xy 23.016508 -22.354817) (xy 22.848843 -22.236467) (xy 22.685924 -22.111665) (xy 22.527998 -21.980601)
			(xy 22.375306 -21.843476) (xy 22.228081 -21.700498) (xy 22.086546 -21.551884) (xy 21.950917 -21.397862)
			(xy 21.8214 -21.238665) (xy 21.698194 -21.074536) (xy 21.581485 -20.905725) (xy 21.471451 -20.732488)
			(xy 21.36826 -20.555091) (xy 21.272069 -20.373803) (xy 21.183024 -20.1889) (xy 21.101261 -20.000663)
			(xy 21.026905 -19.80938) (xy 20.960069 -19.615341) (xy 20.900854 -19.418842) (xy 20.849351 -19.220183)
			(xy 20.805637 -19.019665) (xy 20.769781 -18.817594) (xy 20.741836 -18.614279) (xy 20.721845 -18.410028)
			(xy 20.709838 -18.205152) (xy 20.705834 -17.999964) (xy 1.524 -17.999964) (xy 1.524 -27.342846) (xy 16.523716 -27.342846)
			(xy 16.523716 -26.479246) (xy 16.524206 -26.449278) (xy 16.532029 -26.389856) (xy 16.547542 -26.331963)
			(xy 16.570478 -26.27659) (xy 16.600445 -26.224684) (xy 16.636932 -26.177134) (xy 16.679312 -26.134754)
			(xy 16.726862 -26.098267) (xy 16.778768 -26.0683) (xy 16.834141 -26.045364) (xy 16.892034 -26.029851)
			(xy 16.951456 -26.022028) (xy 17.011392 -26.022028) (xy 17.070814 -26.029851) (xy 17.128707 -26.045364)
			(xy 17.18408 -26.0683) (xy 17.235986 -26.098267) (xy 17.283536 -26.134754) (xy 17.325916 -26.177134)
			(xy 17.362403 -26.224684) (xy 17.39237 -26.27659) (xy 17.415306 -26.331963) (xy 17.430819 -26.389856)
			(xy 17.438642 -26.449278) (xy 17.439132 -26.479246) (xy 17.439132 -27.342846) (xy 42.523664 -27.342846)
			(xy 42.523664 -26.479246) (xy 42.524154 -26.449278) (xy 42.531977 -26.389856) (xy 42.54749 -26.331963)
			(xy 42.570426 -26.27659) (xy 42.600393 -26.224684) (xy 42.63688 -26.177134) (xy 42.67926 -26.134754)
			(xy 42.72681 -26.098267) (xy 42.778716 -26.0683) (xy 42.834089 -26.045364) (xy 42.891982 -26.029851)
			(xy 42.951404 -26.022028) (xy 43.01134 -26.022028) (xy 43.070762 -26.029851) (xy 43.128655 -26.045364)
			(xy 43.184028 -26.0683) (xy 43.235934 -26.098267) (xy 43.283484 -26.134754) (xy 43.325864 -26.177134)
			(xy 43.362351 -26.224684) (xy 43.392318 -26.27659) (xy 43.415254 -26.331963) (xy 43.430767 -26.389856)
			(xy 43.43859 -26.449278) (xy 43.43908 -26.479246) (xy 43.43908 -27.342846) (xy 68.523612 -27.342846)
			(xy 68.523612 -26.479246) (xy 68.524102 -26.449278) (xy 68.531925 -26.389856) (xy 68.547438 -26.331963)
			(xy 68.570374 -26.27659) (xy 68.600341 -26.224684) (xy 68.636828 -26.177134) (xy 68.679208 -26.134754)
			(xy 68.726758 -26.098267) (xy 68.778664 -26.0683) (xy 68.834037 -26.045364) (xy 68.89193 -26.029851)
			(xy 68.951352 -26.022028) (xy 69.011288 -26.022028) (xy 69.07071 -26.029851) (xy 69.128603 -26.045364)
			(xy 69.183976 -26.0683) (xy 69.235882 -26.098267) (xy 69.283432 -26.134754) (xy 69.325812 -26.177134)
			(xy 69.362299 -26.224684) (xy 69.392266 -26.27659) (xy 69.415202 -26.331963) (xy 69.430715 -26.389856)
			(xy 69.438538 -26.449278) (xy 69.439028 -26.479246) (xy 69.439028 -27.342846) (xy 94.52356 -27.342846)
			(xy 94.52356 -26.479246) (xy 94.52405 -26.449278) (xy 94.531873 -26.389856) (xy 94.547386 -26.331963)
			(xy 94.570322 -26.27659) (xy 94.600289 -26.224684) (xy 94.636776 -26.177134) (xy 94.679156 -26.134754)
			(xy 94.726706 -26.098267) (xy 94.778612 -26.0683) (xy 94.833985 -26.045364) (xy 94.891878 -26.029851)
			(xy 94.9513 -26.022028) (xy 95.011236 -26.022028) (xy 95.070658 -26.029851) (xy 95.128551 -26.045364)
			(xy 95.183924 -26.0683) (xy 95.23583 -26.098267) (xy 95.28338 -26.134754) (xy 95.32576 -26.177134)
			(xy 95.362247 -26.224684) (xy 95.392214 -26.27659) (xy 95.41515 -26.331963) (xy 95.430663 -26.389856)
			(xy 95.438486 -26.449278) (xy 95.438976 -26.479246) (xy 95.438976 -27.342846) (xy 132.62356 -27.342846)
			(xy 132.62356 -26.479246) (xy 132.62405 -26.449262) (xy 132.631878 -26.389806) (xy 132.647399 -26.331881)
			(xy 132.670348 -26.276477) (xy 132.700332 -26.224543) (xy 132.736838 -26.176967) (xy 132.779243 -26.134562)
			(xy 132.826819 -26.098056) (xy 132.878753 -26.068072) (xy 132.934157 -26.045123) (xy 132.992082 -26.029602)
			(xy 133.051538 -26.021774) (xy 133.111506 -26.021774) (xy 133.170962 -26.029602) (xy 133.228887 -26.045123)
			(xy 133.284291 -26.068072) (xy 133.336225 -26.098056) (xy 133.383801 -26.134562) (xy 133.426206 -26.176967)
			(xy 133.462712 -26.224543) (xy 133.492696 -26.276477) (xy 133.515645 -26.331881) (xy 133.531166 -26.389806)
			(xy 133.538994 -26.449262) (xy 133.539484 -26.479246) (xy 133.539484 -27.342846) (xy 158.623508 -27.342846)
			(xy 158.623508 -26.479246) (xy 158.623998 -26.449262) (xy 158.631826 -26.389806) (xy 158.647347 -26.331881)
			(xy 158.670296 -26.276477) (xy 158.70028 -26.224543) (xy 158.736786 -26.176967) (xy 158.779191 -26.134562)
			(xy 158.826767 -26.098056) (xy 158.878701 -26.068072) (xy 158.934105 -26.045123) (xy 158.99203 -26.029602)
			(xy 159.051486 -26.021774) (xy 159.111454 -26.021774) (xy 159.17091 -26.029602) (xy 159.228835 -26.045123)
			(xy 159.284239 -26.068072) (xy 159.336173 -26.098056) (xy 159.383749 -26.134562) (xy 159.426154 -26.176967)
			(xy 159.46266 -26.224543) (xy 159.492644 -26.276477) (xy 159.515593 -26.331881) (xy 159.531114 -26.389806)
			(xy 159.538942 -26.449262) (xy 159.539432 -26.479246) (xy 159.539432 -27.342846) (xy 184.623456 -27.342846)
			(xy 184.623456 -26.479246) (xy 184.623946 -26.449262) (xy 184.631774 -26.389806) (xy 184.647295 -26.331881)
			(xy 184.670244 -26.276477) (xy 184.700228 -26.224543) (xy 184.736734 -26.176967) (xy 184.779139 -26.134562)
			(xy 184.826715 -26.098056) (xy 184.878649 -26.068072) (xy 184.934053 -26.045123) (xy 184.991978 -26.029602)
			(xy 185.051434 -26.021774) (xy 185.111402 -26.021774) (xy 185.170858 -26.029602) (xy 185.228783 -26.045123)
			(xy 185.284187 -26.068072) (xy 185.336121 -26.098056) (xy 185.383697 -26.134562) (xy 185.426102 -26.176967)
			(xy 185.462608 -26.224543) (xy 185.492592 -26.276477) (xy 185.515541 -26.331881) (xy 185.531062 -26.389806)
			(xy 185.53889 -26.449262) (xy 185.53938 -26.479246) (xy 185.53938 -27.342846) (xy 210.623404 -27.342846)
			(xy 210.623404 -26.479246) (xy 210.623894 -26.449262) (xy 210.631722 -26.389806) (xy 210.647243 -26.331881)
			(xy 210.670192 -26.276477) (xy 210.700176 -26.224543) (xy 210.736682 -26.176967) (xy 210.779087 -26.134562)
			(xy 210.826663 -26.098056) (xy 210.878597 -26.068072) (xy 210.934001 -26.045123) (xy 210.991926 -26.029602)
			(xy 211.051382 -26.021774) (xy 211.11135 -26.021774) (xy 211.170806 -26.029602) (xy 211.228731 -26.045123)
			(xy 211.284135 -26.068072) (xy 211.336069 -26.098056) (xy 211.383645 -26.134562) (xy 211.42605 -26.176967)
			(xy 211.462556 -26.224543) (xy 211.49254 -26.276477) (xy 211.515489 -26.331881) (xy 211.53101 -26.389806)
			(xy 211.538838 -26.449262) (xy 211.539328 -26.479246) (xy 211.539328 -27.342846) (xy 248.723404 -27.342846)
			(xy 248.723404 -26.479246) (xy 248.723894 -26.449262) (xy 248.731722 -26.389806) (xy 248.747243 -26.331881)
			(xy 248.770192 -26.276477) (xy 248.800176 -26.224543) (xy 248.836682 -26.176967) (xy 248.879087 -26.134562)
			(xy 248.926663 -26.098056) (xy 248.978597 -26.068072) (xy 249.034001 -26.045123) (xy 249.091926 -26.029602)
			(xy 249.151382 -26.021774) (xy 249.21135 -26.021774) (xy 249.270806 -26.029602) (xy 249.328731 -26.045123)
			(xy 249.384135 -26.068072) (xy 249.436069 -26.098056) (xy 249.483645 -26.134562) (xy 249.52605 -26.176967)
			(xy 249.562556 -26.224543) (xy 249.59254 -26.276477) (xy 249.615489 -26.331881) (xy 249.63101 -26.389806)
			(xy 249.638838 -26.449262) (xy 249.639328 -26.479246) (xy 249.639328 -27.342846) (xy 274.723352 -27.342846)
			(xy 274.723352 -26.479246) (xy 274.723842 -26.449262) (xy 274.73167 -26.389806) (xy 274.747191 -26.331881)
			(xy 274.77014 -26.276477) (xy 274.800124 -26.224543) (xy 274.83663 -26.176967) (xy 274.879035 -26.134562)
			(xy 274.926611 -26.098056) (xy 274.978545 -26.068072) (xy 275.033949 -26.045123) (xy 275.091874 -26.029602)
			(xy 275.15133 -26.021774) (xy 275.211298 -26.021774) (xy 275.270754 -26.029602) (xy 275.328679 -26.045123)
			(xy 275.384083 -26.068072) (xy 275.436017 -26.098056) (xy 275.483593 -26.134562) (xy 275.525998 -26.176967)
			(xy 275.562504 -26.224543) (xy 275.592488 -26.276477) (xy 275.615437 -26.331881) (xy 275.630958 -26.389806)
			(xy 275.638786 -26.449262) (xy 275.639276 -26.479246) (xy 275.639276 -27.342846) (xy 300.7233 -27.342846)
			(xy 300.7233 -26.479246) (xy 300.72379 -26.449262) (xy 300.731618 -26.389806) (xy 300.747139 -26.331881)
			(xy 300.770088 -26.276477) (xy 300.800072 -26.224543) (xy 300.836578 -26.176967) (xy 300.878983 -26.134562)
			(xy 300.926559 -26.098056) (xy 300.978493 -26.068072) (xy 301.033897 -26.045123) (xy 301.091822 -26.029602)
			(xy 301.151278 -26.021774) (xy 301.211246 -26.021774) (xy 301.270702 -26.029602) (xy 301.328627 -26.045123)
			(xy 301.384031 -26.068072) (xy 301.435965 -26.098056) (xy 301.483541 -26.134562) (xy 301.525946 -26.176967)
			(xy 301.562452 -26.224543) (xy 301.592436 -26.276477) (xy 301.615385 -26.331881) (xy 301.630906 -26.389806)
			(xy 301.638734 -26.449262) (xy 301.639224 -26.479246) (xy 301.639224 -27.342846) (xy 326.723248 -27.342846)
			(xy 326.723248 -26.479246) (xy 326.723738 -26.449262) (xy 326.731566 -26.389806) (xy 326.747087 -26.331881)
			(xy 326.770036 -26.276477) (xy 326.80002 -26.224543) (xy 326.836526 -26.176967) (xy 326.878931 -26.134562)
			(xy 326.926507 -26.098056) (xy 326.978441 -26.068072) (xy 327.033845 -26.045123) (xy 327.09177 -26.029602)
			(xy 327.151226 -26.021774) (xy 327.211194 -26.021774) (xy 327.27065 -26.029602) (xy 327.328575 -26.045123)
			(xy 327.383979 -26.068072) (xy 327.435913 -26.098056) (xy 327.483489 -26.134562) (xy 327.525894 -26.176967)
			(xy 327.5624 -26.224543) (xy 327.592384 -26.276477) (xy 327.615333 -26.331881) (xy 327.630854 -26.389806)
			(xy 327.638682 -26.449262) (xy 327.639172 -26.479246) (xy 327.639172 -27.342846) (xy 364.823756 -27.342846)
			(xy 364.823756 -26.479246) (xy 364.824246 -26.449278) (xy 364.832069 -26.389856) (xy 364.847582 -26.331963)
			(xy 364.870518 -26.27659) (xy 364.900485 -26.224684) (xy 364.936972 -26.177134) (xy 364.979352 -26.134754)
			(xy 365.026902 -26.098267) (xy 365.078808 -26.0683) (xy 365.134181 -26.045364) (xy 365.192074 -26.029851)
			(xy 365.251496 -26.022028) (xy 365.311432 -26.022028) (xy 365.370854 -26.029851) (xy 365.428747 -26.045364)
			(xy 365.48412 -26.0683) (xy 365.536026 -26.098267) (xy 365.583576 -26.134754) (xy 365.625956 -26.177134)
			(xy 365.662443 -26.224684) (xy 365.69241 -26.27659) (xy 365.715346 -26.331963) (xy 365.730859 -26.389856)
			(xy 365.738682 -26.449278) (xy 365.739172 -26.479246) (xy 365.739172 -27.342846) (xy 390.823704 -27.342846)
			(xy 390.823704 -26.479246) (xy 390.824194 -26.449278) (xy 390.832017 -26.389856) (xy 390.84753 -26.331963)
			(xy 390.870466 -26.27659) (xy 390.900433 -26.224684) (xy 390.93692 -26.177134) (xy 390.9793 -26.134754)
			(xy 391.02685 -26.098267) (xy 391.078756 -26.0683) (xy 391.134129 -26.045364) (xy 391.192022 -26.029851)
			(xy 391.251444 -26.022028) (xy 391.31138 -26.022028) (xy 391.370802 -26.029851) (xy 391.428695 -26.045364)
			(xy 391.484068 -26.0683) (xy 391.535974 -26.098267) (xy 391.583524 -26.134754) (xy 391.625904 -26.177134)
			(xy 391.662391 -26.224684) (xy 391.692358 -26.27659) (xy 391.715294 -26.331963) (xy 391.730807 -26.389856)
			(xy 391.73863 -26.449278) (xy 391.73912 -26.479246) (xy 391.73912 -27.342846) (xy 416.823652 -27.342846)
			(xy 416.823652 -26.479246) (xy 416.824142 -26.449278) (xy 416.831965 -26.389856) (xy 416.847478 -26.331963)
			(xy 416.870414 -26.27659) (xy 416.900381 -26.224684) (xy 416.936868 -26.177134) (xy 416.979248 -26.134754)
			(xy 417.026798 -26.098267) (xy 417.078704 -26.0683) (xy 417.134077 -26.045364) (xy 417.19197 -26.029851)
			(xy 417.251392 -26.022028) (xy 417.311328 -26.022028) (xy 417.37075 -26.029851) (xy 417.428643 -26.045364)
			(xy 417.484016 -26.0683) (xy 417.535922 -26.098267) (xy 417.583472 -26.134754) (xy 417.625852 -26.177134)
			(xy 417.662339 -26.224684) (xy 417.692306 -26.27659) (xy 417.715242 -26.331963) (xy 417.730755 -26.389856)
			(xy 417.738578 -26.449278) (xy 417.739068 -26.479246) (xy 417.739068 -27.342846) (xy 442.8236 -27.342846)
			(xy 442.8236 -26.479246) (xy 442.82409 -26.449278) (xy 442.831913 -26.389856) (xy 442.847426 -26.331963)
			(xy 442.870362 -26.27659) (xy 442.900329 -26.224684) (xy 442.936816 -26.177134) (xy 442.979196 -26.134754)
			(xy 443.026746 -26.098267) (xy 443.078652 -26.0683) (xy 443.134025 -26.045364) (xy 443.191918 -26.029851)
			(xy 443.25134 -26.022028) (xy 443.311276 -26.022028) (xy 443.370698 -26.029851) (xy 443.428591 -26.045364)
			(xy 443.483964 -26.0683) (xy 443.53587 -26.098267) (xy 443.58342 -26.134754) (xy 443.6258 -26.177134)
			(xy 443.662287 -26.224684) (xy 443.692254 -26.27659) (xy 443.71519 -26.331963) (xy 443.730703 -26.389856)
			(xy 443.738526 -26.449278) (xy 443.739016 -26.479246) (xy 443.739016 -27.342846) (xy 443.738526 -27.372814)
			(xy 443.730703 -27.432236) (xy 443.71519 -27.490129) (xy 443.692254 -27.545502) (xy 443.662287 -27.597408)
			(xy 443.6258 -27.644958) (xy 443.58342 -27.687338) (xy 443.53587 -27.723825) (xy 443.483964 -27.753792)
			(xy 443.428591 -27.776728) (xy 443.370698 -27.792241) (xy 443.311276 -27.800064) (xy 443.25134 -27.800064)
			(xy 443.191918 -27.792241) (xy 443.134025 -27.776728) (xy 443.078652 -27.753792) (xy 443.026746 -27.723825)
			(xy 442.979196 -27.687338) (xy 442.936816 -27.644958) (xy 442.900329 -27.597408) (xy 442.870362 -27.545502)
			(xy 442.847426 -27.490129) (xy 442.831913 -27.432236) (xy 442.82409 -27.372814) (xy 442.8236 -27.342846)
			(xy 417.739068 -27.342846) (xy 417.738578 -27.372814) (xy 417.730755 -27.432236) (xy 417.715242 -27.490129)
			(xy 417.692306 -27.545502) (xy 417.662339 -27.597408) (xy 417.625852 -27.644958) (xy 417.583472 -27.687338)
			(xy 417.535922 -27.723825) (xy 417.484016 -27.753792) (xy 417.428643 -27.776728) (xy 417.37075 -27.792241)
			(xy 417.311328 -27.800064) (xy 417.251392 -27.800064) (xy 417.19197 -27.792241) (xy 417.134077 -27.776728)
			(xy 417.078704 -27.753792) (xy 417.026798 -27.723825) (xy 416.979248 -27.687338) (xy 416.936868 -27.644958)
			(xy 416.900381 -27.597408) (xy 416.870414 -27.545502) (xy 416.847478 -27.490129) (xy 416.831965 -27.432236)
			(xy 416.824142 -27.372814) (xy 416.823652 -27.342846) (xy 391.73912 -27.342846) (xy 391.73863 -27.372814)
			(xy 391.730807 -27.432236) (xy 391.715294 -27.490129) (xy 391.692358 -27.545502) (xy 391.662391 -27.597408)
			(xy 391.625904 -27.644958) (xy 391.583524 -27.687338) (xy 391.535974 -27.723825) (xy 391.484068 -27.753792)
			(xy 391.428695 -27.776728) (xy 391.370802 -27.792241) (xy 391.31138 -27.800064) (xy 391.251444 -27.800064)
			(xy 391.192022 -27.792241) (xy 391.134129 -27.776728) (xy 391.078756 -27.753792) (xy 391.02685 -27.723825)
			(xy 390.9793 -27.687338) (xy 390.93692 -27.644958) (xy 390.900433 -27.597408) (xy 390.870466 -27.545502)
			(xy 390.84753 -27.490129) (xy 390.832017 -27.432236) (xy 390.824194 -27.372814) (xy 390.823704 -27.342846)
			(xy 365.739172 -27.342846) (xy 365.738682 -27.372814) (xy 365.730859 -27.432236) (xy 365.715346 -27.490129)
			(xy 365.69241 -27.545502) (xy 365.662443 -27.597408) (xy 365.625956 -27.644958) (xy 365.583576 -27.687338)
			(xy 365.536026 -27.723825) (xy 365.48412 -27.753792) (xy 365.428747 -27.776728) (xy 365.370854 -27.792241)
			(xy 365.311432 -27.800064) (xy 365.251496 -27.800064) (xy 365.192074 -27.792241) (xy 365.134181 -27.776728)
			(xy 365.078808 -27.753792) (xy 365.026902 -27.723825) (xy 364.979352 -27.687338) (xy 364.936972 -27.644958)
			(xy 364.900485 -27.597408) (xy 364.870518 -27.545502) (xy 364.847582 -27.490129) (xy 364.832069 -27.432236)
			(xy 364.824246 -27.372814) (xy 364.823756 -27.342846) (xy 327.639172 -27.342846) (xy 327.638682 -27.37283)
			(xy 327.630854 -27.432286) (xy 327.615333 -27.490211) (xy 327.592384 -27.545615) (xy 327.5624 -27.597549)
			(xy 327.525894 -27.645125) (xy 327.483489 -27.68753) (xy 327.435913 -27.724036) (xy 327.383979 -27.75402)
			(xy 327.328575 -27.776969) (xy 327.27065 -27.79249) (xy 327.211194 -27.800318) (xy 327.151226 -27.800318)
			(xy 327.09177 -27.79249) (xy 327.033845 -27.776969) (xy 326.978441 -27.75402) (xy 326.926507 -27.724036)
			(xy 326.878931 -27.68753) (xy 326.836526 -27.645125) (xy 326.80002 -27.597549) (xy 326.770036 -27.545615)
			(xy 326.747087 -27.490211) (xy 326.731566 -27.432286) (xy 326.723738 -27.37283) (xy 326.723248 -27.342846)
			(xy 301.639224 -27.342846) (xy 301.638734 -27.37283) (xy 301.630906 -27.432286) (xy 301.615385 -27.490211)
			(xy 301.592436 -27.545615) (xy 301.562452 -27.597549) (xy 301.525946 -27.645125) (xy 301.483541 -27.68753)
			(xy 301.435965 -27.724036) (xy 301.384031 -27.75402) (xy 301.328627 -27.776969) (xy 301.270702 -27.79249)
			(xy 301.211246 -27.800318) (xy 301.151278 -27.800318) (xy 301.091822 -27.79249) (xy 301.033897 -27.776969)
			(xy 300.978493 -27.75402) (xy 300.926559 -27.724036) (xy 300.878983 -27.68753) (xy 300.836578 -27.645125)
			(xy 300.800072 -27.597549) (xy 300.770088 -27.545615) (xy 300.747139 -27.490211) (xy 300.731618 -27.432286)
			(xy 300.72379 -27.37283) (xy 300.7233 -27.342846) (xy 275.639276 -27.342846) (xy 275.638786 -27.37283)
			(xy 275.630958 -27.432286) (xy 275.615437 -27.490211) (xy 275.592488 -27.545615) (xy 275.562504 -27.597549)
			(xy 275.525998 -27.645125) (xy 275.483593 -27.68753) (xy 275.436017 -27.724036) (xy 275.384083 -27.75402)
			(xy 275.328679 -27.776969) (xy 275.270754 -27.79249) (xy 275.211298 -27.800318) (xy 275.15133 -27.800318)
			(xy 275.091874 -27.79249) (xy 275.033949 -27.776969) (xy 274.978545 -27.75402) (xy 274.926611 -27.724036)
			(xy 274.879035 -27.68753) (xy 274.83663 -27.645125) (xy 274.800124 -27.597549) (xy 274.77014 -27.545615)
			(xy 274.747191 -27.490211) (xy 274.73167 -27.432286) (xy 274.723842 -27.37283) (xy 274.723352 -27.342846)
			(xy 249.639328 -27.342846) (xy 249.638838 -27.37283) (xy 249.63101 -27.432286) (xy 249.615489 -27.490211)
			(xy 249.59254 -27.545615) (xy 249.562556 -27.597549) (xy 249.52605 -27.645125) (xy 249.483645 -27.68753)
			(xy 249.436069 -27.724036) (xy 249.384135 -27.75402) (xy 249.328731 -27.776969) (xy 249.270806 -27.79249)
			(xy 249.21135 -27.800318) (xy 249.151382 -27.800318) (xy 249.091926 -27.79249) (xy 249.034001 -27.776969)
			(xy 248.978597 -27.75402) (xy 248.926663 -27.724036) (xy 248.879087 -27.68753) (xy 248.836682 -27.645125)
			(xy 248.800176 -27.597549) (xy 248.770192 -27.545615) (xy 248.747243 -27.490211) (xy 248.731722 -27.432286)
			(xy 248.723894 -27.37283) (xy 248.723404 -27.342846) (xy 211.539328 -27.342846) (xy 211.538838 -27.37283)
			(xy 211.53101 -27.432286) (xy 211.515489 -27.490211) (xy 211.49254 -27.545615) (xy 211.462556 -27.597549)
			(xy 211.42605 -27.645125) (xy 211.383645 -27.68753) (xy 211.336069 -27.724036) (xy 211.284135 -27.75402)
			(xy 211.228731 -27.776969) (xy 211.170806 -27.79249) (xy 211.11135 -27.800318) (xy 211.051382 -27.800318)
			(xy 210.991926 -27.79249) (xy 210.934001 -27.776969) (xy 210.878597 -27.75402) (xy 210.826663 -27.724036)
			(xy 210.779087 -27.68753) (xy 210.736682 -27.645125) (xy 210.700176 -27.597549) (xy 210.670192 -27.545615)
			(xy 210.647243 -27.490211) (xy 210.631722 -27.432286) (xy 210.623894 -27.37283) (xy 210.623404 -27.342846)
			(xy 185.53938 -27.342846) (xy 185.53889 -27.37283) (xy 185.531062 -27.432286) (xy 185.515541 -27.490211)
			(xy 185.492592 -27.545615) (xy 185.462608 -27.597549) (xy 185.426102 -27.645125) (xy 185.383697 -27.68753)
			(xy 185.336121 -27.724036) (xy 185.284187 -27.75402) (xy 185.228783 -27.776969) (xy 185.170858 -27.79249)
			(xy 185.111402 -27.800318) (xy 185.051434 -27.800318) (xy 184.991978 -27.79249) (xy 184.934053 -27.776969)
			(xy 184.878649 -27.75402) (xy 184.826715 -27.724036) (xy 184.779139 -27.68753) (xy 184.736734 -27.645125)
			(xy 184.700228 -27.597549) (xy 184.670244 -27.545615) (xy 184.647295 -27.490211) (xy 184.631774 -27.432286)
			(xy 184.623946 -27.37283) (xy 184.623456 -27.342846) (xy 159.539432 -27.342846) (xy 159.538942 -27.37283)
			(xy 159.531114 -27.432286) (xy 159.515593 -27.490211) (xy 159.492644 -27.545615) (xy 159.46266 -27.597549)
			(xy 159.426154 -27.645125) (xy 159.383749 -27.68753) (xy 159.336173 -27.724036) (xy 159.284239 -27.75402)
			(xy 159.228835 -27.776969) (xy 159.17091 -27.79249) (xy 159.111454 -27.800318) (xy 159.051486 -27.800318)
			(xy 158.99203 -27.79249) (xy 158.934105 -27.776969) (xy 158.878701 -27.75402) (xy 158.826767 -27.724036)
			(xy 158.779191 -27.68753) (xy 158.736786 -27.645125) (xy 158.70028 -27.597549) (xy 158.670296 -27.545615)
			(xy 158.647347 -27.490211) (xy 158.631826 -27.432286) (xy 158.623998 -27.37283) (xy 158.623508 -27.342846)
			(xy 133.539484 -27.342846) (xy 133.538994 -27.37283) (xy 133.531166 -27.432286) (xy 133.515645 -27.490211)
			(xy 133.492696 -27.545615) (xy 133.462712 -27.597549) (xy 133.426206 -27.645125) (xy 133.383801 -27.68753)
			(xy 133.336225 -27.724036) (xy 133.284291 -27.75402) (xy 133.228887 -27.776969) (xy 133.170962 -27.79249)
			(xy 133.111506 -27.800318) (xy 133.051538 -27.800318) (xy 132.992082 -27.79249) (xy 132.934157 -27.776969)
			(xy 132.878753 -27.75402) (xy 132.826819 -27.724036) (xy 132.779243 -27.68753) (xy 132.736838 -27.645125)
			(xy 132.700332 -27.597549) (xy 132.670348 -27.545615) (xy 132.647399 -27.490211) (xy 132.631878 -27.432286)
			(xy 132.62405 -27.37283) (xy 132.62356 -27.342846) (xy 95.438976 -27.342846) (xy 95.438486 -27.372814)
			(xy 95.430663 -27.432236) (xy 95.41515 -27.490129) (xy 95.392214 -27.545502) (xy 95.362247 -27.597408)
			(xy 95.32576 -27.644958) (xy 95.28338 -27.687338) (xy 95.23583 -27.723825) (xy 95.183924 -27.753792)
			(xy 95.128551 -27.776728) (xy 95.070658 -27.792241) (xy 95.011236 -27.800064) (xy 94.9513 -27.800064)
			(xy 94.891878 -27.792241) (xy 94.833985 -27.776728) (xy 94.778612 -27.753792) (xy 94.726706 -27.723825)
			(xy 94.679156 -27.687338) (xy 94.636776 -27.644958) (xy 94.600289 -27.597408) (xy 94.570322 -27.545502)
			(xy 94.547386 -27.490129) (xy 94.531873 -27.432236) (xy 94.52405 -27.372814) (xy 94.52356 -27.342846)
			(xy 69.439028 -27.342846) (xy 69.438538 -27.372814) (xy 69.430715 -27.432236) (xy 69.415202 -27.490129)
			(xy 69.392266 -27.545502) (xy 69.362299 -27.597408) (xy 69.325812 -27.644958) (xy 69.283432 -27.687338)
			(xy 69.235882 -27.723825) (xy 69.183976 -27.753792) (xy 69.128603 -27.776728) (xy 69.07071 -27.792241)
			(xy 69.011288 -27.800064) (xy 68.951352 -27.800064) (xy 68.89193 -27.792241) (xy 68.834037 -27.776728)
			(xy 68.778664 -27.753792) (xy 68.726758 -27.723825) (xy 68.679208 -27.687338) (xy 68.636828 -27.644958)
			(xy 68.600341 -27.597408) (xy 68.570374 -27.545502) (xy 68.547438 -27.490129) (xy 68.531925 -27.432236)
			(xy 68.524102 -27.372814) (xy 68.523612 -27.342846) (xy 43.43908 -27.342846) (xy 43.43859 -27.372814)
			(xy 43.430767 -27.432236) (xy 43.415254 -27.490129) (xy 43.392318 -27.545502) (xy 43.362351 -27.597408)
			(xy 43.325864 -27.644958) (xy 43.283484 -27.687338) (xy 43.235934 -27.723825) (xy 43.184028 -27.753792)
			(xy 43.128655 -27.776728) (xy 43.070762 -27.792241) (xy 43.01134 -27.800064) (xy 42.951404 -27.800064)
			(xy 42.891982 -27.792241) (xy 42.834089 -27.776728) (xy 42.778716 -27.753792) (xy 42.72681 -27.723825)
			(xy 42.67926 -27.687338) (xy 42.63688 -27.644958) (xy 42.600393 -27.597408) (xy 42.570426 -27.545502)
			(xy 42.54749 -27.490129) (xy 42.531977 -27.432236) (xy 42.524154 -27.372814) (xy 42.523664 -27.342846)
			(xy 17.439132 -27.342846) (xy 17.438642 -27.372814) (xy 17.430819 -27.432236) (xy 17.415306 -27.490129)
			(xy 17.39237 -27.545502) (xy 17.362403 -27.597408) (xy 17.325916 -27.644958) (xy 17.283536 -27.687338)
			(xy 17.235986 -27.723825) (xy 17.18408 -27.753792) (xy 17.128707 -27.776728) (xy 17.070814 -27.792241)
			(xy 17.011392 -27.800064) (xy 16.951456 -27.800064) (xy 16.892034 -27.792241) (xy 16.834141 -27.776728)
			(xy 16.778768 -27.753792) (xy 16.726862 -27.723825) (xy 16.679312 -27.687338) (xy 16.636932 -27.644958)
			(xy 16.600445 -27.597408) (xy 16.570478 -27.545502) (xy 16.547542 -27.490129) (xy 16.532029 -27.432236)
			(xy 16.524206 -27.372814) (xy 16.523716 -27.342846) (xy 1.524 -27.342846) (xy 1.524 -29.12237) (xy 8.607044 -29.12237)
			(xy 8.607044 -28.25877) (xy 8.607534 -28.228802) (xy 8.615357 -28.16938) (xy 8.63087 -28.111487)
			(xy 8.653806 -28.056114) (xy 8.683773 -28.004208) (xy 8.72026 -27.956658) (xy 8.76264 -27.914278)
			(xy 8.81019 -27.877791) (xy 8.862096 -27.847824) (xy 8.917469 -27.824888) (xy 8.975362 -27.809375)
			(xy 9.034784 -27.801552) (xy 9.09472 -27.801552) (xy 9.154142 -27.809375) (xy 9.212035 -27.824888)
			(xy 9.267408 -27.847824) (xy 9.319314 -27.877791) (xy 9.366864 -27.914278) (xy 9.409244 -27.956658)
			(xy 9.445731 -28.004208) (xy 9.475698 -28.056114) (xy 9.498634 -28.111487) (xy 9.514147 -28.16938)
			(xy 9.52197 -28.228802) (xy 9.52246 -28.25877) (xy 9.52246 -29.114242) (xy 18.847308 -29.114242)
			(xy 18.847308 -28.250642) (xy 18.847798 -28.220658) (xy 18.855626 -28.161202) (xy 18.871147 -28.103277)
			(xy 18.894096 -28.047873) (xy 18.92408 -27.995939) (xy 18.960586 -27.948363) (xy 19.002991 -27.905958)
			(xy 19.050567 -27.869452) (xy 19.102501 -27.839468) (xy 19.157905 -27.816519) (xy 19.21583 -27.800998)
			(xy 19.275286 -27.79317) (xy 19.335254 -27.79317) (xy 19.39471 -27.800998) (xy 19.452635 -27.816519)
			(xy 19.508039 -27.839468) (xy 19.559973 -27.869452) (xy 19.607549 -27.905958) (xy 19.649954 -27.948363)
			(xy 19.68646 -27.995939) (xy 19.716444 -28.047873) (xy 19.739393 -28.103277) (xy 19.754914 -28.161202)
			(xy 19.762742 -28.220658) (xy 19.763232 -28.250642) (xy 19.763232 -29.114242) (xy 19.763099 -29.12237)
			(xy 34.606992 -29.12237) (xy 34.606992 -28.25877) (xy 34.607482 -28.228802) (xy 34.615305 -28.16938)
			(xy 34.630818 -28.111487) (xy 34.653754 -28.056114) (xy 34.683721 -28.004208) (xy 34.720208 -27.956658)
			(xy 34.762588 -27.914278) (xy 34.810138 -27.877791) (xy 34.862044 -27.847824) (xy 34.917417 -27.824888)
			(xy 34.97531 -27.809375) (xy 35.034732 -27.801552) (xy 35.094668 -27.801552) (xy 35.15409 -27.809375)
			(xy 35.211983 -27.824888) (xy 35.267356 -27.847824) (xy 35.319262 -27.877791) (xy 35.366812 -27.914278)
			(xy 35.409192 -27.956658) (xy 35.445679 -28.004208) (xy 35.475646 -28.056114) (xy 35.498582 -28.111487)
			(xy 35.514095 -28.16938) (xy 35.521918 -28.228802) (xy 35.522408 -28.25877) (xy 35.522408 -29.114242)
			(xy 44.847256 -29.114242) (xy 44.847256 -28.250642) (xy 44.847746 -28.220658) (xy 44.855574 -28.161202)
			(xy 44.871095 -28.103277) (xy 44.894044 -28.047873) (xy 44.924028 -27.995939) (xy 44.960534 -27.948363)
			(xy 45.002939 -27.905958) (xy 45.050515 -27.869452) (xy 45.102449 -27.839468) (xy 45.157853 -27.816519)
			(xy 45.215778 -27.800998) (xy 45.275234 -27.79317) (xy 45.335202 -27.79317) (xy 45.394658 -27.800998)
			(xy 45.452583 -27.816519) (xy 45.507987 -27.839468) (xy 45.559921 -27.869452) (xy 45.607497 -27.905958)
			(xy 45.649902 -27.948363) (xy 45.686408 -27.995939) (xy 45.716392 -28.047873) (xy 45.739341 -28.103277)
			(xy 45.754862 -28.161202) (xy 45.76269 -28.220658) (xy 45.76318 -28.250642) (xy 45.76318 -29.114242)
			(xy 45.763047 -29.12237) (xy 60.60694 -29.12237) (xy 60.60694 -28.25877) (xy 60.60743 -28.228802)
			(xy 60.615253 -28.16938) (xy 60.630766 -28.111487) (xy 60.653702 -28.056114) (xy 60.683669 -28.004208)
			(xy 60.720156 -27.956658) (xy 60.762536 -27.914278) (xy 60.810086 -27.877791) (xy 60.861992 -27.847824)
			(xy 60.917365 -27.824888) (xy 60.975258 -27.809375) (xy 61.03468 -27.801552) (xy 61.094616 -27.801552)
			(xy 61.154038 -27.809375) (xy 61.211931 -27.824888) (xy 61.267304 -27.847824) (xy 61.31921 -27.877791)
			(xy 61.36676 -27.914278) (xy 61.40914 -27.956658) (xy 61.445627 -28.004208) (xy 61.475594 -28.056114)
			(xy 61.49853 -28.111487) (xy 61.514043 -28.16938) (xy 61.521866 -28.228802) (xy 61.522356 -28.25877)
			(xy 61.522356 -29.114242) (xy 70.847204 -29.114242) (xy 70.847204 -28.250642) (xy 70.847694 -28.220658)
			(xy 70.855522 -28.161202) (xy 70.871043 -28.103277) (xy 70.893992 -28.047873) (xy 70.923976 -27.995939)
			(xy 70.960482 -27.948363) (xy 71.002887 -27.905958) (xy 71.050463 -27.869452) (xy 71.102397 -27.839468)
			(xy 71.157801 -27.816519) (xy 71.215726 -27.800998) (xy 71.275182 -27.79317) (xy 71.33515 -27.79317)
			(xy 71.394606 -27.800998) (xy 71.452531 -27.816519) (xy 71.507935 -27.839468) (xy 71.559869 -27.869452)
			(xy 71.607445 -27.905958) (xy 71.64985 -27.948363) (xy 71.686356 -27.995939) (xy 71.71634 -28.047873)
			(xy 71.739289 -28.103277) (xy 71.75481 -28.161202) (xy 71.762638 -28.220658) (xy 71.763128 -28.250642)
			(xy 71.763128 -29.114242) (xy 71.762995 -29.12237) (xy 86.606888 -29.12237) (xy 86.606888 -28.25877)
			(xy 86.607378 -28.228802) (xy 86.615201 -28.16938) (xy 86.630714 -28.111487) (xy 86.65365 -28.056114)
			(xy 86.683617 -28.004208) (xy 86.720104 -27.956658) (xy 86.762484 -27.914278) (xy 86.810034 -27.877791)
			(xy 86.86194 -27.847824) (xy 86.917313 -27.824888) (xy 86.975206 -27.809375) (xy 87.034628 -27.801552)
			(xy 87.094564 -27.801552) (xy 87.153986 -27.809375) (xy 87.211879 -27.824888) (xy 87.267252 -27.847824)
			(xy 87.319158 -27.877791) (xy 87.366708 -27.914278) (xy 87.409088 -27.956658) (xy 87.445575 -28.004208)
			(xy 87.475542 -28.056114) (xy 87.498478 -28.111487) (xy 87.513991 -28.16938) (xy 87.521814 -28.228802)
			(xy 87.522304 -28.25877) (xy 87.522304 -29.114242) (xy 96.847152 -29.114242) (xy 96.847152 -28.250642)
			(xy 96.847642 -28.220658) (xy 96.85547 -28.161202) (xy 96.870991 -28.103277) (xy 96.89394 -28.047873)
			(xy 96.923924 -27.995939) (xy 96.96043 -27.948363) (xy 97.002835 -27.905958) (xy 97.050411 -27.869452)
			(xy 97.102345 -27.839468) (xy 97.157749 -27.816519) (xy 97.215674 -27.800998) (xy 97.27513 -27.79317)
			(xy 97.335098 -27.79317) (xy 97.394554 -27.800998) (xy 97.452479 -27.816519) (xy 97.507883 -27.839468)
			(xy 97.559817 -27.869452) (xy 97.607393 -27.905958) (xy 97.649798 -27.948363) (xy 97.686304 -27.995939)
			(xy 97.716288 -28.047873) (xy 97.739237 -28.103277) (xy 97.754758 -28.161202) (xy 97.762586 -28.220658)
			(xy 97.763076 -28.250642) (xy 97.763076 -29.114242) (xy 97.762943 -29.12237) (xy 124.706888 -29.12237)
			(xy 124.706888 -28.25877) (xy 124.707378 -28.228786) (xy 124.715206 -28.16933) (xy 124.730727 -28.111405)
			(xy 124.753676 -28.056001) (xy 124.78366 -28.004067) (xy 124.820166 -27.956491) (xy 124.862571 -27.914086)
			(xy 124.910147 -27.87758) (xy 124.962081 -27.847596) (xy 125.017485 -27.824647) (xy 125.07541 -27.809126)
			(xy 125.134866 -27.801298) (xy 125.194834 -27.801298) (xy 125.25429 -27.809126) (xy 125.312215 -27.824647)
			(xy 125.367619 -27.847596) (xy 125.419553 -27.87758) (xy 125.467129 -27.914086) (xy 125.509534 -27.956491)
			(xy 125.54604 -28.004067) (xy 125.576024 -28.056001) (xy 125.598973 -28.111405) (xy 125.614494 -28.16933)
			(xy 125.622322 -28.228786) (xy 125.622812 -28.25877) (xy 125.622812 -29.114242) (xy 134.94766 -29.114242)
			(xy 134.94766 -28.250642) (xy 134.94815 -28.220674) (xy 134.955973 -28.161252) (xy 134.971486 -28.103359)
			(xy 134.994422 -28.047986) (xy 135.024389 -27.99608) (xy 135.060876 -27.94853) (xy 135.103256 -27.90615)
			(xy 135.150806 -27.869663) (xy 135.202712 -27.839696) (xy 135.258085 -27.81676) (xy 135.315978 -27.801247)
			(xy 135.3754 -27.793424) (xy 135.435336 -27.793424) (xy 135.494758 -27.801247) (xy 135.552651 -27.81676)
			(xy 135.608024 -27.839696) (xy 135.65993 -27.869663) (xy 135.70748 -27.90615) (xy 135.74986 -27.94853)
			(xy 135.786347 -27.99608) (xy 135.816314 -28.047986) (xy 135.83925 -28.103359) (xy 135.854763 -28.161252)
			(xy 135.862586 -28.220674) (xy 135.863076 -28.250642) (xy 135.863076 -29.114242) (xy 135.862943 -29.12237)
			(xy 150.706836 -29.12237) (xy 150.706836 -28.25877) (xy 150.707326 -28.228786) (xy 150.715154 -28.16933)
			(xy 150.730675 -28.111405) (xy 150.753624 -28.056001) (xy 150.783608 -28.004067) (xy 150.820114 -27.956491)
			(xy 150.862519 -27.914086) (xy 150.910095 -27.87758) (xy 150.962029 -27.847596) (xy 151.017433 -27.824647)
			(xy 151.075358 -27.809126) (xy 151.134814 -27.801298) (xy 151.194782 -27.801298) (xy 151.254238 -27.809126)
			(xy 151.312163 -27.824647) (xy 151.367567 -27.847596) (xy 151.419501 -27.87758) (xy 151.467077 -27.914086)
			(xy 151.509482 -27.956491) (xy 151.545988 -28.004067) (xy 151.575972 -28.056001) (xy 151.598921 -28.111405)
			(xy 151.614442 -28.16933) (xy 151.62227 -28.228786) (xy 151.62276 -28.25877) (xy 151.62276 -29.114242)
			(xy 160.947608 -29.114242) (xy 160.947608 -28.250642) (xy 160.948098 -28.220674) (xy 160.955921 -28.161252)
			(xy 160.971434 -28.103359) (xy 160.99437 -28.047986) (xy 161.024337 -27.99608) (xy 161.060824 -27.94853)
			(xy 161.103204 -27.90615) (xy 161.150754 -27.869663) (xy 161.20266 -27.839696) (xy 161.258033 -27.81676)
			(xy 161.315926 -27.801247) (xy 161.375348 -27.793424) (xy 161.435284 -27.793424) (xy 161.494706 -27.801247)
			(xy 161.552599 -27.81676) (xy 161.607972 -27.839696) (xy 161.659878 -27.869663) (xy 161.707428 -27.90615)
			(xy 161.749808 -27.94853) (xy 161.786295 -27.99608) (xy 161.816262 -28.047986) (xy 161.839198 -28.103359)
			(xy 161.854711 -28.161252) (xy 161.862534 -28.220674) (xy 161.863024 -28.250642) (xy 161.863024 -29.114242)
			(xy 161.862891 -29.12237) (xy 176.706784 -29.12237) (xy 176.706784 -28.25877) (xy 176.707274 -28.228786)
			(xy 176.715102 -28.16933) (xy 176.730623 -28.111405) (xy 176.753572 -28.056001) (xy 176.783556 -28.004067)
			(xy 176.820062 -27.956491) (xy 176.862467 -27.914086) (xy 176.910043 -27.87758) (xy 176.961977 -27.847596)
			(xy 177.017381 -27.824647) (xy 177.075306 -27.809126) (xy 177.134762 -27.801298) (xy 177.19473 -27.801298)
			(xy 177.254186 -27.809126) (xy 177.312111 -27.824647) (xy 177.367515 -27.847596) (xy 177.419449 -27.87758)
			(xy 177.467025 -27.914086) (xy 177.50943 -27.956491) (xy 177.545936 -28.004067) (xy 177.57592 -28.056001)
			(xy 177.598869 -28.111405) (xy 177.61439 -28.16933) (xy 177.622218 -28.228786) (xy 177.622708 -28.25877)
			(xy 177.622708 -29.114242) (xy 186.947556 -29.114242) (xy 186.947556 -28.250642) (xy 186.948046 -28.220674)
			(xy 186.955869 -28.161252) (xy 186.971382 -28.103359) (xy 186.994318 -28.047986) (xy 187.024285 -27.99608)
			(xy 187.060772 -27.94853) (xy 187.103152 -27.90615) (xy 187.150702 -27.869663) (xy 187.202608 -27.839696)
			(xy 187.257981 -27.81676) (xy 187.315874 -27.801247) (xy 187.375296 -27.793424) (xy 187.435232 -27.793424)
			(xy 187.494654 -27.801247) (xy 187.552547 -27.81676) (xy 187.60792 -27.839696) (xy 187.659826 -27.869663)
			(xy 187.707376 -27.90615) (xy 187.749756 -27.94853) (xy 187.786243 -27.99608) (xy 187.81621 -28.047986)
			(xy 187.839146 -28.103359) (xy 187.854659 -28.161252) (xy 187.862482 -28.220674) (xy 187.862972 -28.250642)
			(xy 187.862972 -29.114242) (xy 187.862839 -29.12237) (xy 202.706732 -29.12237) (xy 202.706732 -28.25877)
			(xy 202.707222 -28.228786) (xy 202.71505 -28.16933) (xy 202.730571 -28.111405) (xy 202.75352 -28.056001)
			(xy 202.783504 -28.004067) (xy 202.82001 -27.956491) (xy 202.862415 -27.914086) (xy 202.909991 -27.87758)
			(xy 202.961925 -27.847596) (xy 203.017329 -27.824647) (xy 203.075254 -27.809126) (xy 203.13471 -27.801298)
			(xy 203.194678 -27.801298) (xy 203.254134 -27.809126) (xy 203.312059 -27.824647) (xy 203.367463 -27.847596)
			(xy 203.419397 -27.87758) (xy 203.466973 -27.914086) (xy 203.509378 -27.956491) (xy 203.545884 -28.004067)
			(xy 203.575868 -28.056001) (xy 203.598817 -28.111405) (xy 203.614338 -28.16933) (xy 203.622166 -28.228786)
			(xy 203.622656 -28.25877) (xy 203.622656 -29.114242) (xy 212.947504 -29.114242) (xy 212.947504 -28.250642)
			(xy 212.947994 -28.220674) (xy 212.955817 -28.161252) (xy 212.97133 -28.103359) (xy 212.994266 -28.047986)
			(xy 213.024233 -27.99608) (xy 213.06072 -27.94853) (xy 213.1031 -27.90615) (xy 213.15065 -27.869663)
			(xy 213.202556 -27.839696) (xy 213.257929 -27.81676) (xy 213.315822 -27.801247) (xy 213.375244 -27.793424)
			(xy 213.43518 -27.793424) (xy 213.494602 -27.801247) (xy 213.552495 -27.81676) (xy 213.607868 -27.839696)
			(xy 213.659774 -27.869663) (xy 213.707324 -27.90615) (xy 213.749704 -27.94853) (xy 213.786191 -27.99608)
			(xy 213.816158 -28.047986) (xy 213.839094 -28.103359) (xy 213.854607 -28.161252) (xy 213.86243 -28.220674)
			(xy 213.86292 -28.250642) (xy 213.86292 -29.114242) (xy 213.862787 -29.12237) (xy 240.806732 -29.12237)
			(xy 240.806732 -28.25877) (xy 240.807222 -28.228786) (xy 240.81505 -28.16933) (xy 240.830571 -28.111405)
			(xy 240.85352 -28.056001) (xy 240.883504 -28.004067) (xy 240.92001 -27.956491) (xy 240.962415 -27.914086)
			(xy 241.009991 -27.87758) (xy 241.061925 -27.847596) (xy 241.117329 -27.824647) (xy 241.175254 -27.809126)
			(xy 241.23471 -27.801298) (xy 241.294678 -27.801298) (xy 241.354134 -27.809126) (xy 241.412059 -27.824647)
			(xy 241.467463 -27.847596) (xy 241.519397 -27.87758) (xy 241.566973 -27.914086) (xy 241.609378 -27.956491)
			(xy 241.645884 -28.004067) (xy 241.675868 -28.056001) (xy 241.698817 -28.111405) (xy 241.714338 -28.16933)
			(xy 241.722166 -28.228786) (xy 241.722656 -28.25877) (xy 241.722656 -29.114242) (xy 251.047504 -29.114242)
			(xy 251.047504 -28.250642) (xy 251.047994 -28.220674) (xy 251.055817 -28.161252) (xy 251.07133 -28.103359)
			(xy 251.094266 -28.047986) (xy 251.124233 -27.99608) (xy 251.16072 -27.94853) (xy 251.2031 -27.90615)
			(xy 251.25065 -27.869663) (xy 251.302556 -27.839696) (xy 251.357929 -27.81676) (xy 251.415822 -27.801247)
			(xy 251.475244 -27.793424) (xy 251.53518 -27.793424) (xy 251.594602 -27.801247) (xy 251.652495 -27.81676)
			(xy 251.707868 -27.839696) (xy 251.759774 -27.869663) (xy 251.807324 -27.90615) (xy 251.849704 -27.94853)
			(xy 251.886191 -27.99608) (xy 251.916158 -28.047986) (xy 251.939094 -28.103359) (xy 251.954607 -28.161252)
			(xy 251.96243 -28.220674) (xy 251.96292 -28.250642) (xy 251.96292 -29.114242) (xy 251.962787 -29.12237)
			(xy 266.80668 -29.12237) (xy 266.80668 -28.25877) (xy 266.80717 -28.228786) (xy 266.814998 -28.16933)
			(xy 266.830519 -28.111405) (xy 266.853468 -28.056001) (xy 266.883452 -28.004067) (xy 266.919958 -27.956491)
			(xy 266.962363 -27.914086) (xy 267.009939 -27.87758) (xy 267.061873 -27.847596) (xy 267.117277 -27.824647)
			(xy 267.175202 -27.809126) (xy 267.234658 -27.801298) (xy 267.294626 -27.801298) (xy 267.354082 -27.809126)
			(xy 267.412007 -27.824647) (xy 267.467411 -27.847596) (xy 267.519345 -27.87758) (xy 267.566921 -27.914086)
			(xy 267.609326 -27.956491) (xy 267.645832 -28.004067) (xy 267.675816 -28.056001) (xy 267.698765 -28.111405)
			(xy 267.714286 -28.16933) (xy 267.722114 -28.228786) (xy 267.722604 -28.25877) (xy 267.722604 -29.114242)
			(xy 277.047452 -29.114242) (xy 277.047452 -28.250642) (xy 277.047942 -28.220674) (xy 277.055765 -28.161252)
			(xy 277.071278 -28.103359) (xy 277.094214 -28.047986) (xy 277.124181 -27.99608) (xy 277.160668 -27.94853)
			(xy 277.203048 -27.90615) (xy 277.250598 -27.869663) (xy 277.302504 -27.839696) (xy 277.357877 -27.81676)
			(xy 277.41577 -27.801247) (xy 277.475192 -27.793424) (xy 277.535128 -27.793424) (xy 277.59455 -27.801247)
			(xy 277.652443 -27.81676) (xy 277.707816 -27.839696) (xy 277.759722 -27.869663) (xy 277.807272 -27.90615)
			(xy 277.849652 -27.94853) (xy 277.886139 -27.99608) (xy 277.916106 -28.047986) (xy 277.939042 -28.103359)
			(xy 277.954555 -28.161252) (xy 277.962378 -28.220674) (xy 277.962868 -28.250642) (xy 277.962868 -29.114242)
			(xy 277.962735 -29.12237) (xy 292.806628 -29.12237) (xy 292.806628 -28.25877) (xy 292.807118 -28.228786)
			(xy 292.814946 -28.16933) (xy 292.830467 -28.111405) (xy 292.853416 -28.056001) (xy 292.8834 -28.004067)
			(xy 292.919906 -27.956491) (xy 292.962311 -27.914086) (xy 293.009887 -27.87758) (xy 293.061821 -27.847596)
			(xy 293.117225 -27.824647) (xy 293.17515 -27.809126) (xy 293.234606 -27.801298) (xy 293.294574 -27.801298)
			(xy 293.35403 -27.809126) (xy 293.411955 -27.824647) (xy 293.467359 -27.847596) (xy 293.519293 -27.87758)
			(xy 293.566869 -27.914086) (xy 293.609274 -27.956491) (xy 293.64578 -28.004067) (xy 293.675764 -28.056001)
			(xy 293.698713 -28.111405) (xy 293.714234 -28.16933) (xy 293.722062 -28.228786) (xy 293.722552 -28.25877)
			(xy 293.722552 -29.114242) (xy 303.0474 -29.114242) (xy 303.0474 -28.250642) (xy 303.04789 -28.220674)
			(xy 303.055713 -28.161252) (xy 303.071226 -28.103359) (xy 303.094162 -28.047986) (xy 303.124129 -27.99608)
			(xy 303.160616 -27.94853) (xy 303.202996 -27.90615) (xy 303.250546 -27.869663) (xy 303.302452 -27.839696)
			(xy 303.357825 -27.81676) (xy 303.415718 -27.801247) (xy 303.47514 -27.793424) (xy 303.535076 -27.793424)
			(xy 303.594498 -27.801247) (xy 303.652391 -27.81676) (xy 303.707764 -27.839696) (xy 303.75967 -27.869663)
			(xy 303.80722 -27.90615) (xy 303.8496 -27.94853) (xy 303.886087 -27.99608) (xy 303.916054 -28.047986)
			(xy 303.93899 -28.103359) (xy 303.954503 -28.161252) (xy 303.962326 -28.220674) (xy 303.962816 -28.250642)
			(xy 303.962816 -29.114242) (xy 303.962683 -29.12237) (xy 318.806576 -29.12237) (xy 318.806576 -28.25877)
			(xy 318.807066 -28.228786) (xy 318.814894 -28.16933) (xy 318.830415 -28.111405) (xy 318.853364 -28.056001)
			(xy 318.883348 -28.004067) (xy 318.919854 -27.956491) (xy 318.962259 -27.914086) (xy 319.009835 -27.87758)
			(xy 319.061769 -27.847596) (xy 319.117173 -27.824647) (xy 319.175098 -27.809126) (xy 319.234554 -27.801298)
			(xy 319.294522 -27.801298) (xy 319.353978 -27.809126) (xy 319.411903 -27.824647) (xy 319.467307 -27.847596)
			(xy 319.519241 -27.87758) (xy 319.566817 -27.914086) (xy 319.609222 -27.956491) (xy 319.645728 -28.004067)
			(xy 319.675712 -28.056001) (xy 319.698661 -28.111405) (xy 319.714182 -28.16933) (xy 319.72201 -28.228786)
			(xy 319.7225 -28.25877) (xy 319.7225 -29.114242) (xy 329.047348 -29.114242) (xy 329.047348 -28.250642)
			(xy 329.047838 -28.220674) (xy 329.055661 -28.161252) (xy 329.071174 -28.103359) (xy 329.09411 -28.047986)
			(xy 329.124077 -27.99608) (xy 329.160564 -27.94853) (xy 329.202944 -27.90615) (xy 329.250494 -27.869663)
			(xy 329.3024 -27.839696) (xy 329.357773 -27.81676) (xy 329.415666 -27.801247) (xy 329.475088 -27.793424)
			(xy 329.535024 -27.793424) (xy 329.594446 -27.801247) (xy 329.652339 -27.81676) (xy 329.707712 -27.839696)
			(xy 329.759618 -27.869663) (xy 329.807168 -27.90615) (xy 329.849548 -27.94853) (xy 329.886035 -27.99608)
			(xy 329.916002 -28.047986) (xy 329.938938 -28.103359) (xy 329.954451 -28.161252) (xy 329.962274 -28.220674)
			(xy 329.962764 -28.250642) (xy 329.962764 -29.114242) (xy 329.962631 -29.12237) (xy 356.907084 -29.12237)
			(xy 356.907084 -28.25877) (xy 356.907574 -28.228802) (xy 356.915397 -28.16938) (xy 356.93091 -28.111487)
			(xy 356.953846 -28.056114) (xy 356.983813 -28.004208) (xy 357.0203 -27.956658) (xy 357.06268 -27.914278)
			(xy 357.11023 -27.877791) (xy 357.162136 -27.847824) (xy 357.217509 -27.824888) (xy 357.275402 -27.809375)
			(xy 357.334824 -27.801552) (xy 357.39476 -27.801552) (xy 357.454182 -27.809375) (xy 357.512075 -27.824888)
			(xy 357.567448 -27.847824) (xy 357.619354 -27.877791) (xy 357.666904 -27.914278) (xy 357.709284 -27.956658)
			(xy 357.745771 -28.004208) (xy 357.775738 -28.056114) (xy 357.798674 -28.111487) (xy 357.814187 -28.16938)
			(xy 357.82201 -28.228802) (xy 357.8225 -28.25877) (xy 357.8225 -29.114242) (xy 367.147348 -29.114242)
			(xy 367.147348 -28.250642) (xy 367.147838 -28.220658) (xy 367.155666 -28.161202) (xy 367.171187 -28.103277)
			(xy 367.194136 -28.047873) (xy 367.22412 -27.995939) (xy 367.260626 -27.948363) (xy 367.303031 -27.905958)
			(xy 367.350607 -27.869452) (xy 367.402541 -27.839468) (xy 367.457945 -27.816519) (xy 367.51587 -27.800998)
			(xy 367.575326 -27.79317) (xy 367.635294 -27.79317) (xy 367.69475 -27.800998) (xy 367.752675 -27.816519)
			(xy 367.808079 -27.839468) (xy 367.860013 -27.869452) (xy 367.907589 -27.905958) (xy 367.949994 -27.948363)
			(xy 367.9865 -27.995939) (xy 368.016484 -28.047873) (xy 368.039433 -28.103277) (xy 368.054954 -28.161202)
			(xy 368.062782 -28.220658) (xy 368.063272 -28.250642) (xy 368.063272 -29.114242) (xy 368.063139 -29.12237)
			(xy 382.907032 -29.12237) (xy 382.907032 -28.25877) (xy 382.907522 -28.228802) (xy 382.915345 -28.16938)
			(xy 382.930858 -28.111487) (xy 382.953794 -28.056114) (xy 382.983761 -28.004208) (xy 383.020248 -27.956658)
			(xy 383.062628 -27.914278) (xy 383.110178 -27.877791) (xy 383.162084 -27.847824) (xy 383.217457 -27.824888)
			(xy 383.27535 -27.809375) (xy 383.334772 -27.801552) (xy 383.394708 -27.801552) (xy 383.45413 -27.809375)
			(xy 383.512023 -27.824888) (xy 383.567396 -27.847824) (xy 383.619302 -27.877791) (xy 383.666852 -27.914278)
			(xy 383.709232 -27.956658) (xy 383.745719 -28.004208) (xy 383.775686 -28.056114) (xy 383.798622 -28.111487)
			(xy 383.814135 -28.16938) (xy 383.821958 -28.228802) (xy 383.822448 -28.25877) (xy 383.822448 -29.114242)
			(xy 393.147296 -29.114242) (xy 393.147296 -28.250642) (xy 393.147786 -28.220658) (xy 393.155614 -28.161202)
			(xy 393.171135 -28.103277) (xy 393.194084 -28.047873) (xy 393.224068 -27.995939) (xy 393.260574 -27.948363)
			(xy 393.302979 -27.905958) (xy 393.350555 -27.869452) (xy 393.402489 -27.839468) (xy 393.457893 -27.816519)
			(xy 393.515818 -27.800998) (xy 393.575274 -27.79317) (xy 393.635242 -27.79317) (xy 393.694698 -27.800998)
			(xy 393.752623 -27.816519) (xy 393.808027 -27.839468) (xy 393.859961 -27.869452) (xy 393.907537 -27.905958)
			(xy 393.949942 -27.948363) (xy 393.986448 -27.995939) (xy 394.016432 -28.047873) (xy 394.039381 -28.103277)
			(xy 394.054902 -28.161202) (xy 394.06273 -28.220658) (xy 394.06322 -28.250642) (xy 394.06322 -29.114242)
			(xy 394.063087 -29.12237) (xy 408.90698 -29.12237) (xy 408.90698 -28.25877) (xy 408.90747 -28.228802)
			(xy 408.915293 -28.16938) (xy 408.930806 -28.111487) (xy 408.953742 -28.056114) (xy 408.983709 -28.004208)
			(xy 409.020196 -27.956658) (xy 409.062576 -27.914278) (xy 409.110126 -27.877791) (xy 409.162032 -27.847824)
			(xy 409.217405 -27.824888) (xy 409.275298 -27.809375) (xy 409.33472 -27.801552) (xy 409.394656 -27.801552)
			(xy 409.454078 -27.809375) (xy 409.511971 -27.824888) (xy 409.567344 -27.847824) (xy 409.61925 -27.877791)
			(xy 409.6668 -27.914278) (xy 409.70918 -27.956658) (xy 409.745667 -28.004208) (xy 409.775634 -28.056114)
			(xy 409.79857 -28.111487) (xy 409.814083 -28.16938) (xy 409.821906 -28.228802) (xy 409.822396 -28.25877)
			(xy 409.822396 -29.114242) (xy 419.147244 -29.114242) (xy 419.147244 -28.250642) (xy 419.147734 -28.220658)
			(xy 419.155562 -28.161202) (xy 419.171083 -28.103277) (xy 419.194032 -28.047873) (xy 419.224016 -27.995939)
			(xy 419.260522 -27.948363) (xy 419.302927 -27.905958) (xy 419.350503 -27.869452) (xy 419.402437 -27.839468)
			(xy 419.457841 -27.816519) (xy 419.515766 -27.800998) (xy 419.575222 -27.79317) (xy 419.63519 -27.79317)
			(xy 419.694646 -27.800998) (xy 419.752571 -27.816519) (xy 419.807975 -27.839468) (xy 419.859909 -27.869452)
			(xy 419.907485 -27.905958) (xy 419.94989 -27.948363) (xy 419.986396 -27.995939) (xy 420.01638 -28.047873)
			(xy 420.039329 -28.103277) (xy 420.05485 -28.161202) (xy 420.062678 -28.220658) (xy 420.063168 -28.250642)
			(xy 420.063168 -29.114242) (xy 420.063035 -29.12237) (xy 434.906928 -29.12237) (xy 434.906928 -28.25877)
			(xy 434.907418 -28.228802) (xy 434.915241 -28.16938) (xy 434.930754 -28.111487) (xy 434.95369 -28.056114)
			(xy 434.983657 -28.004208) (xy 435.020144 -27.956658) (xy 435.062524 -27.914278) (xy 435.110074 -27.877791)
			(xy 435.16198 -27.847824) (xy 435.217353 -27.824888) (xy 435.275246 -27.809375) (xy 435.334668 -27.801552)
			(xy 435.394604 -27.801552) (xy 435.454026 -27.809375) (xy 435.511919 -27.824888) (xy 435.567292 -27.847824)
			(xy 435.619198 -27.877791) (xy 435.666748 -27.914278) (xy 435.709128 -27.956658) (xy 435.745615 -28.004208)
			(xy 435.775582 -28.056114) (xy 435.798518 -28.111487) (xy 435.814031 -28.16938) (xy 435.821854 -28.228802)
			(xy 435.822344 -28.25877) (xy 435.822344 -29.114242) (xy 445.147192 -29.114242) (xy 445.147192 -28.250642)
			(xy 445.147682 -28.220658) (xy 445.15551 -28.161202) (xy 445.171031 -28.103277) (xy 445.19398 -28.047873)
			(xy 445.223964 -27.995939) (xy 445.26047 -27.948363) (xy 445.302875 -27.905958) (xy 445.350451 -27.869452)
			(xy 445.402385 -27.839468) (xy 445.457789 -27.816519) (xy 445.515714 -27.800998) (xy 445.57517 -27.79317)
			(xy 445.635138 -27.79317) (xy 445.694594 -27.800998) (xy 445.752519 -27.816519) (xy 445.807923 -27.839468)
			(xy 445.859857 -27.869452) (xy 445.907433 -27.905958) (xy 445.949838 -27.948363) (xy 445.986344 -27.995939)
			(xy 446.016328 -28.047873) (xy 446.039277 -28.103277) (xy 446.054798 -28.161202) (xy 446.062626 -28.220658)
			(xy 446.063116 -28.250642) (xy 446.063116 -29.114242) (xy 446.062626 -29.144226) (xy 446.054798 -29.203682)
			(xy 446.039277 -29.261607) (xy 446.016328 -29.317011) (xy 445.986344 -29.368945) (xy 445.949838 -29.416521)
			(xy 445.907433 -29.458926) (xy 445.859857 -29.495432) (xy 445.807923 -29.525416) (xy 445.752519 -29.548365)
			(xy 445.694594 -29.563886) (xy 445.635138 -29.571714) (xy 445.57517 -29.571714) (xy 445.515714 -29.563886)
			(xy 445.457789 -29.548365) (xy 445.402385 -29.525416) (xy 445.350451 -29.495432) (xy 445.302875 -29.458926)
			(xy 445.26047 -29.416521) (xy 445.223964 -29.368945) (xy 445.19398 -29.317011) (xy 445.171031 -29.261607)
			(xy 445.15551 -29.203682) (xy 445.147682 -29.144226) (xy 445.147192 -29.114242) (xy 435.822344 -29.114242)
			(xy 435.822344 -29.12237) (xy 435.821854 -29.152338) (xy 435.814031 -29.21176) (xy 435.798518 -29.269653)
			(xy 435.775582 -29.325026) (xy 435.745615 -29.376932) (xy 435.709128 -29.424482) (xy 435.666748 -29.466862)
			(xy 435.619198 -29.503349) (xy 435.567292 -29.533316) (xy 435.511919 -29.556252) (xy 435.454026 -29.571765)
			(xy 435.394604 -29.579588) (xy 435.334668 -29.579588) (xy 435.275246 -29.571765) (xy 435.217353 -29.556252)
			(xy 435.16198 -29.533316) (xy 435.110074 -29.503349) (xy 435.062524 -29.466862) (xy 435.020144 -29.424482)
			(xy 434.983657 -29.376932) (xy 434.95369 -29.325026) (xy 434.930754 -29.269653) (xy 434.915241 -29.21176)
			(xy 434.907418 -29.152338) (xy 434.906928 -29.12237) (xy 420.063035 -29.12237) (xy 420.062678 -29.144226)
			(xy 420.05485 -29.203682) (xy 420.039329 -29.261607) (xy 420.01638 -29.317011) (xy 419.986396 -29.368945)
			(xy 419.94989 -29.416521) (xy 419.907485 -29.458926) (xy 419.859909 -29.495432) (xy 419.807975 -29.525416)
			(xy 419.752571 -29.548365) (xy 419.694646 -29.563886) (xy 419.63519 -29.571714) (xy 419.575222 -29.571714)
			(xy 419.515766 -29.563886) (xy 419.457841 -29.548365) (xy 419.402437 -29.525416) (xy 419.350503 -29.495432)
			(xy 419.302927 -29.458926) (xy 419.260522 -29.416521) (xy 419.224016 -29.368945) (xy 419.194032 -29.317011)
			(xy 419.171083 -29.261607) (xy 419.155562 -29.203682) (xy 419.147734 -29.144226) (xy 419.147244 -29.114242)
			(xy 409.822396 -29.114242) (xy 409.822396 -29.12237) (xy 409.821906 -29.152338) (xy 409.814083 -29.21176)
			(xy 409.79857 -29.269653) (xy 409.775634 -29.325026) (xy 409.745667 -29.376932) (xy 409.70918 -29.424482)
			(xy 409.6668 -29.466862) (xy 409.61925 -29.503349) (xy 409.567344 -29.533316) (xy 409.511971 -29.556252)
			(xy 409.454078 -29.571765) (xy 409.394656 -29.579588) (xy 409.33472 -29.579588) (xy 409.275298 -29.571765)
			(xy 409.217405 -29.556252) (xy 409.162032 -29.533316) (xy 409.110126 -29.503349) (xy 409.062576 -29.466862)
			(xy 409.020196 -29.424482) (xy 408.983709 -29.376932) (xy 408.953742 -29.325026) (xy 408.930806 -29.269653)
			(xy 408.915293 -29.21176) (xy 408.90747 -29.152338) (xy 408.90698 -29.12237) (xy 394.063087 -29.12237)
			(xy 394.06273 -29.144226) (xy 394.054902 -29.203682) (xy 394.039381 -29.261607) (xy 394.016432 -29.317011)
			(xy 393.986448 -29.368945) (xy 393.949942 -29.416521) (xy 393.907537 -29.458926) (xy 393.859961 -29.495432)
			(xy 393.808027 -29.525416) (xy 393.752623 -29.548365) (xy 393.694698 -29.563886) (xy 393.635242 -29.571714)
			(xy 393.575274 -29.571714) (xy 393.515818 -29.563886) (xy 393.457893 -29.548365) (xy 393.402489 -29.525416)
			(xy 393.350555 -29.495432) (xy 393.302979 -29.458926) (xy 393.260574 -29.416521) (xy 393.224068 -29.368945)
			(xy 393.194084 -29.317011) (xy 393.171135 -29.261607) (xy 393.155614 -29.203682) (xy 393.147786 -29.144226)
			(xy 393.147296 -29.114242) (xy 383.822448 -29.114242) (xy 383.822448 -29.12237) (xy 383.821958 -29.152338)
			(xy 383.814135 -29.21176) (xy 383.798622 -29.269653) (xy 383.775686 -29.325026) (xy 383.745719 -29.376932)
			(xy 383.709232 -29.424482) (xy 383.666852 -29.466862) (xy 383.619302 -29.503349) (xy 383.567396 -29.533316)
			(xy 383.512023 -29.556252) (xy 383.45413 -29.571765) (xy 383.394708 -29.579588) (xy 383.334772 -29.579588)
			(xy 383.27535 -29.571765) (xy 383.217457 -29.556252) (xy 383.162084 -29.533316) (xy 383.110178 -29.503349)
			(xy 383.062628 -29.466862) (xy 383.020248 -29.424482) (xy 382.983761 -29.376932) (xy 382.953794 -29.325026)
			(xy 382.930858 -29.269653) (xy 382.915345 -29.21176) (xy 382.907522 -29.152338) (xy 382.907032 -29.12237)
			(xy 368.063139 -29.12237) (xy 368.062782 -29.144226) (xy 368.054954 -29.203682) (xy 368.039433 -29.261607)
			(xy 368.016484 -29.317011) (xy 367.9865 -29.368945) (xy 367.949994 -29.416521) (xy 367.907589 -29.458926)
			(xy 367.860013 -29.495432) (xy 367.808079 -29.525416) (xy 367.752675 -29.548365) (xy 367.69475 -29.563886)
			(xy 367.635294 -29.571714) (xy 367.575326 -29.571714) (xy 367.51587 -29.563886) (xy 367.457945 -29.548365)
			(xy 367.402541 -29.525416) (xy 367.350607 -29.495432) (xy 367.303031 -29.458926) (xy 367.260626 -29.416521)
			(xy 367.22412 -29.368945) (xy 367.194136 -29.317011) (xy 367.171187 -29.261607) (xy 367.155666 -29.203682)
			(xy 367.147838 -29.144226) (xy 367.147348 -29.114242) (xy 357.8225 -29.114242) (xy 357.8225 -29.12237)
			(xy 357.82201 -29.152338) (xy 357.814187 -29.21176) (xy 357.798674 -29.269653) (xy 357.775738 -29.325026)
			(xy 357.745771 -29.376932) (xy 357.709284 -29.424482) (xy 357.666904 -29.466862) (xy 357.619354 -29.503349)
			(xy 357.567448 -29.533316) (xy 357.512075 -29.556252) (xy 357.454182 -29.571765) (xy 357.39476 -29.579588)
			(xy 357.334824 -29.579588) (xy 357.275402 -29.571765) (xy 357.217509 -29.556252) (xy 357.162136 -29.533316)
			(xy 357.11023 -29.503349) (xy 357.06268 -29.466862) (xy 357.0203 -29.424482) (xy 356.983813 -29.376932)
			(xy 356.953846 -29.325026) (xy 356.93091 -29.269653) (xy 356.915397 -29.21176) (xy 356.907574 -29.152338)
			(xy 356.907084 -29.12237) (xy 329.962631 -29.12237) (xy 329.962274 -29.14421) (xy 329.954451 -29.203632)
			(xy 329.938938 -29.261525) (xy 329.916002 -29.316898) (xy 329.886035 -29.368804) (xy 329.849548 -29.416354)
			(xy 329.807168 -29.458734) (xy 329.759618 -29.495221) (xy 329.707712 -29.525188) (xy 329.652339 -29.548124)
			(xy 329.594446 -29.563637) (xy 329.535024 -29.57146) (xy 329.475088 -29.57146) (xy 329.415666 -29.563637)
			(xy 329.357773 -29.548124) (xy 329.3024 -29.525188) (xy 329.250494 -29.495221) (xy 329.202944 -29.458734)
			(xy 329.160564 -29.416354) (xy 329.124077 -29.368804) (xy 329.09411 -29.316898) (xy 329.071174 -29.261525)
			(xy 329.055661 -29.203632) (xy 329.047838 -29.14421) (xy 329.047348 -29.114242) (xy 319.7225 -29.114242)
			(xy 319.7225 -29.12237) (xy 319.72201 -29.152354) (xy 319.714182 -29.21181) (xy 319.698661 -29.269735)
			(xy 319.675712 -29.325139) (xy 319.645728 -29.377073) (xy 319.609222 -29.424649) (xy 319.566817 -29.467054)
			(xy 319.519241 -29.50356) (xy 319.467307 -29.533544) (xy 319.411903 -29.556493) (xy 319.353978 -29.572014)
			(xy 319.294522 -29.579842) (xy 319.234554 -29.579842) (xy 319.175098 -29.572014) (xy 319.117173 -29.556493)
			(xy 319.061769 -29.533544) (xy 319.009835 -29.50356) (xy 318.962259 -29.467054) (xy 318.919854 -29.424649)
			(xy 318.883348 -29.377073) (xy 318.853364 -29.325139) (xy 318.830415 -29.269735) (xy 318.814894 -29.21181)
			(xy 318.807066 -29.152354) (xy 318.806576 -29.12237) (xy 303.962683 -29.12237) (xy 303.962326 -29.14421)
			(xy 303.954503 -29.203632) (xy 303.93899 -29.261525) (xy 303.916054 -29.316898) (xy 303.886087 -29.368804)
			(xy 303.8496 -29.416354) (xy 303.80722 -29.458734) (xy 303.75967 -29.495221) (xy 303.707764 -29.525188)
			(xy 303.652391 -29.548124) (xy 303.594498 -29.563637) (xy 303.535076 -29.57146) (xy 303.47514 -29.57146)
			(xy 303.415718 -29.563637) (xy 303.357825 -29.548124) (xy 303.302452 -29.525188) (xy 303.250546 -29.495221)
			(xy 303.202996 -29.458734) (xy 303.160616 -29.416354) (xy 303.124129 -29.368804) (xy 303.094162 -29.316898)
			(xy 303.071226 -29.261525) (xy 303.055713 -29.203632) (xy 303.04789 -29.14421) (xy 303.0474 -29.114242)
			(xy 293.722552 -29.114242) (xy 293.722552 -29.12237) (xy 293.722062 -29.152354) (xy 293.714234 -29.21181)
			(xy 293.698713 -29.269735) (xy 293.675764 -29.325139) (xy 293.64578 -29.377073) (xy 293.609274 -29.424649)
			(xy 293.566869 -29.467054) (xy 293.519293 -29.50356) (xy 293.467359 -29.533544) (xy 293.411955 -29.556493)
			(xy 293.35403 -29.572014) (xy 293.294574 -29.579842) (xy 293.234606 -29.579842) (xy 293.17515 -29.572014)
			(xy 293.117225 -29.556493) (xy 293.061821 -29.533544) (xy 293.009887 -29.50356) (xy 292.962311 -29.467054)
			(xy 292.919906 -29.424649) (xy 292.8834 -29.377073) (xy 292.853416 -29.325139) (xy 292.830467 -29.269735)
			(xy 292.814946 -29.21181) (xy 292.807118 -29.152354) (xy 292.806628 -29.12237) (xy 277.962735 -29.12237)
			(xy 277.962378 -29.14421) (xy 277.954555 -29.203632) (xy 277.939042 -29.261525) (xy 277.916106 -29.316898)
			(xy 277.886139 -29.368804) (xy 277.849652 -29.416354) (xy 277.807272 -29.458734) (xy 277.759722 -29.495221)
			(xy 277.707816 -29.525188) (xy 277.652443 -29.548124) (xy 277.59455 -29.563637) (xy 277.535128 -29.57146)
			(xy 277.475192 -29.57146) (xy 277.41577 -29.563637) (xy 277.357877 -29.548124) (xy 277.302504 -29.525188)
			(xy 277.250598 -29.495221) (xy 277.203048 -29.458734) (xy 277.160668 -29.416354) (xy 277.124181 -29.368804)
			(xy 277.094214 -29.316898) (xy 277.071278 -29.261525) (xy 277.055765 -29.203632) (xy 277.047942 -29.14421)
			(xy 277.047452 -29.114242) (xy 267.722604 -29.114242) (xy 267.722604 -29.12237) (xy 267.722114 -29.152354)
			(xy 267.714286 -29.21181) (xy 267.698765 -29.269735) (xy 267.675816 -29.325139) (xy 267.645832 -29.377073)
			(xy 267.609326 -29.424649) (xy 267.566921 -29.467054) (xy 267.519345 -29.50356) (xy 267.467411 -29.533544)
			(xy 267.412007 -29.556493) (xy 267.354082 -29.572014) (xy 267.294626 -29.579842) (xy 267.234658 -29.579842)
			(xy 267.175202 -29.572014) (xy 267.117277 -29.556493) (xy 267.061873 -29.533544) (xy 267.009939 -29.50356)
			(xy 266.962363 -29.467054) (xy 266.919958 -29.424649) (xy 266.883452 -29.377073) (xy 266.853468 -29.325139)
			(xy 266.830519 -29.269735) (xy 266.814998 -29.21181) (xy 266.80717 -29.152354) (xy 266.80668 -29.12237)
			(xy 251.962787 -29.12237) (xy 251.96243 -29.14421) (xy 251.954607 -29.203632) (xy 251.939094 -29.261525)
			(xy 251.916158 -29.316898) (xy 251.886191 -29.368804) (xy 251.849704 -29.416354) (xy 251.807324 -29.458734)
			(xy 251.759774 -29.495221) (xy 251.707868 -29.525188) (xy 251.652495 -29.548124) (xy 251.594602 -29.563637)
			(xy 251.53518 -29.57146) (xy 251.475244 -29.57146) (xy 251.415822 -29.563637) (xy 251.357929 -29.548124)
			(xy 251.302556 -29.525188) (xy 251.25065 -29.495221) (xy 251.2031 -29.458734) (xy 251.16072 -29.416354)
			(xy 251.124233 -29.368804) (xy 251.094266 -29.316898) (xy 251.07133 -29.261525) (xy 251.055817 -29.203632)
			(xy 251.047994 -29.14421) (xy 251.047504 -29.114242) (xy 241.722656 -29.114242) (xy 241.722656 -29.12237)
			(xy 241.722166 -29.152354) (xy 241.714338 -29.21181) (xy 241.698817 -29.269735) (xy 241.675868 -29.325139)
			(xy 241.645884 -29.377073) (xy 241.609378 -29.424649) (xy 241.566973 -29.467054) (xy 241.519397 -29.50356)
			(xy 241.467463 -29.533544) (xy 241.412059 -29.556493) (xy 241.354134 -29.572014) (xy 241.294678 -29.579842)
			(xy 241.23471 -29.579842) (xy 241.175254 -29.572014) (xy 241.117329 -29.556493) (xy 241.061925 -29.533544)
			(xy 241.009991 -29.50356) (xy 240.962415 -29.467054) (xy 240.92001 -29.424649) (xy 240.883504 -29.377073)
			(xy 240.85352 -29.325139) (xy 240.830571 -29.269735) (xy 240.81505 -29.21181) (xy 240.807222 -29.152354)
			(xy 240.806732 -29.12237) (xy 213.862787 -29.12237) (xy 213.86243 -29.14421) (xy 213.854607 -29.203632)
			(xy 213.839094 -29.261525) (xy 213.816158 -29.316898) (xy 213.786191 -29.368804) (xy 213.749704 -29.416354)
			(xy 213.707324 -29.458734) (xy 213.659774 -29.495221) (xy 213.607868 -29.525188) (xy 213.552495 -29.548124)
			(xy 213.494602 -29.563637) (xy 213.43518 -29.57146) (xy 213.375244 -29.57146) (xy 213.315822 -29.563637)
			(xy 213.257929 -29.548124) (xy 213.202556 -29.525188) (xy 213.15065 -29.495221) (xy 213.1031 -29.458734)
			(xy 213.06072 -29.416354) (xy 213.024233 -29.368804) (xy 212.994266 -29.316898) (xy 212.97133 -29.261525)
			(xy 212.955817 -29.203632) (xy 212.947994 -29.14421) (xy 212.947504 -29.114242) (xy 203.622656 -29.114242)
			(xy 203.622656 -29.12237) (xy 203.622166 -29.152354) (xy 203.614338 -29.21181) (xy 203.598817 -29.269735)
			(xy 203.575868 -29.325139) (xy 203.545884 -29.377073) (xy 203.509378 -29.424649) (xy 203.466973 -29.467054)
			(xy 203.419397 -29.50356) (xy 203.367463 -29.533544) (xy 203.312059 -29.556493) (xy 203.254134 -29.572014)
			(xy 203.194678 -29.579842) (xy 203.13471 -29.579842) (xy 203.075254 -29.572014) (xy 203.017329 -29.556493)
			(xy 202.961925 -29.533544) (xy 202.909991 -29.50356) (xy 202.862415 -29.467054) (xy 202.82001 -29.424649)
			(xy 202.783504 -29.377073) (xy 202.75352 -29.325139) (xy 202.730571 -29.269735) (xy 202.71505 -29.21181)
			(xy 202.707222 -29.152354) (xy 202.706732 -29.12237) (xy 187.862839 -29.12237) (xy 187.862482 -29.14421)
			(xy 187.854659 -29.203632) (xy 187.839146 -29.261525) (xy 187.81621 -29.316898) (xy 187.786243 -29.368804)
			(xy 187.749756 -29.416354) (xy 187.707376 -29.458734) (xy 187.659826 -29.495221) (xy 187.60792 -29.525188)
			(xy 187.552547 -29.548124) (xy 187.494654 -29.563637) (xy 187.435232 -29.57146) (xy 187.375296 -29.57146)
			(xy 187.315874 -29.563637) (xy 187.257981 -29.548124) (xy 187.202608 -29.525188) (xy 187.150702 -29.495221)
			(xy 187.103152 -29.458734) (xy 187.060772 -29.416354) (xy 187.024285 -29.368804) (xy 186.994318 -29.316898)
			(xy 186.971382 -29.261525) (xy 186.955869 -29.203632) (xy 186.948046 -29.14421) (xy 186.947556 -29.114242)
			(xy 177.622708 -29.114242) (xy 177.622708 -29.12237) (xy 177.622218 -29.152354) (xy 177.61439 -29.21181)
			(xy 177.598869 -29.269735) (xy 177.57592 -29.325139) (xy 177.545936 -29.377073) (xy 177.50943 -29.424649)
			(xy 177.467025 -29.467054) (xy 177.419449 -29.50356) (xy 177.367515 -29.533544) (xy 177.312111 -29.556493)
			(xy 177.254186 -29.572014) (xy 177.19473 -29.579842) (xy 177.134762 -29.579842) (xy 177.075306 -29.572014)
			(xy 177.017381 -29.556493) (xy 176.961977 -29.533544) (xy 176.910043 -29.50356) (xy 176.862467 -29.467054)
			(xy 176.820062 -29.424649) (xy 176.783556 -29.377073) (xy 176.753572 -29.325139) (xy 176.730623 -29.269735)
			(xy 176.715102 -29.21181) (xy 176.707274 -29.152354) (xy 176.706784 -29.12237) (xy 161.862891 -29.12237)
			(xy 161.862534 -29.14421) (xy 161.854711 -29.203632) (xy 161.839198 -29.261525) (xy 161.816262 -29.316898)
			(xy 161.786295 -29.368804) (xy 161.749808 -29.416354) (xy 161.707428 -29.458734) (xy 161.659878 -29.495221)
			(xy 161.607972 -29.525188) (xy 161.552599 -29.548124) (xy 161.494706 -29.563637) (xy 161.435284 -29.57146)
			(xy 161.375348 -29.57146) (xy 161.315926 -29.563637) (xy 161.258033 -29.548124) (xy 161.20266 -29.525188)
			(xy 161.150754 -29.495221) (xy 161.103204 -29.458734) (xy 161.060824 -29.416354) (xy 161.024337 -29.368804)
			(xy 160.99437 -29.316898) (xy 160.971434 -29.261525) (xy 160.955921 -29.203632) (xy 160.948098 -29.14421)
			(xy 160.947608 -29.114242) (xy 151.62276 -29.114242) (xy 151.62276 -29.12237) (xy 151.62227 -29.152354)
			(xy 151.614442 -29.21181) (xy 151.598921 -29.269735) (xy 151.575972 -29.325139) (xy 151.545988 -29.377073)
			(xy 151.509482 -29.424649) (xy 151.467077 -29.467054) (xy 151.419501 -29.50356) (xy 151.367567 -29.533544)
			(xy 151.312163 -29.556493) (xy 151.254238 -29.572014) (xy 151.194782 -29.579842) (xy 151.134814 -29.579842)
			(xy 151.075358 -29.572014) (xy 151.017433 -29.556493) (xy 150.962029 -29.533544) (xy 150.910095 -29.50356)
			(xy 150.862519 -29.467054) (xy 150.820114 -29.424649) (xy 150.783608 -29.377073) (xy 150.753624 -29.325139)
			(xy 150.730675 -29.269735) (xy 150.715154 -29.21181) (xy 150.707326 -29.152354) (xy 150.706836 -29.12237)
			(xy 135.862943 -29.12237) (xy 135.862586 -29.14421) (xy 135.854763 -29.203632) (xy 135.83925 -29.261525)
			(xy 135.816314 -29.316898) (xy 135.786347 -29.368804) (xy 135.74986 -29.416354) (xy 135.70748 -29.458734)
			(xy 135.65993 -29.495221) (xy 135.608024 -29.525188) (xy 135.552651 -29.548124) (xy 135.494758 -29.563637)
			(xy 135.435336 -29.57146) (xy 135.3754 -29.57146) (xy 135.315978 -29.563637) (xy 135.258085 -29.548124)
			(xy 135.202712 -29.525188) (xy 135.150806 -29.495221) (xy 135.103256 -29.458734) (xy 135.060876 -29.416354)
			(xy 135.024389 -29.368804) (xy 134.994422 -29.316898) (xy 134.971486 -29.261525) (xy 134.955973 -29.203632)
			(xy 134.94815 -29.14421) (xy 134.94766 -29.114242) (xy 125.622812 -29.114242) (xy 125.622812 -29.12237)
			(xy 125.622322 -29.152354) (xy 125.614494 -29.21181) (xy 125.598973 -29.269735) (xy 125.576024 -29.325139)
			(xy 125.54604 -29.377073) (xy 125.509534 -29.424649) (xy 125.467129 -29.467054) (xy 125.419553 -29.50356)
			(xy 125.367619 -29.533544) (xy 125.312215 -29.556493) (xy 125.25429 -29.572014) (xy 125.194834 -29.579842)
			(xy 125.134866 -29.579842) (xy 125.07541 -29.572014) (xy 125.017485 -29.556493) (xy 124.962081 -29.533544)
			(xy 124.910147 -29.50356) (xy 124.862571 -29.467054) (xy 124.820166 -29.424649) (xy 124.78366 -29.377073)
			(xy 124.753676 -29.325139) (xy 124.730727 -29.269735) (xy 124.715206 -29.21181) (xy 124.707378 -29.152354)
			(xy 124.706888 -29.12237) (xy 97.762943 -29.12237) (xy 97.762586 -29.144226) (xy 97.754758 -29.203682)
			(xy 97.739237 -29.261607) (xy 97.716288 -29.317011) (xy 97.686304 -29.368945) (xy 97.649798 -29.416521)
			(xy 97.607393 -29.458926) (xy 97.559817 -29.495432) (xy 97.507883 -29.525416) (xy 97.452479 -29.548365)
			(xy 97.394554 -29.563886) (xy 97.335098 -29.571714) (xy 97.27513 -29.571714) (xy 97.215674 -29.563886)
			(xy 97.157749 -29.548365) (xy 97.102345 -29.525416) (xy 97.050411 -29.495432) (xy 97.002835 -29.458926)
			(xy 96.96043 -29.416521) (xy 96.923924 -29.368945) (xy 96.89394 -29.317011) (xy 96.870991 -29.261607)
			(xy 96.85547 -29.203682) (xy 96.847642 -29.144226) (xy 96.847152 -29.114242) (xy 87.522304 -29.114242)
			(xy 87.522304 -29.12237) (xy 87.521814 -29.152338) (xy 87.513991 -29.21176) (xy 87.498478 -29.269653)
			(xy 87.475542 -29.325026) (xy 87.445575 -29.376932) (xy 87.409088 -29.424482) (xy 87.366708 -29.466862)
			(xy 87.319158 -29.503349) (xy 87.267252 -29.533316) (xy 87.211879 -29.556252) (xy 87.153986 -29.571765)
			(xy 87.094564 -29.579588) (xy 87.034628 -29.579588) (xy 86.975206 -29.571765) (xy 86.917313 -29.556252)
			(xy 86.86194 -29.533316) (xy 86.810034 -29.503349) (xy 86.762484 -29.466862) (xy 86.720104 -29.424482)
			(xy 86.683617 -29.376932) (xy 86.65365 -29.325026) (xy 86.630714 -29.269653) (xy 86.615201 -29.21176)
			(xy 86.607378 -29.152338) (xy 86.606888 -29.12237) (xy 71.762995 -29.12237) (xy 71.762638 -29.144226)
			(xy 71.75481 -29.203682) (xy 71.739289 -29.261607) (xy 71.71634 -29.317011) (xy 71.686356 -29.368945)
			(xy 71.64985 -29.416521) (xy 71.607445 -29.458926) (xy 71.559869 -29.495432) (xy 71.507935 -29.525416)
			(xy 71.452531 -29.548365) (xy 71.394606 -29.563886) (xy 71.33515 -29.571714) (xy 71.275182 -29.571714)
			(xy 71.215726 -29.563886) (xy 71.157801 -29.548365) (xy 71.102397 -29.525416) (xy 71.050463 -29.495432)
			(xy 71.002887 -29.458926) (xy 70.960482 -29.416521) (xy 70.923976 -29.368945) (xy 70.893992 -29.317011)
			(xy 70.871043 -29.261607) (xy 70.855522 -29.203682) (xy 70.847694 -29.144226) (xy 70.847204 -29.114242)
			(xy 61.522356 -29.114242) (xy 61.522356 -29.12237) (xy 61.521866 -29.152338) (xy 61.514043 -29.21176)
			(xy 61.49853 -29.269653) (xy 61.475594 -29.325026) (xy 61.445627 -29.376932) (xy 61.40914 -29.424482)
			(xy 61.36676 -29.466862) (xy 61.31921 -29.503349) (xy 61.267304 -29.533316) (xy 61.211931 -29.556252)
			(xy 61.154038 -29.571765) (xy 61.094616 -29.579588) (xy 61.03468 -29.579588) (xy 60.975258 -29.571765)
			(xy 60.917365 -29.556252) (xy 60.861992 -29.533316) (xy 60.810086 -29.503349) (xy 60.762536 -29.466862)
			(xy 60.720156 -29.424482) (xy 60.683669 -29.376932) (xy 60.653702 -29.325026) (xy 60.630766 -29.269653)
			(xy 60.615253 -29.21176) (xy 60.60743 -29.152338) (xy 60.60694 -29.12237) (xy 45.763047 -29.12237)
			(xy 45.76269 -29.144226) (xy 45.754862 -29.203682) (xy 45.739341 -29.261607) (xy 45.716392 -29.317011)
			(xy 45.686408 -29.368945) (xy 45.649902 -29.416521) (xy 45.607497 -29.458926) (xy 45.559921 -29.495432)
			(xy 45.507987 -29.525416) (xy 45.452583 -29.548365) (xy 45.394658 -29.563886) (xy 45.335202 -29.571714)
			(xy 45.275234 -29.571714) (xy 45.215778 -29.563886) (xy 45.157853 -29.548365) (xy 45.102449 -29.525416)
			(xy 45.050515 -29.495432) (xy 45.002939 -29.458926) (xy 44.960534 -29.416521) (xy 44.924028 -29.368945)
			(xy 44.894044 -29.317011) (xy 44.871095 -29.261607) (xy 44.855574 -29.203682) (xy 44.847746 -29.144226)
			(xy 44.847256 -29.114242) (xy 35.522408 -29.114242) (xy 35.522408 -29.12237) (xy 35.521918 -29.152338)
			(xy 35.514095 -29.21176) (xy 35.498582 -29.269653) (xy 35.475646 -29.325026) (xy 35.445679 -29.376932)
			(xy 35.409192 -29.424482) (xy 35.366812 -29.466862) (xy 35.319262 -29.503349) (xy 35.267356 -29.533316)
			(xy 35.211983 -29.556252) (xy 35.15409 -29.571765) (xy 35.094668 -29.579588) (xy 35.034732 -29.579588)
			(xy 34.97531 -29.571765) (xy 34.917417 -29.556252) (xy 34.862044 -29.533316) (xy 34.810138 -29.503349)
			(xy 34.762588 -29.466862) (xy 34.720208 -29.424482) (xy 34.683721 -29.376932) (xy 34.653754 -29.325026)
			(xy 34.630818 -29.269653) (xy 34.615305 -29.21176) (xy 34.607482 -29.152338) (xy 34.606992 -29.12237)
			(xy 19.763099 -29.12237) (xy 19.762742 -29.144226) (xy 19.754914 -29.203682) (xy 19.739393 -29.261607)
			(xy 19.716444 -29.317011) (xy 19.68646 -29.368945) (xy 19.649954 -29.416521) (xy 19.607549 -29.458926)
			(xy 19.559973 -29.495432) (xy 19.508039 -29.525416) (xy 19.452635 -29.548365) (xy 19.39471 -29.563886)
			(xy 19.335254 -29.571714) (xy 19.275286 -29.571714) (xy 19.21583 -29.563886) (xy 19.157905 -29.548365)
			(xy 19.102501 -29.525416) (xy 19.050567 -29.495432) (xy 19.002991 -29.458926) (xy 18.960586 -29.416521)
			(xy 18.92408 -29.368945) (xy 18.894096 -29.317011) (xy 18.871147 -29.261607) (xy 18.855626 -29.203682)
			(xy 18.847798 -29.144226) (xy 18.847308 -29.114242) (xy 9.52246 -29.114242) (xy 9.52246 -29.12237)
			(xy 9.52197 -29.152338) (xy 9.514147 -29.21176) (xy 9.498634 -29.269653) (xy 9.475698 -29.325026)
			(xy 9.445731 -29.376932) (xy 9.409244 -29.424482) (xy 9.366864 -29.466862) (xy 9.319314 -29.503349)
			(xy 9.267408 -29.533316) (xy 9.212035 -29.556252) (xy 9.154142 -29.571765) (xy 9.09472 -29.579588)
			(xy 9.034784 -29.579588) (xy 8.975362 -29.571765) (xy 8.917469 -29.556252) (xy 8.862096 -29.533316)
			(xy 8.81019 -29.503349) (xy 8.76264 -29.466862) (xy 8.72026 -29.424482) (xy 8.683773 -29.376932)
			(xy 8.653806 -29.325026) (xy 8.63087 -29.269653) (xy 8.615357 -29.21176) (xy 8.607534 -29.152338)
			(xy 8.607044 -29.12237) (xy 1.524 -29.12237) (xy 1.524 -30.922468) (xy 6.752844 -30.922468) (xy 6.752844 -30.058868)
			(xy 6.753334 -30.0289) (xy 6.761157 -29.969478) (xy 6.77667 -29.911585) (xy 6.799606 -29.856212)
			(xy 6.829573 -29.804306) (xy 6.86606 -29.756756) (xy 6.90844 -29.714376) (xy 6.95599 -29.677889)
			(xy 7.007896 -29.647922) (xy 7.063269 -29.624986) (xy 7.121162 -29.609473) (xy 7.180584 -29.60165)
			(xy 7.24052 -29.60165) (xy 7.299942 -29.609473) (xy 7.357835 -29.624986) (xy 7.413208 -29.647922)
			(xy 7.465114 -29.677889) (xy 7.512664 -29.714376) (xy 7.555044 -29.756756) (xy 7.591531 -29.804306)
			(xy 7.621498 -29.856212) (xy 7.644434 -29.911585) (xy 7.659947 -29.969478) (xy 7.66777 -30.0289)
			(xy 7.66826 -30.058868) (xy 7.66826 -30.92069) (xy 21.489416 -30.92069) (xy 21.489416 -30.05709)
			(xy 21.489906 -30.027106) (xy 21.497734 -29.96765) (xy 21.513255 -29.909725) (xy 21.536204 -29.854321)
			(xy 21.566188 -29.802387) (xy 21.602694 -29.754811) (xy 21.645099 -29.712406) (xy 21.692675 -29.6759)
			(xy 21.744609 -29.645916) (xy 21.800013 -29.622967) (xy 21.857938 -29.607446) (xy 21.917394 -29.599618)
			(xy 21.977362 -29.599618) (xy 22.036818 -29.607446) (xy 22.094743 -29.622967) (xy 22.150147 -29.645916)
			(xy 22.202081 -29.6759) (xy 22.249657 -29.712406) (xy 22.292062 -29.754811) (xy 22.328568 -29.802387)
			(xy 22.358552 -29.854321) (xy 22.381501 -29.909725) (xy 22.397022 -29.96765) (xy 22.40485 -30.027106)
			(xy 22.40534 -30.05709) (xy 22.40534 -30.92069) (xy 22.405311 -30.922468) (xy 32.752792 -30.922468)
			(xy 32.752792 -30.058868) (xy 32.753282 -30.0289) (xy 32.761105 -29.969478) (xy 32.776618 -29.911585)
			(xy 32.799554 -29.856212) (xy 32.829521 -29.804306) (xy 32.866008 -29.756756) (xy 32.908388 -29.714376)
			(xy 32.955938 -29.677889) (xy 33.007844 -29.647922) (xy 33.063217 -29.624986) (xy 33.12111 -29.609473)
			(xy 33.180532 -29.60165) (xy 33.240468 -29.60165) (xy 33.29989 -29.609473) (xy 33.357783 -29.624986)
			(xy 33.413156 -29.647922) (xy 33.465062 -29.677889) (xy 33.512612 -29.714376) (xy 33.554992 -29.756756)
			(xy 33.591479 -29.804306) (xy 33.621446 -29.856212) (xy 33.644382 -29.911585) (xy 33.659895 -29.969478)
			(xy 33.667718 -30.0289) (xy 33.668208 -30.058868) (xy 33.668208 -30.92069) (xy 47.489364 -30.92069)
			(xy 47.489364 -30.05709) (xy 47.489854 -30.027106) (xy 47.497682 -29.96765) (xy 47.513203 -29.909725)
			(xy 47.536152 -29.854321) (xy 47.566136 -29.802387) (xy 47.602642 -29.754811) (xy 47.645047 -29.712406)
			(xy 47.692623 -29.6759) (xy 47.744557 -29.645916) (xy 47.799961 -29.622967) (xy 47.857886 -29.607446)
			(xy 47.917342 -29.599618) (xy 47.97731 -29.599618) (xy 48.036766 -29.607446) (xy 48.094691 -29.622967)
			(xy 48.150095 -29.645916) (xy 48.202029 -29.6759) (xy 48.249605 -29.712406) (xy 48.29201 -29.754811)
			(xy 48.328516 -29.802387) (xy 48.3585 -29.854321) (xy 48.381449 -29.909725) (xy 48.39697 -29.96765)
			(xy 48.404798 -30.027106) (xy 48.405288 -30.05709) (xy 48.405288 -30.92069) (xy 48.405259 -30.922468)
			(xy 58.75274 -30.922468) (xy 58.75274 -30.058868) (xy 58.75323 -30.0289) (xy 58.761053 -29.969478)
			(xy 58.776566 -29.911585) (xy 58.799502 -29.856212) (xy 58.829469 -29.804306) (xy 58.865956 -29.756756)
			(xy 58.908336 -29.714376) (xy 58.955886 -29.677889) (xy 59.007792 -29.647922) (xy 59.063165 -29.624986)
			(xy 59.121058 -29.609473) (xy 59.18048 -29.60165) (xy 59.240416 -29.60165) (xy 59.299838 -29.609473)
			(xy 59.357731 -29.624986) (xy 59.413104 -29.647922) (xy 59.46501 -29.677889) (xy 59.51256 -29.714376)
			(xy 59.55494 -29.756756) (xy 59.591427 -29.804306) (xy 59.621394 -29.856212) (xy 59.64433 -29.911585)
			(xy 59.659843 -29.969478) (xy 59.667666 -30.0289) (xy 59.668156 -30.058868) (xy 59.668156 -30.92069)
			(xy 73.489312 -30.92069) (xy 73.489312 -30.05709) (xy 73.489802 -30.027106) (xy 73.49763 -29.96765)
			(xy 73.513151 -29.909725) (xy 73.5361 -29.854321) (xy 73.566084 -29.802387) (xy 73.60259 -29.754811)
			(xy 73.644995 -29.712406) (xy 73.692571 -29.6759) (xy 73.744505 -29.645916) (xy 73.799909 -29.622967)
			(xy 73.857834 -29.607446) (xy 73.91729 -29.599618) (xy 73.977258 -29.599618) (xy 74.036714 -29.607446)
			(xy 74.094639 -29.622967) (xy 74.150043 -29.645916) (xy 74.201977 -29.6759) (xy 74.249553 -29.712406)
			(xy 74.291958 -29.754811) (xy 74.328464 -29.802387) (xy 74.358448 -29.854321) (xy 74.381397 -29.909725)
			(xy 74.396918 -29.96765) (xy 74.404746 -30.027106) (xy 74.405236 -30.05709) (xy 74.405236 -30.92069)
			(xy 74.405207 -30.922468) (xy 84.752688 -30.922468) (xy 84.752688 -30.058868) (xy 84.753178 -30.0289)
			(xy 84.761001 -29.969478) (xy 84.776514 -29.911585) (xy 84.79945 -29.856212) (xy 84.829417 -29.804306)
			(xy 84.865904 -29.756756) (xy 84.908284 -29.714376) (xy 84.955834 -29.677889) (xy 85.00774 -29.647922)
			(xy 85.063113 -29.624986) (xy 85.121006 -29.609473) (xy 85.180428 -29.60165) (xy 85.240364 -29.60165)
			(xy 85.299786 -29.609473) (xy 85.357679 -29.624986) (xy 85.413052 -29.647922) (xy 85.464958 -29.677889)
			(xy 85.512508 -29.714376) (xy 85.554888 -29.756756) (xy 85.591375 -29.804306) (xy 85.621342 -29.856212)
			(xy 85.644278 -29.911585) (xy 85.659791 -29.969478) (xy 85.667614 -30.0289) (xy 85.668104 -30.058868)
			(xy 85.668104 -30.92069) (xy 99.48926 -30.92069) (xy 99.48926 -30.05709) (xy 99.48975 -30.027106)
			(xy 99.497578 -29.96765) (xy 99.513099 -29.909725) (xy 99.536048 -29.854321) (xy 99.566032 -29.802387)
			(xy 99.602538 -29.754811) (xy 99.644943 -29.712406) (xy 99.692519 -29.6759) (xy 99.744453 -29.645916)
			(xy 99.799857 -29.622967) (xy 99.857782 -29.607446) (xy 99.917238 -29.599618) (xy 99.977206 -29.599618)
			(xy 100.036662 -29.607446) (xy 100.094587 -29.622967) (xy 100.149991 -29.645916) (xy 100.201925 -29.6759)
			(xy 100.249501 -29.712406) (xy 100.291906 -29.754811) (xy 100.328412 -29.802387) (xy 100.358396 -29.854321)
			(xy 100.381345 -29.909725) (xy 100.396866 -29.96765) (xy 100.404694 -30.027106) (xy 100.405184 -30.05709)
			(xy 100.405184 -30.92069) (xy 100.405155 -30.922468) (xy 122.852688 -30.922468) (xy 122.852688 -30.058868)
			(xy 122.853178 -30.028884) (xy 122.861006 -29.969428) (xy 122.876527 -29.911503) (xy 122.899476 -29.856099)
			(xy 122.92946 -29.804165) (xy 122.965966 -29.756589) (xy 123.008371 -29.714184) (xy 123.055947 -29.677678)
			(xy 123.107881 -29.647694) (xy 123.163285 -29.624745) (xy 123.22121 -29.609224) (xy 123.280666 -29.601396)
			(xy 123.340634 -29.601396) (xy 123.40009 -29.609224) (xy 123.458015 -29.624745) (xy 123.513419 -29.647694)
			(xy 123.565353 -29.677678) (xy 123.612929 -29.714184) (xy 123.655334 -29.756589) (xy 123.69184 -29.804165)
			(xy 123.721824 -29.856099) (xy 123.744773 -29.911503) (xy 123.760294 -29.969428) (xy 123.768122 -30.028884)
			(xy 123.768612 -30.058868) (xy 123.768612 -30.92069) (xy 137.589768 -30.92069) (xy 137.589768 -30.05709)
			(xy 137.590258 -30.027122) (xy 137.598081 -29.9677) (xy 137.613594 -29.909807) (xy 137.63653 -29.854434)
			(xy 137.666497 -29.802528) (xy 137.702984 -29.754978) (xy 137.745364 -29.712598) (xy 137.792914 -29.676111)
			(xy 137.84482 -29.646144) (xy 137.900193 -29.623208) (xy 137.958086 -29.607695) (xy 138.017508 -29.599872)
			(xy 138.077444 -29.599872) (xy 138.136866 -29.607695) (xy 138.194759 -29.623208) (xy 138.250132 -29.646144)
			(xy 138.302038 -29.676111) (xy 138.349588 -29.712598) (xy 138.391968 -29.754978) (xy 138.428455 -29.802528)
			(xy 138.458422 -29.854434) (xy 138.481358 -29.909807) (xy 138.496871 -29.9677) (xy 138.504694 -30.027122)
			(xy 138.505184 -30.05709) (xy 138.505184 -30.92069) (xy 138.505155 -30.922468) (xy 148.852636 -30.922468)
			(xy 148.852636 -30.058868) (xy 148.853126 -30.028884) (xy 148.860954 -29.969428) (xy 148.876475 -29.911503)
			(xy 148.899424 -29.856099) (xy 148.929408 -29.804165) (xy 148.965914 -29.756589) (xy 149.008319 -29.714184)
			(xy 149.055895 -29.677678) (xy 149.107829 -29.647694) (xy 149.163233 -29.624745) (xy 149.221158 -29.609224)
			(xy 149.280614 -29.601396) (xy 149.340582 -29.601396) (xy 149.400038 -29.609224) (xy 149.457963 -29.624745)
			(xy 149.513367 -29.647694) (xy 149.565301 -29.677678) (xy 149.612877 -29.714184) (xy 149.655282 -29.756589)
			(xy 149.691788 -29.804165) (xy 149.721772 -29.856099) (xy 149.744721 -29.911503) (xy 149.760242 -29.969428)
			(xy 149.76807 -30.028884) (xy 149.76856 -30.058868) (xy 149.76856 -30.92069) (xy 163.589716 -30.92069)
			(xy 163.589716 -30.05709) (xy 163.590206 -30.027122) (xy 163.598029 -29.9677) (xy 163.613542 -29.909807)
			(xy 163.636478 -29.854434) (xy 163.666445 -29.802528) (xy 163.702932 -29.754978) (xy 163.745312 -29.712598)
			(xy 163.792862 -29.676111) (xy 163.844768 -29.646144) (xy 163.900141 -29.623208) (xy 163.958034 -29.607695)
			(xy 164.017456 -29.599872) (xy 164.077392 -29.599872) (xy 164.136814 -29.607695) (xy 164.194707 -29.623208)
			(xy 164.25008 -29.646144) (xy 164.301986 -29.676111) (xy 164.349536 -29.712598) (xy 164.391916 -29.754978)
			(xy 164.428403 -29.802528) (xy 164.45837 -29.854434) (xy 164.481306 -29.909807) (xy 164.496819 -29.9677)
			(xy 164.504642 -30.027122) (xy 164.505132 -30.05709) (xy 164.505132 -30.92069) (xy 164.505103 -30.922468)
			(xy 174.852584 -30.922468) (xy 174.852584 -30.058868) (xy 174.853074 -30.028884) (xy 174.860902 -29.969428)
			(xy 174.876423 -29.911503) (xy 174.899372 -29.856099) (xy 174.929356 -29.804165) (xy 174.965862 -29.756589)
			(xy 175.008267 -29.714184) (xy 175.055843 -29.677678) (xy 175.107777 -29.647694) (xy 175.163181 -29.624745)
			(xy 175.221106 -29.609224) (xy 175.280562 -29.601396) (xy 175.34053 -29.601396) (xy 175.399986 -29.609224)
			(xy 175.457911 -29.624745) (xy 175.513315 -29.647694) (xy 175.565249 -29.677678) (xy 175.612825 -29.714184)
			(xy 175.65523 -29.756589) (xy 175.691736 -29.804165) (xy 175.72172 -29.856099) (xy 175.744669 -29.911503)
			(xy 175.76019 -29.969428) (xy 175.768018 -30.028884) (xy 175.768508 -30.058868) (xy 175.768508 -30.92069)
			(xy 189.589664 -30.92069) (xy 189.589664 -30.05709) (xy 189.590154 -30.027122) (xy 189.597977 -29.9677)
			(xy 189.61349 -29.909807) (xy 189.636426 -29.854434) (xy 189.666393 -29.802528) (xy 189.70288 -29.754978)
			(xy 189.74526 -29.712598) (xy 189.79281 -29.676111) (xy 189.844716 -29.646144) (xy 189.900089 -29.623208)
			(xy 189.957982 -29.607695) (xy 190.017404 -29.599872) (xy 190.07734 -29.599872) (xy 190.136762 -29.607695)
			(xy 190.194655 -29.623208) (xy 190.250028 -29.646144) (xy 190.301934 -29.676111) (xy 190.349484 -29.712598)
			(xy 190.391864 -29.754978) (xy 190.428351 -29.802528) (xy 190.458318 -29.854434) (xy 190.481254 -29.909807)
			(xy 190.496767 -29.9677) (xy 190.50459 -30.027122) (xy 190.50508 -30.05709) (xy 190.50508 -30.92069)
			(xy 190.505051 -30.922468) (xy 200.852532 -30.922468) (xy 200.852532 -30.058868) (xy 200.853022 -30.028884)
			(xy 200.86085 -29.969428) (xy 200.876371 -29.911503) (xy 200.89932 -29.856099) (xy 200.929304 -29.804165)
			(xy 200.96581 -29.756589) (xy 201.008215 -29.714184) (xy 201.055791 -29.677678) (xy 201.107725 -29.647694)
			(xy 201.163129 -29.624745) (xy 201.221054 -29.609224) (xy 201.28051 -29.601396) (xy 201.340478 -29.601396)
			(xy 201.399934 -29.609224) (xy 201.457859 -29.624745) (xy 201.513263 -29.647694) (xy 201.565197 -29.677678)
			(xy 201.612773 -29.714184) (xy 201.655178 -29.756589) (xy 201.691684 -29.804165) (xy 201.721668 -29.856099)
			(xy 201.744617 -29.911503) (xy 201.760138 -29.969428) (xy 201.767966 -30.028884) (xy 201.768456 -30.058868)
			(xy 201.768456 -30.92069) (xy 215.589612 -30.92069) (xy 215.589612 -30.05709) (xy 215.590102 -30.027122)
			(xy 215.597925 -29.9677) (xy 215.613438 -29.909807) (xy 215.636374 -29.854434) (xy 215.666341 -29.802528)
			(xy 215.702828 -29.754978) (xy 215.745208 -29.712598) (xy 215.792758 -29.676111) (xy 215.844664 -29.646144)
			(xy 215.900037 -29.623208) (xy 215.95793 -29.607695) (xy 216.017352 -29.599872) (xy 216.077288 -29.599872)
			(xy 216.13671 -29.607695) (xy 216.194603 -29.623208) (xy 216.249976 -29.646144) (xy 216.301882 -29.676111)
			(xy 216.349432 -29.712598) (xy 216.391812 -29.754978) (xy 216.428299 -29.802528) (xy 216.458266 -29.854434)
			(xy 216.481202 -29.909807) (xy 216.496715 -29.9677) (xy 216.504538 -30.027122) (xy 216.505028 -30.05709)
			(xy 216.505028 -30.92069) (xy 216.504999 -30.922468) (xy 238.952532 -30.922468) (xy 238.952532 -30.058868)
			(xy 238.953022 -30.028884) (xy 238.96085 -29.969428) (xy 238.976371 -29.911503) (xy 238.99932 -29.856099)
			(xy 239.029304 -29.804165) (xy 239.06581 -29.756589) (xy 239.108215 -29.714184) (xy 239.155791 -29.677678)
			(xy 239.207725 -29.647694) (xy 239.263129 -29.624745) (xy 239.321054 -29.609224) (xy 239.38051 -29.601396)
			(xy 239.440478 -29.601396) (xy 239.499934 -29.609224) (xy 239.557859 -29.624745) (xy 239.613263 -29.647694)
			(xy 239.665197 -29.677678) (xy 239.712773 -29.714184) (xy 239.755178 -29.756589) (xy 239.791684 -29.804165)
			(xy 239.821668 -29.856099) (xy 239.844617 -29.911503) (xy 239.860138 -29.969428) (xy 239.867966 -30.028884)
			(xy 239.868456 -30.058868) (xy 239.868456 -30.92069) (xy 253.689612 -30.92069) (xy 253.689612 -30.05709)
			(xy 253.690102 -30.027122) (xy 253.697925 -29.9677) (xy 253.713438 -29.909807) (xy 253.736374 -29.854434)
			(xy 253.766341 -29.802528) (xy 253.802828 -29.754978) (xy 253.845208 -29.712598) (xy 253.892758 -29.676111)
			(xy 253.944664 -29.646144) (xy 254.000037 -29.623208) (xy 254.05793 -29.607695) (xy 254.117352 -29.599872)
			(xy 254.177288 -29.599872) (xy 254.23671 -29.607695) (xy 254.294603 -29.623208) (xy 254.349976 -29.646144)
			(xy 254.401882 -29.676111) (xy 254.449432 -29.712598) (xy 254.491812 -29.754978) (xy 254.528299 -29.802528)
			(xy 254.558266 -29.854434) (xy 254.581202 -29.909807) (xy 254.596715 -29.9677) (xy 254.604538 -30.027122)
			(xy 254.605028 -30.05709) (xy 254.605028 -30.92069) (xy 254.604999 -30.922468) (xy 264.95248 -30.922468)
			(xy 264.95248 -30.058868) (xy 264.95297 -30.028884) (xy 264.960798 -29.969428) (xy 264.976319 -29.911503)
			(xy 264.999268 -29.856099) (xy 265.029252 -29.804165) (xy 265.065758 -29.756589) (xy 265.108163 -29.714184)
			(xy 265.155739 -29.677678) (xy 265.207673 -29.647694) (xy 265.263077 -29.624745) (xy 265.321002 -29.609224)
			(xy 265.380458 -29.601396) (xy 265.440426 -29.601396) (xy 265.499882 -29.609224) (xy 265.557807 -29.624745)
			(xy 265.613211 -29.647694) (xy 265.665145 -29.677678) (xy 265.712721 -29.714184) (xy 265.755126 -29.756589)
			(xy 265.791632 -29.804165) (xy 265.821616 -29.856099) (xy 265.844565 -29.911503) (xy 265.860086 -29.969428)
			(xy 265.867914 -30.028884) (xy 265.868404 -30.058868) (xy 265.868404 -30.92069) (xy 279.68956 -30.92069)
			(xy 279.68956 -30.05709) (xy 279.69005 -30.027122) (xy 279.697873 -29.9677) (xy 279.713386 -29.909807)
			(xy 279.736322 -29.854434) (xy 279.766289 -29.802528) (xy 279.802776 -29.754978) (xy 279.845156 -29.712598)
			(xy 279.892706 -29.676111) (xy 279.944612 -29.646144) (xy 279.999985 -29.623208) (xy 280.057878 -29.607695)
			(xy 280.1173 -29.599872) (xy 280.177236 -29.599872) (xy 280.236658 -29.607695) (xy 280.294551 -29.623208)
			(xy 280.349924 -29.646144) (xy 280.40183 -29.676111) (xy 280.44938 -29.712598) (xy 280.49176 -29.754978)
			(xy 280.528247 -29.802528) (xy 280.558214 -29.854434) (xy 280.58115 -29.909807) (xy 280.596663 -29.9677)
			(xy 280.604486 -30.027122) (xy 280.604976 -30.05709) (xy 280.604976 -30.92069) (xy 280.604947 -30.922468)
			(xy 290.952428 -30.922468) (xy 290.952428 -30.058868) (xy 290.952918 -30.028884) (xy 290.960746 -29.969428)
			(xy 290.976267 -29.911503) (xy 290.999216 -29.856099) (xy 291.0292 -29.804165) (xy 291.065706 -29.756589)
			(xy 291.108111 -29.714184) (xy 291.155687 -29.677678) (xy 291.207621 -29.647694) (xy 291.263025 -29.624745)
			(xy 291.32095 -29.609224) (xy 291.380406 -29.601396) (xy 291.440374 -29.601396) (xy 291.49983 -29.609224)
			(xy 291.557755 -29.624745) (xy 291.613159 -29.647694) (xy 291.665093 -29.677678) (xy 291.712669 -29.714184)
			(xy 291.755074 -29.756589) (xy 291.79158 -29.804165) (xy 291.821564 -29.856099) (xy 291.844513 -29.911503)
			(xy 291.860034 -29.969428) (xy 291.867862 -30.028884) (xy 291.868352 -30.058868) (xy 291.868352 -30.92069)
			(xy 305.689508 -30.92069) (xy 305.689508 -30.05709) (xy 305.689998 -30.027122) (xy 305.697821 -29.9677)
			(xy 305.713334 -29.909807) (xy 305.73627 -29.854434) (xy 305.766237 -29.802528) (xy 305.802724 -29.754978)
			(xy 305.845104 -29.712598) (xy 305.892654 -29.676111) (xy 305.94456 -29.646144) (xy 305.999933 -29.623208)
			(xy 306.057826 -29.607695) (xy 306.117248 -29.599872) (xy 306.177184 -29.599872) (xy 306.236606 -29.607695)
			(xy 306.294499 -29.623208) (xy 306.349872 -29.646144) (xy 306.401778 -29.676111) (xy 306.449328 -29.712598)
			(xy 306.491708 -29.754978) (xy 306.528195 -29.802528) (xy 306.558162 -29.854434) (xy 306.581098 -29.909807)
			(xy 306.596611 -29.9677) (xy 306.604434 -30.027122) (xy 306.604924 -30.05709) (xy 306.604924 -30.92069)
			(xy 306.604895 -30.922468) (xy 316.952376 -30.922468) (xy 316.952376 -30.058868) (xy 316.952866 -30.028884)
			(xy 316.960694 -29.969428) (xy 316.976215 -29.911503) (xy 316.999164 -29.856099) (xy 317.029148 -29.804165)
			(xy 317.065654 -29.756589) (xy 317.108059 -29.714184) (xy 317.155635 -29.677678) (xy 317.207569 -29.647694)
			(xy 317.262973 -29.624745) (xy 317.320898 -29.609224) (xy 317.380354 -29.601396) (xy 317.440322 -29.601396)
			(xy 317.499778 -29.609224) (xy 317.557703 -29.624745) (xy 317.613107 -29.647694) (xy 317.665041 -29.677678)
			(xy 317.712617 -29.714184) (xy 317.755022 -29.756589) (xy 317.791528 -29.804165) (xy 317.821512 -29.856099)
			(xy 317.844461 -29.911503) (xy 317.859982 -29.969428) (xy 317.86781 -30.028884) (xy 317.8683 -30.058868)
			(xy 317.8683 -30.92069) (xy 331.689456 -30.92069) (xy 331.689456 -30.05709) (xy 331.689946 -30.027122)
			(xy 331.697769 -29.9677) (xy 331.713282 -29.909807) (xy 331.736218 -29.854434) (xy 331.766185 -29.802528)
			(xy 331.802672 -29.754978) (xy 331.845052 -29.712598) (xy 331.892602 -29.676111) (xy 331.944508 -29.646144)
			(xy 331.999881 -29.623208) (xy 332.057774 -29.607695) (xy 332.117196 -29.599872) (xy 332.177132 -29.599872)
			(xy 332.236554 -29.607695) (xy 332.294447 -29.623208) (xy 332.34982 -29.646144) (xy 332.401726 -29.676111)
			(xy 332.449276 -29.712598) (xy 332.491656 -29.754978) (xy 332.528143 -29.802528) (xy 332.55811 -29.854434)
			(xy 332.581046 -29.909807) (xy 332.596559 -29.9677) (xy 332.604382 -30.027122) (xy 332.604872 -30.05709)
			(xy 332.604872 -30.92069) (xy 332.604843 -30.922468) (xy 355.052884 -30.922468) (xy 355.052884 -30.058868)
			(xy 355.053374 -30.0289) (xy 355.061197 -29.969478) (xy 355.07671 -29.911585) (xy 355.099646 -29.856212)
			(xy 355.129613 -29.804306) (xy 355.1661 -29.756756) (xy 355.20848 -29.714376) (xy 355.25603 -29.677889)
			(xy 355.307936 -29.647922) (xy 355.363309 -29.624986) (xy 355.421202 -29.609473) (xy 355.480624 -29.60165)
			(xy 355.54056 -29.60165) (xy 355.599982 -29.609473) (xy 355.657875 -29.624986) (xy 355.713248 -29.647922)
			(xy 355.765154 -29.677889) (xy 355.812704 -29.714376) (xy 355.855084 -29.756756) (xy 355.891571 -29.804306)
			(xy 355.921538 -29.856212) (xy 355.944474 -29.911585) (xy 355.959987 -29.969478) (xy 355.96781 -30.0289)
			(xy 355.9683 -30.058868) (xy 355.9683 -30.92069) (xy 369.789456 -30.92069) (xy 369.789456 -30.05709)
			(xy 369.789946 -30.027106) (xy 369.797774 -29.96765) (xy 369.813295 -29.909725) (xy 369.836244 -29.854321)
			(xy 369.866228 -29.802387) (xy 369.902734 -29.754811) (xy 369.945139 -29.712406) (xy 369.992715 -29.6759)
			(xy 370.044649 -29.645916) (xy 370.100053 -29.622967) (xy 370.157978 -29.607446) (xy 370.217434 -29.599618)
			(xy 370.277402 -29.599618) (xy 370.336858 -29.607446) (xy 370.394783 -29.622967) (xy 370.450187 -29.645916)
			(xy 370.502121 -29.6759) (xy 370.549697 -29.712406) (xy 370.592102 -29.754811) (xy 370.628608 -29.802387)
			(xy 370.658592 -29.854321) (xy 370.681541 -29.909725) (xy 370.697062 -29.96765) (xy 370.70489 -30.027106)
			(xy 370.70538 -30.05709) (xy 370.70538 -30.92069) (xy 370.705351 -30.922468) (xy 381.052832 -30.922468)
			(xy 381.052832 -30.058868) (xy 381.053322 -30.0289) (xy 381.061145 -29.969478) (xy 381.076658 -29.911585)
			(xy 381.099594 -29.856212) (xy 381.129561 -29.804306) (xy 381.166048 -29.756756) (xy 381.208428 -29.714376)
			(xy 381.255978 -29.677889) (xy 381.307884 -29.647922) (xy 381.363257 -29.624986) (xy 381.42115 -29.609473)
			(xy 381.480572 -29.60165) (xy 381.540508 -29.60165) (xy 381.59993 -29.609473) (xy 381.657823 -29.624986)
			(xy 381.713196 -29.647922) (xy 381.765102 -29.677889) (xy 381.812652 -29.714376) (xy 381.855032 -29.756756)
			(xy 381.891519 -29.804306) (xy 381.921486 -29.856212) (xy 381.944422 -29.911585) (xy 381.959935 -29.969478)
			(xy 381.967758 -30.0289) (xy 381.968248 -30.058868) (xy 381.968248 -30.92069) (xy 395.789404 -30.92069)
			(xy 395.789404 -30.05709) (xy 395.789894 -30.027106) (xy 395.797722 -29.96765) (xy 395.813243 -29.909725)
			(xy 395.836192 -29.854321) (xy 395.866176 -29.802387) (xy 395.902682 -29.754811) (xy 395.945087 -29.712406)
			(xy 395.992663 -29.6759) (xy 396.044597 -29.645916) (xy 396.100001 -29.622967) (xy 396.157926 -29.607446)
			(xy 396.217382 -29.599618) (xy 396.27735 -29.599618) (xy 396.336806 -29.607446) (xy 396.394731 -29.622967)
			(xy 396.450135 -29.645916) (xy 396.502069 -29.6759) (xy 396.549645 -29.712406) (xy 396.59205 -29.754811)
			(xy 396.628556 -29.802387) (xy 396.65854 -29.854321) (xy 396.681489 -29.909725) (xy 396.69701 -29.96765)
			(xy 396.704838 -30.027106) (xy 396.705328 -30.05709) (xy 396.705328 -30.92069) (xy 396.705299 -30.922468)
			(xy 407.05278 -30.922468) (xy 407.05278 -30.058868) (xy 407.05327 -30.0289) (xy 407.061093 -29.969478)
			(xy 407.076606 -29.911585) (xy 407.099542 -29.856212) (xy 407.129509 -29.804306) (xy 407.165996 -29.756756)
			(xy 407.208376 -29.714376) (xy 407.255926 -29.677889) (xy 407.307832 -29.647922) (xy 407.363205 -29.624986)
			(xy 407.421098 -29.609473) (xy 407.48052 -29.60165) (xy 407.540456 -29.60165) (xy 407.599878 -29.609473)
			(xy 407.657771 -29.624986) (xy 407.713144 -29.647922) (xy 407.76505 -29.677889) (xy 407.8126 -29.714376)
			(xy 407.85498 -29.756756) (xy 407.891467 -29.804306) (xy 407.921434 -29.856212) (xy 407.94437 -29.911585)
			(xy 407.959883 -29.969478) (xy 407.967706 -30.0289) (xy 407.968196 -30.058868) (xy 407.968196 -30.92069)
			(xy 421.789352 -30.92069) (xy 421.789352 -30.05709) (xy 421.789842 -30.027106) (xy 421.79767 -29.96765)
			(xy 421.813191 -29.909725) (xy 421.83614 -29.854321) (xy 421.866124 -29.802387) (xy 421.90263 -29.754811)
			(xy 421.945035 -29.712406) (xy 421.992611 -29.6759) (xy 422.044545 -29.645916) (xy 422.099949 -29.622967)
			(xy 422.157874 -29.607446) (xy 422.21733 -29.599618) (xy 422.277298 -29.599618) (xy 422.336754 -29.607446)
			(xy 422.394679 -29.622967) (xy 422.450083 -29.645916) (xy 422.502017 -29.6759) (xy 422.549593 -29.712406)
			(xy 422.591998 -29.754811) (xy 422.628504 -29.802387) (xy 422.658488 -29.854321) (xy 422.681437 -29.909725)
			(xy 422.696958 -29.96765) (xy 422.704786 -30.027106) (xy 422.705276 -30.05709) (xy 422.705276 -30.92069)
			(xy 422.705247 -30.922468) (xy 433.052728 -30.922468) (xy 433.052728 -30.058868) (xy 433.053218 -30.0289)
			(xy 433.061041 -29.969478) (xy 433.076554 -29.911585) (xy 433.09949 -29.856212) (xy 433.129457 -29.804306)
			(xy 433.165944 -29.756756) (xy 433.208324 -29.714376) (xy 433.255874 -29.677889) (xy 433.30778 -29.647922)
			(xy 433.363153 -29.624986) (xy 433.421046 -29.609473) (xy 433.480468 -29.60165) (xy 433.540404 -29.60165)
			(xy 433.599826 -29.609473) (xy 433.657719 -29.624986) (xy 433.713092 -29.647922) (xy 433.764998 -29.677889)
			(xy 433.812548 -29.714376) (xy 433.854928 -29.756756) (xy 433.891415 -29.804306) (xy 433.921382 -29.856212)
			(xy 433.944318 -29.911585) (xy 433.959831 -29.969478) (xy 433.967654 -30.0289) (xy 433.968144 -30.058868)
			(xy 433.968144 -30.92069) (xy 447.7893 -30.92069) (xy 447.7893 -30.05709) (xy 447.78979 -30.027106)
			(xy 447.797618 -29.96765) (xy 447.813139 -29.909725) (xy 447.836088 -29.854321) (xy 447.866072 -29.802387)
			(xy 447.902578 -29.754811) (xy 447.944983 -29.712406) (xy 447.992559 -29.6759) (xy 448.044493 -29.645916)
			(xy 448.099897 -29.622967) (xy 448.157822 -29.607446) (xy 448.217278 -29.599618) (xy 448.277246 -29.599618)
			(xy 448.336702 -29.607446) (xy 448.394627 -29.622967) (xy 448.450031 -29.645916) (xy 448.501965 -29.6759)
			(xy 448.549541 -29.712406) (xy 448.591946 -29.754811) (xy 448.628452 -29.802387) (xy 448.658436 -29.854321)
			(xy 448.681385 -29.909725) (xy 448.696906 -29.96765) (xy 448.704734 -30.027106) (xy 448.705224 -30.05709)
			(xy 448.705224 -30.745738) (xy 457.614517 -30.745738) (xy 457.614517 -30.616598) (xy 457.622467 -30.487703)
			(xy 457.638337 -30.359543) (xy 457.662066 -30.232602) (xy 457.693565 -30.107363) (xy 457.732714 -29.9843)
			(xy 457.779365 -29.863881) (xy 457.83334 -29.746562) (xy 457.894435 -29.632788) (xy 457.962418 -29.522991)
			(xy 458.037032 -29.417588) (xy 458.117993 -29.316978) (xy 458.204993 -29.221543) (xy 458.297704 -29.131644)
			(xy 458.395774 -29.047623) (xy 458.498829 -28.969799) (xy 458.60648 -28.898467) (xy 458.718319 -28.833897)
			(xy 458.83392 -28.776335) (xy 458.952845 -28.725998) (xy 459.074644 -28.683078) (xy 459.198854 -28.647737)
			(xy 459.325003 -28.62011) (xy 459.452615 -28.600301) (xy 459.581204 -28.588385) (xy 459.710282 -28.584409)
			(xy 459.83936 -28.588385) (xy 459.967949 -28.600301) (xy 460.095561 -28.62011) (xy 460.22171 -28.647737)
			(xy 460.34592 -28.683078) (xy 460.467719 -28.725998) (xy 460.586644 -28.776335) (xy 460.702245 -28.833897)
			(xy 460.814084 -28.898467) (xy 460.921735 -28.969799) (xy 461.02479 -29.047623) (xy 461.12286 -29.131644)
			(xy 461.215571 -29.221543) (xy 461.302571 -29.316978) (xy 461.383532 -29.417588) (xy 461.458146 -29.522991)
			(xy 461.526129 -29.632788) (xy 461.587224 -29.746562) (xy 461.641199 -29.863881) (xy 461.68785 -29.9843)
			(xy 461.726999 -30.107363) (xy 461.758498 -30.232602) (xy 461.782227 -30.359543) (xy 461.798097 -30.487703)
			(xy 461.806047 -30.616598) (xy 461.806544 -30.681168) (xy 461.806047 -30.745738) (xy 461.798097 -30.874633)
			(xy 461.782227 -31.002793) (xy 461.758498 -31.129734) (xy 461.726999 -31.254973) (xy 461.68785 -31.378036)
			(xy 461.641199 -31.498455) (xy 461.587224 -31.615774) (xy 461.526129 -31.729548) (xy 461.458146 -31.839345)
			(xy 461.383532 -31.944748) (xy 461.302571 -32.045358) (xy 461.215571 -32.140793) (xy 461.12286 -32.230692)
			(xy 461.02479 -32.314713) (xy 460.921735 -32.392537) (xy 460.814084 -32.463869) (xy 460.702245 -32.528439)
			(xy 460.586644 -32.586001) (xy 460.467719 -32.636338) (xy 460.34592 -32.679258) (xy 460.22171 -32.714599)
			(xy 460.095561 -32.742226) (xy 459.967949 -32.762035) (xy 459.83936 -32.773951) (xy 459.710282 -32.777928)
			(xy 459.581204 -32.773951) (xy 459.452615 -32.762035) (xy 459.325003 -32.742226) (xy 459.198854 -32.714599)
			(xy 459.074644 -32.679258) (xy 458.952845 -32.636338) (xy 458.83392 -32.586001) (xy 458.718319 -32.528439)
			(xy 458.60648 -32.463869) (xy 458.498829 -32.392537) (xy 458.395774 -32.314713) (xy 458.297704 -32.230692)
			(xy 458.204993 -32.140793) (xy 458.117993 -32.045358) (xy 458.037032 -31.944748) (xy 457.962418 -31.839345)
			(xy 457.894435 -31.729548) (xy 457.83334 -31.615774) (xy 457.779365 -31.498455) (xy 457.732714 -31.378036)
			(xy 457.693565 -31.254973) (xy 457.662066 -31.129734) (xy 457.638337 -31.002793) (xy 457.622467 -30.874633)
			(xy 457.614517 -30.745738) (xy 448.705224 -30.745738) (xy 448.705224 -30.92069) (xy 448.704734 -30.950674)
			(xy 448.696906 -31.01013) (xy 448.681385 -31.068055) (xy 448.658436 -31.123459) (xy 448.628452 -31.175393)
			(xy 448.591946 -31.222969) (xy 448.549541 -31.265374) (xy 448.501965 -31.30188) (xy 448.450031 -31.331864)
			(xy 448.394627 -31.354813) (xy 448.336702 -31.370334) (xy 448.277246 -31.378162) (xy 448.217278 -31.378162)
			(xy 448.157822 -31.370334) (xy 448.099897 -31.354813) (xy 448.044493 -31.331864) (xy 447.992559 -31.30188)
			(xy 447.944983 -31.265374) (xy 447.902578 -31.222969) (xy 447.866072 -31.175393) (xy 447.836088 -31.123459)
			(xy 447.813139 -31.068055) (xy 447.797618 -31.01013) (xy 447.78979 -30.950674) (xy 447.7893 -30.92069)
			(xy 433.968144 -30.92069) (xy 433.968144 -30.922468) (xy 433.967654 -30.952436) (xy 433.959831 -31.011858)
			(xy 433.944318 -31.069751) (xy 433.921382 -31.125124) (xy 433.891415 -31.17703) (xy 433.854928 -31.22458)
			(xy 433.812548 -31.26696) (xy 433.764998 -31.303447) (xy 433.713092 -31.333414) (xy 433.657719 -31.35635)
			(xy 433.599826 -31.371863) (xy 433.540404 -31.379686) (xy 433.480468 -31.379686) (xy 433.421046 -31.371863)
			(xy 433.363153 -31.35635) (xy 433.30778 -31.333414) (xy 433.255874 -31.303447) (xy 433.208324 -31.26696)
			(xy 433.165944 -31.22458) (xy 433.129457 -31.17703) (xy 433.09949 -31.125124) (xy 433.076554 -31.069751)
			(xy 433.061041 -31.011858) (xy 433.053218 -30.952436) (xy 433.052728 -30.922468) (xy 422.705247 -30.922468)
			(xy 422.704786 -30.950674) (xy 422.696958 -31.01013) (xy 422.681437 -31.068055) (xy 422.658488 -31.123459)
			(xy 422.628504 -31.175393) (xy 422.591998 -31.222969) (xy 422.549593 -31.265374) (xy 422.502017 -31.30188)
			(xy 422.450083 -31.331864) (xy 422.394679 -31.354813) (xy 422.336754 -31.370334) (xy 422.277298 -31.378162)
			(xy 422.21733 -31.378162) (xy 422.157874 -31.370334) (xy 422.099949 -31.354813) (xy 422.044545 -31.331864)
			(xy 421.992611 -31.30188) (xy 421.945035 -31.265374) (xy 421.90263 -31.222969) (xy 421.866124 -31.175393)
			(xy 421.83614 -31.123459) (xy 421.813191 -31.068055) (xy 421.79767 -31.01013) (xy 421.789842 -30.950674)
			(xy 421.789352 -30.92069) (xy 407.968196 -30.92069) (xy 407.968196 -30.922468) (xy 407.967706 -30.952436)
			(xy 407.959883 -31.011858) (xy 407.94437 -31.069751) (xy 407.921434 -31.125124) (xy 407.891467 -31.17703)
			(xy 407.85498 -31.22458) (xy 407.8126 -31.26696) (xy 407.76505 -31.303447) (xy 407.713144 -31.333414)
			(xy 407.657771 -31.35635) (xy 407.599878 -31.371863) (xy 407.540456 -31.379686) (xy 407.48052 -31.379686)
			(xy 407.421098 -31.371863) (xy 407.363205 -31.35635) (xy 407.307832 -31.333414) (xy 407.255926 -31.303447)
			(xy 407.208376 -31.26696) (xy 407.165996 -31.22458) (xy 407.129509 -31.17703) (xy 407.099542 -31.125124)
			(xy 407.076606 -31.069751) (xy 407.061093 -31.011858) (xy 407.05327 -30.952436) (xy 407.05278 -30.922468)
			(xy 396.705299 -30.922468) (xy 396.704838 -30.950674) (xy 396.69701 -31.01013) (xy 396.681489 -31.068055)
			(xy 396.65854 -31.123459) (xy 396.628556 -31.175393) (xy 396.59205 -31.222969) (xy 396.549645 -31.265374)
			(xy 396.502069 -31.30188) (xy 396.450135 -31.331864) (xy 396.394731 -31.354813) (xy 396.336806 -31.370334)
			(xy 396.27735 -31.378162) (xy 396.217382 -31.378162) (xy 396.157926 -31.370334) (xy 396.100001 -31.354813)
			(xy 396.044597 -31.331864) (xy 395.992663 -31.30188) (xy 395.945087 -31.265374) (xy 395.902682 -31.222969)
			(xy 395.866176 -31.175393) (xy 395.836192 -31.123459) (xy 395.813243 -31.068055) (xy 395.797722 -31.01013)
			(xy 395.789894 -30.950674) (xy 395.789404 -30.92069) (xy 381.968248 -30.92069) (xy 381.968248 -30.922468)
			(xy 381.967758 -30.952436) (xy 381.959935 -31.011858) (xy 381.944422 -31.069751) (xy 381.921486 -31.125124)
			(xy 381.891519 -31.17703) (xy 381.855032 -31.22458) (xy 381.812652 -31.26696) (xy 381.765102 -31.303447)
			(xy 381.713196 -31.333414) (xy 381.657823 -31.35635) (xy 381.59993 -31.371863) (xy 381.540508 -31.379686)
			(xy 381.480572 -31.379686) (xy 381.42115 -31.371863) (xy 381.363257 -31.35635) (xy 381.307884 -31.333414)
			(xy 381.255978 -31.303447) (xy 381.208428 -31.26696) (xy 381.166048 -31.22458) (xy 381.129561 -31.17703)
			(xy 381.099594 -31.125124) (xy 381.076658 -31.069751) (xy 381.061145 -31.011858) (xy 381.053322 -30.952436)
			(xy 381.052832 -30.922468) (xy 370.705351 -30.922468) (xy 370.70489 -30.950674) (xy 370.697062 -31.01013)
			(xy 370.681541 -31.068055) (xy 370.658592 -31.123459) (xy 370.628608 -31.175393) (xy 370.592102 -31.222969)
			(xy 370.549697 -31.265374) (xy 370.502121 -31.30188) (xy 370.450187 -31.331864) (xy 370.394783 -31.354813)
			(xy 370.336858 -31.370334) (xy 370.277402 -31.378162) (xy 370.217434 -31.378162) (xy 370.157978 -31.370334)
			(xy 370.100053 -31.354813) (xy 370.044649 -31.331864) (xy 369.992715 -31.30188) (xy 369.945139 -31.265374)
			(xy 369.902734 -31.222969) (xy 369.866228 -31.175393) (xy 369.836244 -31.123459) (xy 369.813295 -31.068055)
			(xy 369.797774 -31.01013) (xy 369.789946 -30.950674) (xy 369.789456 -30.92069) (xy 355.9683 -30.92069)
			(xy 355.9683 -30.922468) (xy 355.96781 -30.952436) (xy 355.959987 -31.011858) (xy 355.944474 -31.069751)
			(xy 355.921538 -31.125124) (xy 355.891571 -31.17703) (xy 355.855084 -31.22458) (xy 355.812704 -31.26696)
			(xy 355.765154 -31.303447) (xy 355.713248 -31.333414) (xy 355.657875 -31.35635) (xy 355.599982 -31.371863)
			(xy 355.54056 -31.379686) (xy 355.480624 -31.379686) (xy 355.421202 -31.371863) (xy 355.363309 -31.35635)
			(xy 355.307936 -31.333414) (xy 355.25603 -31.303447) (xy 355.20848 -31.26696) (xy 355.1661 -31.22458)
			(xy 355.129613 -31.17703) (xy 355.099646 -31.125124) (xy 355.07671 -31.069751) (xy 355.061197 -31.011858)
			(xy 355.053374 -30.952436) (xy 355.052884 -30.922468) (xy 332.604843 -30.922468) (xy 332.604382 -30.950658)
			(xy 332.596559 -31.01008) (xy 332.581046 -31.067973) (xy 332.55811 -31.123346) (xy 332.528143 -31.175252)
			(xy 332.491656 -31.222802) (xy 332.449276 -31.265182) (xy 332.401726 -31.301669) (xy 332.34982 -31.331636)
			(xy 332.294447 -31.354572) (xy 332.236554 -31.370085) (xy 332.177132 -31.377908) (xy 332.117196 -31.377908)
			(xy 332.057774 -31.370085) (xy 331.999881 -31.354572) (xy 331.944508 -31.331636) (xy 331.892602 -31.301669)
			(xy 331.845052 -31.265182) (xy 331.802672 -31.222802) (xy 331.766185 -31.175252) (xy 331.736218 -31.123346)
			(xy 331.713282 -31.067973) (xy 331.697769 -31.01008) (xy 331.689946 -30.950658) (xy 331.689456 -30.92069)
			(xy 317.8683 -30.92069) (xy 317.8683 -30.922468) (xy 317.86781 -30.952452) (xy 317.859982 -31.011908)
			(xy 317.844461 -31.069833) (xy 317.821512 -31.125237) (xy 317.791528 -31.177171) (xy 317.755022 -31.224747)
			(xy 317.712617 -31.267152) (xy 317.665041 -31.303658) (xy 317.613107 -31.333642) (xy 317.557703 -31.356591)
			(xy 317.499778 -31.372112) (xy 317.440322 -31.37994) (xy 317.380354 -31.37994) (xy 317.320898 -31.372112)
			(xy 317.262973 -31.356591) (xy 317.207569 -31.333642) (xy 317.155635 -31.303658) (xy 317.108059 -31.267152)
			(xy 317.065654 -31.224747) (xy 317.029148 -31.177171) (xy 316.999164 -31.125237) (xy 316.976215 -31.069833)
			(xy 316.960694 -31.011908) (xy 316.952866 -30.952452) (xy 316.952376 -30.922468) (xy 306.604895 -30.922468)
			(xy 306.604434 -30.950658) (xy 306.596611 -31.01008) (xy 306.581098 -31.067973) (xy 306.558162 -31.123346)
			(xy 306.528195 -31.175252) (xy 306.491708 -31.222802) (xy 306.449328 -31.265182) (xy 306.401778 -31.301669)
			(xy 306.349872 -31.331636) (xy 306.294499 -31.354572) (xy 306.236606 -31.370085) (xy 306.177184 -31.377908)
			(xy 306.117248 -31.377908) (xy 306.057826 -31.370085) (xy 305.999933 -31.354572) (xy 305.94456 -31.331636)
			(xy 305.892654 -31.301669) (xy 305.845104 -31.265182) (xy 305.802724 -31.222802) (xy 305.766237 -31.175252)
			(xy 305.73627 -31.123346) (xy 305.713334 -31.067973) (xy 305.697821 -31.01008) (xy 305.689998 -30.950658)
			(xy 305.689508 -30.92069) (xy 291.868352 -30.92069) (xy 291.868352 -30.922468) (xy 291.867862 -30.952452)
			(xy 291.860034 -31.011908) (xy 291.844513 -31.069833) (xy 291.821564 -31.125237) (xy 291.79158 -31.177171)
			(xy 291.755074 -31.224747) (xy 291.712669 -31.267152) (xy 291.665093 -31.303658) (xy 291.613159 -31.333642)
			(xy 291.557755 -31.356591) (xy 291.49983 -31.372112) (xy 291.440374 -31.37994) (xy 291.380406 -31.37994)
			(xy 291.32095 -31.372112) (xy 291.263025 -31.356591) (xy 291.207621 -31.333642) (xy 291.155687 -31.303658)
			(xy 291.108111 -31.267152) (xy 291.065706 -31.224747) (xy 291.0292 -31.177171) (xy 290.999216 -31.125237)
			(xy 290.976267 -31.069833) (xy 290.960746 -31.011908) (xy 290.952918 -30.952452) (xy 290.952428 -30.922468)
			(xy 280.604947 -30.922468) (xy 280.604486 -30.950658) (xy 280.596663 -31.01008) (xy 280.58115 -31.067973)
			(xy 280.558214 -31.123346) (xy 280.528247 -31.175252) (xy 280.49176 -31.222802) (xy 280.44938 -31.265182)
			(xy 280.40183 -31.301669) (xy 280.349924 -31.331636) (xy 280.294551 -31.354572) (xy 280.236658 -31.370085)
			(xy 280.177236 -31.377908) (xy 280.1173 -31.377908) (xy 280.057878 -31.370085) (xy 279.999985 -31.354572)
			(xy 279.944612 -31.331636) (xy 279.892706 -31.301669) (xy 279.845156 -31.265182) (xy 279.802776 -31.222802)
			(xy 279.766289 -31.175252) (xy 279.736322 -31.123346) (xy 279.713386 -31.067973) (xy 279.697873 -31.01008)
			(xy 279.69005 -30.950658) (xy 279.68956 -30.92069) (xy 265.868404 -30.92069) (xy 265.868404 -30.922468)
			(xy 265.867914 -30.952452) (xy 265.860086 -31.011908) (xy 265.844565 -31.069833) (xy 265.821616 -31.125237)
			(xy 265.791632 -31.177171) (xy 265.755126 -31.224747) (xy 265.712721 -31.267152) (xy 265.665145 -31.303658)
			(xy 265.613211 -31.333642) (xy 265.557807 -31.356591) (xy 265.499882 -31.372112) (xy 265.440426 -31.37994)
			(xy 265.380458 -31.37994) (xy 265.321002 -31.372112) (xy 265.263077 -31.356591) (xy 265.207673 -31.333642)
			(xy 265.155739 -31.303658) (xy 265.108163 -31.267152) (xy 265.065758 -31.224747) (xy 265.029252 -31.177171)
			(xy 264.999268 -31.125237) (xy 264.976319 -31.069833) (xy 264.960798 -31.011908) (xy 264.95297 -30.952452)
			(xy 264.95248 -30.922468) (xy 254.604999 -30.922468) (xy 254.604538 -30.950658) (xy 254.596715 -31.01008)
			(xy 254.581202 -31.067973) (xy 254.558266 -31.123346) (xy 254.528299 -31.175252) (xy 254.491812 -31.222802)
			(xy 254.449432 -31.265182) (xy 254.401882 -31.301669) (xy 254.349976 -31.331636) (xy 254.294603 -31.354572)
			(xy 254.23671 -31.370085) (xy 254.177288 -31.377908) (xy 254.117352 -31.377908) (xy 254.05793 -31.370085)
			(xy 254.000037 -31.354572) (xy 253.944664 -31.331636) (xy 253.892758 -31.301669) (xy 253.845208 -31.265182)
			(xy 253.802828 -31.222802) (xy 253.766341 -31.175252) (xy 253.736374 -31.123346) (xy 253.713438 -31.067973)
			(xy 253.697925 -31.01008) (xy 253.690102 -30.950658) (xy 253.689612 -30.92069) (xy 239.868456 -30.92069)
			(xy 239.868456 -30.922468) (xy 239.867966 -30.952452) (xy 239.860138 -31.011908) (xy 239.844617 -31.069833)
			(xy 239.821668 -31.125237) (xy 239.791684 -31.177171) (xy 239.755178 -31.224747) (xy 239.712773 -31.267152)
			(xy 239.665197 -31.303658) (xy 239.613263 -31.333642) (xy 239.557859 -31.356591) (xy 239.499934 -31.372112)
			(xy 239.440478 -31.37994) (xy 239.38051 -31.37994) (xy 239.321054 -31.372112) (xy 239.263129 -31.356591)
			(xy 239.207725 -31.333642) (xy 239.155791 -31.303658) (xy 239.108215 -31.267152) (xy 239.06581 -31.224747)
			(xy 239.029304 -31.177171) (xy 238.99932 -31.125237) (xy 238.976371 -31.069833) (xy 238.96085 -31.011908)
			(xy 238.953022 -30.952452) (xy 238.952532 -30.922468) (xy 216.504999 -30.922468) (xy 216.504538 -30.950658)
			(xy 216.496715 -31.01008) (xy 216.481202 -31.067973) (xy 216.458266 -31.123346) (xy 216.428299 -31.175252)
			(xy 216.391812 -31.222802) (xy 216.349432 -31.265182) (xy 216.301882 -31.301669) (xy 216.249976 -31.331636)
			(xy 216.194603 -31.354572) (xy 216.13671 -31.370085) (xy 216.077288 -31.377908) (xy 216.017352 -31.377908)
			(xy 215.95793 -31.370085) (xy 215.900037 -31.354572) (xy 215.844664 -31.331636) (xy 215.792758 -31.301669)
			(xy 215.745208 -31.265182) (xy 215.702828 -31.222802) (xy 215.666341 -31.175252) (xy 215.636374 -31.123346)
			(xy 215.613438 -31.067973) (xy 215.597925 -31.01008) (xy 215.590102 -30.950658) (xy 215.589612 -30.92069)
			(xy 201.768456 -30.92069) (xy 201.768456 -30.922468) (xy 201.767966 -30.952452) (xy 201.760138 -31.011908)
			(xy 201.744617 -31.069833) (xy 201.721668 -31.125237) (xy 201.691684 -31.177171) (xy 201.655178 -31.224747)
			(xy 201.612773 -31.267152) (xy 201.565197 -31.303658) (xy 201.513263 -31.333642) (xy 201.457859 -31.356591)
			(xy 201.399934 -31.372112) (xy 201.340478 -31.37994) (xy 201.28051 -31.37994) (xy 201.221054 -31.372112)
			(xy 201.163129 -31.356591) (xy 201.107725 -31.333642) (xy 201.055791 -31.303658) (xy 201.008215 -31.267152)
			(xy 200.96581 -31.224747) (xy 200.929304 -31.177171) (xy 200.89932 -31.125237) (xy 200.876371 -31.069833)
			(xy 200.86085 -31.011908) (xy 200.853022 -30.952452) (xy 200.852532 -30.922468) (xy 190.505051 -30.922468)
			(xy 190.50459 -30.950658) (xy 190.496767 -31.01008) (xy 190.481254 -31.067973) (xy 190.458318 -31.123346)
			(xy 190.428351 -31.175252) (xy 190.391864 -31.222802) (xy 190.349484 -31.265182) (xy 190.301934 -31.301669)
			(xy 190.250028 -31.331636) (xy 190.194655 -31.354572) (xy 190.136762 -31.370085) (xy 190.07734 -31.377908)
			(xy 190.017404 -31.377908) (xy 189.957982 -31.370085) (xy 189.900089 -31.354572) (xy 189.844716 -31.331636)
			(xy 189.79281 -31.301669) (xy 189.74526 -31.265182) (xy 189.70288 -31.222802) (xy 189.666393 -31.175252)
			(xy 189.636426 -31.123346) (xy 189.61349 -31.067973) (xy 189.597977 -31.01008) (xy 189.590154 -30.950658)
			(xy 189.589664 -30.92069) (xy 175.768508 -30.92069) (xy 175.768508 -30.922468) (xy 175.768018 -30.952452)
			(xy 175.76019 -31.011908) (xy 175.744669 -31.069833) (xy 175.72172 -31.125237) (xy 175.691736 -31.177171)
			(xy 175.65523 -31.224747) (xy 175.612825 -31.267152) (xy 175.565249 -31.303658) (xy 175.513315 -31.333642)
			(xy 175.457911 -31.356591) (xy 175.399986 -31.372112) (xy 175.34053 -31.37994) (xy 175.280562 -31.37994)
			(xy 175.221106 -31.372112) (xy 175.163181 -31.356591) (xy 175.107777 -31.333642) (xy 175.055843 -31.303658)
			(xy 175.008267 -31.267152) (xy 174.965862 -31.224747) (xy 174.929356 -31.177171) (xy 174.899372 -31.125237)
			(xy 174.876423 -31.069833) (xy 174.860902 -31.011908) (xy 174.853074 -30.952452) (xy 174.852584 -30.922468)
			(xy 164.505103 -30.922468) (xy 164.504642 -30.950658) (xy 164.496819 -31.01008) (xy 164.481306 -31.067973)
			(xy 164.45837 -31.123346) (xy 164.428403 -31.175252) (xy 164.391916 -31.222802) (xy 164.349536 -31.265182)
			(xy 164.301986 -31.301669) (xy 164.25008 -31.331636) (xy 164.194707 -31.354572) (xy 164.136814 -31.370085)
			(xy 164.077392 -31.377908) (xy 164.017456 -31.377908) (xy 163.958034 -31.370085) (xy 163.900141 -31.354572)
			(xy 163.844768 -31.331636) (xy 163.792862 -31.301669) (xy 163.745312 -31.265182) (xy 163.702932 -31.222802)
			(xy 163.666445 -31.175252) (xy 163.636478 -31.123346) (xy 163.613542 -31.067973) (xy 163.598029 -31.01008)
			(xy 163.590206 -30.950658) (xy 163.589716 -30.92069) (xy 149.76856 -30.92069) (xy 149.76856 -30.922468)
			(xy 149.76807 -30.952452) (xy 149.760242 -31.011908) (xy 149.744721 -31.069833) (xy 149.721772 -31.125237)
			(xy 149.691788 -31.177171) (xy 149.655282 -31.224747) (xy 149.612877 -31.267152) (xy 149.565301 -31.303658)
			(xy 149.513367 -31.333642) (xy 149.457963 -31.356591) (xy 149.400038 -31.372112) (xy 149.340582 -31.37994)
			(xy 149.280614 -31.37994) (xy 149.221158 -31.372112) (xy 149.163233 -31.356591) (xy 149.107829 -31.333642)
			(xy 149.055895 -31.303658) (xy 149.008319 -31.267152) (xy 148.965914 -31.224747) (xy 148.929408 -31.177171)
			(xy 148.899424 -31.125237) (xy 148.876475 -31.069833) (xy 148.860954 -31.011908) (xy 148.853126 -30.952452)
			(xy 148.852636 -30.922468) (xy 138.505155 -30.922468) (xy 138.504694 -30.950658) (xy 138.496871 -31.01008)
			(xy 138.481358 -31.067973) (xy 138.458422 -31.123346) (xy 138.428455 -31.175252) (xy 138.391968 -31.222802)
			(xy 138.349588 -31.265182) (xy 138.302038 -31.301669) (xy 138.250132 -31.331636) (xy 138.194759 -31.354572)
			(xy 138.136866 -31.370085) (xy 138.077444 -31.377908) (xy 138.017508 -31.377908) (xy 137.958086 -31.370085)
			(xy 137.900193 -31.354572) (xy 137.84482 -31.331636) (xy 137.792914 -31.301669) (xy 137.745364 -31.265182)
			(xy 137.702984 -31.222802) (xy 137.666497 -31.175252) (xy 137.63653 -31.123346) (xy 137.613594 -31.067973)
			(xy 137.598081 -31.01008) (xy 137.590258 -30.950658) (xy 137.589768 -30.92069) (xy 123.768612 -30.92069)
			(xy 123.768612 -30.922468) (xy 123.768122 -30.952452) (xy 123.760294 -31.011908) (xy 123.744773 -31.069833)
			(xy 123.721824 -31.125237) (xy 123.69184 -31.177171) (xy 123.655334 -31.224747) (xy 123.612929 -31.267152)
			(xy 123.565353 -31.303658) (xy 123.513419 -31.333642) (xy 123.458015 -31.356591) (xy 123.40009 -31.372112)
			(xy 123.340634 -31.37994) (xy 123.280666 -31.37994) (xy 123.22121 -31.372112) (xy 123.163285 -31.356591)
			(xy 123.107881 -31.333642) (xy 123.055947 -31.303658) (xy 123.008371 -31.267152) (xy 122.965966 -31.224747)
			(xy 122.92946 -31.177171) (xy 122.899476 -31.125237) (xy 122.876527 -31.069833) (xy 122.861006 -31.011908)
			(xy 122.853178 -30.952452) (xy 122.852688 -30.922468) (xy 100.405155 -30.922468) (xy 100.404694 -30.950674)
			(xy 100.396866 -31.01013) (xy 100.381345 -31.068055) (xy 100.358396 -31.123459) (xy 100.328412 -31.175393)
			(xy 100.291906 -31.222969) (xy 100.249501 -31.265374) (xy 100.201925 -31.30188) (xy 100.149991 -31.331864)
			(xy 100.094587 -31.354813) (xy 100.036662 -31.370334) (xy 99.977206 -31.378162) (xy 99.917238 -31.378162)
			(xy 99.857782 -31.370334) (xy 99.799857 -31.354813) (xy 99.744453 -31.331864) (xy 99.692519 -31.30188)
			(xy 99.644943 -31.265374) (xy 99.602538 -31.222969) (xy 99.566032 -31.175393) (xy 99.536048 -31.123459)
			(xy 99.513099 -31.068055) (xy 99.497578 -31.01013) (xy 99.48975 -30.950674) (xy 99.48926 -30.92069)
			(xy 85.668104 -30.92069) (xy 85.668104 -30.922468) (xy 85.667614 -30.952436) (xy 85.659791 -31.011858)
			(xy 85.644278 -31.069751) (xy 85.621342 -31.125124) (xy 85.591375 -31.17703) (xy 85.554888 -31.22458)
			(xy 85.512508 -31.26696) (xy 85.464958 -31.303447) (xy 85.413052 -31.333414) (xy 85.357679 -31.35635)
			(xy 85.299786 -31.371863) (xy 85.240364 -31.379686) (xy 85.180428 -31.379686) (xy 85.121006 -31.371863)
			(xy 85.063113 -31.35635) (xy 85.00774 -31.333414) (xy 84.955834 -31.303447) (xy 84.908284 -31.26696)
			(xy 84.865904 -31.22458) (xy 84.829417 -31.17703) (xy 84.79945 -31.125124) (xy 84.776514 -31.069751)
			(xy 84.761001 -31.011858) (xy 84.753178 -30.952436) (xy 84.752688 -30.922468) (xy 74.405207 -30.922468)
			(xy 74.404746 -30.950674) (xy 74.396918 -31.01013) (xy 74.381397 -31.068055) (xy 74.358448 -31.123459)
			(xy 74.328464 -31.175393) (xy 74.291958 -31.222969) (xy 74.249553 -31.265374) (xy 74.201977 -31.30188)
			(xy 74.150043 -31.331864) (xy 74.094639 -31.354813) (xy 74.036714 -31.370334) (xy 73.977258 -31.378162)
			(xy 73.91729 -31.378162) (xy 73.857834 -31.370334) (xy 73.799909 -31.354813) (xy 73.744505 -31.331864)
			(xy 73.692571 -31.30188) (xy 73.644995 -31.265374) (xy 73.60259 -31.222969) (xy 73.566084 -31.175393)
			(xy 73.5361 -31.123459) (xy 73.513151 -31.068055) (xy 73.49763 -31.01013) (xy 73.489802 -30.950674)
			(xy 73.489312 -30.92069) (xy 59.668156 -30.92069) (xy 59.668156 -30.922468) (xy 59.667666 -30.952436)
			(xy 59.659843 -31.011858) (xy 59.64433 -31.069751) (xy 59.621394 -31.125124) (xy 59.591427 -31.17703)
			(xy 59.55494 -31.22458) (xy 59.51256 -31.26696) (xy 59.46501 -31.303447) (xy 59.413104 -31.333414)
			(xy 59.357731 -31.35635) (xy 59.299838 -31.371863) (xy 59.240416 -31.379686) (xy 59.18048 -31.379686)
			(xy 59.121058 -31.371863) (xy 59.063165 -31.35635) (xy 59.007792 -31.333414) (xy 58.955886 -31.303447)
			(xy 58.908336 -31.26696) (xy 58.865956 -31.22458) (xy 58.829469 -31.17703) (xy 58.799502 -31.125124)
			(xy 58.776566 -31.069751) (xy 58.761053 -31.011858) (xy 58.75323 -30.952436) (xy 58.75274 -30.922468)
			(xy 48.405259 -30.922468) (xy 48.404798 -30.950674) (xy 48.39697 -31.01013) (xy 48.381449 -31.068055)
			(xy 48.3585 -31.123459) (xy 48.328516 -31.175393) (xy 48.29201 -31.222969) (xy 48.249605 -31.265374)
			(xy 48.202029 -31.30188) (xy 48.150095 -31.331864) (xy 48.094691 -31.354813) (xy 48.036766 -31.370334)
			(xy 47.97731 -31.378162) (xy 47.917342 -31.378162) (xy 47.857886 -31.370334) (xy 47.799961 -31.354813)
			(xy 47.744557 -31.331864) (xy 47.692623 -31.30188) (xy 47.645047 -31.265374) (xy 47.602642 -31.222969)
			(xy 47.566136 -31.175393) (xy 47.536152 -31.123459) (xy 47.513203 -31.068055) (xy 47.497682 -31.01013)
			(xy 47.489854 -30.950674) (xy 47.489364 -30.92069) (xy 33.668208 -30.92069) (xy 33.668208 -30.922468)
			(xy 33.667718 -30.952436) (xy 33.659895 -31.011858) (xy 33.644382 -31.069751) (xy 33.621446 -31.125124)
			(xy 33.591479 -31.17703) (xy 33.554992 -31.22458) (xy 33.512612 -31.26696) (xy 33.465062 -31.303447)
			(xy 33.413156 -31.333414) (xy 33.357783 -31.35635) (xy 33.29989 -31.371863) (xy 33.240468 -31.379686)
			(xy 33.180532 -31.379686) (xy 33.12111 -31.371863) (xy 33.063217 -31.35635) (xy 33.007844 -31.333414)
			(xy 32.955938 -31.303447) (xy 32.908388 -31.26696) (xy 32.866008 -31.22458) (xy 32.829521 -31.17703)
			(xy 32.799554 -31.125124) (xy 32.776618 -31.069751) (xy 32.761105 -31.011858) (xy 32.753282 -30.952436)
			(xy 32.752792 -30.922468) (xy 22.405311 -30.922468) (xy 22.40485 -30.950674) (xy 22.397022 -31.01013)
			(xy 22.381501 -31.068055) (xy 22.358552 -31.123459) (xy 22.328568 -31.175393) (xy 22.292062 -31.222969)
			(xy 22.249657 -31.265374) (xy 22.202081 -31.30188) (xy 22.150147 -31.331864) (xy 22.094743 -31.354813)
			(xy 22.036818 -31.370334) (xy 21.977362 -31.378162) (xy 21.917394 -31.378162) (xy 21.857938 -31.370334)
			(xy 21.800013 -31.354813) (xy 21.744609 -31.331864) (xy 21.692675 -31.30188) (xy 21.645099 -31.265374)
			(xy 21.602694 -31.222969) (xy 21.566188 -31.175393) (xy 21.536204 -31.123459) (xy 21.513255 -31.068055)
			(xy 21.497734 -31.01013) (xy 21.489906 -30.950674) (xy 21.489416 -30.92069) (xy 7.66826 -30.92069)
			(xy 7.66826 -30.922468) (xy 7.66777 -30.952436) (xy 7.659947 -31.011858) (xy 7.644434 -31.069751)
			(xy 7.621498 -31.125124) (xy 7.591531 -31.17703) (xy 7.555044 -31.22458) (xy 7.512664 -31.26696)
			(xy 7.465114 -31.303447) (xy 7.413208 -31.333414) (xy 7.357835 -31.35635) (xy 7.299942 -31.371863)
			(xy 7.24052 -31.379686) (xy 7.180584 -31.379686) (xy 7.121162 -31.371863) (xy 7.063269 -31.35635)
			(xy 7.007896 -31.333414) (xy 6.95599 -31.303447) (xy 6.90844 -31.26696) (xy 6.86606 -31.22458) (xy 6.829573 -31.17703)
			(xy 6.799606 -31.125124) (xy 6.77667 -31.069751) (xy 6.761157 -31.011858) (xy 6.753334 -30.952436)
			(xy 6.752844 -30.922468) (xy 1.524 -30.922468) (xy 1.524 -32.722312) (xy 8.607044 -32.722312) (xy 8.607044 -31.858712)
			(xy 8.607534 -31.828744) (xy 8.615357 -31.769322) (xy 8.63087 -31.711429) (xy 8.653806 -31.656056)
			(xy 8.683773 -31.60415) (xy 8.72026 -31.5566) (xy 8.76264 -31.51422) (xy 8.81019 -31.477733) (xy 8.862096 -31.447766)
			(xy 8.917469 -31.42483) (xy 8.975362 -31.409317) (xy 9.034784 -31.401494) (xy 9.09472 -31.401494)
			(xy 9.154142 -31.409317) (xy 9.212035 -31.42483) (xy 9.267408 -31.447766) (xy 9.319314 -31.477733)
			(xy 9.366864 -31.51422) (xy 9.409244 -31.5566) (xy 9.445731 -31.60415) (xy 9.475698 -31.656056) (xy 9.498634 -31.711429)
			(xy 9.514147 -31.769322) (xy 9.52197 -31.828744) (xy 9.52246 -31.858712) (xy 9.52246 -32.714184)
			(xy 18.847308 -32.714184) (xy 18.847308 -31.850584) (xy 18.847798 -31.8206) (xy 18.855626 -31.761144)
			(xy 18.871147 -31.703219) (xy 18.894096 -31.647815) (xy 18.92408 -31.595881) (xy 18.960586 -31.548305)
			(xy 19.002991 -31.5059) (xy 19.050567 -31.469394) (xy 19.102501 -31.43941) (xy 19.157905 -31.416461)
			(xy 19.21583 -31.40094) (xy 19.275286 -31.393112) (xy 19.335254 -31.393112) (xy 19.39471 -31.40094)
			(xy 19.452635 -31.416461) (xy 19.508039 -31.43941) (xy 19.559973 -31.469394) (xy 19.607549 -31.5059)
			(xy 19.649954 -31.548305) (xy 19.68646 -31.595881) (xy 19.716444 -31.647815) (xy 19.739393 -31.703219)
			(xy 19.754914 -31.761144) (xy 19.762742 -31.8206) (xy 19.763232 -31.850584) (xy 19.763232 -32.714184)
			(xy 19.763099 -32.722312) (xy 34.606992 -32.722312) (xy 34.606992 -31.858712) (xy 34.607482 -31.828744)
			(xy 34.615305 -31.769322) (xy 34.630818 -31.711429) (xy 34.653754 -31.656056) (xy 34.683721 -31.60415)
			(xy 34.720208 -31.5566) (xy 34.762588 -31.51422) (xy 34.810138 -31.477733) (xy 34.862044 -31.447766)
			(xy 34.917417 -31.42483) (xy 34.97531 -31.409317) (xy 35.034732 -31.401494) (xy 35.094668 -31.401494)
			(xy 35.15409 -31.409317) (xy 35.211983 -31.42483) (xy 35.267356 -31.447766) (xy 35.319262 -31.477733)
			(xy 35.366812 -31.51422) (xy 35.409192 -31.5566) (xy 35.445679 -31.60415) (xy 35.475646 -31.656056)
			(xy 35.498582 -31.711429) (xy 35.514095 -31.769322) (xy 35.521918 -31.828744) (xy 35.522408 -31.858712)
			(xy 35.522408 -32.714184) (xy 44.847256 -32.714184) (xy 44.847256 -31.850584) (xy 44.847746 -31.8206)
			(xy 44.855574 -31.761144) (xy 44.871095 -31.703219) (xy 44.894044 -31.647815) (xy 44.924028 -31.595881)
			(xy 44.960534 -31.548305) (xy 45.002939 -31.5059) (xy 45.050515 -31.469394) (xy 45.102449 -31.43941)
			(xy 45.157853 -31.416461) (xy 45.215778 -31.40094) (xy 45.275234 -31.393112) (xy 45.335202 -31.393112)
			(xy 45.394658 -31.40094) (xy 45.452583 -31.416461) (xy 45.507987 -31.43941) (xy 45.559921 -31.469394)
			(xy 45.607497 -31.5059) (xy 45.649902 -31.548305) (xy 45.686408 -31.595881) (xy 45.716392 -31.647815)
			(xy 45.739341 -31.703219) (xy 45.754862 -31.761144) (xy 45.76269 -31.8206) (xy 45.76318 -31.850584)
			(xy 45.76318 -32.714184) (xy 45.763047 -32.722312) (xy 60.60694 -32.722312) (xy 60.60694 -31.858712)
			(xy 60.60743 -31.828744) (xy 60.615253 -31.769322) (xy 60.630766 -31.711429) (xy 60.653702 -31.656056)
			(xy 60.683669 -31.60415) (xy 60.720156 -31.5566) (xy 60.762536 -31.51422) (xy 60.810086 -31.477733)
			(xy 60.861992 -31.447766) (xy 60.917365 -31.42483) (xy 60.975258 -31.409317) (xy 61.03468 -31.401494)
			(xy 61.094616 -31.401494) (xy 61.154038 -31.409317) (xy 61.211931 -31.42483) (xy 61.267304 -31.447766)
			(xy 61.31921 -31.477733) (xy 61.36676 -31.51422) (xy 61.40914 -31.5566) (xy 61.445627 -31.60415)
			(xy 61.475594 -31.656056) (xy 61.49853 -31.711429) (xy 61.514043 -31.769322) (xy 61.521866 -31.828744)
			(xy 61.522356 -31.858712) (xy 61.522356 -32.714184) (xy 70.847204 -32.714184) (xy 70.847204 -31.850584)
			(xy 70.847694 -31.8206) (xy 70.855522 -31.761144) (xy 70.871043 -31.703219) (xy 70.893992 -31.647815)
			(xy 70.923976 -31.595881) (xy 70.960482 -31.548305) (xy 71.002887 -31.5059) (xy 71.050463 -31.469394)
			(xy 71.102397 -31.43941) (xy 71.157801 -31.416461) (xy 71.215726 -31.40094) (xy 71.275182 -31.393112)
			(xy 71.33515 -31.393112) (xy 71.394606 -31.40094) (xy 71.452531 -31.416461) (xy 71.507935 -31.43941)
			(xy 71.559869 -31.469394) (xy 71.607445 -31.5059) (xy 71.64985 -31.548305) (xy 71.686356 -31.595881)
			(xy 71.71634 -31.647815) (xy 71.739289 -31.703219) (xy 71.75481 -31.761144) (xy 71.762638 -31.8206)
			(xy 71.763128 -31.850584) (xy 71.763128 -32.714184) (xy 71.762995 -32.722312) (xy 86.606888 -32.722312)
			(xy 86.606888 -31.858712) (xy 86.607378 -31.828744) (xy 86.615201 -31.769322) (xy 86.630714 -31.711429)
			(xy 86.65365 -31.656056) (xy 86.683617 -31.60415) (xy 86.720104 -31.5566) (xy 86.762484 -31.51422)
			(xy 86.810034 -31.477733) (xy 86.86194 -31.447766) (xy 86.917313 -31.42483) (xy 86.975206 -31.409317)
			(xy 87.034628 -31.401494) (xy 87.094564 -31.401494) (xy 87.153986 -31.409317) (xy 87.211879 -31.42483)
			(xy 87.267252 -31.447766) (xy 87.319158 -31.477733) (xy 87.366708 -31.51422) (xy 87.409088 -31.5566)
			(xy 87.445575 -31.60415) (xy 87.475542 -31.656056) (xy 87.498478 -31.711429) (xy 87.513991 -31.769322)
			(xy 87.521814 -31.828744) (xy 87.522304 -31.858712) (xy 87.522304 -32.714184) (xy 96.847152 -32.714184)
			(xy 96.847152 -31.850584) (xy 96.847642 -31.8206) (xy 96.85547 -31.761144) (xy 96.870991 -31.703219)
			(xy 96.89394 -31.647815) (xy 96.923924 -31.595881) (xy 96.96043 -31.548305) (xy 97.002835 -31.5059)
			(xy 97.050411 -31.469394) (xy 97.102345 -31.43941) (xy 97.157749 -31.416461) (xy 97.215674 -31.40094)
			(xy 97.27513 -31.393112) (xy 97.335098 -31.393112) (xy 97.394554 -31.40094) (xy 97.452479 -31.416461)
			(xy 97.507883 -31.43941) (xy 97.559817 -31.469394) (xy 97.607393 -31.5059) (xy 97.649798 -31.548305)
			(xy 97.686304 -31.595881) (xy 97.716288 -31.647815) (xy 97.739237 -31.703219) (xy 97.754758 -31.761144)
			(xy 97.762586 -31.8206) (xy 97.763076 -31.850584) (xy 97.763076 -32.714184) (xy 97.762943 -32.722312)
			(xy 124.706888 -32.722312) (xy 124.706888 -31.858712) (xy 124.707378 -31.828728) (xy 124.715206 -31.769272)
			(xy 124.730727 -31.711347) (xy 124.753676 -31.655943) (xy 124.78366 -31.604009) (xy 124.820166 -31.556433)
			(xy 124.862571 -31.514028) (xy 124.910147 -31.477522) (xy 124.962081 -31.447538) (xy 125.017485 -31.424589)
			(xy 125.07541 -31.409068) (xy 125.134866 -31.40124) (xy 125.194834 -31.40124) (xy 125.25429 -31.409068)
			(xy 125.312215 -31.424589) (xy 125.367619 -31.447538) (xy 125.419553 -31.477522) (xy 125.467129 -31.514028)
			(xy 125.509534 -31.556433) (xy 125.54604 -31.604009) (xy 125.576024 -31.655943) (xy 125.598973 -31.711347)
			(xy 125.614494 -31.769272) (xy 125.622322 -31.828728) (xy 125.622812 -31.858712) (xy 125.622812 -32.714184)
			(xy 134.94766 -32.714184) (xy 134.94766 -31.850584) (xy 134.94815 -31.820616) (xy 134.955973 -31.761194)
			(xy 134.971486 -31.703301) (xy 134.994422 -31.647928) (xy 135.024389 -31.596022) (xy 135.060876 -31.548472)
			(xy 135.103256 -31.506092) (xy 135.150806 -31.469605) (xy 135.202712 -31.439638) (xy 135.258085 -31.416702)
			(xy 135.315978 -31.401189) (xy 135.3754 -31.393366) (xy 135.435336 -31.393366) (xy 135.494758 -31.401189)
			(xy 135.552651 -31.416702) (xy 135.608024 -31.439638) (xy 135.65993 -31.469605) (xy 135.70748 -31.506092)
			(xy 135.74986 -31.548472) (xy 135.786347 -31.596022) (xy 135.816314 -31.647928) (xy 135.83925 -31.703301)
			(xy 135.854763 -31.761194) (xy 135.862586 -31.820616) (xy 135.863076 -31.850584) (xy 135.863076 -32.714184)
			(xy 135.862943 -32.722312) (xy 150.706836 -32.722312) (xy 150.706836 -31.858712) (xy 150.707326 -31.828728)
			(xy 150.715154 -31.769272) (xy 150.730675 -31.711347) (xy 150.753624 -31.655943) (xy 150.783608 -31.604009)
			(xy 150.820114 -31.556433) (xy 150.862519 -31.514028) (xy 150.910095 -31.477522) (xy 150.962029 -31.447538)
			(xy 151.017433 -31.424589) (xy 151.075358 -31.409068) (xy 151.134814 -31.40124) (xy 151.194782 -31.40124)
			(xy 151.254238 -31.409068) (xy 151.312163 -31.424589) (xy 151.367567 -31.447538) (xy 151.419501 -31.477522)
			(xy 151.467077 -31.514028) (xy 151.509482 -31.556433) (xy 151.545988 -31.604009) (xy 151.575972 -31.655943)
			(xy 151.598921 -31.711347) (xy 151.614442 -31.769272) (xy 151.62227 -31.828728) (xy 151.62276 -31.858712)
			(xy 151.62276 -32.714184) (xy 160.947608 -32.714184) (xy 160.947608 -31.850584) (xy 160.948098 -31.820616)
			(xy 160.955921 -31.761194) (xy 160.971434 -31.703301) (xy 160.99437 -31.647928) (xy 161.024337 -31.596022)
			(xy 161.060824 -31.548472) (xy 161.103204 -31.506092) (xy 161.150754 -31.469605) (xy 161.20266 -31.439638)
			(xy 161.258033 -31.416702) (xy 161.315926 -31.401189) (xy 161.375348 -31.393366) (xy 161.435284 -31.393366)
			(xy 161.494706 -31.401189) (xy 161.552599 -31.416702) (xy 161.607972 -31.439638) (xy 161.659878 -31.469605)
			(xy 161.707428 -31.506092) (xy 161.749808 -31.548472) (xy 161.786295 -31.596022) (xy 161.816262 -31.647928)
			(xy 161.839198 -31.703301) (xy 161.854711 -31.761194) (xy 161.862534 -31.820616) (xy 161.863024 -31.850584)
			(xy 161.863024 -32.714184) (xy 161.862891 -32.722312) (xy 176.706784 -32.722312) (xy 176.706784 -31.858712)
			(xy 176.707274 -31.828728) (xy 176.715102 -31.769272) (xy 176.730623 -31.711347) (xy 176.753572 -31.655943)
			(xy 176.783556 -31.604009) (xy 176.820062 -31.556433) (xy 176.862467 -31.514028) (xy 176.910043 -31.477522)
			(xy 176.961977 -31.447538) (xy 177.017381 -31.424589) (xy 177.075306 -31.409068) (xy 177.134762 -31.40124)
			(xy 177.19473 -31.40124) (xy 177.254186 -31.409068) (xy 177.312111 -31.424589) (xy 177.367515 -31.447538)
			(xy 177.419449 -31.477522) (xy 177.467025 -31.514028) (xy 177.50943 -31.556433) (xy 177.545936 -31.604009)
			(xy 177.57592 -31.655943) (xy 177.598869 -31.711347) (xy 177.61439 -31.769272) (xy 177.622218 -31.828728)
			(xy 177.622708 -31.858712) (xy 177.622708 -32.714184) (xy 186.947556 -32.714184) (xy 186.947556 -31.850584)
			(xy 186.948046 -31.820616) (xy 186.955869 -31.761194) (xy 186.971382 -31.703301) (xy 186.994318 -31.647928)
			(xy 187.024285 -31.596022) (xy 187.060772 -31.548472) (xy 187.103152 -31.506092) (xy 187.150702 -31.469605)
			(xy 187.202608 -31.439638) (xy 187.257981 -31.416702) (xy 187.315874 -31.401189) (xy 187.375296 -31.393366)
			(xy 187.435232 -31.393366) (xy 187.494654 -31.401189) (xy 187.552547 -31.416702) (xy 187.60792 -31.439638)
			(xy 187.659826 -31.469605) (xy 187.707376 -31.506092) (xy 187.749756 -31.548472) (xy 187.786243 -31.596022)
			(xy 187.81621 -31.647928) (xy 187.839146 -31.703301) (xy 187.854659 -31.761194) (xy 187.862482 -31.820616)
			(xy 187.862972 -31.850584) (xy 187.862972 -32.714184) (xy 187.862839 -32.722312) (xy 202.706732 -32.722312)
			(xy 202.706732 -31.858712) (xy 202.707222 -31.828728) (xy 202.71505 -31.769272) (xy 202.730571 -31.711347)
			(xy 202.75352 -31.655943) (xy 202.783504 -31.604009) (xy 202.82001 -31.556433) (xy 202.862415 -31.514028)
			(xy 202.909991 -31.477522) (xy 202.961925 -31.447538) (xy 203.017329 -31.424589) (xy 203.075254 -31.409068)
			(xy 203.13471 -31.40124) (xy 203.194678 -31.40124) (xy 203.254134 -31.409068) (xy 203.312059 -31.424589)
			(xy 203.367463 -31.447538) (xy 203.419397 -31.477522) (xy 203.466973 -31.514028) (xy 203.509378 -31.556433)
			(xy 203.545884 -31.604009) (xy 203.575868 -31.655943) (xy 203.598817 -31.711347) (xy 203.614338 -31.769272)
			(xy 203.622166 -31.828728) (xy 203.622656 -31.858712) (xy 203.622656 -32.714184) (xy 212.947504 -32.714184)
			(xy 212.947504 -31.850584) (xy 212.947994 -31.820616) (xy 212.955817 -31.761194) (xy 212.97133 -31.703301)
			(xy 212.994266 -31.647928) (xy 213.024233 -31.596022) (xy 213.06072 -31.548472) (xy 213.1031 -31.506092)
			(xy 213.15065 -31.469605) (xy 213.202556 -31.439638) (xy 213.257929 -31.416702) (xy 213.315822 -31.401189)
			(xy 213.375244 -31.393366) (xy 213.43518 -31.393366) (xy 213.494602 -31.401189) (xy 213.552495 -31.416702)
			(xy 213.607868 -31.439638) (xy 213.659774 -31.469605) (xy 213.707324 -31.506092) (xy 213.749704 -31.548472)
			(xy 213.786191 -31.596022) (xy 213.816158 -31.647928) (xy 213.839094 -31.703301) (xy 213.854607 -31.761194)
			(xy 213.86243 -31.820616) (xy 213.86292 -31.850584) (xy 213.86292 -32.714184) (xy 213.862787 -32.722312)
			(xy 240.806732 -32.722312) (xy 240.806732 -31.858712) (xy 240.807222 -31.828728) (xy 240.81505 -31.769272)
			(xy 240.830571 -31.711347) (xy 240.85352 -31.655943) (xy 240.883504 -31.604009) (xy 240.92001 -31.556433)
			(xy 240.962415 -31.514028) (xy 241.009991 -31.477522) (xy 241.061925 -31.447538) (xy 241.117329 -31.424589)
			(xy 241.175254 -31.409068) (xy 241.23471 -31.40124) (xy 241.294678 -31.40124) (xy 241.354134 -31.409068)
			(xy 241.412059 -31.424589) (xy 241.467463 -31.447538) (xy 241.519397 -31.477522) (xy 241.566973 -31.514028)
			(xy 241.609378 -31.556433) (xy 241.645884 -31.604009) (xy 241.675868 -31.655943) (xy 241.698817 -31.711347)
			(xy 241.714338 -31.769272) (xy 241.722166 -31.828728) (xy 241.722656 -31.858712) (xy 241.722656 -32.714184)
			(xy 251.047504 -32.714184) (xy 251.047504 -31.850584) (xy 251.047994 -31.820616) (xy 251.055817 -31.761194)
			(xy 251.07133 -31.703301) (xy 251.094266 -31.647928) (xy 251.124233 -31.596022) (xy 251.16072 -31.548472)
			(xy 251.2031 -31.506092) (xy 251.25065 -31.469605) (xy 251.302556 -31.439638) (xy 251.357929 -31.416702)
			(xy 251.415822 -31.401189) (xy 251.475244 -31.393366) (xy 251.53518 -31.393366) (xy 251.594602 -31.401189)
			(xy 251.652495 -31.416702) (xy 251.707868 -31.439638) (xy 251.759774 -31.469605) (xy 251.807324 -31.506092)
			(xy 251.849704 -31.548472) (xy 251.886191 -31.596022) (xy 251.916158 -31.647928) (xy 251.939094 -31.703301)
			(xy 251.954607 -31.761194) (xy 251.96243 -31.820616) (xy 251.96292 -31.850584) (xy 251.96292 -32.714184)
			(xy 251.962787 -32.722312) (xy 266.80668 -32.722312) (xy 266.80668 -31.858712) (xy 266.80717 -31.828728)
			(xy 266.814998 -31.769272) (xy 266.830519 -31.711347) (xy 266.853468 -31.655943) (xy 266.883452 -31.604009)
			(xy 266.919958 -31.556433) (xy 266.962363 -31.514028) (xy 267.009939 -31.477522) (xy 267.061873 -31.447538)
			(xy 267.117277 -31.424589) (xy 267.175202 -31.409068) (xy 267.234658 -31.40124) (xy 267.294626 -31.40124)
			(xy 267.354082 -31.409068) (xy 267.412007 -31.424589) (xy 267.467411 -31.447538) (xy 267.519345 -31.477522)
			(xy 267.566921 -31.514028) (xy 267.609326 -31.556433) (xy 267.645832 -31.604009) (xy 267.675816 -31.655943)
			(xy 267.698765 -31.711347) (xy 267.714286 -31.769272) (xy 267.722114 -31.828728) (xy 267.722604 -31.858712)
			(xy 267.722604 -32.714184) (xy 277.047452 -32.714184) (xy 277.047452 -31.850584) (xy 277.047942 -31.820616)
			(xy 277.055765 -31.761194) (xy 277.071278 -31.703301) (xy 277.094214 -31.647928) (xy 277.124181 -31.596022)
			(xy 277.160668 -31.548472) (xy 277.203048 -31.506092) (xy 277.250598 -31.469605) (xy 277.302504 -31.439638)
			(xy 277.357877 -31.416702) (xy 277.41577 -31.401189) (xy 277.475192 -31.393366) (xy 277.535128 -31.393366)
			(xy 277.59455 -31.401189) (xy 277.652443 -31.416702) (xy 277.707816 -31.439638) (xy 277.759722 -31.469605)
			(xy 277.807272 -31.506092) (xy 277.849652 -31.548472) (xy 277.886139 -31.596022) (xy 277.916106 -31.647928)
			(xy 277.939042 -31.703301) (xy 277.954555 -31.761194) (xy 277.962378 -31.820616) (xy 277.962868 -31.850584)
			(xy 277.962868 -32.714184) (xy 277.962735 -32.722312) (xy 292.806628 -32.722312) (xy 292.806628 -31.858712)
			(xy 292.807118 -31.828728) (xy 292.814946 -31.769272) (xy 292.830467 -31.711347) (xy 292.853416 -31.655943)
			(xy 292.8834 -31.604009) (xy 292.919906 -31.556433) (xy 292.962311 -31.514028) (xy 293.009887 -31.477522)
			(xy 293.061821 -31.447538) (xy 293.117225 -31.424589) (xy 293.17515 -31.409068) (xy 293.234606 -31.40124)
			(xy 293.294574 -31.40124) (xy 293.35403 -31.409068) (xy 293.411955 -31.424589) (xy 293.467359 -31.447538)
			(xy 293.519293 -31.477522) (xy 293.566869 -31.514028) (xy 293.609274 -31.556433) (xy 293.64578 -31.604009)
			(xy 293.675764 -31.655943) (xy 293.698713 -31.711347) (xy 293.714234 -31.769272) (xy 293.722062 -31.828728)
			(xy 293.722552 -31.858712) (xy 293.722552 -32.714184) (xy 303.0474 -32.714184) (xy 303.0474 -31.850584)
			(xy 303.04789 -31.820616) (xy 303.055713 -31.761194) (xy 303.071226 -31.703301) (xy 303.094162 -31.647928)
			(xy 303.124129 -31.596022) (xy 303.160616 -31.548472) (xy 303.202996 -31.506092) (xy 303.250546 -31.469605)
			(xy 303.302452 -31.439638) (xy 303.357825 -31.416702) (xy 303.415718 -31.401189) (xy 303.47514 -31.393366)
			(xy 303.535076 -31.393366) (xy 303.594498 -31.401189) (xy 303.652391 -31.416702) (xy 303.707764 -31.439638)
			(xy 303.75967 -31.469605) (xy 303.80722 -31.506092) (xy 303.8496 -31.548472) (xy 303.886087 -31.596022)
			(xy 303.916054 -31.647928) (xy 303.93899 -31.703301) (xy 303.954503 -31.761194) (xy 303.962326 -31.820616)
			(xy 303.962816 -31.850584) (xy 303.962816 -32.714184) (xy 303.962683 -32.722312) (xy 318.806576 -32.722312)
			(xy 318.806576 -31.858712) (xy 318.807066 -31.828728) (xy 318.814894 -31.769272) (xy 318.830415 -31.711347)
			(xy 318.853364 -31.655943) (xy 318.883348 -31.604009) (xy 318.919854 -31.556433) (xy 318.962259 -31.514028)
			(xy 319.009835 -31.477522) (xy 319.061769 -31.447538) (xy 319.117173 -31.424589) (xy 319.175098 -31.409068)
			(xy 319.234554 -31.40124) (xy 319.294522 -31.40124) (xy 319.353978 -31.409068) (xy 319.411903 -31.424589)
			(xy 319.467307 -31.447538) (xy 319.519241 -31.477522) (xy 319.566817 -31.514028) (xy 319.609222 -31.556433)
			(xy 319.645728 -31.604009) (xy 319.675712 -31.655943) (xy 319.698661 -31.711347) (xy 319.714182 -31.769272)
			(xy 319.72201 -31.828728) (xy 319.7225 -31.858712) (xy 319.7225 -32.714184) (xy 329.047348 -32.714184)
			(xy 329.047348 -31.850584) (xy 329.047838 -31.820616) (xy 329.055661 -31.761194) (xy 329.071174 -31.703301)
			(xy 329.09411 -31.647928) (xy 329.124077 -31.596022) (xy 329.160564 -31.548472) (xy 329.202944 -31.506092)
			(xy 329.250494 -31.469605) (xy 329.3024 -31.439638) (xy 329.357773 -31.416702) (xy 329.415666 -31.401189)
			(xy 329.475088 -31.393366) (xy 329.535024 -31.393366) (xy 329.594446 -31.401189) (xy 329.652339 -31.416702)
			(xy 329.707712 -31.439638) (xy 329.759618 -31.469605) (xy 329.807168 -31.506092) (xy 329.849548 -31.548472)
			(xy 329.886035 -31.596022) (xy 329.916002 -31.647928) (xy 329.938938 -31.703301) (xy 329.954451 -31.761194)
			(xy 329.962274 -31.820616) (xy 329.962764 -31.850584) (xy 329.962764 -32.714184) (xy 329.962631 -32.722312)
			(xy 356.907084 -32.722312) (xy 356.907084 -31.858712) (xy 356.907574 -31.828744) (xy 356.915397 -31.769322)
			(xy 356.93091 -31.711429) (xy 356.953846 -31.656056) (xy 356.983813 -31.60415) (xy 357.0203 -31.5566)
			(xy 357.06268 -31.51422) (xy 357.11023 -31.477733) (xy 357.162136 -31.447766) (xy 357.217509 -31.42483)
			(xy 357.275402 -31.409317) (xy 357.334824 -31.401494) (xy 357.39476 -31.401494) (xy 357.454182 -31.409317)
			(xy 357.512075 -31.42483) (xy 357.567448 -31.447766) (xy 357.619354 -31.477733) (xy 357.666904 -31.51422)
			(xy 357.709284 -31.5566) (xy 357.745771 -31.60415) (xy 357.775738 -31.656056) (xy 357.798674 -31.711429)
			(xy 357.814187 -31.769322) (xy 357.82201 -31.828744) (xy 357.8225 -31.858712) (xy 357.8225 -32.714184)
			(xy 367.147348 -32.714184) (xy 367.147348 -31.850584) (xy 367.147838 -31.8206) (xy 367.155666 -31.761144)
			(xy 367.171187 -31.703219) (xy 367.194136 -31.647815) (xy 367.22412 -31.595881) (xy 367.260626 -31.548305)
			(xy 367.303031 -31.5059) (xy 367.350607 -31.469394) (xy 367.402541 -31.43941) (xy 367.457945 -31.416461)
			(xy 367.51587 -31.40094) (xy 367.575326 -31.393112) (xy 367.635294 -31.393112) (xy 367.69475 -31.40094)
			(xy 367.752675 -31.416461) (xy 367.808079 -31.43941) (xy 367.860013 -31.469394) (xy 367.907589 -31.5059)
			(xy 367.949994 -31.548305) (xy 367.9865 -31.595881) (xy 368.016484 -31.647815) (xy 368.039433 -31.703219)
			(xy 368.054954 -31.761144) (xy 368.062782 -31.8206) (xy 368.063272 -31.850584) (xy 368.063272 -32.714184)
			(xy 368.063139 -32.722312) (xy 382.907032 -32.722312) (xy 382.907032 -31.858712) (xy 382.907522 -31.828744)
			(xy 382.915345 -31.769322) (xy 382.930858 -31.711429) (xy 382.953794 -31.656056) (xy 382.983761 -31.60415)
			(xy 383.020248 -31.5566) (xy 383.062628 -31.51422) (xy 383.110178 -31.477733) (xy 383.162084 -31.447766)
			(xy 383.217457 -31.42483) (xy 383.27535 -31.409317) (xy 383.334772 -31.401494) (xy 383.394708 -31.401494)
			(xy 383.45413 -31.409317) (xy 383.512023 -31.42483) (xy 383.567396 -31.447766) (xy 383.619302 -31.477733)
			(xy 383.666852 -31.51422) (xy 383.709232 -31.5566) (xy 383.745719 -31.60415) (xy 383.775686 -31.656056)
			(xy 383.798622 -31.711429) (xy 383.814135 -31.769322) (xy 383.821958 -31.828744) (xy 383.822448 -31.858712)
			(xy 383.822448 -32.714184) (xy 393.147296 -32.714184) (xy 393.147296 -31.850584) (xy 393.147786 -31.8206)
			(xy 393.155614 -31.761144) (xy 393.171135 -31.703219) (xy 393.194084 -31.647815) (xy 393.224068 -31.595881)
			(xy 393.260574 -31.548305) (xy 393.302979 -31.5059) (xy 393.350555 -31.469394) (xy 393.402489 -31.43941)
			(xy 393.457893 -31.416461) (xy 393.515818 -31.40094) (xy 393.575274 -31.393112) (xy 393.635242 -31.393112)
			(xy 393.694698 -31.40094) (xy 393.752623 -31.416461) (xy 393.808027 -31.43941) (xy 393.859961 -31.469394)
			(xy 393.907537 -31.5059) (xy 393.949942 -31.548305) (xy 393.986448 -31.595881) (xy 394.016432 -31.647815)
			(xy 394.039381 -31.703219) (xy 394.054902 -31.761144) (xy 394.06273 -31.8206) (xy 394.06322 -31.850584)
			(xy 394.06322 -32.714184) (xy 394.063087 -32.722312) (xy 408.90698 -32.722312) (xy 408.90698 -31.858712)
			(xy 408.90747 -31.828744) (xy 408.915293 -31.769322) (xy 408.930806 -31.711429) (xy 408.953742 -31.656056)
			(xy 408.983709 -31.60415) (xy 409.020196 -31.5566) (xy 409.062576 -31.51422) (xy 409.110126 -31.477733)
			(xy 409.162032 -31.447766) (xy 409.217405 -31.42483) (xy 409.275298 -31.409317) (xy 409.33472 -31.401494)
			(xy 409.394656 -31.401494) (xy 409.454078 -31.409317) (xy 409.511971 -31.42483) (xy 409.567344 -31.447766)
			(xy 409.61925 -31.477733) (xy 409.6668 -31.51422) (xy 409.70918 -31.5566) (xy 409.745667 -31.60415)
			(xy 409.775634 -31.656056) (xy 409.79857 -31.711429) (xy 409.814083 -31.769322) (xy 409.821906 -31.828744)
			(xy 409.822396 -31.858712) (xy 409.822396 -32.714184) (xy 419.147244 -32.714184) (xy 419.147244 -31.850584)
			(xy 419.147734 -31.8206) (xy 419.155562 -31.761144) (xy 419.171083 -31.703219) (xy 419.194032 -31.647815)
			(xy 419.224016 -31.595881) (xy 419.260522 -31.548305) (xy 419.302927 -31.5059) (xy 419.350503 -31.469394)
			(xy 419.402437 -31.43941) (xy 419.457841 -31.416461) (xy 419.515766 -31.40094) (xy 419.575222 -31.393112)
			(xy 419.63519 -31.393112) (xy 419.694646 -31.40094) (xy 419.752571 -31.416461) (xy 419.807975 -31.43941)
			(xy 419.859909 -31.469394) (xy 419.907485 -31.5059) (xy 419.94989 -31.548305) (xy 419.986396 -31.595881)
			(xy 420.01638 -31.647815) (xy 420.039329 -31.703219) (xy 420.05485 -31.761144) (xy 420.062678 -31.8206)
			(xy 420.063168 -31.850584) (xy 420.063168 -32.714184) (xy 420.063035 -32.722312) (xy 434.906928 -32.722312)
			(xy 434.906928 -31.858712) (xy 434.907418 -31.828744) (xy 434.915241 -31.769322) (xy 434.930754 -31.711429)
			(xy 434.95369 -31.656056) (xy 434.983657 -31.60415) (xy 435.020144 -31.5566) (xy 435.062524 -31.51422)
			(xy 435.110074 -31.477733) (xy 435.16198 -31.447766) (xy 435.217353 -31.42483) (xy 435.275246 -31.409317)
			(xy 435.334668 -31.401494) (xy 435.394604 -31.401494) (xy 435.454026 -31.409317) (xy 435.511919 -31.42483)
			(xy 435.567292 -31.447766) (xy 435.619198 -31.477733) (xy 435.666748 -31.51422) (xy 435.709128 -31.5566)
			(xy 435.745615 -31.60415) (xy 435.775582 -31.656056) (xy 435.798518 -31.711429) (xy 435.814031 -31.769322)
			(xy 435.821854 -31.828744) (xy 435.822344 -31.858712) (xy 435.822344 -32.714184) (xy 445.147192 -32.714184)
			(xy 445.147192 -31.850584) (xy 445.147682 -31.8206) (xy 445.15551 -31.761144) (xy 445.171031 -31.703219)
			(xy 445.19398 -31.647815) (xy 445.223964 -31.595881) (xy 445.26047 -31.548305) (xy 445.302875 -31.5059)
			(xy 445.350451 -31.469394) (xy 445.402385 -31.43941) (xy 445.457789 -31.416461) (xy 445.515714 -31.40094)
			(xy 445.57517 -31.393112) (xy 445.635138 -31.393112) (xy 445.694594 -31.40094) (xy 445.752519 -31.416461)
			(xy 445.807923 -31.43941) (xy 445.859857 -31.469394) (xy 445.907433 -31.5059) (xy 445.949838 -31.548305)
			(xy 445.986344 -31.595881) (xy 446.016328 -31.647815) (xy 446.039277 -31.703219) (xy 446.054798 -31.761144)
			(xy 446.062626 -31.8206) (xy 446.063116 -31.850584) (xy 446.063116 -32.714184) (xy 446.062626 -32.744168)
			(xy 446.054798 -32.803624) (xy 446.039277 -32.861549) (xy 446.016328 -32.916953) (xy 445.986344 -32.968887)
			(xy 445.949838 -33.016463) (xy 445.907433 -33.058868) (xy 445.859857 -33.095374) (xy 445.807923 -33.125358)
			(xy 445.752519 -33.148307) (xy 445.694594 -33.163828) (xy 445.635138 -33.171656) (xy 445.57517 -33.171656)
			(xy 445.515714 -33.163828) (xy 445.457789 -33.148307) (xy 445.402385 -33.125358) (xy 445.350451 -33.095374)
			(xy 445.302875 -33.058868) (xy 445.26047 -33.016463) (xy 445.223964 -32.968887) (xy 445.19398 -32.916953)
			(xy 445.171031 -32.861549) (xy 445.15551 -32.803624) (xy 445.147682 -32.744168) (xy 445.147192 -32.714184)
			(xy 435.822344 -32.714184) (xy 435.822344 -32.722312) (xy 435.821854 -32.75228) (xy 435.814031 -32.811702)
			(xy 435.798518 -32.869595) (xy 435.775582 -32.924968) (xy 435.745615 -32.976874) (xy 435.709128 -33.024424)
			(xy 435.666748 -33.066804) (xy 435.619198 -33.103291) (xy 435.567292 -33.133258) (xy 435.511919 -33.156194)
			(xy 435.454026 -33.171707) (xy 435.394604 -33.17953) (xy 435.334668 -33.17953) (xy 435.275246 -33.171707)
			(xy 435.217353 -33.156194) (xy 435.16198 -33.133258) (xy 435.110074 -33.103291) (xy 435.062524 -33.066804)
			(xy 435.020144 -33.024424) (xy 434.983657 -32.976874) (xy 434.95369 -32.924968) (xy 434.930754 -32.869595)
			(xy 434.915241 -32.811702) (xy 434.907418 -32.75228) (xy 434.906928 -32.722312) (xy 420.063035 -32.722312)
			(xy 420.062678 -32.744168) (xy 420.05485 -32.803624) (xy 420.039329 -32.861549) (xy 420.01638 -32.916953)
			(xy 419.986396 -32.968887) (xy 419.94989 -33.016463) (xy 419.907485 -33.058868) (xy 419.859909 -33.095374)
			(xy 419.807975 -33.125358) (xy 419.752571 -33.148307) (xy 419.694646 -33.163828) (xy 419.63519 -33.171656)
			(xy 419.575222 -33.171656) (xy 419.515766 -33.163828) (xy 419.457841 -33.148307) (xy 419.402437 -33.125358)
			(xy 419.350503 -33.095374) (xy 419.302927 -33.058868) (xy 419.260522 -33.016463) (xy 419.224016 -32.968887)
			(xy 419.194032 -32.916953) (xy 419.171083 -32.861549) (xy 419.155562 -32.803624) (xy 419.147734 -32.744168)
			(xy 419.147244 -32.714184) (xy 409.822396 -32.714184) (xy 409.822396 -32.722312) (xy 409.821906 -32.75228)
			(xy 409.814083 -32.811702) (xy 409.79857 -32.869595) (xy 409.775634 -32.924968) (xy 409.745667 -32.976874)
			(xy 409.70918 -33.024424) (xy 409.6668 -33.066804) (xy 409.61925 -33.103291) (xy 409.567344 -33.133258)
			(xy 409.511971 -33.156194) (xy 409.454078 -33.171707) (xy 409.394656 -33.17953) (xy 409.33472 -33.17953)
			(xy 409.275298 -33.171707) (xy 409.217405 -33.156194) (xy 409.162032 -33.133258) (xy 409.110126 -33.103291)
			(xy 409.062576 -33.066804) (xy 409.020196 -33.024424) (xy 408.983709 -32.976874) (xy 408.953742 -32.924968)
			(xy 408.930806 -32.869595) (xy 408.915293 -32.811702) (xy 408.90747 -32.75228) (xy 408.90698 -32.722312)
			(xy 394.063087 -32.722312) (xy 394.06273 -32.744168) (xy 394.054902 -32.803624) (xy 394.039381 -32.861549)
			(xy 394.016432 -32.916953) (xy 393.986448 -32.968887) (xy 393.949942 -33.016463) (xy 393.907537 -33.058868)
			(xy 393.859961 -33.095374) (xy 393.808027 -33.125358) (xy 393.752623 -33.148307) (xy 393.694698 -33.163828)
			(xy 393.635242 -33.171656) (xy 393.575274 -33.171656) (xy 393.515818 -33.163828) (xy 393.457893 -33.148307)
			(xy 393.402489 -33.125358) (xy 393.350555 -33.095374) (xy 393.302979 -33.058868) (xy 393.260574 -33.016463)
			(xy 393.224068 -32.968887) (xy 393.194084 -32.916953) (xy 393.171135 -32.861549) (xy 393.155614 -32.803624)
			(xy 393.147786 -32.744168) (xy 393.147296 -32.714184) (xy 383.822448 -32.714184) (xy 383.822448 -32.722312)
			(xy 383.821958 -32.75228) (xy 383.814135 -32.811702) (xy 383.798622 -32.869595) (xy 383.775686 -32.924968)
			(xy 383.745719 -32.976874) (xy 383.709232 -33.024424) (xy 383.666852 -33.066804) (xy 383.619302 -33.103291)
			(xy 383.567396 -33.133258) (xy 383.512023 -33.156194) (xy 383.45413 -33.171707) (xy 383.394708 -33.17953)
			(xy 383.334772 -33.17953) (xy 383.27535 -33.171707) (xy 383.217457 -33.156194) (xy 383.162084 -33.133258)
			(xy 383.110178 -33.103291) (xy 383.062628 -33.066804) (xy 383.020248 -33.024424) (xy 382.983761 -32.976874)
			(xy 382.953794 -32.924968) (xy 382.930858 -32.869595) (xy 382.915345 -32.811702) (xy 382.907522 -32.75228)
			(xy 382.907032 -32.722312) (xy 368.063139 -32.722312) (xy 368.062782 -32.744168) (xy 368.054954 -32.803624)
			(xy 368.039433 -32.861549) (xy 368.016484 -32.916953) (xy 367.9865 -32.968887) (xy 367.949994 -33.016463)
			(xy 367.907589 -33.058868) (xy 367.860013 -33.095374) (xy 367.808079 -33.125358) (xy 367.752675 -33.148307)
			(xy 367.69475 -33.163828) (xy 367.635294 -33.171656) (xy 367.575326 -33.171656) (xy 367.51587 -33.163828)
			(xy 367.457945 -33.148307) (xy 367.402541 -33.125358) (xy 367.350607 -33.095374) (xy 367.303031 -33.058868)
			(xy 367.260626 -33.016463) (xy 367.22412 -32.968887) (xy 367.194136 -32.916953) (xy 367.171187 -32.861549)
			(xy 367.155666 -32.803624) (xy 367.147838 -32.744168) (xy 367.147348 -32.714184) (xy 357.8225 -32.714184)
			(xy 357.8225 -32.722312) (xy 357.82201 -32.75228) (xy 357.814187 -32.811702) (xy 357.798674 -32.869595)
			(xy 357.775738 -32.924968) (xy 357.745771 -32.976874) (xy 357.709284 -33.024424) (xy 357.666904 -33.066804)
			(xy 357.619354 -33.103291) (xy 357.567448 -33.133258) (xy 357.512075 -33.156194) (xy 357.454182 -33.171707)
			(xy 357.39476 -33.17953) (xy 357.334824 -33.17953) (xy 357.275402 -33.171707) (xy 357.217509 -33.156194)
			(xy 357.162136 -33.133258) (xy 357.11023 -33.103291) (xy 357.06268 -33.066804) (xy 357.0203 -33.024424)
			(xy 356.983813 -32.976874) (xy 356.953846 -32.924968) (xy 356.93091 -32.869595) (xy 356.915397 -32.811702)
			(xy 356.907574 -32.75228) (xy 356.907084 -32.722312) (xy 329.962631 -32.722312) (xy 329.962274 -32.744152)
			(xy 329.954451 -32.803574) (xy 329.938938 -32.861467) (xy 329.916002 -32.91684) (xy 329.886035 -32.968746)
			(xy 329.849548 -33.016296) (xy 329.807168 -33.058676) (xy 329.759618 -33.095163) (xy 329.707712 -33.12513)
			(xy 329.652339 -33.148066) (xy 329.594446 -33.163579) (xy 329.535024 -33.171402) (xy 329.475088 -33.171402)
			(xy 329.415666 -33.163579) (xy 329.357773 -33.148066) (xy 329.3024 -33.12513) (xy 329.250494 -33.095163)
			(xy 329.202944 -33.058676) (xy 329.160564 -33.016296) (xy 329.124077 -32.968746) (xy 329.09411 -32.91684)
			(xy 329.071174 -32.861467) (xy 329.055661 -32.803574) (xy 329.047838 -32.744152) (xy 329.047348 -32.714184)
			(xy 319.7225 -32.714184) (xy 319.7225 -32.722312) (xy 319.72201 -32.752296) (xy 319.714182 -32.811752)
			(xy 319.698661 -32.869677) (xy 319.675712 -32.925081) (xy 319.645728 -32.977015) (xy 319.609222 -33.024591)
			(xy 319.566817 -33.066996) (xy 319.519241 -33.103502) (xy 319.467307 -33.133486) (xy 319.411903 -33.156435)
			(xy 319.353978 -33.171956) (xy 319.294522 -33.179784) (xy 319.234554 -33.179784) (xy 319.175098 -33.171956)
			(xy 319.117173 -33.156435) (xy 319.061769 -33.133486) (xy 319.009835 -33.103502) (xy 318.962259 -33.066996)
			(xy 318.919854 -33.024591) (xy 318.883348 -32.977015) (xy 318.853364 -32.925081) (xy 318.830415 -32.869677)
			(xy 318.814894 -32.811752) (xy 318.807066 -32.752296) (xy 318.806576 -32.722312) (xy 303.962683 -32.722312)
			(xy 303.962326 -32.744152) (xy 303.954503 -32.803574) (xy 303.93899 -32.861467) (xy 303.916054 -32.91684)
			(xy 303.886087 -32.968746) (xy 303.8496 -33.016296) (xy 303.80722 -33.058676) (xy 303.75967 -33.095163)
			(xy 303.707764 -33.12513) (xy 303.652391 -33.148066) (xy 303.594498 -33.163579) (xy 303.535076 -33.171402)
			(xy 303.47514 -33.171402) (xy 303.415718 -33.163579) (xy 303.357825 -33.148066) (xy 303.302452 -33.12513)
			(xy 303.250546 -33.095163) (xy 303.202996 -33.058676) (xy 303.160616 -33.016296) (xy 303.124129 -32.968746)
			(xy 303.094162 -32.91684) (xy 303.071226 -32.861467) (xy 303.055713 -32.803574) (xy 303.04789 -32.744152)
			(xy 303.0474 -32.714184) (xy 293.722552 -32.714184) (xy 293.722552 -32.722312) (xy 293.722062 -32.752296)
			(xy 293.714234 -32.811752) (xy 293.698713 -32.869677) (xy 293.675764 -32.925081) (xy 293.64578 -32.977015)
			(xy 293.609274 -33.024591) (xy 293.566869 -33.066996) (xy 293.519293 -33.103502) (xy 293.467359 -33.133486)
			(xy 293.411955 -33.156435) (xy 293.35403 -33.171956) (xy 293.294574 -33.179784) (xy 293.234606 -33.179784)
			(xy 293.17515 -33.171956) (xy 293.117225 -33.156435) (xy 293.061821 -33.133486) (xy 293.009887 -33.103502)
			(xy 292.962311 -33.066996) (xy 292.919906 -33.024591) (xy 292.8834 -32.977015) (xy 292.853416 -32.925081)
			(xy 292.830467 -32.869677) (xy 292.814946 -32.811752) (xy 292.807118 -32.752296) (xy 292.806628 -32.722312)
			(xy 277.962735 -32.722312) (xy 277.962378 -32.744152) (xy 277.954555 -32.803574) (xy 277.939042 -32.861467)
			(xy 277.916106 -32.91684) (xy 277.886139 -32.968746) (xy 277.849652 -33.016296) (xy 277.807272 -33.058676)
			(xy 277.759722 -33.095163) (xy 277.707816 -33.12513) (xy 277.652443 -33.148066) (xy 277.59455 -33.163579)
			(xy 277.535128 -33.171402) (xy 277.475192 -33.171402) (xy 277.41577 -33.163579) (xy 277.357877 -33.148066)
			(xy 277.302504 -33.12513) (xy 277.250598 -33.095163) (xy 277.203048 -33.058676) (xy 277.160668 -33.016296)
			(xy 277.124181 -32.968746) (xy 277.094214 -32.91684) (xy 277.071278 -32.861467) (xy 277.055765 -32.803574)
			(xy 277.047942 -32.744152) (xy 277.047452 -32.714184) (xy 267.722604 -32.714184) (xy 267.722604 -32.722312)
			(xy 267.722114 -32.752296) (xy 267.714286 -32.811752) (xy 267.698765 -32.869677) (xy 267.675816 -32.925081)
			(xy 267.645832 -32.977015) (xy 267.609326 -33.024591) (xy 267.566921 -33.066996) (xy 267.519345 -33.103502)
			(xy 267.467411 -33.133486) (xy 267.412007 -33.156435) (xy 267.354082 -33.171956) (xy 267.294626 -33.179784)
			(xy 267.234658 -33.179784) (xy 267.175202 -33.171956) (xy 267.117277 -33.156435) (xy 267.061873 -33.133486)
			(xy 267.009939 -33.103502) (xy 266.962363 -33.066996) (xy 266.919958 -33.024591) (xy 266.883452 -32.977015)
			(xy 266.853468 -32.925081) (xy 266.830519 -32.869677) (xy 266.814998 -32.811752) (xy 266.80717 -32.752296)
			(xy 266.80668 -32.722312) (xy 251.962787 -32.722312) (xy 251.96243 -32.744152) (xy 251.954607 -32.803574)
			(xy 251.939094 -32.861467) (xy 251.916158 -32.91684) (xy 251.886191 -32.968746) (xy 251.849704 -33.016296)
			(xy 251.807324 -33.058676) (xy 251.759774 -33.095163) (xy 251.707868 -33.12513) (xy 251.652495 -33.148066)
			(xy 251.594602 -33.163579) (xy 251.53518 -33.171402) (xy 251.475244 -33.171402) (xy 251.415822 -33.163579)
			(xy 251.357929 -33.148066) (xy 251.302556 -33.12513) (xy 251.25065 -33.095163) (xy 251.2031 -33.058676)
			(xy 251.16072 -33.016296) (xy 251.124233 -32.968746) (xy 251.094266 -32.91684) (xy 251.07133 -32.861467)
			(xy 251.055817 -32.803574) (xy 251.047994 -32.744152) (xy 251.047504 -32.714184) (xy 241.722656 -32.714184)
			(xy 241.722656 -32.722312) (xy 241.722166 -32.752296) (xy 241.714338 -32.811752) (xy 241.698817 -32.869677)
			(xy 241.675868 -32.925081) (xy 241.645884 -32.977015) (xy 241.609378 -33.024591) (xy 241.566973 -33.066996)
			(xy 241.519397 -33.103502) (xy 241.467463 -33.133486) (xy 241.412059 -33.156435) (xy 241.354134 -33.171956)
			(xy 241.294678 -33.179784) (xy 241.23471 -33.179784) (xy 241.175254 -33.171956) (xy 241.117329 -33.156435)
			(xy 241.061925 -33.133486) (xy 241.009991 -33.103502) (xy 240.962415 -33.066996) (xy 240.92001 -33.024591)
			(xy 240.883504 -32.977015) (xy 240.85352 -32.925081) (xy 240.830571 -32.869677) (xy 240.81505 -32.811752)
			(xy 240.807222 -32.752296) (xy 240.806732 -32.722312) (xy 213.862787 -32.722312) (xy 213.86243 -32.744152)
			(xy 213.854607 -32.803574) (xy 213.839094 -32.861467) (xy 213.816158 -32.91684) (xy 213.786191 -32.968746)
			(xy 213.749704 -33.016296) (xy 213.707324 -33.058676) (xy 213.659774 -33.095163) (xy 213.607868 -33.12513)
			(xy 213.552495 -33.148066) (xy 213.494602 -33.163579) (xy 213.43518 -33.171402) (xy 213.375244 -33.171402)
			(xy 213.315822 -33.163579) (xy 213.257929 -33.148066) (xy 213.202556 -33.12513) (xy 213.15065 -33.095163)
			(xy 213.1031 -33.058676) (xy 213.06072 -33.016296) (xy 213.024233 -32.968746) (xy 212.994266 -32.91684)
			(xy 212.97133 -32.861467) (xy 212.955817 -32.803574) (xy 212.947994 -32.744152) (xy 212.947504 -32.714184)
			(xy 203.622656 -32.714184) (xy 203.622656 -32.722312) (xy 203.622166 -32.752296) (xy 203.614338 -32.811752)
			(xy 203.598817 -32.869677) (xy 203.575868 -32.925081) (xy 203.545884 -32.977015) (xy 203.509378 -33.024591)
			(xy 203.466973 -33.066996) (xy 203.419397 -33.103502) (xy 203.367463 -33.133486) (xy 203.312059 -33.156435)
			(xy 203.254134 -33.171956) (xy 203.194678 -33.179784) (xy 203.13471 -33.179784) (xy 203.075254 -33.171956)
			(xy 203.017329 -33.156435) (xy 202.961925 -33.133486) (xy 202.909991 -33.103502) (xy 202.862415 -33.066996)
			(xy 202.82001 -33.024591) (xy 202.783504 -32.977015) (xy 202.75352 -32.925081) (xy 202.730571 -32.869677)
			(xy 202.71505 -32.811752) (xy 202.707222 -32.752296) (xy 202.706732 -32.722312) (xy 187.862839 -32.722312)
			(xy 187.862482 -32.744152) (xy 187.854659 -32.803574) (xy 187.839146 -32.861467) (xy 187.81621 -32.91684)
			(xy 187.786243 -32.968746) (xy 187.749756 -33.016296) (xy 187.707376 -33.058676) (xy 187.659826 -33.095163)
			(xy 187.60792 -33.12513) (xy 187.552547 -33.148066) (xy 187.494654 -33.163579) (xy 187.435232 -33.171402)
			(xy 187.375296 -33.171402) (xy 187.315874 -33.163579) (xy 187.257981 -33.148066) (xy 187.202608 -33.12513)
			(xy 187.150702 -33.095163) (xy 187.103152 -33.058676) (xy 187.060772 -33.016296) (xy 187.024285 -32.968746)
			(xy 186.994318 -32.91684) (xy 186.971382 -32.861467) (xy 186.955869 -32.803574) (xy 186.948046 -32.744152)
			(xy 186.947556 -32.714184) (xy 177.622708 -32.714184) (xy 177.622708 -32.722312) (xy 177.622218 -32.752296)
			(xy 177.61439 -32.811752) (xy 177.598869 -32.869677) (xy 177.57592 -32.925081) (xy 177.545936 -32.977015)
			(xy 177.50943 -33.024591) (xy 177.467025 -33.066996) (xy 177.419449 -33.103502) (xy 177.367515 -33.133486)
			(xy 177.312111 -33.156435) (xy 177.254186 -33.171956) (xy 177.19473 -33.179784) (xy 177.134762 -33.179784)
			(xy 177.075306 -33.171956) (xy 177.017381 -33.156435) (xy 176.961977 -33.133486) (xy 176.910043 -33.103502)
			(xy 176.862467 -33.066996) (xy 176.820062 -33.024591) (xy 176.783556 -32.977015) (xy 176.753572 -32.925081)
			(xy 176.730623 -32.869677) (xy 176.715102 -32.811752) (xy 176.707274 -32.752296) (xy 176.706784 -32.722312)
			(xy 161.862891 -32.722312) (xy 161.862534 -32.744152) (xy 161.854711 -32.803574) (xy 161.839198 -32.861467)
			(xy 161.816262 -32.91684) (xy 161.786295 -32.968746) (xy 161.749808 -33.016296) (xy 161.707428 -33.058676)
			(xy 161.659878 -33.095163) (xy 161.607972 -33.12513) (xy 161.552599 -33.148066) (xy 161.494706 -33.163579)
			(xy 161.435284 -33.171402) (xy 161.375348 -33.171402) (xy 161.315926 -33.163579) (xy 161.258033 -33.148066)
			(xy 161.20266 -33.12513) (xy 161.150754 -33.095163) (xy 161.103204 -33.058676) (xy 161.060824 -33.016296)
			(xy 161.024337 -32.968746) (xy 160.99437 -32.91684) (xy 160.971434 -32.861467) (xy 160.955921 -32.803574)
			(xy 160.948098 -32.744152) (xy 160.947608 -32.714184) (xy 151.62276 -32.714184) (xy 151.62276 -32.722312)
			(xy 151.62227 -32.752296) (xy 151.614442 -32.811752) (xy 151.598921 -32.869677) (xy 151.575972 -32.925081)
			(xy 151.545988 -32.977015) (xy 151.509482 -33.024591) (xy 151.467077 -33.066996) (xy 151.419501 -33.103502)
			(xy 151.367567 -33.133486) (xy 151.312163 -33.156435) (xy 151.254238 -33.171956) (xy 151.194782 -33.179784)
			(xy 151.134814 -33.179784) (xy 151.075358 -33.171956) (xy 151.017433 -33.156435) (xy 150.962029 -33.133486)
			(xy 150.910095 -33.103502) (xy 150.862519 -33.066996) (xy 150.820114 -33.024591) (xy 150.783608 -32.977015)
			(xy 150.753624 -32.925081) (xy 150.730675 -32.869677) (xy 150.715154 -32.811752) (xy 150.707326 -32.752296)
			(xy 150.706836 -32.722312) (xy 135.862943 -32.722312) (xy 135.862586 -32.744152) (xy 135.854763 -32.803574)
			(xy 135.83925 -32.861467) (xy 135.816314 -32.91684) (xy 135.786347 -32.968746) (xy 135.74986 -33.016296)
			(xy 135.70748 -33.058676) (xy 135.65993 -33.095163) (xy 135.608024 -33.12513) (xy 135.552651 -33.148066)
			(xy 135.494758 -33.163579) (xy 135.435336 -33.171402) (xy 135.3754 -33.171402) (xy 135.315978 -33.163579)
			(xy 135.258085 -33.148066) (xy 135.202712 -33.12513) (xy 135.150806 -33.095163) (xy 135.103256 -33.058676)
			(xy 135.060876 -33.016296) (xy 135.024389 -32.968746) (xy 134.994422 -32.91684) (xy 134.971486 -32.861467)
			(xy 134.955973 -32.803574) (xy 134.94815 -32.744152) (xy 134.94766 -32.714184) (xy 125.622812 -32.714184)
			(xy 125.622812 -32.722312) (xy 125.622322 -32.752296) (xy 125.614494 -32.811752) (xy 125.598973 -32.869677)
			(xy 125.576024 -32.925081) (xy 125.54604 -32.977015) (xy 125.509534 -33.024591) (xy 125.467129 -33.066996)
			(xy 125.419553 -33.103502) (xy 125.367619 -33.133486) (xy 125.312215 -33.156435) (xy 125.25429 -33.171956)
			(xy 125.194834 -33.179784) (xy 125.134866 -33.179784) (xy 125.07541 -33.171956) (xy 125.017485 -33.156435)
			(xy 124.962081 -33.133486) (xy 124.910147 -33.103502) (xy 124.862571 -33.066996) (xy 124.820166 -33.024591)
			(xy 124.78366 -32.977015) (xy 124.753676 -32.925081) (xy 124.730727 -32.869677) (xy 124.715206 -32.811752)
			(xy 124.707378 -32.752296) (xy 124.706888 -32.722312) (xy 97.762943 -32.722312) (xy 97.762586 -32.744168)
			(xy 97.754758 -32.803624) (xy 97.739237 -32.861549) (xy 97.716288 -32.916953) (xy 97.686304 -32.968887)
			(xy 97.649798 -33.016463) (xy 97.607393 -33.058868) (xy 97.559817 -33.095374) (xy 97.507883 -33.125358)
			(xy 97.452479 -33.148307) (xy 97.394554 -33.163828) (xy 97.335098 -33.171656) (xy 97.27513 -33.171656)
			(xy 97.215674 -33.163828) (xy 97.157749 -33.148307) (xy 97.102345 -33.125358) (xy 97.050411 -33.095374)
			(xy 97.002835 -33.058868) (xy 96.96043 -33.016463) (xy 96.923924 -32.968887) (xy 96.89394 -32.916953)
			(xy 96.870991 -32.861549) (xy 96.85547 -32.803624) (xy 96.847642 -32.744168) (xy 96.847152 -32.714184)
			(xy 87.522304 -32.714184) (xy 87.522304 -32.722312) (xy 87.521814 -32.75228) (xy 87.513991 -32.811702)
			(xy 87.498478 -32.869595) (xy 87.475542 -32.924968) (xy 87.445575 -32.976874) (xy 87.409088 -33.024424)
			(xy 87.366708 -33.066804) (xy 87.319158 -33.103291) (xy 87.267252 -33.133258) (xy 87.211879 -33.156194)
			(xy 87.153986 -33.171707) (xy 87.094564 -33.17953) (xy 87.034628 -33.17953) (xy 86.975206 -33.171707)
			(xy 86.917313 -33.156194) (xy 86.86194 -33.133258) (xy 86.810034 -33.103291) (xy 86.762484 -33.066804)
			(xy 86.720104 -33.024424) (xy 86.683617 -32.976874) (xy 86.65365 -32.924968) (xy 86.630714 -32.869595)
			(xy 86.615201 -32.811702) (xy 86.607378 -32.75228) (xy 86.606888 -32.722312) (xy 71.762995 -32.722312)
			(xy 71.762638 -32.744168) (xy 71.75481 -32.803624) (xy 71.739289 -32.861549) (xy 71.71634 -32.916953)
			(xy 71.686356 -32.968887) (xy 71.64985 -33.016463) (xy 71.607445 -33.058868) (xy 71.559869 -33.095374)
			(xy 71.507935 -33.125358) (xy 71.452531 -33.148307) (xy 71.394606 -33.163828) (xy 71.33515 -33.171656)
			(xy 71.275182 -33.171656) (xy 71.215726 -33.163828) (xy 71.157801 -33.148307) (xy 71.102397 -33.125358)
			(xy 71.050463 -33.095374) (xy 71.002887 -33.058868) (xy 70.960482 -33.016463) (xy 70.923976 -32.968887)
			(xy 70.893992 -32.916953) (xy 70.871043 -32.861549) (xy 70.855522 -32.803624) (xy 70.847694 -32.744168)
			(xy 70.847204 -32.714184) (xy 61.522356 -32.714184) (xy 61.522356 -32.722312) (xy 61.521866 -32.75228)
			(xy 61.514043 -32.811702) (xy 61.49853 -32.869595) (xy 61.475594 -32.924968) (xy 61.445627 -32.976874)
			(xy 61.40914 -33.024424) (xy 61.36676 -33.066804) (xy 61.31921 -33.103291) (xy 61.267304 -33.133258)
			(xy 61.211931 -33.156194) (xy 61.154038 -33.171707) (xy 61.094616 -33.17953) (xy 61.03468 -33.17953)
			(xy 60.975258 -33.171707) (xy 60.917365 -33.156194) (xy 60.861992 -33.133258) (xy 60.810086 -33.103291)
			(xy 60.762536 -33.066804) (xy 60.720156 -33.024424) (xy 60.683669 -32.976874) (xy 60.653702 -32.924968)
			(xy 60.630766 -32.869595) (xy 60.615253 -32.811702) (xy 60.60743 -32.75228) (xy 60.60694 -32.722312)
			(xy 45.763047 -32.722312) (xy 45.76269 -32.744168) (xy 45.754862 -32.803624) (xy 45.739341 -32.861549)
			(xy 45.716392 -32.916953) (xy 45.686408 -32.968887) (xy 45.649902 -33.016463) (xy 45.607497 -33.058868)
			(xy 45.559921 -33.095374) (xy 45.507987 -33.125358) (xy 45.452583 -33.148307) (xy 45.394658 -33.163828)
			(xy 45.335202 -33.171656) (xy 45.275234 -33.171656) (xy 45.215778 -33.163828) (xy 45.157853 -33.148307)
			(xy 45.102449 -33.125358) (xy 45.050515 -33.095374) (xy 45.002939 -33.058868) (xy 44.960534 -33.016463)
			(xy 44.924028 -32.968887) (xy 44.894044 -32.916953) (xy 44.871095 -32.861549) (xy 44.855574 -32.803624)
			(xy 44.847746 -32.744168) (xy 44.847256 -32.714184) (xy 35.522408 -32.714184) (xy 35.522408 -32.722312)
			(xy 35.521918 -32.75228) (xy 35.514095 -32.811702) (xy 35.498582 -32.869595) (xy 35.475646 -32.924968)
			(xy 35.445679 -32.976874) (xy 35.409192 -33.024424) (xy 35.366812 -33.066804) (xy 35.319262 -33.103291)
			(xy 35.267356 -33.133258) (xy 35.211983 -33.156194) (xy 35.15409 -33.171707) (xy 35.094668 -33.17953)
			(xy 35.034732 -33.17953) (xy 34.97531 -33.171707) (xy 34.917417 -33.156194) (xy 34.862044 -33.133258)
			(xy 34.810138 -33.103291) (xy 34.762588 -33.066804) (xy 34.720208 -33.024424) (xy 34.683721 -32.976874)
			(xy 34.653754 -32.924968) (xy 34.630818 -32.869595) (xy 34.615305 -32.811702) (xy 34.607482 -32.75228)
			(xy 34.606992 -32.722312) (xy 19.763099 -32.722312) (xy 19.762742 -32.744168) (xy 19.754914 -32.803624)
			(xy 19.739393 -32.861549) (xy 19.716444 -32.916953) (xy 19.68646 -32.968887) (xy 19.649954 -33.016463)
			(xy 19.607549 -33.058868) (xy 19.559973 -33.095374) (xy 19.508039 -33.125358) (xy 19.452635 -33.148307)
			(xy 19.39471 -33.163828) (xy 19.335254 -33.171656) (xy 19.275286 -33.171656) (xy 19.21583 -33.163828)
			(xy 19.157905 -33.148307) (xy 19.102501 -33.125358) (xy 19.050567 -33.095374) (xy 19.002991 -33.058868)
			(xy 18.960586 -33.016463) (xy 18.92408 -32.968887) (xy 18.894096 -32.916953) (xy 18.871147 -32.861549)
			(xy 18.855626 -32.803624) (xy 18.847798 -32.744168) (xy 18.847308 -32.714184) (xy 9.52246 -32.714184)
			(xy 9.52246 -32.722312) (xy 9.52197 -32.75228) (xy 9.514147 -32.811702) (xy 9.498634 -32.869595)
			(xy 9.475698 -32.924968) (xy 9.445731 -32.976874) (xy 9.409244 -33.024424) (xy 9.366864 -33.066804)
			(xy 9.319314 -33.103291) (xy 9.267408 -33.133258) (xy 9.212035 -33.156194) (xy 9.154142 -33.171707)
			(xy 9.09472 -33.17953) (xy 9.034784 -33.17953) (xy 8.975362 -33.171707) (xy 8.917469 -33.156194)
			(xy 8.862096 -33.133258) (xy 8.81019 -33.103291) (xy 8.76264 -33.066804) (xy 8.72026 -33.024424)
			(xy 8.683773 -32.976874) (xy 8.653806 -32.924968) (xy 8.63087 -32.869595) (xy 8.615357 -32.811702)
			(xy 8.607534 -32.75228) (xy 8.607044 -32.722312) (xy 1.524 -32.722312) (xy 1.524 -34.52241) (xy 6.752844 -34.52241)
			(xy 6.752844 -33.65881) (xy 6.753334 -33.628842) (xy 6.761157 -33.56942) (xy 6.77667 -33.511527)
			(xy 6.799606 -33.456154) (xy 6.829573 -33.404248) (xy 6.86606 -33.356698) (xy 6.90844 -33.314318)
			(xy 6.95599 -33.277831) (xy 7.007896 -33.247864) (xy 7.063269 -33.224928) (xy 7.121162 -33.209415)
			(xy 7.180584 -33.201592) (xy 7.24052 -33.201592) (xy 7.299942 -33.209415) (xy 7.357835 -33.224928)
			(xy 7.413208 -33.247864) (xy 7.465114 -33.277831) (xy 7.512664 -33.314318) (xy 7.555044 -33.356698)
			(xy 7.591531 -33.404248) (xy 7.621498 -33.456154) (xy 7.644434 -33.511527) (xy 7.659947 -33.56942)
			(xy 7.66777 -33.628842) (xy 7.66826 -33.65881) (xy 7.66826 -34.520886) (xy 21.489416 -34.520886)
			(xy 21.489416 -33.657286) (xy 21.489906 -33.627302) (xy 21.497734 -33.567846) (xy 21.513255 -33.509921)
			(xy 21.536204 -33.454517) (xy 21.566188 -33.402583) (xy 21.602694 -33.355007) (xy 21.645099 -33.312602)
			(xy 21.692675 -33.276096) (xy 21.744609 -33.246112) (xy 21.800013 -33.223163) (xy 21.857938 -33.207642)
			(xy 21.917394 -33.199814) (xy 21.977362 -33.199814) (xy 22.036818 -33.207642) (xy 22.094743 -33.223163)
			(xy 22.150147 -33.246112) (xy 22.202081 -33.276096) (xy 22.249657 -33.312602) (xy 22.292062 -33.355007)
			(xy 22.328568 -33.402583) (xy 22.358552 -33.454517) (xy 22.381501 -33.509921) (xy 22.397022 -33.567846)
			(xy 22.40485 -33.627302) (xy 22.40534 -33.657286) (xy 22.40534 -34.520886) (xy 22.405315 -34.52241)
			(xy 32.752792 -34.52241) (xy 32.752792 -33.65881) (xy 32.753282 -33.628842) (xy 32.761105 -33.56942)
			(xy 32.776618 -33.511527) (xy 32.799554 -33.456154) (xy 32.829521 -33.404248) (xy 32.866008 -33.356698)
			(xy 32.908388 -33.314318) (xy 32.955938 -33.277831) (xy 33.007844 -33.247864) (xy 33.063217 -33.224928)
			(xy 33.12111 -33.209415) (xy 33.180532 -33.201592) (xy 33.240468 -33.201592) (xy 33.29989 -33.209415)
			(xy 33.357783 -33.224928) (xy 33.413156 -33.247864) (xy 33.465062 -33.277831) (xy 33.512612 -33.314318)
			(xy 33.554992 -33.356698) (xy 33.591479 -33.404248) (xy 33.621446 -33.456154) (xy 33.644382 -33.511527)
			(xy 33.659895 -33.56942) (xy 33.667718 -33.628842) (xy 33.668208 -33.65881) (xy 33.668208 -34.520886)
			(xy 47.489364 -34.520886) (xy 47.489364 -33.657286) (xy 47.489854 -33.627302) (xy 47.497682 -33.567846)
			(xy 47.513203 -33.509921) (xy 47.536152 -33.454517) (xy 47.566136 -33.402583) (xy 47.602642 -33.355007)
			(xy 47.645047 -33.312602) (xy 47.692623 -33.276096) (xy 47.744557 -33.246112) (xy 47.799961 -33.223163)
			(xy 47.857886 -33.207642) (xy 47.917342 -33.199814) (xy 47.97731 -33.199814) (xy 48.036766 -33.207642)
			(xy 48.094691 -33.223163) (xy 48.150095 -33.246112) (xy 48.202029 -33.276096) (xy 48.249605 -33.312602)
			(xy 48.29201 -33.355007) (xy 48.328516 -33.402583) (xy 48.3585 -33.454517) (xy 48.381449 -33.509921)
			(xy 48.39697 -33.567846) (xy 48.404798 -33.627302) (xy 48.405288 -33.657286) (xy 48.405288 -34.520886)
			(xy 48.405263 -34.52241) (xy 58.75274 -34.52241) (xy 58.75274 -33.65881) (xy 58.75323 -33.628842)
			(xy 58.761053 -33.56942) (xy 58.776566 -33.511527) (xy 58.799502 -33.456154) (xy 58.829469 -33.404248)
			(xy 58.865956 -33.356698) (xy 58.908336 -33.314318) (xy 58.955886 -33.277831) (xy 59.007792 -33.247864)
			(xy 59.063165 -33.224928) (xy 59.121058 -33.209415) (xy 59.18048 -33.201592) (xy 59.240416 -33.201592)
			(xy 59.299838 -33.209415) (xy 59.357731 -33.224928) (xy 59.413104 -33.247864) (xy 59.46501 -33.277831)
			(xy 59.51256 -33.314318) (xy 59.55494 -33.356698) (xy 59.591427 -33.404248) (xy 59.621394 -33.456154)
			(xy 59.64433 -33.511527) (xy 59.659843 -33.56942) (xy 59.667666 -33.628842) (xy 59.668156 -33.65881)
			(xy 59.668156 -34.520886) (xy 73.489312 -34.520886) (xy 73.489312 -33.657286) (xy 73.489802 -33.627302)
			(xy 73.49763 -33.567846) (xy 73.513151 -33.509921) (xy 73.5361 -33.454517) (xy 73.566084 -33.402583)
			(xy 73.60259 -33.355007) (xy 73.644995 -33.312602) (xy 73.692571 -33.276096) (xy 73.744505 -33.246112)
			(xy 73.799909 -33.223163) (xy 73.857834 -33.207642) (xy 73.91729 -33.199814) (xy 73.977258 -33.199814)
			(xy 74.036714 -33.207642) (xy 74.094639 -33.223163) (xy 74.150043 -33.246112) (xy 74.201977 -33.276096)
			(xy 74.249553 -33.312602) (xy 74.291958 -33.355007) (xy 74.328464 -33.402583) (xy 74.358448 -33.454517)
			(xy 74.381397 -33.509921) (xy 74.396918 -33.567846) (xy 74.404746 -33.627302) (xy 74.405236 -33.657286)
			(xy 74.405236 -34.520886) (xy 74.405211 -34.52241) (xy 84.752688 -34.52241) (xy 84.752688 -33.65881)
			(xy 84.753178 -33.628842) (xy 84.761001 -33.56942) (xy 84.776514 -33.511527) (xy 84.79945 -33.456154)
			(xy 84.829417 -33.404248) (xy 84.865904 -33.356698) (xy 84.908284 -33.314318) (xy 84.955834 -33.277831)
			(xy 85.00774 -33.247864) (xy 85.063113 -33.224928) (xy 85.121006 -33.209415) (xy 85.180428 -33.201592)
			(xy 85.240364 -33.201592) (xy 85.299786 -33.209415) (xy 85.357679 -33.224928) (xy 85.413052 -33.247864)
			(xy 85.464958 -33.277831) (xy 85.512508 -33.314318) (xy 85.554888 -33.356698) (xy 85.591375 -33.404248)
			(xy 85.621342 -33.456154) (xy 85.644278 -33.511527) (xy 85.659791 -33.56942) (xy 85.667614 -33.628842)
			(xy 85.668104 -33.65881) (xy 85.668104 -34.520886) (xy 99.48926 -34.520886) (xy 99.48926 -33.657286)
			(xy 99.48975 -33.627302) (xy 99.497578 -33.567846) (xy 99.513099 -33.509921) (xy 99.536048 -33.454517)
			(xy 99.566032 -33.402583) (xy 99.602538 -33.355007) (xy 99.644943 -33.312602) (xy 99.692519 -33.276096)
			(xy 99.744453 -33.246112) (xy 99.799857 -33.223163) (xy 99.857782 -33.207642) (xy 99.917238 -33.199814)
			(xy 99.977206 -33.199814) (xy 100.036662 -33.207642) (xy 100.094587 -33.223163) (xy 100.149991 -33.246112)
			(xy 100.201925 -33.276096) (xy 100.249501 -33.312602) (xy 100.291906 -33.355007) (xy 100.328412 -33.402583)
			(xy 100.358396 -33.454517) (xy 100.381345 -33.509921) (xy 100.396866 -33.567846) (xy 100.404694 -33.627302)
			(xy 100.405184 -33.657286) (xy 100.405184 -34.520886) (xy 100.405159 -34.52241) (xy 122.852688 -34.52241)
			(xy 122.852688 -33.65881) (xy 122.853178 -33.628826) (xy 122.861006 -33.56937) (xy 122.876527 -33.511445)
			(xy 122.899476 -33.456041) (xy 122.92946 -33.404107) (xy 122.965966 -33.356531) (xy 123.008371 -33.314126)
			(xy 123.055947 -33.27762) (xy 123.107881 -33.247636) (xy 123.163285 -33.224687) (xy 123.22121 -33.209166)
			(xy 123.280666 -33.201338) (xy 123.340634 -33.201338) (xy 123.40009 -33.209166) (xy 123.458015 -33.224687)
			(xy 123.513419 -33.247636) (xy 123.565353 -33.27762) (xy 123.612929 -33.314126) (xy 123.655334 -33.356531)
			(xy 123.69184 -33.404107) (xy 123.721824 -33.456041) (xy 123.744773 -33.511445) (xy 123.760294 -33.56937)
			(xy 123.768122 -33.628826) (xy 123.768612 -33.65881) (xy 123.768612 -34.520886) (xy 137.589768 -34.520886)
			(xy 137.589768 -33.657286) (xy 137.590258 -33.627318) (xy 137.598081 -33.567896) (xy 137.613594 -33.510003)
			(xy 137.63653 -33.45463) (xy 137.666497 -33.402724) (xy 137.702984 -33.355174) (xy 137.745364 -33.312794)
			(xy 137.792914 -33.276307) (xy 137.84482 -33.24634) (xy 137.900193 -33.223404) (xy 137.958086 -33.207891)
			(xy 138.017508 -33.200068) (xy 138.077444 -33.200068) (xy 138.136866 -33.207891) (xy 138.194759 -33.223404)
			(xy 138.250132 -33.24634) (xy 138.302038 -33.276307) (xy 138.349588 -33.312794) (xy 138.391968 -33.355174)
			(xy 138.428455 -33.402724) (xy 138.458422 -33.45463) (xy 138.481358 -33.510003) (xy 138.496871 -33.567896)
			(xy 138.504694 -33.627318) (xy 138.505184 -33.657286) (xy 138.505184 -34.520886) (xy 138.505159 -34.52241)
			(xy 148.852636 -34.52241) (xy 148.852636 -33.65881) (xy 148.853126 -33.628826) (xy 148.860954 -33.56937)
			(xy 148.876475 -33.511445) (xy 148.899424 -33.456041) (xy 148.929408 -33.404107) (xy 148.965914 -33.356531)
			(xy 149.008319 -33.314126) (xy 149.055895 -33.27762) (xy 149.107829 -33.247636) (xy 149.163233 -33.224687)
			(xy 149.221158 -33.209166) (xy 149.280614 -33.201338) (xy 149.340582 -33.201338) (xy 149.400038 -33.209166)
			(xy 149.457963 -33.224687) (xy 149.513367 -33.247636) (xy 149.565301 -33.27762) (xy 149.612877 -33.314126)
			(xy 149.655282 -33.356531) (xy 149.691788 -33.404107) (xy 149.721772 -33.456041) (xy 149.744721 -33.511445)
			(xy 149.760242 -33.56937) (xy 149.76807 -33.628826) (xy 149.76856 -33.65881) (xy 149.76856 -34.520886)
			(xy 163.589716 -34.520886) (xy 163.589716 -33.657286) (xy 163.590206 -33.627318) (xy 163.598029 -33.567896)
			(xy 163.613542 -33.510003) (xy 163.636478 -33.45463) (xy 163.666445 -33.402724) (xy 163.702932 -33.355174)
			(xy 163.745312 -33.312794) (xy 163.792862 -33.276307) (xy 163.844768 -33.24634) (xy 163.900141 -33.223404)
			(xy 163.958034 -33.207891) (xy 164.017456 -33.200068) (xy 164.077392 -33.200068) (xy 164.136814 -33.207891)
			(xy 164.194707 -33.223404) (xy 164.25008 -33.24634) (xy 164.301986 -33.276307) (xy 164.349536 -33.312794)
			(xy 164.391916 -33.355174) (xy 164.428403 -33.402724) (xy 164.45837 -33.45463) (xy 164.481306 -33.510003)
			(xy 164.496819 -33.567896) (xy 164.504642 -33.627318) (xy 164.505132 -33.657286) (xy 164.505132 -34.520886)
			(xy 164.505107 -34.52241) (xy 174.852584 -34.52241) (xy 174.852584 -33.65881) (xy 174.853074 -33.628826)
			(xy 174.860902 -33.56937) (xy 174.876423 -33.511445) (xy 174.899372 -33.456041) (xy 174.929356 -33.404107)
			(xy 174.965862 -33.356531) (xy 175.008267 -33.314126) (xy 175.055843 -33.27762) (xy 175.107777 -33.247636)
			(xy 175.163181 -33.224687) (xy 175.221106 -33.209166) (xy 175.280562 -33.201338) (xy 175.34053 -33.201338)
			(xy 175.399986 -33.209166) (xy 175.457911 -33.224687) (xy 175.513315 -33.247636) (xy 175.565249 -33.27762)
			(xy 175.612825 -33.314126) (xy 175.65523 -33.356531) (xy 175.691736 -33.404107) (xy 175.72172 -33.456041)
			(xy 175.744669 -33.511445) (xy 175.76019 -33.56937) (xy 175.768018 -33.628826) (xy 175.768508 -33.65881)
			(xy 175.768508 -34.520886) (xy 189.589664 -34.520886) (xy 189.589664 -33.657286) (xy 189.590154 -33.627318)
			(xy 189.597977 -33.567896) (xy 189.61349 -33.510003) (xy 189.636426 -33.45463) (xy 189.666393 -33.402724)
			(xy 189.70288 -33.355174) (xy 189.74526 -33.312794) (xy 189.79281 -33.276307) (xy 189.844716 -33.24634)
			(xy 189.900089 -33.223404) (xy 189.957982 -33.207891) (xy 190.017404 -33.200068) (xy 190.07734 -33.200068)
			(xy 190.136762 -33.207891) (xy 190.194655 -33.223404) (xy 190.250028 -33.24634) (xy 190.301934 -33.276307)
			(xy 190.349484 -33.312794) (xy 190.391864 -33.355174) (xy 190.428351 -33.402724) (xy 190.458318 -33.45463)
			(xy 190.481254 -33.510003) (xy 190.496767 -33.567896) (xy 190.50459 -33.627318) (xy 190.50508 -33.657286)
			(xy 190.50508 -34.520886) (xy 190.505055 -34.52241) (xy 200.852532 -34.52241) (xy 200.852532 -33.65881)
			(xy 200.853022 -33.628826) (xy 200.86085 -33.56937) (xy 200.876371 -33.511445) (xy 200.89932 -33.456041)
			(xy 200.929304 -33.404107) (xy 200.96581 -33.356531) (xy 201.008215 -33.314126) (xy 201.055791 -33.27762)
			(xy 201.107725 -33.247636) (xy 201.163129 -33.224687) (xy 201.221054 -33.209166) (xy 201.28051 -33.201338)
			(xy 201.340478 -33.201338) (xy 201.399934 -33.209166) (xy 201.457859 -33.224687) (xy 201.513263 -33.247636)
			(xy 201.565197 -33.27762) (xy 201.612773 -33.314126) (xy 201.655178 -33.356531) (xy 201.691684 -33.404107)
			(xy 201.721668 -33.456041) (xy 201.744617 -33.511445) (xy 201.760138 -33.56937) (xy 201.767966 -33.628826)
			(xy 201.768456 -33.65881) (xy 201.768456 -34.520886) (xy 215.589612 -34.520886) (xy 215.589612 -33.657286)
			(xy 215.590102 -33.627318) (xy 215.597925 -33.567896) (xy 215.613438 -33.510003) (xy 215.636374 -33.45463)
			(xy 215.666341 -33.402724) (xy 215.702828 -33.355174) (xy 215.745208 -33.312794) (xy 215.792758 -33.276307)
			(xy 215.844664 -33.24634) (xy 215.900037 -33.223404) (xy 215.95793 -33.207891) (xy 216.017352 -33.200068)
			(xy 216.077288 -33.200068) (xy 216.13671 -33.207891) (xy 216.194603 -33.223404) (xy 216.249976 -33.24634)
			(xy 216.301882 -33.276307) (xy 216.349432 -33.312794) (xy 216.391812 -33.355174) (xy 216.428299 -33.402724)
			(xy 216.458266 -33.45463) (xy 216.481202 -33.510003) (xy 216.496715 -33.567896) (xy 216.504538 -33.627318)
			(xy 216.505028 -33.657286) (xy 216.505028 -34.520886) (xy 216.505003 -34.52241) (xy 238.952532 -34.52241)
			(xy 238.952532 -33.65881) (xy 238.953022 -33.628826) (xy 238.96085 -33.56937) (xy 238.976371 -33.511445)
			(xy 238.99932 -33.456041) (xy 239.029304 -33.404107) (xy 239.06581 -33.356531) (xy 239.108215 -33.314126)
			(xy 239.155791 -33.27762) (xy 239.207725 -33.247636) (xy 239.263129 -33.224687) (xy 239.321054 -33.209166)
			(xy 239.38051 -33.201338) (xy 239.440478 -33.201338) (xy 239.499934 -33.209166) (xy 239.557859 -33.224687)
			(xy 239.613263 -33.247636) (xy 239.665197 -33.27762) (xy 239.712773 -33.314126) (xy 239.755178 -33.356531)
			(xy 239.791684 -33.404107) (xy 239.821668 -33.456041) (xy 239.844617 -33.511445) (xy 239.860138 -33.56937)
			(xy 239.867966 -33.628826) (xy 239.868456 -33.65881) (xy 239.868456 -34.520886) (xy 253.689612 -34.520886)
			(xy 253.689612 -33.657286) (xy 253.690102 -33.627318) (xy 253.697925 -33.567896) (xy 253.713438 -33.510003)
			(xy 253.736374 -33.45463) (xy 253.766341 -33.402724) (xy 253.802828 -33.355174) (xy 253.845208 -33.312794)
			(xy 253.892758 -33.276307) (xy 253.944664 -33.24634) (xy 254.000037 -33.223404) (xy 254.05793 -33.207891)
			(xy 254.117352 -33.200068) (xy 254.177288 -33.200068) (xy 254.23671 -33.207891) (xy 254.294603 -33.223404)
			(xy 254.349976 -33.24634) (xy 254.401882 -33.276307) (xy 254.449432 -33.312794) (xy 254.491812 -33.355174)
			(xy 254.528299 -33.402724) (xy 254.558266 -33.45463) (xy 254.581202 -33.510003) (xy 254.596715 -33.567896)
			(xy 254.604538 -33.627318) (xy 254.605028 -33.657286) (xy 254.605028 -34.520886) (xy 254.605003 -34.52241)
			(xy 264.95248 -34.52241) (xy 264.95248 -33.65881) (xy 264.95297 -33.628826) (xy 264.960798 -33.56937)
			(xy 264.976319 -33.511445) (xy 264.999268 -33.456041) (xy 265.029252 -33.404107) (xy 265.065758 -33.356531)
			(xy 265.108163 -33.314126) (xy 265.155739 -33.27762) (xy 265.207673 -33.247636) (xy 265.263077 -33.224687)
			(xy 265.321002 -33.209166) (xy 265.380458 -33.201338) (xy 265.440426 -33.201338) (xy 265.499882 -33.209166)
			(xy 265.557807 -33.224687) (xy 265.613211 -33.247636) (xy 265.665145 -33.27762) (xy 265.712721 -33.314126)
			(xy 265.755126 -33.356531) (xy 265.791632 -33.404107) (xy 265.821616 -33.456041) (xy 265.844565 -33.511445)
			(xy 265.860086 -33.56937) (xy 265.867914 -33.628826) (xy 265.868404 -33.65881) (xy 265.868404 -34.520886)
			(xy 279.68956 -34.520886) (xy 279.68956 -33.657286) (xy 279.69005 -33.627318) (xy 279.697873 -33.567896)
			(xy 279.713386 -33.510003) (xy 279.736322 -33.45463) (xy 279.766289 -33.402724) (xy 279.802776 -33.355174)
			(xy 279.845156 -33.312794) (xy 279.892706 -33.276307) (xy 279.944612 -33.24634) (xy 279.999985 -33.223404)
			(xy 280.057878 -33.207891) (xy 280.1173 -33.200068) (xy 280.177236 -33.200068) (xy 280.236658 -33.207891)
			(xy 280.294551 -33.223404) (xy 280.349924 -33.24634) (xy 280.40183 -33.276307) (xy 280.44938 -33.312794)
			(xy 280.49176 -33.355174) (xy 280.528247 -33.402724) (xy 280.558214 -33.45463) (xy 280.58115 -33.510003)
			(xy 280.596663 -33.567896) (xy 280.604486 -33.627318) (xy 280.604976 -33.657286) (xy 280.604976 -34.520886)
			(xy 280.604951 -34.52241) (xy 290.952428 -34.52241) (xy 290.952428 -33.65881) (xy 290.952918 -33.628826)
			(xy 290.960746 -33.56937) (xy 290.976267 -33.511445) (xy 290.999216 -33.456041) (xy 291.0292 -33.404107)
			(xy 291.065706 -33.356531) (xy 291.108111 -33.314126) (xy 291.155687 -33.27762) (xy 291.207621 -33.247636)
			(xy 291.263025 -33.224687) (xy 291.32095 -33.209166) (xy 291.380406 -33.201338) (xy 291.440374 -33.201338)
			(xy 291.49983 -33.209166) (xy 291.557755 -33.224687) (xy 291.613159 -33.247636) (xy 291.665093 -33.27762)
			(xy 291.712669 -33.314126) (xy 291.755074 -33.356531) (xy 291.79158 -33.404107) (xy 291.821564 -33.456041)
			(xy 291.844513 -33.511445) (xy 291.860034 -33.56937) (xy 291.867862 -33.628826) (xy 291.868352 -33.65881)
			(xy 291.868352 -34.520886) (xy 305.689508 -34.520886) (xy 305.689508 -33.657286) (xy 305.689998 -33.627318)
			(xy 305.697821 -33.567896) (xy 305.713334 -33.510003) (xy 305.73627 -33.45463) (xy 305.766237 -33.402724)
			(xy 305.802724 -33.355174) (xy 305.845104 -33.312794) (xy 305.892654 -33.276307) (xy 305.94456 -33.24634)
			(xy 305.999933 -33.223404) (xy 306.057826 -33.207891) (xy 306.117248 -33.200068) (xy 306.177184 -33.200068)
			(xy 306.236606 -33.207891) (xy 306.294499 -33.223404) (xy 306.349872 -33.24634) (xy 306.401778 -33.276307)
			(xy 306.449328 -33.312794) (xy 306.491708 -33.355174) (xy 306.528195 -33.402724) (xy 306.558162 -33.45463)
			(xy 306.581098 -33.510003) (xy 306.596611 -33.567896) (xy 306.604434 -33.627318) (xy 306.604924 -33.657286)
			(xy 306.604924 -34.520886) (xy 306.604899 -34.52241) (xy 316.952376 -34.52241) (xy 316.952376 -33.65881)
			(xy 316.952866 -33.628826) (xy 316.960694 -33.56937) (xy 316.976215 -33.511445) (xy 316.999164 -33.456041)
			(xy 317.029148 -33.404107) (xy 317.065654 -33.356531) (xy 317.108059 -33.314126) (xy 317.155635 -33.27762)
			(xy 317.207569 -33.247636) (xy 317.262973 -33.224687) (xy 317.320898 -33.209166) (xy 317.380354 -33.201338)
			(xy 317.440322 -33.201338) (xy 317.499778 -33.209166) (xy 317.557703 -33.224687) (xy 317.613107 -33.247636)
			(xy 317.665041 -33.27762) (xy 317.712617 -33.314126) (xy 317.755022 -33.356531) (xy 317.791528 -33.404107)
			(xy 317.821512 -33.456041) (xy 317.844461 -33.511445) (xy 317.859982 -33.56937) (xy 317.86781 -33.628826)
			(xy 317.8683 -33.65881) (xy 317.8683 -34.520886) (xy 331.689456 -34.520886) (xy 331.689456 -33.657286)
			(xy 331.689946 -33.627318) (xy 331.697769 -33.567896) (xy 331.713282 -33.510003) (xy 331.736218 -33.45463)
			(xy 331.766185 -33.402724) (xy 331.802672 -33.355174) (xy 331.845052 -33.312794) (xy 331.892602 -33.276307)
			(xy 331.944508 -33.24634) (xy 331.999881 -33.223404) (xy 332.057774 -33.207891) (xy 332.117196 -33.200068)
			(xy 332.177132 -33.200068) (xy 332.236554 -33.207891) (xy 332.294447 -33.223404) (xy 332.34982 -33.24634)
			(xy 332.401726 -33.276307) (xy 332.449276 -33.312794) (xy 332.491656 -33.355174) (xy 332.528143 -33.402724)
			(xy 332.55811 -33.45463) (xy 332.581046 -33.510003) (xy 332.596559 -33.567896) (xy 332.604382 -33.627318)
			(xy 332.604872 -33.657286) (xy 332.604872 -34.520886) (xy 332.604847 -34.52241) (xy 355.052884 -34.52241)
			(xy 355.052884 -33.65881) (xy 355.053374 -33.628842) (xy 355.061197 -33.56942) (xy 355.07671 -33.511527)
			(xy 355.099646 -33.456154) (xy 355.129613 -33.404248) (xy 355.1661 -33.356698) (xy 355.20848 -33.314318)
			(xy 355.25603 -33.277831) (xy 355.307936 -33.247864) (xy 355.363309 -33.224928) (xy 355.421202 -33.209415)
			(xy 355.480624 -33.201592) (xy 355.54056 -33.201592) (xy 355.599982 -33.209415) (xy 355.657875 -33.224928)
			(xy 355.713248 -33.247864) (xy 355.765154 -33.277831) (xy 355.812704 -33.314318) (xy 355.855084 -33.356698)
			(xy 355.891571 -33.404248) (xy 355.921538 -33.456154) (xy 355.944474 -33.511527) (xy 355.959987 -33.56942)
			(xy 355.96781 -33.628842) (xy 355.9683 -33.65881) (xy 355.9683 -34.520886) (xy 369.789456 -34.520886)
			(xy 369.789456 -33.657286) (xy 369.789946 -33.627302) (xy 369.797774 -33.567846) (xy 369.813295 -33.509921)
			(xy 369.836244 -33.454517) (xy 369.866228 -33.402583) (xy 369.902734 -33.355007) (xy 369.945139 -33.312602)
			(xy 369.992715 -33.276096) (xy 370.044649 -33.246112) (xy 370.100053 -33.223163) (xy 370.157978 -33.207642)
			(xy 370.217434 -33.199814) (xy 370.277402 -33.199814) (xy 370.336858 -33.207642) (xy 370.394783 -33.223163)
			(xy 370.450187 -33.246112) (xy 370.502121 -33.276096) (xy 370.549697 -33.312602) (xy 370.592102 -33.355007)
			(xy 370.628608 -33.402583) (xy 370.658592 -33.454517) (xy 370.681541 -33.509921) (xy 370.697062 -33.567846)
			(xy 370.70489 -33.627302) (xy 370.70538 -33.657286) (xy 370.70538 -34.520886) (xy 370.705355 -34.52241)
			(xy 381.052832 -34.52241) (xy 381.052832 -33.65881) (xy 381.053322 -33.628842) (xy 381.061145 -33.56942)
			(xy 381.076658 -33.511527) (xy 381.099594 -33.456154) (xy 381.129561 -33.404248) (xy 381.166048 -33.356698)
			(xy 381.208428 -33.314318) (xy 381.255978 -33.277831) (xy 381.307884 -33.247864) (xy 381.363257 -33.224928)
			(xy 381.42115 -33.209415) (xy 381.480572 -33.201592) (xy 381.540508 -33.201592) (xy 381.59993 -33.209415)
			(xy 381.657823 -33.224928) (xy 381.713196 -33.247864) (xy 381.765102 -33.277831) (xy 381.812652 -33.314318)
			(xy 381.855032 -33.356698) (xy 381.891519 -33.404248) (xy 381.921486 -33.456154) (xy 381.944422 -33.511527)
			(xy 381.959935 -33.56942) (xy 381.967758 -33.628842) (xy 381.968248 -33.65881) (xy 381.968248 -34.520886)
			(xy 395.789404 -34.520886) (xy 395.789404 -33.657286) (xy 395.789894 -33.627302) (xy 395.797722 -33.567846)
			(xy 395.813243 -33.509921) (xy 395.836192 -33.454517) (xy 395.866176 -33.402583) (xy 395.902682 -33.355007)
			(xy 395.945087 -33.312602) (xy 395.992663 -33.276096) (xy 396.044597 -33.246112) (xy 396.100001 -33.223163)
			(xy 396.157926 -33.207642) (xy 396.217382 -33.199814) (xy 396.27735 -33.199814) (xy 396.336806 -33.207642)
			(xy 396.394731 -33.223163) (xy 396.450135 -33.246112) (xy 396.502069 -33.276096) (xy 396.549645 -33.312602)
			(xy 396.59205 -33.355007) (xy 396.628556 -33.402583) (xy 396.65854 -33.454517) (xy 396.681489 -33.509921)
			(xy 396.69701 -33.567846) (xy 396.704838 -33.627302) (xy 396.705328 -33.657286) (xy 396.705328 -34.520886)
			(xy 396.705303 -34.52241) (xy 407.05278 -34.52241) (xy 407.05278 -33.65881) (xy 407.05327 -33.628842)
			(xy 407.061093 -33.56942) (xy 407.076606 -33.511527) (xy 407.099542 -33.456154) (xy 407.129509 -33.404248)
			(xy 407.165996 -33.356698) (xy 407.208376 -33.314318) (xy 407.255926 -33.277831) (xy 407.307832 -33.247864)
			(xy 407.363205 -33.224928) (xy 407.421098 -33.209415) (xy 407.48052 -33.201592) (xy 407.540456 -33.201592)
			(xy 407.599878 -33.209415) (xy 407.657771 -33.224928) (xy 407.713144 -33.247864) (xy 407.76505 -33.277831)
			(xy 407.8126 -33.314318) (xy 407.85498 -33.356698) (xy 407.891467 -33.404248) (xy 407.921434 -33.456154)
			(xy 407.94437 -33.511527) (xy 407.959883 -33.56942) (xy 407.967706 -33.628842) (xy 407.968196 -33.65881)
			(xy 407.968196 -34.520886) (xy 421.789352 -34.520886) (xy 421.789352 -33.657286) (xy 421.789842 -33.627302)
			(xy 421.79767 -33.567846) (xy 421.813191 -33.509921) (xy 421.83614 -33.454517) (xy 421.866124 -33.402583)
			(xy 421.90263 -33.355007) (xy 421.945035 -33.312602) (xy 421.992611 -33.276096) (xy 422.044545 -33.246112)
			(xy 422.099949 -33.223163) (xy 422.157874 -33.207642) (xy 422.21733 -33.199814) (xy 422.277298 -33.199814)
			(xy 422.336754 -33.207642) (xy 422.394679 -33.223163) (xy 422.450083 -33.246112) (xy 422.502017 -33.276096)
			(xy 422.549593 -33.312602) (xy 422.591998 -33.355007) (xy 422.628504 -33.402583) (xy 422.658488 -33.454517)
			(xy 422.681437 -33.509921) (xy 422.696958 -33.567846) (xy 422.704786 -33.627302) (xy 422.705276 -33.657286)
			(xy 422.705276 -34.520886) (xy 422.705251 -34.52241) (xy 433.052728 -34.52241) (xy 433.052728 -33.65881)
			(xy 433.053218 -33.628842) (xy 433.061041 -33.56942) (xy 433.076554 -33.511527) (xy 433.09949 -33.456154)
			(xy 433.129457 -33.404248) (xy 433.165944 -33.356698) (xy 433.208324 -33.314318) (xy 433.255874 -33.277831)
			(xy 433.30778 -33.247864) (xy 433.363153 -33.224928) (xy 433.421046 -33.209415) (xy 433.480468 -33.201592)
			(xy 433.540404 -33.201592) (xy 433.599826 -33.209415) (xy 433.657719 -33.224928) (xy 433.713092 -33.247864)
			(xy 433.764998 -33.277831) (xy 433.812548 -33.314318) (xy 433.854928 -33.356698) (xy 433.891415 -33.404248)
			(xy 433.921382 -33.456154) (xy 433.944318 -33.511527) (xy 433.959831 -33.56942) (xy 433.967654 -33.628842)
			(xy 433.968144 -33.65881) (xy 433.968144 -34.520886) (xy 447.7893 -34.520886) (xy 447.7893 -33.657286)
			(xy 447.78979 -33.627302) (xy 447.797618 -33.567846) (xy 447.813139 -33.509921) (xy 447.836088 -33.454517)
			(xy 447.866072 -33.402583) (xy 447.902578 -33.355007) (xy 447.944983 -33.312602) (xy 447.992559 -33.276096)
			(xy 448.044493 -33.246112) (xy 448.099897 -33.223163) (xy 448.157822 -33.207642) (xy 448.217278 -33.199814)
			(xy 448.277246 -33.199814) (xy 448.336702 -33.207642) (xy 448.394627 -33.223163) (xy 448.450031 -33.246112)
			(xy 448.501965 -33.276096) (xy 448.549541 -33.312602) (xy 448.591946 -33.355007) (xy 448.628452 -33.402583)
			(xy 448.658436 -33.454517) (xy 448.681385 -33.509921) (xy 448.696906 -33.567846) (xy 448.704734 -33.627302)
			(xy 448.705224 -33.657286) (xy 448.705224 -34.520886) (xy 448.704734 -34.55087) (xy 448.696906 -34.610326)
			(xy 448.681385 -34.668251) (xy 448.658436 -34.723655) (xy 448.628452 -34.775589) (xy 448.591946 -34.823165)
			(xy 448.549541 -34.86557) (xy 448.501965 -34.902076) (xy 448.450031 -34.93206) (xy 448.394627 -34.955009)
			(xy 448.336702 -34.97053) (xy 448.277246 -34.978358) (xy 448.217278 -34.978358) (xy 448.157822 -34.97053)
			(xy 448.099897 -34.955009) (xy 448.044493 -34.93206) (xy 447.992559 -34.902076) (xy 447.944983 -34.86557)
			(xy 447.902578 -34.823165) (xy 447.866072 -34.775589) (xy 447.836088 -34.723655) (xy 447.813139 -34.668251)
			(xy 447.797618 -34.610326) (xy 447.78979 -34.55087) (xy 447.7893 -34.520886) (xy 433.968144 -34.520886)
			(xy 433.968144 -34.52241) (xy 433.967654 -34.552378) (xy 433.959831 -34.6118) (xy 433.944318 -34.669693)
			(xy 433.921382 -34.725066) (xy 433.891415 -34.776972) (xy 433.854928 -34.824522) (xy 433.812548 -34.866902)
			(xy 433.764998 -34.903389) (xy 433.713092 -34.933356) (xy 433.657719 -34.956292) (xy 433.599826 -34.971805)
			(xy 433.540404 -34.979628) (xy 433.480468 -34.979628) (xy 433.421046 -34.971805) (xy 433.363153 -34.956292)
			(xy 433.30778 -34.933356) (xy 433.255874 -34.903389) (xy 433.208324 -34.866902) (xy 433.165944 -34.824522)
			(xy 433.129457 -34.776972) (xy 433.09949 -34.725066) (xy 433.076554 -34.669693) (xy 433.061041 -34.6118)
			(xy 433.053218 -34.552378) (xy 433.052728 -34.52241) (xy 422.705251 -34.52241) (xy 422.704786 -34.55087)
			(xy 422.696958 -34.610326) (xy 422.681437 -34.668251) (xy 422.658488 -34.723655) (xy 422.628504 -34.775589)
			(xy 422.591998 -34.823165) (xy 422.549593 -34.86557) (xy 422.502017 -34.902076) (xy 422.450083 -34.93206)
			(xy 422.394679 -34.955009) (xy 422.336754 -34.97053) (xy 422.277298 -34.978358) (xy 422.21733 -34.978358)
			(xy 422.157874 -34.97053) (xy 422.099949 -34.955009) (xy 422.044545 -34.93206) (xy 421.992611 -34.902076)
			(xy 421.945035 -34.86557) (xy 421.90263 -34.823165) (xy 421.866124 -34.775589) (xy 421.83614 -34.723655)
			(xy 421.813191 -34.668251) (xy 421.79767 -34.610326) (xy 421.789842 -34.55087) (xy 421.789352 -34.520886)
			(xy 407.968196 -34.520886) (xy 407.968196 -34.52241) (xy 407.967706 -34.552378) (xy 407.959883 -34.6118)
			(xy 407.94437 -34.669693) (xy 407.921434 -34.725066) (xy 407.891467 -34.776972) (xy 407.85498 -34.824522)
			(xy 407.8126 -34.866902) (xy 407.76505 -34.903389) (xy 407.713144 -34.933356) (xy 407.657771 -34.956292)
			(xy 407.599878 -34.971805) (xy 407.540456 -34.979628) (xy 407.48052 -34.979628) (xy 407.421098 -34.971805)
			(xy 407.363205 -34.956292) (xy 407.307832 -34.933356) (xy 407.255926 -34.903389) (xy 407.208376 -34.866902)
			(xy 407.165996 -34.824522) (xy 407.129509 -34.776972) (xy 407.099542 -34.725066) (xy 407.076606 -34.669693)
			(xy 407.061093 -34.6118) (xy 407.05327 -34.552378) (xy 407.05278 -34.52241) (xy 396.705303 -34.52241)
			(xy 396.704838 -34.55087) (xy 396.69701 -34.610326) (xy 396.681489 -34.668251) (xy 396.65854 -34.723655)
			(xy 396.628556 -34.775589) (xy 396.59205 -34.823165) (xy 396.549645 -34.86557) (xy 396.502069 -34.902076)
			(xy 396.450135 -34.93206) (xy 396.394731 -34.955009) (xy 396.336806 -34.97053) (xy 396.27735 -34.978358)
			(xy 396.217382 -34.978358) (xy 396.157926 -34.97053) (xy 396.100001 -34.955009) (xy 396.044597 -34.93206)
			(xy 395.992663 -34.902076) (xy 395.945087 -34.86557) (xy 395.902682 -34.823165) (xy 395.866176 -34.775589)
			(xy 395.836192 -34.723655) (xy 395.813243 -34.668251) (xy 395.797722 -34.610326) (xy 395.789894 -34.55087)
			(xy 395.789404 -34.520886) (xy 381.968248 -34.520886) (xy 381.968248 -34.52241) (xy 381.967758 -34.552378)
			(xy 381.959935 -34.6118) (xy 381.944422 -34.669693) (xy 381.921486 -34.725066) (xy 381.891519 -34.776972)
			(xy 381.855032 -34.824522) (xy 381.812652 -34.866902) (xy 381.765102 -34.903389) (xy 381.713196 -34.933356)
			(xy 381.657823 -34.956292) (xy 381.59993 -34.971805) (xy 381.540508 -34.979628) (xy 381.480572 -34.979628)
			(xy 381.42115 -34.971805) (xy 381.363257 -34.956292) (xy 381.307884 -34.933356) (xy 381.255978 -34.903389)
			(xy 381.208428 -34.866902) (xy 381.166048 -34.824522) (xy 381.129561 -34.776972) (xy 381.099594 -34.725066)
			(xy 381.076658 -34.669693) (xy 381.061145 -34.6118) (xy 381.053322 -34.552378) (xy 381.052832 -34.52241)
			(xy 370.705355 -34.52241) (xy 370.70489 -34.55087) (xy 370.697062 -34.610326) (xy 370.681541 -34.668251)
			(xy 370.658592 -34.723655) (xy 370.628608 -34.775589) (xy 370.592102 -34.823165) (xy 370.549697 -34.86557)
			(xy 370.502121 -34.902076) (xy 370.450187 -34.93206) (xy 370.394783 -34.955009) (xy 370.336858 -34.97053)
			(xy 370.277402 -34.978358) (xy 370.217434 -34.978358) (xy 370.157978 -34.97053) (xy 370.100053 -34.955009)
			(xy 370.044649 -34.93206) (xy 369.992715 -34.902076) (xy 369.945139 -34.86557) (xy 369.902734 -34.823165)
			(xy 369.866228 -34.775589) (xy 369.836244 -34.723655) (xy 369.813295 -34.668251) (xy 369.797774 -34.610326)
			(xy 369.789946 -34.55087) (xy 369.789456 -34.520886) (xy 355.9683 -34.520886) (xy 355.9683 -34.52241)
			(xy 355.96781 -34.552378) (xy 355.959987 -34.6118) (xy 355.944474 -34.669693) (xy 355.921538 -34.725066)
			(xy 355.891571 -34.776972) (xy 355.855084 -34.824522) (xy 355.812704 -34.866902) (xy 355.765154 -34.903389)
			(xy 355.713248 -34.933356) (xy 355.657875 -34.956292) (xy 355.599982 -34.971805) (xy 355.54056 -34.979628)
			(xy 355.480624 -34.979628) (xy 355.421202 -34.971805) (xy 355.363309 -34.956292) (xy 355.307936 -34.933356)
			(xy 355.25603 -34.903389) (xy 355.20848 -34.866902) (xy 355.1661 -34.824522) (xy 355.129613 -34.776972)
			(xy 355.099646 -34.725066) (xy 355.07671 -34.669693) (xy 355.061197 -34.6118) (xy 355.053374 -34.552378)
			(xy 355.052884 -34.52241) (xy 332.604847 -34.52241) (xy 332.604382 -34.550854) (xy 332.596559 -34.610276)
			(xy 332.581046 -34.668169) (xy 332.55811 -34.723542) (xy 332.528143 -34.775448) (xy 332.491656 -34.822998)
			(xy 332.449276 -34.865378) (xy 332.401726 -34.901865) (xy 332.34982 -34.931832) (xy 332.294447 -34.954768)
			(xy 332.236554 -34.970281) (xy 332.177132 -34.978104) (xy 332.117196 -34.978104) (xy 332.057774 -34.970281)
			(xy 331.999881 -34.954768) (xy 331.944508 -34.931832) (xy 331.892602 -34.901865) (xy 331.845052 -34.865378)
			(xy 331.802672 -34.822998) (xy 331.766185 -34.775448) (xy 331.736218 -34.723542) (xy 331.713282 -34.668169)
			(xy 331.697769 -34.610276) (xy 331.689946 -34.550854) (xy 331.689456 -34.520886) (xy 317.8683 -34.520886)
			(xy 317.8683 -34.52241) (xy 317.86781 -34.552394) (xy 317.859982 -34.61185) (xy 317.844461 -34.669775)
			(xy 317.821512 -34.725179) (xy 317.791528 -34.777113) (xy 317.755022 -34.824689) (xy 317.712617 -34.867094)
			(xy 317.665041 -34.9036) (xy 317.613107 -34.933584) (xy 317.557703 -34.956533) (xy 317.499778 -34.972054)
			(xy 317.440322 -34.979882) (xy 317.380354 -34.979882) (xy 317.320898 -34.972054) (xy 317.262973 -34.956533)
			(xy 317.207569 -34.933584) (xy 317.155635 -34.9036) (xy 317.108059 -34.867094) (xy 317.065654 -34.824689)
			(xy 317.029148 -34.777113) (xy 316.999164 -34.725179) (xy 316.976215 -34.669775) (xy 316.960694 -34.61185)
			(xy 316.952866 -34.552394) (xy 316.952376 -34.52241) (xy 306.604899 -34.52241) (xy 306.604434 -34.550854)
			(xy 306.596611 -34.610276) (xy 306.581098 -34.668169) (xy 306.558162 -34.723542) (xy 306.528195 -34.775448)
			(xy 306.491708 -34.822998) (xy 306.449328 -34.865378) (xy 306.401778 -34.901865) (xy 306.349872 -34.931832)
			(xy 306.294499 -34.954768) (xy 306.236606 -34.970281) (xy 306.177184 -34.978104) (xy 306.117248 -34.978104)
			(xy 306.057826 -34.970281) (xy 305.999933 -34.954768) (xy 305.94456 -34.931832) (xy 305.892654 -34.901865)
			(xy 305.845104 -34.865378) (xy 305.802724 -34.822998) (xy 305.766237 -34.775448) (xy 305.73627 -34.723542)
			(xy 305.713334 -34.668169) (xy 305.697821 -34.610276) (xy 305.689998 -34.550854) (xy 305.689508 -34.520886)
			(xy 291.868352 -34.520886) (xy 291.868352 -34.52241) (xy 291.867862 -34.552394) (xy 291.860034 -34.61185)
			(xy 291.844513 -34.669775) (xy 291.821564 -34.725179) (xy 291.79158 -34.777113) (xy 291.755074 -34.824689)
			(xy 291.712669 -34.867094) (xy 291.665093 -34.9036) (xy 291.613159 -34.933584) (xy 291.557755 -34.956533)
			(xy 291.49983 -34.972054) (xy 291.440374 -34.979882) (xy 291.380406 -34.979882) (xy 291.32095 -34.972054)
			(xy 291.263025 -34.956533) (xy 291.207621 -34.933584) (xy 291.155687 -34.9036) (xy 291.108111 -34.867094)
			(xy 291.065706 -34.824689) (xy 291.0292 -34.777113) (xy 290.999216 -34.725179) (xy 290.976267 -34.669775)
			(xy 290.960746 -34.61185) (xy 290.952918 -34.552394) (xy 290.952428 -34.52241) (xy 280.604951 -34.52241)
			(xy 280.604486 -34.550854) (xy 280.596663 -34.610276) (xy 280.58115 -34.668169) (xy 280.558214 -34.723542)
			(xy 280.528247 -34.775448) (xy 280.49176 -34.822998) (xy 280.44938 -34.865378) (xy 280.40183 -34.901865)
			(xy 280.349924 -34.931832) (xy 280.294551 -34.954768) (xy 280.236658 -34.970281) (xy 280.177236 -34.978104)
			(xy 280.1173 -34.978104) (xy 280.057878 -34.970281) (xy 279.999985 -34.954768) (xy 279.944612 -34.931832)
			(xy 279.892706 -34.901865) (xy 279.845156 -34.865378) (xy 279.802776 -34.822998) (xy 279.766289 -34.775448)
			(xy 279.736322 -34.723542) (xy 279.713386 -34.668169) (xy 279.697873 -34.610276) (xy 279.69005 -34.550854)
			(xy 279.68956 -34.520886) (xy 265.868404 -34.520886) (xy 265.868404 -34.52241) (xy 265.867914 -34.552394)
			(xy 265.860086 -34.61185) (xy 265.844565 -34.669775) (xy 265.821616 -34.725179) (xy 265.791632 -34.777113)
			(xy 265.755126 -34.824689) (xy 265.712721 -34.867094) (xy 265.665145 -34.9036) (xy 265.613211 -34.933584)
			(xy 265.557807 -34.956533) (xy 265.499882 -34.972054) (xy 265.440426 -34.979882) (xy 265.380458 -34.979882)
			(xy 265.321002 -34.972054) (xy 265.263077 -34.956533) (xy 265.207673 -34.933584) (xy 265.155739 -34.9036)
			(xy 265.108163 -34.867094) (xy 265.065758 -34.824689) (xy 265.029252 -34.777113) (xy 264.999268 -34.725179)
			(xy 264.976319 -34.669775) (xy 264.960798 -34.61185) (xy 264.95297 -34.552394) (xy 264.95248 -34.52241)
			(xy 254.605003 -34.52241) (xy 254.604538 -34.550854) (xy 254.596715 -34.610276) (xy 254.581202 -34.668169)
			(xy 254.558266 -34.723542) (xy 254.528299 -34.775448) (xy 254.491812 -34.822998) (xy 254.449432 -34.865378)
			(xy 254.401882 -34.901865) (xy 254.349976 -34.931832) (xy 254.294603 -34.954768) (xy 254.23671 -34.970281)
			(xy 254.177288 -34.978104) (xy 254.117352 -34.978104) (xy 254.05793 -34.970281) (xy 254.000037 -34.954768)
			(xy 253.944664 -34.931832) (xy 253.892758 -34.901865) (xy 253.845208 -34.865378) (xy 253.802828 -34.822998)
			(xy 253.766341 -34.775448) (xy 253.736374 -34.723542) (xy 253.713438 -34.668169) (xy 253.697925 -34.610276)
			(xy 253.690102 -34.550854) (xy 253.689612 -34.520886) (xy 239.868456 -34.520886) (xy 239.868456 -34.52241)
			(xy 239.867966 -34.552394) (xy 239.860138 -34.61185) (xy 239.844617 -34.669775) (xy 239.821668 -34.725179)
			(xy 239.791684 -34.777113) (xy 239.755178 -34.824689) (xy 239.712773 -34.867094) (xy 239.665197 -34.9036)
			(xy 239.613263 -34.933584) (xy 239.557859 -34.956533) (xy 239.499934 -34.972054) (xy 239.440478 -34.979882)
			(xy 239.38051 -34.979882) (xy 239.321054 -34.972054) (xy 239.263129 -34.956533) (xy 239.207725 -34.933584)
			(xy 239.155791 -34.9036) (xy 239.108215 -34.867094) (xy 239.06581 -34.824689) (xy 239.029304 -34.777113)
			(xy 238.99932 -34.725179) (xy 238.976371 -34.669775) (xy 238.96085 -34.61185) (xy 238.953022 -34.552394)
			(xy 238.952532 -34.52241) (xy 216.505003 -34.52241) (xy 216.504538 -34.550854) (xy 216.496715 -34.610276)
			(xy 216.481202 -34.668169) (xy 216.458266 -34.723542) (xy 216.428299 -34.775448) (xy 216.391812 -34.822998)
			(xy 216.349432 -34.865378) (xy 216.301882 -34.901865) (xy 216.249976 -34.931832) (xy 216.194603 -34.954768)
			(xy 216.13671 -34.970281) (xy 216.077288 -34.978104) (xy 216.017352 -34.978104) (xy 215.95793 -34.970281)
			(xy 215.900037 -34.954768) (xy 215.844664 -34.931832) (xy 215.792758 -34.901865) (xy 215.745208 -34.865378)
			(xy 215.702828 -34.822998) (xy 215.666341 -34.775448) (xy 215.636374 -34.723542) (xy 215.613438 -34.668169)
			(xy 215.597925 -34.610276) (xy 215.590102 -34.550854) (xy 215.589612 -34.520886) (xy 201.768456 -34.520886)
			(xy 201.768456 -34.52241) (xy 201.767966 -34.552394) (xy 201.760138 -34.61185) (xy 201.744617 -34.669775)
			(xy 201.721668 -34.725179) (xy 201.691684 -34.777113) (xy 201.655178 -34.824689) (xy 201.612773 -34.867094)
			(xy 201.565197 -34.9036) (xy 201.513263 -34.933584) (xy 201.457859 -34.956533) (xy 201.399934 -34.972054)
			(xy 201.340478 -34.979882) (xy 201.28051 -34.979882) (xy 201.221054 -34.972054) (xy 201.163129 -34.956533)
			(xy 201.107725 -34.933584) (xy 201.055791 -34.9036) (xy 201.008215 -34.867094) (xy 200.96581 -34.824689)
			(xy 200.929304 -34.777113) (xy 200.89932 -34.725179) (xy 200.876371 -34.669775) (xy 200.86085 -34.61185)
			(xy 200.853022 -34.552394) (xy 200.852532 -34.52241) (xy 190.505055 -34.52241) (xy 190.50459 -34.550854)
			(xy 190.496767 -34.610276) (xy 190.481254 -34.668169) (xy 190.458318 -34.723542) (xy 190.428351 -34.775448)
			(xy 190.391864 -34.822998) (xy 190.349484 -34.865378) (xy 190.301934 -34.901865) (xy 190.250028 -34.931832)
			(xy 190.194655 -34.954768) (xy 190.136762 -34.970281) (xy 190.07734 -34.978104) (xy 190.017404 -34.978104)
			(xy 189.957982 -34.970281) (xy 189.900089 -34.954768) (xy 189.844716 -34.931832) (xy 189.79281 -34.901865)
			(xy 189.74526 -34.865378) (xy 189.70288 -34.822998) (xy 189.666393 -34.775448) (xy 189.636426 -34.723542)
			(xy 189.61349 -34.668169) (xy 189.597977 -34.610276) (xy 189.590154 -34.550854) (xy 189.589664 -34.520886)
			(xy 175.768508 -34.520886) (xy 175.768508 -34.52241) (xy 175.768018 -34.552394) (xy 175.76019 -34.61185)
			(xy 175.744669 -34.669775) (xy 175.72172 -34.725179) (xy 175.691736 -34.777113) (xy 175.65523 -34.824689)
			(xy 175.612825 -34.867094) (xy 175.565249 -34.9036) (xy 175.513315 -34.933584) (xy 175.457911 -34.956533)
			(xy 175.399986 -34.972054) (xy 175.34053 -34.979882) (xy 175.280562 -34.979882) (xy 175.221106 -34.972054)
			(xy 175.163181 -34.956533) (xy 175.107777 -34.933584) (xy 175.055843 -34.9036) (xy 175.008267 -34.867094)
			(xy 174.965862 -34.824689) (xy 174.929356 -34.777113) (xy 174.899372 -34.725179) (xy 174.876423 -34.669775)
			(xy 174.860902 -34.61185) (xy 174.853074 -34.552394) (xy 174.852584 -34.52241) (xy 164.505107 -34.52241)
			(xy 164.504642 -34.550854) (xy 164.496819 -34.610276) (xy 164.481306 -34.668169) (xy 164.45837 -34.723542)
			(xy 164.428403 -34.775448) (xy 164.391916 -34.822998) (xy 164.349536 -34.865378) (xy 164.301986 -34.901865)
			(xy 164.25008 -34.931832) (xy 164.194707 -34.954768) (xy 164.136814 -34.970281) (xy 164.077392 -34.978104)
			(xy 164.017456 -34.978104) (xy 163.958034 -34.970281) (xy 163.900141 -34.954768) (xy 163.844768 -34.931832)
			(xy 163.792862 -34.901865) (xy 163.745312 -34.865378) (xy 163.702932 -34.822998) (xy 163.666445 -34.775448)
			(xy 163.636478 -34.723542) (xy 163.613542 -34.668169) (xy 163.598029 -34.610276) (xy 163.590206 -34.550854)
			(xy 163.589716 -34.520886) (xy 149.76856 -34.520886) (xy 149.76856 -34.52241) (xy 149.76807 -34.552394)
			(xy 149.760242 -34.61185) (xy 149.744721 -34.669775) (xy 149.721772 -34.725179) (xy 149.691788 -34.777113)
			(xy 149.655282 -34.824689) (xy 149.612877 -34.867094) (xy 149.565301 -34.9036) (xy 149.513367 -34.933584)
			(xy 149.457963 -34.956533) (xy 149.400038 -34.972054) (xy 149.340582 -34.979882) (xy 149.280614 -34.979882)
			(xy 149.221158 -34.972054) (xy 149.163233 -34.956533) (xy 149.107829 -34.933584) (xy 149.055895 -34.9036)
			(xy 149.008319 -34.867094) (xy 148.965914 -34.824689) (xy 148.929408 -34.777113) (xy 148.899424 -34.725179)
			(xy 148.876475 -34.669775) (xy 148.860954 -34.61185) (xy 148.853126 -34.552394) (xy 148.852636 -34.52241)
			(xy 138.505159 -34.52241) (xy 138.504694 -34.550854) (xy 138.496871 -34.610276) (xy 138.481358 -34.668169)
			(xy 138.458422 -34.723542) (xy 138.428455 -34.775448) (xy 138.391968 -34.822998) (xy 138.349588 -34.865378)
			(xy 138.302038 -34.901865) (xy 138.250132 -34.931832) (xy 138.194759 -34.954768) (xy 138.136866 -34.970281)
			(xy 138.077444 -34.978104) (xy 138.017508 -34.978104) (xy 137.958086 -34.970281) (xy 137.900193 -34.954768)
			(xy 137.84482 -34.931832) (xy 137.792914 -34.901865) (xy 137.745364 -34.865378) (xy 137.702984 -34.822998)
			(xy 137.666497 -34.775448) (xy 137.63653 -34.723542) (xy 137.613594 -34.668169) (xy 137.598081 -34.610276)
			(xy 137.590258 -34.550854) (xy 137.589768 -34.520886) (xy 123.768612 -34.520886) (xy 123.768612 -34.52241)
			(xy 123.768122 -34.552394) (xy 123.760294 -34.61185) (xy 123.744773 -34.669775) (xy 123.721824 -34.725179)
			(xy 123.69184 -34.777113) (xy 123.655334 -34.824689) (xy 123.612929 -34.867094) (xy 123.565353 -34.9036)
			(xy 123.513419 -34.933584) (xy 123.458015 -34.956533) (xy 123.40009 -34.972054) (xy 123.340634 -34.979882)
			(xy 123.280666 -34.979882) (xy 123.22121 -34.972054) (xy 123.163285 -34.956533) (xy 123.107881 -34.933584)
			(xy 123.055947 -34.9036) (xy 123.008371 -34.867094) (xy 122.965966 -34.824689) (xy 122.92946 -34.777113)
			(xy 122.899476 -34.725179) (xy 122.876527 -34.669775) (xy 122.861006 -34.61185) (xy 122.853178 -34.552394)
			(xy 122.852688 -34.52241) (xy 100.405159 -34.52241) (xy 100.404694 -34.55087) (xy 100.396866 -34.610326)
			(xy 100.381345 -34.668251) (xy 100.358396 -34.723655) (xy 100.328412 -34.775589) (xy 100.291906 -34.823165)
			(xy 100.249501 -34.86557) (xy 100.201925 -34.902076) (xy 100.149991 -34.93206) (xy 100.094587 -34.955009)
			(xy 100.036662 -34.97053) (xy 99.977206 -34.978358) (xy 99.917238 -34.978358) (xy 99.857782 -34.97053)
			(xy 99.799857 -34.955009) (xy 99.744453 -34.93206) (xy 99.692519 -34.902076) (xy 99.644943 -34.86557)
			(xy 99.602538 -34.823165) (xy 99.566032 -34.775589) (xy 99.536048 -34.723655) (xy 99.513099 -34.668251)
			(xy 99.497578 -34.610326) (xy 99.48975 -34.55087) (xy 99.48926 -34.520886) (xy 85.668104 -34.520886)
			(xy 85.668104 -34.52241) (xy 85.667614 -34.552378) (xy 85.659791 -34.6118) (xy 85.644278 -34.669693)
			(xy 85.621342 -34.725066) (xy 85.591375 -34.776972) (xy 85.554888 -34.824522) (xy 85.512508 -34.866902)
			(xy 85.464958 -34.903389) (xy 85.413052 -34.933356) (xy 85.357679 -34.956292) (xy 85.299786 -34.971805)
			(xy 85.240364 -34.979628) (xy 85.180428 -34.979628) (xy 85.121006 -34.971805) (xy 85.063113 -34.956292)
			(xy 85.00774 -34.933356) (xy 84.955834 -34.903389) (xy 84.908284 -34.866902) (xy 84.865904 -34.824522)
			(xy 84.829417 -34.776972) (xy 84.79945 -34.725066) (xy 84.776514 -34.669693) (xy 84.761001 -34.6118)
			(xy 84.753178 -34.552378) (xy 84.752688 -34.52241) (xy 74.405211 -34.52241) (xy 74.404746 -34.55087)
			(xy 74.396918 -34.610326) (xy 74.381397 -34.668251) (xy 74.358448 -34.723655) (xy 74.328464 -34.775589)
			(xy 74.291958 -34.823165) (xy 74.249553 -34.86557) (xy 74.201977 -34.902076) (xy 74.150043 -34.93206)
			(xy 74.094639 -34.955009) (xy 74.036714 -34.97053) (xy 73.977258 -34.978358) (xy 73.91729 -34.978358)
			(xy 73.857834 -34.97053) (xy 73.799909 -34.955009) (xy 73.744505 -34.93206) (xy 73.692571 -34.902076)
			(xy 73.644995 -34.86557) (xy 73.60259 -34.823165) (xy 73.566084 -34.775589) (xy 73.5361 -34.723655)
			(xy 73.513151 -34.668251) (xy 73.49763 -34.610326) (xy 73.489802 -34.55087) (xy 73.489312 -34.520886)
			(xy 59.668156 -34.520886) (xy 59.668156 -34.52241) (xy 59.667666 -34.552378) (xy 59.659843 -34.6118)
			(xy 59.64433 -34.669693) (xy 59.621394 -34.725066) (xy 59.591427 -34.776972) (xy 59.55494 -34.824522)
			(xy 59.51256 -34.866902) (xy 59.46501 -34.903389) (xy 59.413104 -34.933356) (xy 59.357731 -34.956292)
			(xy 59.299838 -34.971805) (xy 59.240416 -34.979628) (xy 59.18048 -34.979628) (xy 59.121058 -34.971805)
			(xy 59.063165 -34.956292) (xy 59.007792 -34.933356) (xy 58.955886 -34.903389) (xy 58.908336 -34.866902)
			(xy 58.865956 -34.824522) (xy 58.829469 -34.776972) (xy 58.799502 -34.725066) (xy 58.776566 -34.669693)
			(xy 58.761053 -34.6118) (xy 58.75323 -34.552378) (xy 58.75274 -34.52241) (xy 48.405263 -34.52241)
			(xy 48.404798 -34.55087) (xy 48.39697 -34.610326) (xy 48.381449 -34.668251) (xy 48.3585 -34.723655)
			(xy 48.328516 -34.775589) (xy 48.29201 -34.823165) (xy 48.249605 -34.86557) (xy 48.202029 -34.902076)
			(xy 48.150095 -34.93206) (xy 48.094691 -34.955009) (xy 48.036766 -34.97053) (xy 47.97731 -34.978358)
			(xy 47.917342 -34.978358) (xy 47.857886 -34.97053) (xy 47.799961 -34.955009) (xy 47.744557 -34.93206)
			(xy 47.692623 -34.902076) (xy 47.645047 -34.86557) (xy 47.602642 -34.823165) (xy 47.566136 -34.775589)
			(xy 47.536152 -34.723655) (xy 47.513203 -34.668251) (xy 47.497682 -34.610326) (xy 47.489854 -34.55087)
			(xy 47.489364 -34.520886) (xy 33.668208 -34.520886) (xy 33.668208 -34.52241) (xy 33.667718 -34.552378)
			(xy 33.659895 -34.6118) (xy 33.644382 -34.669693) (xy 33.621446 -34.725066) (xy 33.591479 -34.776972)
			(xy 33.554992 -34.824522) (xy 33.512612 -34.866902) (xy 33.465062 -34.903389) (xy 33.413156 -34.933356)
			(xy 33.357783 -34.956292) (xy 33.29989 -34.971805) (xy 33.240468 -34.979628) (xy 33.180532 -34.979628)
			(xy 33.12111 -34.971805) (xy 33.063217 -34.956292) (xy 33.007844 -34.933356) (xy 32.955938 -34.903389)
			(xy 32.908388 -34.866902) (xy 32.866008 -34.824522) (xy 32.829521 -34.776972) (xy 32.799554 -34.725066)
			(xy 32.776618 -34.669693) (xy 32.761105 -34.6118) (xy 32.753282 -34.552378) (xy 32.752792 -34.52241)
			(xy 22.405315 -34.52241) (xy 22.40485 -34.55087) (xy 22.397022 -34.610326) (xy 22.381501 -34.668251)
			(xy 22.358552 -34.723655) (xy 22.328568 -34.775589) (xy 22.292062 -34.823165) (xy 22.249657 -34.86557)
			(xy 22.202081 -34.902076) (xy 22.150147 -34.93206) (xy 22.094743 -34.955009) (xy 22.036818 -34.97053)
			(xy 21.977362 -34.978358) (xy 21.917394 -34.978358) (xy 21.857938 -34.97053) (xy 21.800013 -34.955009)
			(xy 21.744609 -34.93206) (xy 21.692675 -34.902076) (xy 21.645099 -34.86557) (xy 21.602694 -34.823165)
			(xy 21.566188 -34.775589) (xy 21.536204 -34.723655) (xy 21.513255 -34.668251) (xy 21.497734 -34.610326)
			(xy 21.489906 -34.55087) (xy 21.489416 -34.520886) (xy 7.66826 -34.520886) (xy 7.66826 -34.52241)
			(xy 7.66777 -34.552378) (xy 7.659947 -34.6118) (xy 7.644434 -34.669693) (xy 7.621498 -34.725066)
			(xy 7.591531 -34.776972) (xy 7.555044 -34.824522) (xy 7.512664 -34.866902) (xy 7.465114 -34.903389)
			(xy 7.413208 -34.933356) (xy 7.357835 -34.956292) (xy 7.299942 -34.971805) (xy 7.24052 -34.979628)
			(xy 7.180584 -34.979628) (xy 7.121162 -34.971805) (xy 7.063269 -34.956292) (xy 7.007896 -34.933356)
			(xy 6.95599 -34.903389) (xy 6.90844 -34.866902) (xy 6.86606 -34.824522) (xy 6.829573 -34.776972)
			(xy 6.799606 -34.725066) (xy 6.77667 -34.669693) (xy 6.761157 -34.6118) (xy 6.753334 -34.552378)
			(xy 6.752844 -34.52241) (xy 1.524 -34.52241) (xy 1.524 -36.60013) (xy 11.998459 -36.60013) (xy 12.002463 -36.512245)
			(xy 12.014443 -36.425088) (xy 12.034298 -36.339381) (xy 12.061865 -36.255836) (xy 12.096915 -36.175143)
			(xy 12.139157 -36.097971) (xy 12.188242 -36.024961) (xy 12.243763 -35.956717) (xy 12.30526 -35.893804)
			(xy 12.372222 -35.836744) (xy 12.444096 -35.78601) (xy 12.520286 -35.742022) (xy 12.60016 -35.705144)
			(xy 12.683057 -35.675683) (xy 12.768289 -35.653881) (xy 12.855151 -35.639921) (xy 12.942922 -35.633917)
			(xy 13.030876 -35.63592) (xy 13.118283 -35.645912) (xy 13.204419 -35.663812) (xy 13.288571 -35.68947)
			(xy 13.370041 -35.722674) (xy 13.448154 -35.763148) (xy 13.522262 -35.810559) (xy 13.591753 -35.864512)
			(xy 13.656049 -35.92456) (xy 13.714618 -35.990207) (xy 13.766975 -36.060907) (xy 13.812687 -36.136076)
			(xy 13.851373 -36.21509) (xy 13.882714 -36.297295) (xy 13.906449 -36.382009) (xy 13.922383 -36.46853)
			(xy 13.930383 -36.556142) (xy 13.930884 -36.60013) (xy 37.998407 -36.60013) (xy 38.002411 -36.512245)
			(xy 38.014391 -36.425088) (xy 38.034246 -36.339381) (xy 38.061813 -36.255836) (xy 38.096863 -36.175143)
			(xy 38.139105 -36.097971) (xy 38.18819 -36.024961) (xy 38.243711 -35.956717) (xy 38.305208 -35.893804)
			(xy 38.37217 -35.836744) (xy 38.444044 -35.78601) (xy 38.520234 -35.742022) (xy 38.600108 -35.705144)
			(xy 38.683005 -35.675683) (xy 38.768237 -35.653881) (xy 38.855099 -35.639921) (xy 38.94287 -35.633917)
			(xy 39.030824 -35.63592) (xy 39.118231 -35.645912) (xy 39.204367 -35.663812) (xy 39.288519 -35.68947)
			(xy 39.369989 -35.722674) (xy 39.448102 -35.763148) (xy 39.52221 -35.810559) (xy 39.591701 -35.864512)
			(xy 39.655997 -35.92456) (xy 39.714566 -35.990207) (xy 39.766923 -36.060907) (xy 39.812635 -36.136076)
			(xy 39.851321 -36.21509) (xy 39.882662 -36.297295) (xy 39.906397 -36.382009) (xy 39.922331 -36.46853)
			(xy 39.930331 -36.556142) (xy 39.930832 -36.60013) (xy 63.998355 -36.60013) (xy 64.002359 -36.512245)
			(xy 64.014339 -36.425088) (xy 64.034194 -36.339381) (xy 64.061761 -36.255836) (xy 64.096811 -36.175143)
			(xy 64.139053 -36.097971) (xy 64.188138 -36.024961) (xy 64.243659 -35.956717) (xy 64.305156 -35.893804)
			(xy 64.372118 -35.836744) (xy 64.443992 -35.78601) (xy 64.520182 -35.742022) (xy 64.600056 -35.705144)
			(xy 64.682953 -35.675683) (xy 64.768185 -35.653881) (xy 64.855047 -35.639921) (xy 64.942818 -35.633917)
			(xy 65.030772 -35.63592) (xy 65.118179 -35.645912) (xy 65.204315 -35.663812) (xy 65.288467 -35.68947)
			(xy 65.369937 -35.722674) (xy 65.44805 -35.763148) (xy 65.522158 -35.810559) (xy 65.591649 -35.864512)
			(xy 65.655945 -35.92456) (xy 65.714514 -35.990207) (xy 65.766871 -36.060907) (xy 65.812583 -36.136076)
			(xy 65.851269 -36.21509) (xy 65.88261 -36.297295) (xy 65.906345 -36.382009) (xy 65.922279 -36.46853)
			(xy 65.930279 -36.556142) (xy 65.93078 -36.60013) (xy 89.998303 -36.60013) (xy 90.002307 -36.512245)
			(xy 90.014287 -36.425088) (xy 90.034142 -36.339381) (xy 90.061709 -36.255836) (xy 90.096759 -36.175143)
			(xy 90.139001 -36.097971) (xy 90.188086 -36.024961) (xy 90.243607 -35.956717) (xy 90.305104 -35.893804)
			(xy 90.372066 -35.836744) (xy 90.44394 -35.78601) (xy 90.52013 -35.742022) (xy 90.600004 -35.705144)
			(xy 90.682901 -35.675683) (xy 90.768133 -35.653881) (xy 90.854995 -35.639921) (xy 90.942766 -35.633917)
			(xy 91.03072 -35.63592) (xy 91.118127 -35.645912) (xy 91.204263 -35.663812) (xy 91.288415 -35.68947)
			(xy 91.369885 -35.722674) (xy 91.447998 -35.763148) (xy 91.522106 -35.810559) (xy 91.591597 -35.864512)
			(xy 91.655893 -35.92456) (xy 91.714462 -35.990207) (xy 91.766819 -36.060907) (xy 91.812531 -36.136076)
			(xy 91.851217 -36.21509) (xy 91.882558 -36.297295) (xy 91.906293 -36.382009) (xy 91.922227 -36.46853)
			(xy 91.930227 -36.556142) (xy 91.930728 -36.60013) (xy 128.098557 -36.60013) (xy 128.102561 -36.512245)
			(xy 128.114541 -36.425088) (xy 128.134396 -36.339381) (xy 128.161963 -36.255836) (xy 128.197013 -36.175143)
			(xy 128.239255 -36.097971) (xy 128.28834 -36.024961) (xy 128.343861 -35.956717) (xy 128.405358 -35.893804)
			(xy 128.47232 -35.836744) (xy 128.544194 -35.78601) (xy 128.620384 -35.742022) (xy 128.700258 -35.705144)
			(xy 128.783155 -35.675683) (xy 128.868387 -35.653881) (xy 128.955249 -35.639921) (xy 129.04302 -35.633917)
			(xy 129.130974 -35.63592) (xy 129.218381 -35.645912) (xy 129.304517 -35.663812) (xy 129.388669 -35.68947)
			(xy 129.470139 -35.722674) (xy 129.548252 -35.763148) (xy 129.62236 -35.810559) (xy 129.691851 -35.864512)
			(xy 129.756147 -35.92456) (xy 129.814716 -35.990207) (xy 129.867073 -36.060907) (xy 129.912785 -36.136076)
			(xy 129.951471 -36.21509) (xy 129.982812 -36.297295) (xy 130.006547 -36.382009) (xy 130.022481 -36.46853)
			(xy 130.030481 -36.556142) (xy 130.030982 -36.60013) (xy 154.098505 -36.60013) (xy 154.102509 -36.512245)
			(xy 154.114489 -36.425088) (xy 154.134344 -36.339381) (xy 154.161911 -36.255836) (xy 154.196961 -36.175143)
			(xy 154.239203 -36.097971) (xy 154.288288 -36.024961) (xy 154.343809 -35.956717) (xy 154.405306 -35.893804)
			(xy 154.472268 -35.836744) (xy 154.544142 -35.78601) (xy 154.620332 -35.742022) (xy 154.700206 -35.705144)
			(xy 154.783103 -35.675683) (xy 154.868335 -35.653881) (xy 154.955197 -35.639921) (xy 155.042968 -35.633917)
			(xy 155.130922 -35.63592) (xy 155.218329 -35.645912) (xy 155.304465 -35.663812) (xy 155.388617 -35.68947)
			(xy 155.470087 -35.722674) (xy 155.5482 -35.763148) (xy 155.622308 -35.810559) (xy 155.691799 -35.864512)
			(xy 155.756095 -35.92456) (xy 155.814664 -35.990207) (xy 155.867021 -36.060907) (xy 155.912733 -36.136076)
			(xy 155.951419 -36.21509) (xy 155.98276 -36.297295) (xy 156.006495 -36.382009) (xy 156.022429 -36.46853)
			(xy 156.030429 -36.556142) (xy 156.03093 -36.60013) (xy 180.098453 -36.60013) (xy 180.102457 -36.512245)
			(xy 180.114437 -36.425088) (xy 180.134292 -36.339381) (xy 180.161859 -36.255836) (xy 180.196909 -36.175143)
			(xy 180.239151 -36.097971) (xy 180.288236 -36.024961) (xy 180.343757 -35.956717) (xy 180.405254 -35.893804)
			(xy 180.472216 -35.836744) (xy 180.54409 -35.78601) (xy 180.62028 -35.742022) (xy 180.700154 -35.705144)
			(xy 180.783051 -35.675683) (xy 180.868283 -35.653881) (xy 180.955145 -35.639921) (xy 181.042916 -35.633917)
			(xy 181.13087 -35.63592) (xy 181.218277 -35.645912) (xy 181.304413 -35.663812) (xy 181.388565 -35.68947)
			(xy 181.470035 -35.722674) (xy 181.548148 -35.763148) (xy 181.622256 -35.810559) (xy 181.691747 -35.864512)
			(xy 181.756043 -35.92456) (xy 181.814612 -35.990207) (xy 181.866969 -36.060907) (xy 181.912681 -36.136076)
			(xy 181.951367 -36.21509) (xy 181.982708 -36.297295) (xy 182.006443 -36.382009) (xy 182.022377 -36.46853)
			(xy 182.030377 -36.556142) (xy 182.030878 -36.60013) (xy 206.098655 -36.60013) (xy 206.102659 -36.512245)
			(xy 206.114639 -36.425088) (xy 206.134494 -36.339381) (xy 206.162061 -36.255836) (xy 206.197111 -36.175143)
			(xy 206.239353 -36.097971) (xy 206.288438 -36.024961) (xy 206.343959 -35.956717) (xy 206.405456 -35.893804)
			(xy 206.472418 -35.836744) (xy 206.544292 -35.78601) (xy 206.620482 -35.742022) (xy 206.700356 -35.705144)
			(xy 206.783253 -35.675683) (xy 206.868485 -35.653881) (xy 206.955347 -35.639921) (xy 207.043118 -35.633917)
			(xy 207.131072 -35.63592) (xy 207.218479 -35.645912) (xy 207.304615 -35.663812) (xy 207.388767 -35.68947)
			(xy 207.470237 -35.722674) (xy 207.54835 -35.763148) (xy 207.622458 -35.810559) (xy 207.691949 -35.864512)
			(xy 207.756245 -35.92456) (xy 207.814814 -35.990207) (xy 207.867171 -36.060907) (xy 207.912883 -36.136076)
			(xy 207.951569 -36.21509) (xy 207.98291 -36.297295) (xy 208.006645 -36.382009) (xy 208.022579 -36.46853)
			(xy 208.030579 -36.556142) (xy 208.03108 -36.60013) (xy 244.198655 -36.60013) (xy 244.202659 -36.512245)
			(xy 244.214639 -36.425088) (xy 244.234494 -36.339381) (xy 244.262061 -36.255836) (xy 244.297111 -36.175143)
			(xy 244.339353 -36.097971) (xy 244.388438 -36.024961) (xy 244.443959 -35.956717) (xy 244.505456 -35.893804)
			(xy 244.572418 -35.836744) (xy 244.644292 -35.78601) (xy 244.720482 -35.742022) (xy 244.800356 -35.705144)
			(xy 244.883253 -35.675683) (xy 244.968485 -35.653881) (xy 245.055347 -35.639921) (xy 245.143118 -35.633917)
			(xy 245.231072 -35.63592) (xy 245.318479 -35.645912) (xy 245.404615 -35.663812) (xy 245.488767 -35.68947)
			(xy 245.570237 -35.722674) (xy 245.64835 -35.763148) (xy 245.722458 -35.810559) (xy 245.791949 -35.864512)
			(xy 245.856245 -35.92456) (xy 245.914814 -35.990207) (xy 245.967171 -36.060907) (xy 246.012883 -36.136076)
			(xy 246.051569 -36.21509) (xy 246.08291 -36.297295) (xy 246.106645 -36.382009) (xy 246.122579 -36.46853)
			(xy 246.130579 -36.556142) (xy 246.13108 -36.60013) (xy 270.198603 -36.60013) (xy 270.202607 -36.512245)
			(xy 270.214587 -36.425088) (xy 270.234442 -36.339381) (xy 270.262009 -36.255836) (xy 270.297059 -36.175143)
			(xy 270.339301 -36.097971) (xy 270.388386 -36.024961) (xy 270.443907 -35.956717) (xy 270.505404 -35.893804)
			(xy 270.572366 -35.836744) (xy 270.64424 -35.78601) (xy 270.72043 -35.742022) (xy 270.800304 -35.705144)
			(xy 270.883201 -35.675683) (xy 270.968433 -35.653881) (xy 271.055295 -35.639921) (xy 271.143066 -35.633917)
			(xy 271.23102 -35.63592) (xy 271.318427 -35.645912) (xy 271.404563 -35.663812) (xy 271.488715 -35.68947)
			(xy 271.570185 -35.722674) (xy 271.648298 -35.763148) (xy 271.722406 -35.810559) (xy 271.791897 -35.864512)
			(xy 271.856193 -35.92456) (xy 271.914762 -35.990207) (xy 271.967119 -36.060907) (xy 272.012831 -36.136076)
			(xy 272.051517 -36.21509) (xy 272.082858 -36.297295) (xy 272.106593 -36.382009) (xy 272.122527 -36.46853)
			(xy 272.130527 -36.556142) (xy 272.131028 -36.60013) (xy 296.198551 -36.60013) (xy 296.202555 -36.512245)
			(xy 296.214535 -36.425088) (xy 296.23439 -36.339381) (xy 296.261957 -36.255836) (xy 296.297007 -36.175143)
			(xy 296.339249 -36.097971) (xy 296.388334 -36.024961) (xy 296.443855 -35.956717) (xy 296.505352 -35.893804)
			(xy 296.572314 -35.836744) (xy 296.644188 -35.78601) (xy 296.720378 -35.742022) (xy 296.800252 -35.705144)
			(xy 296.883149 -35.675683) (xy 296.968381 -35.653881) (xy 297.055243 -35.639921) (xy 297.143014 -35.633917)
			(xy 297.230968 -35.63592) (xy 297.318375 -35.645912) (xy 297.404511 -35.663812) (xy 297.488663 -35.68947)
			(xy 297.570133 -35.722674) (xy 297.648246 -35.763148) (xy 297.722354 -35.810559) (xy 297.791845 -35.864512)
			(xy 297.856141 -35.92456) (xy 297.91471 -35.990207) (xy 297.967067 -36.060907) (xy 298.012779 -36.136076)
			(xy 298.051465 -36.21509) (xy 298.082806 -36.297295) (xy 298.106541 -36.382009) (xy 298.122475 -36.46853)
			(xy 298.130475 -36.556142) (xy 298.130976 -36.60013) (xy 322.198245 -36.60013) (xy 322.202249 -36.512245)
			(xy 322.214229 -36.425088) (xy 322.234084 -36.339381) (xy 322.261651 -36.255836) (xy 322.296701 -36.175143)
			(xy 322.338943 -36.097971) (xy 322.388028 -36.024961) (xy 322.443549 -35.956717) (xy 322.505046 -35.893804)
			(xy 322.572008 -35.836744) (xy 322.643882 -35.78601) (xy 322.720072 -35.742022) (xy 322.799946 -35.705144)
			(xy 322.882843 -35.675683) (xy 322.968075 -35.653881) (xy 323.054937 -35.639921) (xy 323.142708 -35.633917)
			(xy 323.230662 -35.63592) (xy 323.318069 -35.645912) (xy 323.404205 -35.663812) (xy 323.488357 -35.68947)
			(xy 323.569827 -35.722674) (xy 323.64794 -35.763148) (xy 323.722048 -35.810559) (xy 323.791539 -35.864512)
			(xy 323.855835 -35.92456) (xy 323.914404 -35.990207) (xy 323.966761 -36.060907) (xy 324.012473 -36.136076)
			(xy 324.051159 -36.21509) (xy 324.0825 -36.297295) (xy 324.106235 -36.382009) (xy 324.122169 -36.46853)
			(xy 324.130169 -36.556142) (xy 324.13067 -36.60013) (xy 360.298499 -36.60013) (xy 360.302503 -36.512245)
			(xy 360.314483 -36.425088) (xy 360.334338 -36.339381) (xy 360.361905 -36.255836) (xy 360.396955 -36.175143)
			(xy 360.439197 -36.097971) (xy 360.488282 -36.024961) (xy 360.543803 -35.956717) (xy 360.6053 -35.893804)
			(xy 360.672262 -35.836744) (xy 360.744136 -35.78601) (xy 360.820326 -35.742022) (xy 360.9002 -35.705144)
			(xy 360.983097 -35.675683) (xy 361.068329 -35.653881) (xy 361.155191 -35.639921) (xy 361.242962 -35.633917)
			(xy 361.330916 -35.63592) (xy 361.418323 -35.645912) (xy 361.504459 -35.663812) (xy 361.588611 -35.68947)
			(xy 361.670081 -35.722674) (xy 361.748194 -35.763148) (xy 361.822302 -35.810559) (xy 361.891793 -35.864512)
			(xy 361.956089 -35.92456) (xy 362.014658 -35.990207) (xy 362.067015 -36.060907) (xy 362.112727 -36.136076)
			(xy 362.151413 -36.21509) (xy 362.182754 -36.297295) (xy 362.206489 -36.382009) (xy 362.222423 -36.46853)
			(xy 362.230423 -36.556142) (xy 362.230924 -36.60013) (xy 386.298447 -36.60013) (xy 386.302451 -36.512245)
			(xy 386.314431 -36.425088) (xy 386.334286 -36.339381) (xy 386.361853 -36.255836) (xy 386.396903 -36.175143)
			(xy 386.439145 -36.097971) (xy 386.48823 -36.024961) (xy 386.543751 -35.956717) (xy 386.605248 -35.893804)
			(xy 386.67221 -35.836744) (xy 386.744084 -35.78601) (xy 386.820274 -35.742022) (xy 386.900148 -35.705144)
			(xy 386.983045 -35.675683) (xy 387.068277 -35.653881) (xy 387.155139 -35.639921) (xy 387.24291 -35.633917)
			(xy 387.330864 -35.63592) (xy 387.418271 -35.645912) (xy 387.504407 -35.663812) (xy 387.588559 -35.68947)
			(xy 387.670029 -35.722674) (xy 387.748142 -35.763148) (xy 387.82225 -35.810559) (xy 387.891741 -35.864512)
			(xy 387.956037 -35.92456) (xy 388.014606 -35.990207) (xy 388.066963 -36.060907) (xy 388.112675 -36.136076)
			(xy 388.151361 -36.21509) (xy 388.182702 -36.297295) (xy 388.206437 -36.382009) (xy 388.222371 -36.46853)
			(xy 388.230371 -36.556142) (xy 388.230872 -36.60013) (xy 412.298649 -36.60013) (xy 412.302653 -36.512245)
			(xy 412.314633 -36.425088) (xy 412.334488 -36.339381) (xy 412.362055 -36.255836) (xy 412.397105 -36.175143)
			(xy 412.439347 -36.097971) (xy 412.488432 -36.024961) (xy 412.543953 -35.956717) (xy 412.60545 -35.893804)
			(xy 412.672412 -35.836744) (xy 412.744286 -35.78601) (xy 412.820476 -35.742022) (xy 412.90035 -35.705144)
			(xy 412.983247 -35.675683) (xy 413.068479 -35.653881) (xy 413.155341 -35.639921) (xy 413.243112 -35.633917)
			(xy 413.331066 -35.63592) (xy 413.418473 -35.645912) (xy 413.504609 -35.663812) (xy 413.588761 -35.68947)
			(xy 413.670231 -35.722674) (xy 413.748344 -35.763148) (xy 413.822452 -35.810559) (xy 413.891943 -35.864512)
			(xy 413.956239 -35.92456) (xy 414.014808 -35.990207) (xy 414.067165 -36.060907) (xy 414.112877 -36.136076)
			(xy 414.151563 -36.21509) (xy 414.182904 -36.297295) (xy 414.206639 -36.382009) (xy 414.222573 -36.46853)
			(xy 414.230573 -36.556142) (xy 414.231074 -36.60013) (xy 438.298597 -36.60013) (xy 438.302601 -36.512245)
			(xy 438.314581 -36.425088) (xy 438.334436 -36.339381) (xy 438.362003 -36.255836) (xy 438.397053 -36.175143)
			(xy 438.439295 -36.097971) (xy 438.48838 -36.024961) (xy 438.543901 -35.956717) (xy 438.605398 -35.893804)
			(xy 438.67236 -35.836744) (xy 438.744234 -35.78601) (xy 438.820424 -35.742022) (xy 438.900298 -35.705144)
			(xy 438.983195 -35.675683) (xy 439.068427 -35.653881) (xy 439.155289 -35.639921) (xy 439.24306 -35.633917)
			(xy 439.331014 -35.63592) (xy 439.418421 -35.645912) (xy 439.504557 -35.663812) (xy 439.588709 -35.68947)
			(xy 439.670179 -35.722674) (xy 439.748292 -35.763148) (xy 439.8224 -35.810559) (xy 439.891891 -35.864512)
			(xy 439.956187 -35.92456) (xy 440.014756 -35.990207) (xy 440.067113 -36.060907) (xy 440.112825 -36.136076)
			(xy 440.151511 -36.21509) (xy 440.182852 -36.297295) (xy 440.206587 -36.382009) (xy 440.222521 -36.46853)
			(xy 440.230521 -36.556142) (xy 440.231022 -36.60013) (xy 440.230521 -36.644118) (xy 440.222521 -36.73173)
			(xy 440.206587 -36.818251) (xy 440.182852 -36.902965) (xy 440.151511 -36.98517) (xy 440.112825 -37.064184)
			(xy 440.067113 -37.139353) (xy 440.014756 -37.210053) (xy 439.956187 -37.2757) (xy 439.891891 -37.335748)
			(xy 439.8224 -37.389701) (xy 439.748292 -37.437112) (xy 439.670179 -37.477586) (xy 439.588709 -37.51079)
			(xy 439.504557 -37.536448) (xy 439.418421 -37.554348) (xy 439.331014 -37.56434) (xy 439.24306 -37.566343)
			(xy 439.155289 -37.560339) (xy 439.068427 -37.546379) (xy 438.983195 -37.524577) (xy 438.900298 -37.495116)
			(xy 438.820424 -37.458238) (xy 438.744234 -37.41425) (xy 438.67236 -37.363516) (xy 438.605398 -37.306456)
			(xy 438.543901 -37.243543) (xy 438.48838 -37.175299) (xy 438.439295 -37.102289) (xy 438.397053 -37.025117)
			(xy 438.362003 -36.944424) (xy 438.334436 -36.860879) (xy 438.314581 -36.775172) (xy 438.302601 -36.688015)
			(xy 438.298597 -36.60013) (xy 414.231074 -36.60013) (xy 414.230573 -36.644118) (xy 414.222573 -36.73173)
			(xy 414.206639 -36.818251) (xy 414.182904 -36.902965) (xy 414.151563 -36.98517) (xy 414.112877 -37.064184)
			(xy 414.067165 -37.139353) (xy 414.014808 -37.210053) (xy 413.956239 -37.2757) (xy 413.891943 -37.335748)
			(xy 413.822452 -37.389701) (xy 413.748344 -37.437112) (xy 413.670231 -37.477586) (xy 413.588761 -37.51079)
			(xy 413.504609 -37.536448) (xy 413.418473 -37.554348) (xy 413.331066 -37.56434) (xy 413.243112 -37.566343)
			(xy 413.155341 -37.560339) (xy 413.068479 -37.546379) (xy 412.983247 -37.524577) (xy 412.90035 -37.495116)
			(xy 412.820476 -37.458238) (xy 412.744286 -37.41425) (xy 412.672412 -37.363516) (xy 412.60545 -37.306456)
			(xy 412.543953 -37.243543) (xy 412.488432 -37.175299) (xy 412.439347 -37.102289) (xy 412.397105 -37.025117)
			(xy 412.362055 -36.944424) (xy 412.334488 -36.860879) (xy 412.314633 -36.775172) (xy 412.302653 -36.688015)
			(xy 412.298649 -36.60013) (xy 388.230872 -36.60013) (xy 388.230371 -36.644118) (xy 388.222371 -36.73173)
			(xy 388.206437 -36.818251) (xy 388.182702 -36.902965) (xy 388.151361 -36.98517) (xy 388.112675 -37.064184)
			(xy 388.066963 -37.139353) (xy 388.014606 -37.210053) (xy 387.956037 -37.2757) (xy 387.891741 -37.335748)
			(xy 387.82225 -37.389701) (xy 387.748142 -37.437112) (xy 387.670029 -37.477586) (xy 387.588559 -37.51079)
			(xy 387.504407 -37.536448) (xy 387.418271 -37.554348) (xy 387.330864 -37.56434) (xy 387.24291 -37.566343)
			(xy 387.155139 -37.560339) (xy 387.068277 -37.546379) (xy 386.983045 -37.524577) (xy 386.900148 -37.495116)
			(xy 386.820274 -37.458238) (xy 386.744084 -37.41425) (xy 386.67221 -37.363516) (xy 386.605248 -37.306456)
			(xy 386.543751 -37.243543) (xy 386.48823 -37.175299) (xy 386.439145 -37.102289) (xy 386.396903 -37.025117)
			(xy 386.361853 -36.944424) (xy 386.334286 -36.860879) (xy 386.314431 -36.775172) (xy 386.302451 -36.688015)
			(xy 386.298447 -36.60013) (xy 362.230924 -36.60013) (xy 362.230423 -36.644118) (xy 362.222423 -36.73173)
			(xy 362.206489 -36.818251) (xy 362.182754 -36.902965) (xy 362.151413 -36.98517) (xy 362.112727 -37.064184)
			(xy 362.067015 -37.139353) (xy 362.014658 -37.210053) (xy 361.956089 -37.2757) (xy 361.891793 -37.335748)
			(xy 361.822302 -37.389701) (xy 361.748194 -37.437112) (xy 361.670081 -37.477586) (xy 361.588611 -37.51079)
			(xy 361.504459 -37.536448) (xy 361.418323 -37.554348) (xy 361.330916 -37.56434) (xy 361.242962 -37.566343)
			(xy 361.155191 -37.560339) (xy 361.068329 -37.546379) (xy 360.983097 -37.524577) (xy 360.9002 -37.495116)
			(xy 360.820326 -37.458238) (xy 360.744136 -37.41425) (xy 360.672262 -37.363516) (xy 360.6053 -37.306456)
			(xy 360.543803 -37.243543) (xy 360.488282 -37.175299) (xy 360.439197 -37.102289) (xy 360.396955 -37.025117)
			(xy 360.361905 -36.944424) (xy 360.334338 -36.860879) (xy 360.314483 -36.775172) (xy 360.302503 -36.688015)
			(xy 360.298499 -36.60013) (xy 324.13067 -36.60013) (xy 324.130169 -36.644118) (xy 324.122169 -36.73173)
			(xy 324.106235 -36.818251) (xy 324.0825 -36.902965) (xy 324.051159 -36.98517) (xy 324.012473 -37.064184)
			(xy 323.966761 -37.139353) (xy 323.914404 -37.210053) (xy 323.855835 -37.2757) (xy 323.791539 -37.335748)
			(xy 323.722048 -37.389701) (xy 323.64794 -37.437112) (xy 323.569827 -37.477586) (xy 323.488357 -37.51079)
			(xy 323.404205 -37.536448) (xy 323.318069 -37.554348) (xy 323.230662 -37.56434) (xy 323.142708 -37.566343)
			(xy 323.054937 -37.560339) (xy 322.968075 -37.546379) (xy 322.882843 -37.524577) (xy 322.799946 -37.495116)
			(xy 322.720072 -37.458238) (xy 322.643882 -37.41425) (xy 322.572008 -37.363516) (xy 322.505046 -37.306456)
			(xy 322.443549 -37.243543) (xy 322.388028 -37.175299) (xy 322.338943 -37.102289) (xy 322.296701 -37.025117)
			(xy 322.261651 -36.944424) (xy 322.234084 -36.860879) (xy 322.214229 -36.775172) (xy 322.202249 -36.688015)
			(xy 322.198245 -36.60013) (xy 298.130976 -36.60013) (xy 298.130475 -36.644118) (xy 298.122475 -36.73173)
			(xy 298.106541 -36.818251) (xy 298.082806 -36.902965) (xy 298.051465 -36.98517) (xy 298.012779 -37.064184)
			(xy 297.967067 -37.139353) (xy 297.91471 -37.210053) (xy 297.856141 -37.2757) (xy 297.791845 -37.335748)
			(xy 297.722354 -37.389701) (xy 297.648246 -37.437112) (xy 297.570133 -37.477586) (xy 297.488663 -37.51079)
			(xy 297.404511 -37.536448) (xy 297.318375 -37.554348) (xy 297.230968 -37.56434) (xy 297.143014 -37.566343)
			(xy 297.055243 -37.560339) (xy 296.968381 -37.546379) (xy 296.883149 -37.524577) (xy 296.800252 -37.495116)
			(xy 296.720378 -37.458238) (xy 296.644188 -37.41425) (xy 296.572314 -37.363516) (xy 296.505352 -37.306456)
			(xy 296.443855 -37.243543) (xy 296.388334 -37.175299) (xy 296.339249 -37.102289) (xy 296.297007 -37.025117)
			(xy 296.261957 -36.944424) (xy 296.23439 -36.860879) (xy 296.214535 -36.775172) (xy 296.202555 -36.688015)
			(xy 296.198551 -36.60013) (xy 272.131028 -36.60013) (xy 272.130527 -36.644118) (xy 272.122527 -36.73173)
			(xy 272.106593 -36.818251) (xy 272.082858 -36.902965) (xy 272.051517 -36.98517) (xy 272.012831 -37.064184)
			(xy 271.967119 -37.139353) (xy 271.914762 -37.210053) (xy 271.856193 -37.2757) (xy 271.791897 -37.335748)
			(xy 271.722406 -37.389701) (xy 271.648298 -37.437112) (xy 271.570185 -37.477586) (xy 271.488715 -37.51079)
			(xy 271.404563 -37.536448) (xy 271.318427 -37.554348) (xy 271.23102 -37.56434) (xy 271.143066 -37.566343)
			(xy 271.055295 -37.560339) (xy 270.968433 -37.546379) (xy 270.883201 -37.524577) (xy 270.800304 -37.495116)
			(xy 270.72043 -37.458238) (xy 270.64424 -37.41425) (xy 270.572366 -37.363516) (xy 270.505404 -37.306456)
			(xy 270.443907 -37.243543) (xy 270.388386 -37.175299) (xy 270.339301 -37.102289) (xy 270.297059 -37.025117)
			(xy 270.262009 -36.944424) (xy 270.234442 -36.860879) (xy 270.214587 -36.775172) (xy 270.202607 -36.688015)
			(xy 270.198603 -36.60013) (xy 246.13108 -36.60013) (xy 246.130579 -36.644118) (xy 246.122579 -36.73173)
			(xy 246.106645 -36.818251) (xy 246.08291 -36.902965) (xy 246.051569 -36.98517) (xy 246.012883 -37.064184)
			(xy 245.967171 -37.139353) (xy 245.914814 -37.210053) (xy 245.856245 -37.2757) (xy 245.791949 -37.335748)
			(xy 245.722458 -37.389701) (xy 245.64835 -37.437112) (xy 245.570237 -37.477586) (xy 245.488767 -37.51079)
			(xy 245.404615 -37.536448) (xy 245.318479 -37.554348) (xy 245.231072 -37.56434) (xy 245.143118 -37.566343)
			(xy 245.055347 -37.560339) (xy 244.968485 -37.546379) (xy 244.883253 -37.524577) (xy 244.800356 -37.495116)
			(xy 244.720482 -37.458238) (xy 244.644292 -37.41425) (xy 244.572418 -37.363516) (xy 244.505456 -37.306456)
			(xy 244.443959 -37.243543) (xy 244.388438 -37.175299) (xy 244.339353 -37.102289) (xy 244.297111 -37.025117)
			(xy 244.262061 -36.944424) (xy 244.234494 -36.860879) (xy 244.214639 -36.775172) (xy 244.202659 -36.688015)
			(xy 244.198655 -36.60013) (xy 208.03108 -36.60013) (xy 208.030579 -36.644118) (xy 208.022579 -36.73173)
			(xy 208.006645 -36.818251) (xy 207.98291 -36.902965) (xy 207.951569 -36.98517) (xy 207.912883 -37.064184)
			(xy 207.867171 -37.139353) (xy 207.814814 -37.210053) (xy 207.756245 -37.2757) (xy 207.691949 -37.335748)
			(xy 207.622458 -37.389701) (xy 207.54835 -37.437112) (xy 207.470237 -37.477586) (xy 207.388767 -37.51079)
			(xy 207.304615 -37.536448) (xy 207.218479 -37.554348) (xy 207.131072 -37.56434) (xy 207.043118 -37.566343)
			(xy 206.955347 -37.560339) (xy 206.868485 -37.546379) (xy 206.783253 -37.524577) (xy 206.700356 -37.495116)
			(xy 206.620482 -37.458238) (xy 206.544292 -37.41425) (xy 206.472418 -37.363516) (xy 206.405456 -37.306456)
			(xy 206.343959 -37.243543) (xy 206.288438 -37.175299) (xy 206.239353 -37.102289) (xy 206.197111 -37.025117)
			(xy 206.162061 -36.944424) (xy 206.134494 -36.860879) (xy 206.114639 -36.775172) (xy 206.102659 -36.688015)
			(xy 206.098655 -36.60013) (xy 182.030878 -36.60013) (xy 182.030377 -36.644118) (xy 182.022377 -36.73173)
			(xy 182.006443 -36.818251) (xy 181.982708 -36.902965) (xy 181.951367 -36.98517) (xy 181.912681 -37.064184)
			(xy 181.866969 -37.139353) (xy 181.814612 -37.210053) (xy 181.756043 -37.2757) (xy 181.691747 -37.335748)
			(xy 181.622256 -37.389701) (xy 181.548148 -37.437112) (xy 181.470035 -37.477586) (xy 181.388565 -37.51079)
			(xy 181.304413 -37.536448) (xy 181.218277 -37.554348) (xy 181.13087 -37.56434) (xy 181.042916 -37.566343)
			(xy 180.955145 -37.560339) (xy 180.868283 -37.546379) (xy 180.783051 -37.524577) (xy 180.700154 -37.495116)
			(xy 180.62028 -37.458238) (xy 180.54409 -37.41425) (xy 180.472216 -37.363516) (xy 180.405254 -37.306456)
			(xy 180.343757 -37.243543) (xy 180.288236 -37.175299) (xy 180.239151 -37.102289) (xy 180.196909 -37.025117)
			(xy 180.161859 -36.944424) (xy 180.134292 -36.860879) (xy 180.114437 -36.775172) (xy 180.102457 -36.688015)
			(xy 180.098453 -36.60013) (xy 156.03093 -36.60013) (xy 156.030429 -36.644118) (xy 156.022429 -36.73173)
			(xy 156.006495 -36.818251) (xy 155.98276 -36.902965) (xy 155.951419 -36.98517) (xy 155.912733 -37.064184)
			(xy 155.867021 -37.139353) (xy 155.814664 -37.210053) (xy 155.756095 -37.2757) (xy 155.691799 -37.335748)
			(xy 155.622308 -37.389701) (xy 155.5482 -37.437112) (xy 155.470087 -37.477586) (xy 155.388617 -37.51079)
			(xy 155.304465 -37.536448) (xy 155.218329 -37.554348) (xy 155.130922 -37.56434) (xy 155.042968 -37.566343)
			(xy 154.955197 -37.560339) (xy 154.868335 -37.546379) (xy 154.783103 -37.524577) (xy 154.700206 -37.495116)
			(xy 154.620332 -37.458238) (xy 154.544142 -37.41425) (xy 154.472268 -37.363516) (xy 154.405306 -37.306456)
			(xy 154.343809 -37.243543) (xy 154.288288 -37.175299) (xy 154.239203 -37.102289) (xy 154.196961 -37.025117)
			(xy 154.161911 -36.944424) (xy 154.134344 -36.860879) (xy 154.114489 -36.775172) (xy 154.102509 -36.688015)
			(xy 154.098505 -36.60013) (xy 130.030982 -36.60013) (xy 130.030481 -36.644118) (xy 130.022481 -36.73173)
			(xy 130.006547 -36.818251) (xy 129.982812 -36.902965) (xy 129.951471 -36.98517) (xy 129.912785 -37.064184)
			(xy 129.867073 -37.139353) (xy 129.814716 -37.210053) (xy 129.756147 -37.2757) (xy 129.691851 -37.335748)
			(xy 129.62236 -37.389701) (xy 129.548252 -37.437112) (xy 129.470139 -37.477586) (xy 129.388669 -37.51079)
			(xy 129.304517 -37.536448) (xy 129.218381 -37.554348) (xy 129.130974 -37.56434) (xy 129.04302 -37.566343)
			(xy 128.955249 -37.560339) (xy 128.868387 -37.546379) (xy 128.783155 -37.524577) (xy 128.700258 -37.495116)
			(xy 128.620384 -37.458238) (xy 128.544194 -37.41425) (xy 128.47232 -37.363516) (xy 128.405358 -37.306456)
			(xy 128.343861 -37.243543) (xy 128.28834 -37.175299) (xy 128.239255 -37.102289) (xy 128.197013 -37.025117)
			(xy 128.161963 -36.944424) (xy 128.134396 -36.860879) (xy 128.114541 -36.775172) (xy 128.102561 -36.688015)
			(xy 128.098557 -36.60013) (xy 91.930728 -36.60013) (xy 91.930227 -36.644118) (xy 91.922227 -36.73173)
			(xy 91.906293 -36.818251) (xy 91.882558 -36.902965) (xy 91.851217 -36.98517) (xy 91.812531 -37.064184)
			(xy 91.766819 -37.139353) (xy 91.714462 -37.210053) (xy 91.655893 -37.2757) (xy 91.591597 -37.335748)
			(xy 91.522106 -37.389701) (xy 91.447998 -37.437112) (xy 91.369885 -37.477586) (xy 91.288415 -37.51079)
			(xy 91.204263 -37.536448) (xy 91.118127 -37.554348) (xy 91.03072 -37.56434) (xy 90.942766 -37.566343)
			(xy 90.854995 -37.560339) (xy 90.768133 -37.546379) (xy 90.682901 -37.524577) (xy 90.600004 -37.495116)
			(xy 90.52013 -37.458238) (xy 90.44394 -37.41425) (xy 90.372066 -37.363516) (xy 90.305104 -37.306456)
			(xy 90.243607 -37.243543) (xy 90.188086 -37.175299) (xy 90.139001 -37.102289) (xy 90.096759 -37.025117)
			(xy 90.061709 -36.944424) (xy 90.034142 -36.860879) (xy 90.014287 -36.775172) (xy 90.002307 -36.688015)
			(xy 89.998303 -36.60013) (xy 65.93078 -36.60013) (xy 65.930279 -36.644118) (xy 65.922279 -36.73173)
			(xy 65.906345 -36.818251) (xy 65.88261 -36.902965) (xy 65.851269 -36.98517) (xy 65.812583 -37.064184)
			(xy 65.766871 -37.139353) (xy 65.714514 -37.210053) (xy 65.655945 -37.2757) (xy 65.591649 -37.335748)
			(xy 65.522158 -37.389701) (xy 65.44805 -37.437112) (xy 65.369937 -37.477586) (xy 65.288467 -37.51079)
			(xy 65.204315 -37.536448) (xy 65.118179 -37.554348) (xy 65.030772 -37.56434) (xy 64.942818 -37.566343)
			(xy 64.855047 -37.560339) (xy 64.768185 -37.546379) (xy 64.682953 -37.524577) (xy 64.600056 -37.495116)
			(xy 64.520182 -37.458238) (xy 64.443992 -37.41425) (xy 64.372118 -37.363516) (xy 64.305156 -37.306456)
			(xy 64.243659 -37.243543) (xy 64.188138 -37.175299) (xy 64.139053 -37.102289) (xy 64.096811 -37.025117)
			(xy 64.061761 -36.944424) (xy 64.034194 -36.860879) (xy 64.014339 -36.775172) (xy 64.002359 -36.688015)
			(xy 63.998355 -36.60013) (xy 39.930832 -36.60013) (xy 39.930331 -36.644118) (xy 39.922331 -36.73173)
			(xy 39.906397 -36.818251) (xy 39.882662 -36.902965) (xy 39.851321 -36.98517) (xy 39.812635 -37.064184)
			(xy 39.766923 -37.139353) (xy 39.714566 -37.210053) (xy 39.655997 -37.2757) (xy 39.591701 -37.335748)
			(xy 39.52221 -37.389701) (xy 39.448102 -37.437112) (xy 39.369989 -37.477586) (xy 39.288519 -37.51079)
			(xy 39.204367 -37.536448) (xy 39.118231 -37.554348) (xy 39.030824 -37.56434) (xy 38.94287 -37.566343)
			(xy 38.855099 -37.560339) (xy 38.768237 -37.546379) (xy 38.683005 -37.524577) (xy 38.600108 -37.495116)
			(xy 38.520234 -37.458238) (xy 38.444044 -37.41425) (xy 38.37217 -37.363516) (xy 38.305208 -37.306456)
			(xy 38.243711 -37.243543) (xy 38.18819 -37.175299) (xy 38.139105 -37.102289) (xy 38.096863 -37.025117)
			(xy 38.061813 -36.944424) (xy 38.034246 -36.860879) (xy 38.014391 -36.775172) (xy 38.002411 -36.688015)
			(xy 37.998407 -36.60013) (xy 13.930884 -36.60013) (xy 13.930383 -36.644118) (xy 13.922383 -36.73173)
			(xy 13.906449 -36.818251) (xy 13.882714 -36.902965) (xy 13.851373 -36.98517) (xy 13.812687 -37.064184)
			(xy 13.766975 -37.139353) (xy 13.714618 -37.210053) (xy 13.656049 -37.2757) (xy 13.591753 -37.335748)
			(xy 13.522262 -37.389701) (xy 13.448154 -37.437112) (xy 13.370041 -37.477586) (xy 13.288571 -37.51079)
			(xy 13.204419 -37.536448) (xy 13.118283 -37.554348) (xy 13.030876 -37.56434) (xy 12.942922 -37.566343)
			(xy 12.855151 -37.560339) (xy 12.768289 -37.546379) (xy 12.683057 -37.524577) (xy 12.60016 -37.495116)
			(xy 12.520286 -37.458238) (xy 12.444096 -37.41425) (xy 12.372222 -37.363516) (xy 12.30526 -37.306456)
			(xy 12.243763 -37.243543) (xy 12.188242 -37.175299) (xy 12.139157 -37.102289) (xy 12.096915 -37.025117)
			(xy 12.061865 -36.944424) (xy 12.034298 -36.860879) (xy 12.014443 -36.775172) (xy 12.002463 -36.688015)
			(xy 11.998459 -36.60013) (xy 1.524 -36.60013) (xy 1.524 -58.69846) (xy 229.808777 -58.69846) (xy 229.808777 -58.601788)
			(xy 229.81676 -58.505445) (xy 229.832672 -58.410091) (xy 229.856404 -58.316377) (xy 229.887793 -58.224943)
			(xy 229.926626 -58.136412) (xy 229.972637 -58.051392) (xy 230.025512 -57.970461) (xy 230.08489 -57.894172)
			(xy 230.150364 -57.823048) (xy 230.221488 -57.757574) (xy 230.297777 -57.698196) (xy 230.378708 -57.645321)
			(xy 230.463728 -57.59931) (xy 230.552259 -57.560477) (xy 230.643693 -57.529088) (xy 230.737407 -57.505356)
			(xy 230.832761 -57.489444) (xy 230.929104 -57.481461) (xy 231.025776 -57.481461) (xy 231.122119 -57.489444)
			(xy 231.217473 -57.505356) (xy 231.311187 -57.529088) (xy 231.402621 -57.560477) (xy 231.491152 -57.59931)
			(xy 231.576172 -57.645321) (xy 231.657103 -57.698196) (xy 231.733392 -57.757574) (xy 231.804516 -57.823048)
			(xy 231.86999 -57.894172) (xy 231.929368 -57.970461) (xy 231.982243 -58.051392) (xy 232.028254 -58.136412)
			(xy 232.067087 -58.224943) (xy 232.098476 -58.316377) (xy 232.122208 -58.410091) (xy 232.13812 -58.505445)
			(xy 232.146103 -58.601788) (xy 232.146602 -58.650124) (xy 232.146103 -58.69846) (xy 232.13812 -58.794803)
			(xy 232.122208 -58.890157) (xy 232.098476 -58.983871) (xy 232.067087 -59.075305) (xy 232.028254 -59.163836)
			(xy 231.982243 -59.248856) (xy 231.929368 -59.329787) (xy 231.86999 -59.406076) (xy 231.804516 -59.4772)
			(xy 231.733392 -59.542674) (xy 231.657103 -59.602052) (xy 231.576172 -59.654927) (xy 231.491152 -59.700938)
			(xy 231.402621 -59.739771) (xy 231.311187 -59.77116) (xy 231.217473 -59.794892) (xy 231.122119 -59.810804)
			(xy 231.025776 -59.818787) (xy 230.929104 -59.818787) (xy 230.832761 -59.810804) (xy 230.737407 -59.794892)
			(xy 230.643693 -59.77116) (xy 230.552259 -59.739771) (xy 230.463728 -59.700938) (xy 230.378708 -59.654927)
			(xy 230.297777 -59.602052) (xy 230.221488 -59.542674) (xy 230.150364 -59.4772) (xy 230.08489 -59.406076)
			(xy 230.025512 -59.329787) (xy 229.972637 -59.248856) (xy 229.926626 -59.163836) (xy 229.887793 -59.075305)
			(xy 229.856404 -58.983871) (xy 229.832672 -58.890157) (xy 229.81676 -58.794803) (xy 229.808777 -58.69846)
			(xy 1.524 -58.69846) (xy 1.524 -60.13196) (xy 226.436428 -60.13196) (xy 226.436428 -59.26836) (xy 226.436918 -59.238392)
			(xy 226.444741 -59.17897) (xy 226.460254 -59.121077) (xy 226.48319 -59.065704) (xy 226.513157 -59.013798)
			(xy 226.549644 -58.966248) (xy 226.592024 -58.923868) (xy 226.639574 -58.887381) (xy 226.69148 -58.857414)
			(xy 226.746853 -58.834478) (xy 226.804746 -58.818965) (xy 226.864168 -58.811142) (xy 226.924104 -58.811142)
			(xy 226.983526 -58.818965) (xy 227.041419 -58.834478) (xy 227.096792 -58.857414) (xy 227.148698 -58.887381)
			(xy 227.196248 -58.923868) (xy 227.238628 -58.966248) (xy 227.275115 -59.013798) (xy 227.305082 -59.065704)
			(xy 227.328018 -59.121077) (xy 227.343531 -59.17897) (xy 227.351354 -59.238392) (xy 227.351844 -59.26836)
			(xy 227.351844 -60.13196) (xy 227.351354 -60.161928) (xy 227.343531 -60.22135) (xy 227.328018 -60.279243)
			(xy 227.305082 -60.334616) (xy 227.275115 -60.386522) (xy 227.238628 -60.434072) (xy 227.196248 -60.476452)
			(xy 227.148698 -60.512939) (xy 227.096792 -60.542906) (xy 227.041419 -60.565842) (xy 226.983526 -60.581355)
			(xy 226.924104 -60.589178) (xy 226.864168 -60.589178) (xy 226.804746 -60.581355) (xy 226.746853 -60.565842)
			(xy 226.69148 -60.542906) (xy 226.639574 -60.512939) (xy 226.592024 -60.476452) (xy 226.549644 -60.434072)
			(xy 226.513157 -60.386522) (xy 226.48319 -60.334616) (xy 226.460254 -60.279243) (xy 226.444741 -60.22135)
			(xy 226.436918 -60.161928) (xy 226.436428 -60.13196) (xy 1.524 -60.13196) (xy 1.524 -72.700134) (xy 112.441236 -72.700134)
			(xy 112.44524 -72.494946) (xy 112.457247 -72.29007) (xy 112.477238 -72.085819) (xy 112.505183 -71.882504)
			(xy 112.541039 -71.680433) (xy 112.584753 -71.479915) (xy 112.636256 -71.281256) (xy 112.695471 -71.084757)
			(xy 112.762307 -70.890718) (xy 112.836663 -70.699435) (xy 112.918426 -70.511198) (xy 113.007471 -70.326295)
			(xy 113.103662 -70.145007) (xy 113.206853 -69.96761) (xy 113.316887 -69.794373) (xy 113.433596 -69.625562)
			(xy 113.556802 -69.461433) (xy 113.686319 -69.302236) (xy 113.821948 -69.148214) (xy 113.963483 -68.9996)
			(xy 114.110708 -68.856622) (xy 114.2634 -68.719497) (xy 114.421326 -68.588433) (xy 114.584245 -68.463631)
			(xy 114.75191 -68.345281) (xy 114.924064 -68.233562) (xy 115.100446 -68.128645) (xy 115.280787 -68.03069)
			(xy 115.464813 -67.939846) (xy 115.652243 -67.85625) (xy 115.842792 -67.780031) (xy 116.036169 -67.711305)
			(xy 116.232081 -67.650176) (xy 116.430228 -67.596737) (xy 116.63031 -67.55107) (xy 116.832021 -67.513243)
			(xy 117.035054 -67.483316) (xy 117.239101 -67.461333) (xy 117.44385 -67.447328) (xy 117.648989 -67.441322)
			(xy 117.854206 -67.443324) (xy 118.059189 -67.453332) (xy 118.263626 -67.471329) (xy 118.467204 -67.497289)
			(xy 118.669615 -67.531172) (xy 118.870549 -67.572927) (xy 119.069702 -67.62249) (xy 119.266769 -67.679785)
			(xy 119.461451 -67.744725) (xy 119.653451 -67.817211) (xy 119.842476 -67.897134) (xy 120.028239 -67.98437)
			(xy 120.210457 -68.078788) (xy 120.388853 -68.180243) (xy 120.563154 -68.288582) (xy 120.733096 -68.403638)
			(xy 120.898419 -68.525238) (xy 121.058872 -68.653195) (xy 121.214211 -68.787314) (xy 121.364198 -68.927393)
			(xy 121.508606 -69.073217) (xy 121.647214 -69.224563) (xy 121.779812 -69.381203) (xy 121.906198 -69.542897)
			(xy 122.026178 -69.709399) (xy 122.085084 -69.79826) (xy 229.808777 -69.79826) (xy 229.808777 -69.701588)
			(xy 229.81676 -69.605245) (xy 229.832672 -69.509891) (xy 229.856404 -69.416177) (xy 229.887793 -69.324743)
			(xy 229.926626 -69.236212) (xy 229.972637 -69.151192) (xy 230.025512 -69.070261) (xy 230.08489 -68.993972)
			(xy 230.150364 -68.922848) (xy 230.221488 -68.857374) (xy 230.297777 -68.797996) (xy 230.378708 -68.745121)
			(xy 230.463728 -68.69911) (xy 230.552259 -68.660277) (xy 230.643693 -68.628888) (xy 230.737407 -68.605156)
			(xy 230.832761 -68.589244) (xy 230.929104 -68.581261) (xy 231.025776 -68.581261) (xy 231.122119 -68.589244)
			(xy 231.217473 -68.605156) (xy 231.311187 -68.628888) (xy 231.402621 -68.660277) (xy 231.491152 -68.69911)
			(xy 231.576172 -68.745121) (xy 231.657103 -68.797996) (xy 231.733392 -68.857374) (xy 231.804516 -68.922848)
			(xy 231.86999 -68.993972) (xy 231.929368 -69.070261) (xy 231.982243 -69.151192) (xy 232.028254 -69.236212)
			(xy 232.067087 -69.324743) (xy 232.098476 -69.416177) (xy 232.122208 -69.509891) (xy 232.13812 -69.605245)
			(xy 232.146103 -69.701588) (xy 232.146602 -69.749924) (xy 232.146103 -69.79826) (xy 232.13812 -69.894603)
			(xy 232.122208 -69.989957) (xy 232.098476 -70.083671) (xy 232.067087 -70.175105) (xy 232.028254 -70.263636)
			(xy 231.982243 -70.348656) (xy 231.929368 -70.429587) (xy 231.86999 -70.505876) (xy 231.804516 -70.577)
			(xy 231.733392 -70.642474) (xy 231.657103 -70.701852) (xy 231.576172 -70.754727) (xy 231.491152 -70.800738)
			(xy 231.402621 -70.839571) (xy 231.311187 -70.87096) (xy 231.217473 -70.894692) (xy 231.122119 -70.910604)
			(xy 231.025776 -70.918587) (xy 230.929104 -70.918587) (xy 230.832761 -70.910604) (xy 230.737407 -70.894692)
			(xy 230.643693 -70.87096) (xy 230.552259 -70.839571) (xy 230.463728 -70.800738) (xy 230.378708 -70.754727)
			(xy 230.297777 -70.701852) (xy 230.221488 -70.642474) (xy 230.150364 -70.577) (xy 230.08489 -70.505876)
			(xy 230.025512 -70.429587) (xy 229.972637 -70.348656) (xy 229.926626 -70.263636) (xy 229.887793 -70.175105)
			(xy 229.856404 -70.083671) (xy 229.832672 -69.989957) (xy 229.81676 -69.894603) (xy 229.808777 -69.79826)
			(xy 122.085084 -69.79826) (xy 122.139571 -69.880455) (xy 122.246204 -70.055805) (xy 122.345914 -70.235182)
			(xy 122.43855 -70.418312) (xy 122.52397 -70.604918) (xy 122.602044 -70.794714) (xy 122.672654 -70.987412)
			(xy 122.735691 -71.182718) (xy 122.791061 -71.380334) (xy 122.838678 -71.579961) (xy 122.87847 -71.781293)
			(xy 122.910377 -71.984025) (xy 122.93435 -72.187847) (xy 122.950352 -72.39245) (xy 122.958359 -72.59752)
			(xy 122.958859 -72.69988) (xy 344.640924 -72.69988) (xy 344.644928 -72.494692) (xy 344.656935 -72.289816)
			(xy 344.676926 -72.085565) (xy 344.704871 -71.88225) (xy 344.740727 -71.680179) (xy 344.784441 -71.479661)
			(xy 344.835944 -71.281002) (xy 344.895159 -71.084503) (xy 344.961995 -70.890464) (xy 345.036351 -70.699181)
			(xy 345.118114 -70.510944) (xy 345.207159 -70.326041) (xy 345.30335 -70.144753) (xy 345.406541 -69.967356)
			(xy 345.516575 -69.794119) (xy 345.633284 -69.625308) (xy 345.75649 -69.461179) (xy 345.886007 -69.301982)
			(xy 346.021636 -69.14796) (xy 346.163171 -68.999346) (xy 346.310396 -68.856368) (xy 346.463088 -68.719243)
			(xy 346.621014 -68.588179) (xy 346.783933 -68.463377) (xy 346.951598 -68.345027) (xy 347.123752 -68.233308)
			(xy 347.300134 -68.128391) (xy 347.480475 -68.030436) (xy 347.664501 -67.939592) (xy 347.851931 -67.855996)
			(xy 348.04248 -67.779777) (xy 348.235857 -67.711051) (xy 348.431769 -67.649922) (xy 348.629916 -67.596483)
			(xy 348.829998 -67.550816) (xy 349.031709 -67.512989) (xy 349.234742 -67.483062) (xy 349.438789 -67.461079)
			(xy 349.643538 -67.447074) (xy 349.848677 -67.441068) (xy 350.053894 -67.44307) (xy 350.258877 -67.453078)
			(xy 350.463314 -67.471075) (xy 350.666892 -67.497035) (xy 350.869303 -67.530918) (xy 351.070237 -67.572673)
			(xy 351.26939 -67.622236) (xy 351.466457 -67.679531) (xy 351.661139 -67.744471) (xy 351.853139 -67.816957)
			(xy 352.042164 -67.89688) (xy 352.227927 -67.984116) (xy 352.410145 -68.078534) (xy 352.588541 -68.179989)
			(xy 352.762842 -68.288328) (xy 352.932784 -68.403384) (xy 353.098107 -68.524984) (xy 353.25856 -68.652941)
			(xy 353.413899 -68.78706) (xy 353.563886 -68.927139) (xy 353.708294 -69.072963) (xy 353.846902 -69.224309)
			(xy 353.9795 -69.380949) (xy 354.105886 -69.542643) (xy 354.225866 -69.709145) (xy 354.339259 -69.880201)
			(xy 354.445892 -70.055551) (xy 354.545602 -70.234928) (xy 354.638238 -70.418058) (xy 354.723658 -70.604664)
			(xy 354.801732 -70.79446) (xy 354.872342 -70.987158) (xy 354.935379 -71.182464) (xy 354.990749 -71.38008)
			(xy 355.038366 -71.579707) (xy 355.078158 -71.781039) (xy 355.110065 -71.983771) (xy 355.134038 -72.187593)
			(xy 355.15004 -72.392196) (xy 355.158047 -72.597266) (xy 355.158548 -72.69988) (xy 355.158047 -72.802494)
			(xy 355.15004 -73.007564) (xy 355.134038 -73.212167) (xy 355.110065 -73.415989) (xy 355.078158 -73.618721)
			(xy 355.038366 -73.820053) (xy 354.990749 -74.01968) (xy 354.935379 -74.217296) (xy 354.872342 -74.412602)
			(xy 354.801732 -74.6053) (xy 354.723658 -74.795096) (xy 354.638238 -74.981702) (xy 354.545602 -75.164832)
			(xy 354.445892 -75.344209) (xy 354.339259 -75.519559) (xy 354.225866 -75.690615) (xy 354.105886 -75.857117)
			(xy 353.9795 -76.018811) (xy 353.846902 -76.175451) (xy 353.708294 -76.326797) (xy 353.563886 -76.472621)
			(xy 353.413899 -76.6127) (xy 353.25856 -76.746819) (xy 353.098107 -76.874776) (xy 352.932784 -76.996376)
			(xy 352.762842 -77.111432) (xy 352.588541 -77.219771) (xy 352.410145 -77.321226) (xy 352.227927 -77.415644)
			(xy 352.042164 -77.50288) (xy 351.853139 -77.582803) (xy 351.661139 -77.655289) (xy 351.466457 -77.720229)
			(xy 351.26939 -77.777524) (xy 351.070237 -77.827087) (xy 350.869303 -77.868842) (xy 350.666892 -77.902725)
			(xy 350.463314 -77.928685) (xy 350.258877 -77.946682) (xy 350.053894 -77.95669) (xy 349.848677 -77.958692)
			(xy 349.643538 -77.952686) (xy 349.438789 -77.938681) (xy 349.234742 -77.916698) (xy 349.031709 -77.886771)
			(xy 348.829998 -77.848944) (xy 348.629916 -77.803277) (xy 348.431769 -77.749838) (xy 348.235857 -77.688709)
			(xy 348.04248 -77.619983) (xy 347.851931 -77.543764) (xy 347.664501 -77.460168) (xy 347.480475 -77.369324)
			(xy 347.300134 -77.271369) (xy 347.123752 -77.166452) (xy 346.951598 -77.054733) (xy 346.783933 -76.936383)
			(xy 346.621014 -76.811581) (xy 346.463088 -76.680517) (xy 346.310396 -76.543392) (xy 346.163171 -76.400414)
			(xy 346.021636 -76.2518) (xy 345.886007 -76.097778) (xy 345.75649 -75.938581) (xy 345.633284 -75.774452)
			(xy 345.516575 -75.605641) (xy 345.406541 -75.432404) (xy 345.30335 -75.255007) (xy 345.207159 -75.073719)
			(xy 345.118114 -74.888816) (xy 345.036351 -74.700579) (xy 344.961995 -74.509296) (xy 344.895159 -74.315257)
			(xy 344.835944 -74.118758) (xy 344.784441 -73.920099) (xy 344.740727 -73.719581) (xy 344.704871 -73.51751)
			(xy 344.676926 -73.314195) (xy 344.656935 -73.109944) (xy 344.644928 -72.905068) (xy 344.640924 -72.69988)
			(xy 122.958859 -72.69988) (xy 122.95886 -72.700134) (xy 122.958359 -72.802748) (xy 122.950352 -73.007818)
			(xy 122.93435 -73.212421) (xy 122.910377 -73.416243) (xy 122.87847 -73.618975) (xy 122.838678 -73.820307)
			(xy 122.791061 -74.019934) (xy 122.735691 -74.21755) (xy 122.672654 -74.412856) (xy 122.602044 -74.605554)
			(xy 122.52397 -74.79535) (xy 122.43855 -74.981956) (xy 122.345914 -75.165086) (xy 122.277376 -75.288385)
			(xy 262.150829 -75.288385) (xy 262.150829 -75.228415) (xy 262.158657 -75.168959) (xy 262.174178 -75.111033)
			(xy 262.197128 -75.055628) (xy 262.227114 -75.003693) (xy 262.263621 -74.956116) (xy 262.306027 -74.913712)
			(xy 262.353605 -74.877206) (xy 262.405541 -74.847222) (xy 262.460946 -74.824274) (xy 262.518872 -74.808754)
			(xy 262.578329 -74.800928) (xy 262.608314 -74.80046) (xy 263.471914 -74.80046) (xy 263.501899 -74.800907)
			(xy 263.561356 -74.808736) (xy 263.619283 -74.824259) (xy 263.674687 -74.84721) (xy 263.726623 -74.877196)
			(xy 263.7742 -74.913705) (xy 263.816604 -74.956111) (xy 263.853111 -75.003689) (xy 263.883096 -75.055625)
			(xy 263.906045 -75.111031) (xy 263.921566 -75.168958) (xy 263.929394 -75.228415) (xy 263.929394 -75.288385)
			(xy 263.921566 -75.347842) (xy 263.906045 -75.405769) (xy 263.883096 -75.461175) (xy 263.853111 -75.513111)
			(xy 263.816604 -75.560689) (xy 263.7742 -75.603095) (xy 263.726623 -75.639604) (xy 263.674687 -75.66959)
			(xy 263.619283 -75.692541) (xy 263.561356 -75.708064) (xy 263.501899 -75.715893) (xy 263.471914 -75.716384)
			(xy 262.608314 -75.716384) (xy 262.578329 -75.715872) (xy 262.518872 -75.708046) (xy 262.460946 -75.692526)
			(xy 262.405541 -75.669578) (xy 262.353605 -75.639594) (xy 262.306027 -75.603088) (xy 262.263621 -75.560684)
			(xy 262.227114 -75.513107) (xy 262.197128 -75.461172) (xy 262.174178 -75.405767) (xy 262.158657 -75.347841)
			(xy 262.150829 -75.288385) (xy 122.277376 -75.288385) (xy 122.246204 -75.344463) (xy 122.139571 -75.519813)
			(xy 122.026178 -75.690869) (xy 121.906198 -75.857371) (xy 121.779812 -76.019065) (xy 121.647214 -76.175705)
			(xy 121.508606 -76.327051) (xy 121.364198 -76.472875) (xy 121.214211 -76.612954) (xy 121.058872 -76.747073)
			(xy 120.959794 -76.826085) (xy 229.640845 -76.826085) (xy 229.640845 -76.766115) (xy 229.648673 -76.706658)
			(xy 229.664196 -76.648731) (xy 229.687147 -76.593327) (xy 229.717134 -76.541392) (xy 229.753643 -76.493816)
			(xy 229.796051 -76.451413) (xy 229.84363 -76.414908) (xy 229.895568 -76.384926) (xy 229.950975 -76.361981)
			(xy 230.008903 -76.346464) (xy 230.068361 -76.338642) (xy 230.098346 -76.338176) (xy 230.961946 -76.338176)
			(xy 230.991931 -76.338593) (xy 231.051387 -76.346426) (xy 231.109312 -76.361952) (xy 231.164715 -76.384906)
			(xy 231.216648 -76.414894) (xy 231.264223 -76.451404) (xy 231.306626 -76.493811) (xy 231.343131 -76.54139)
			(xy 231.373114 -76.593326) (xy 231.396063 -76.648732) (xy 231.411583 -76.706658) (xy 231.41941 -76.766115)
			(xy 231.41941 -76.826085) (xy 231.411583 -76.885542) (xy 231.396063 -76.943468) (xy 231.373114 -76.998874)
			(xy 231.343131 -77.05081) (xy 231.306626 -77.098389) (xy 231.264223 -77.140796) (xy 231.216648 -77.177306)
			(xy 231.164715 -77.207294) (xy 231.109312 -77.230248) (xy 231.051387 -77.245774) (xy 230.991931 -77.253607)
			(xy 230.961946 -77.2541) (xy 230.098346 -77.2541) (xy 230.068361 -77.253558) (xy 230.008903 -77.245736)
			(xy 229.950975 -77.230219) (xy 229.895568 -77.207274) (xy 229.84363 -77.177292) (xy 229.796051 -77.140787)
			(xy 229.753643 -77.098384) (xy 229.717134 -77.050808) (xy 229.687147 -76.998873) (xy 229.664196 -76.943469)
			(xy 229.648673 -76.885542) (xy 229.640845 -76.826085) (xy 120.959794 -76.826085) (xy 120.898419 -76.87503)
			(xy 120.733096 -76.99663) (xy 120.563154 -77.111686) (xy 120.388853 -77.220025) (xy 120.210457 -77.32148)
			(xy 120.028239 -77.415898) (xy 119.842476 -77.503134) (xy 119.653451 -77.583057) (xy 119.461451 -77.655543)
			(xy 119.266769 -77.720483) (xy 119.069702 -77.777778) (xy 118.870549 -77.827341) (xy 118.669615 -77.869096)
			(xy 118.467204 -77.902979) (xy 118.263626 -77.928939) (xy 118.059189 -77.946936) (xy 117.854206 -77.956944)
			(xy 117.648989 -77.958946) (xy 117.44385 -77.95294) (xy 117.239101 -77.938935) (xy 117.035054 -77.916952)
			(xy 116.832021 -77.887025) (xy 116.63031 -77.849198) (xy 116.430228 -77.803531) (xy 116.232081 -77.750092)
			(xy 116.036169 -77.688963) (xy 115.842792 -77.620237) (xy 115.652243 -77.544018) (xy 115.464813 -77.460422)
			(xy 115.280787 -77.369578) (xy 115.100446 -77.271623) (xy 114.924064 -77.166706) (xy 114.75191 -77.054987)
			(xy 114.584245 -76.936637) (xy 114.421326 -76.811835) (xy 114.2634 -76.680771) (xy 114.110708 -76.543646)
			(xy 113.963483 -76.400668) (xy 113.821948 -76.252054) (xy 113.686319 -76.098032) (xy 113.556802 -75.938835)
			(xy 113.433596 -75.774706) (xy 113.316887 -75.605895) (xy 113.206853 -75.432658) (xy 113.103662 -75.255261)
			(xy 113.007471 -75.073973) (xy 112.918426 -74.88907) (xy 112.836663 -74.700833) (xy 112.762307 -74.50955)
			(xy 112.695471 -74.315511) (xy 112.636256 -74.119012) (xy 112.584753 -73.920353) (xy 112.541039 -73.719835)
			(xy 112.505183 -73.517764) (xy 112.477238 -73.314449) (xy 112.457247 -73.110198) (xy 112.44524 -72.905322)
			(xy 112.441236 -72.700134) (xy 1.524 -72.700134) (xy 1.524 -77.365367) (xy 105.150162 -77.365367)
			(xy 105.150162 -77.305433) (xy 105.157985 -77.246011) (xy 105.173496 -77.188119) (xy 105.19643 -77.132746)
			(xy 105.226396 -77.08084) (xy 105.26288 -77.03329) (xy 105.305258 -76.990908) (xy 105.352805 -76.954419)
			(xy 105.404708 -76.924449) (xy 105.460079 -76.901509) (xy 105.51797 -76.885993) (xy 105.577391 -76.878165)
			(xy 105.607358 -76.877672) (xy 106.470958 -76.877672) (xy 106.500928 -76.878178) (xy 106.560354 -76.885997)
			(xy 106.618252 -76.901506) (xy 106.67363 -76.92444) (xy 106.72554 -76.954406) (xy 106.773095 -76.990892)
			(xy 106.81548 -77.033273) (xy 106.851971 -77.080825) (xy 106.881942 -77.132732) (xy 106.904881 -77.188108)
			(xy 106.920395 -77.246004) (xy 106.928219 -77.305431) (xy 106.928219 -77.365367) (xy 109.150162 -77.365367)
			(xy 109.150162 -77.305433) (xy 109.157984 -77.246012) (xy 109.173495 -77.18812) (xy 109.196429 -77.132748)
			(xy 109.226394 -77.080843) (xy 109.262878 -77.033292) (xy 109.305255 -76.990911) (xy 109.352801 -76.954422)
			(xy 109.404703 -76.924452) (xy 109.460073 -76.901511) (xy 109.517963 -76.885994) (xy 109.577383 -76.878165)
			(xy 109.60735 -76.877672) (xy 110.47095 -76.877672) (xy 110.50092 -76.878178) (xy 110.560347 -76.885996)
			(xy 110.618246 -76.901504) (xy 110.673625 -76.924437) (xy 110.725536 -76.954403) (xy 110.773092 -76.990889)
			(xy 110.815478 -77.03327) (xy 110.851969 -77.080822) (xy 110.881941 -77.13273) (xy 110.90488 -77.188107)
			(xy 110.920395 -77.246003) (xy 110.928219 -77.30543) (xy 110.928219 -77.36537) (xy 110.920395 -77.424797)
			(xy 110.90488 -77.482693) (xy 110.881941 -77.53807) (xy 110.851969 -77.589978) (xy 110.815478 -77.63753)
			(xy 110.773092 -77.679911) (xy 110.725536 -77.716397) (xy 110.673625 -77.746363) (xy 110.618246 -77.769296)
			(xy 110.560347 -77.784804) (xy 110.50092 -77.792622) (xy 110.47095 -77.793088) (xy 109.60735 -77.793088)
			(xy 109.577383 -77.792635) (xy 109.517963 -77.784806) (xy 109.460073 -77.769289) (xy 109.404703 -77.746348)
			(xy 109.352801 -77.716378) (xy 109.305255 -77.679889) (xy 109.262878 -77.637508) (xy 109.226394 -77.589957)
			(xy 109.196429 -77.538052) (xy 109.173495 -77.48268) (xy 109.157984 -77.424788) (xy 109.150162 -77.365367)
			(xy 106.928219 -77.365367) (xy 106.928219 -77.365369) (xy 106.920395 -77.424796) (xy 106.904881 -77.482692)
			(xy 106.881942 -77.538068) (xy 106.851971 -77.589975) (xy 106.81548 -77.637527) (xy 106.773095 -77.679908)
			(xy 106.72554 -77.716394) (xy 106.67363 -77.74636) (xy 106.618252 -77.769294) (xy 106.560354 -77.784803)
			(xy 106.500928 -77.792622) (xy 106.470958 -77.793088) (xy 105.607358 -77.793088) (xy 105.577391 -77.792635)
			(xy 105.51797 -77.784807) (xy 105.460079 -77.769291) (xy 105.404708 -77.746351) (xy 105.352805 -77.716381)
			(xy 105.305258 -77.679892) (xy 105.26288 -77.63751) (xy 105.226396 -77.58996) (xy 105.19643 -77.538054)
			(xy 105.173496 -77.482681) (xy 105.157985 -77.424789) (xy 105.150162 -77.365367) (xy 1.524 -77.365367)
			(xy 1.524 -78.127367) (xy 107.150162 -78.127367) (xy 107.150162 -78.067433) (xy 107.157984 -78.008012)
			(xy 107.173496 -77.950119) (xy 107.19643 -77.894747) (xy 107.226395 -77.842842) (xy 107.262879 -77.795291)
			(xy 107.305256 -77.752909) (xy 107.352803 -77.716421) (xy 107.404706 -77.68645) (xy 107.460076 -77.66351)
			(xy 107.517966 -77.647993) (xy 107.577387 -77.640165) (xy 107.607354 -77.639672) (xy 108.470954 -77.639672)
			(xy 108.500924 -77.640178) (xy 108.560351 -77.647996) (xy 108.618249 -77.663505) (xy 108.673627 -77.686438)
			(xy 108.725538 -77.716405) (xy 108.773094 -77.752891) (xy 108.815479 -77.795272) (xy 108.85197 -77.842823)
			(xy 108.881941 -77.894731) (xy 108.90488 -77.950107) (xy 108.920395 -78.008004) (xy 108.928219 -78.06743)
			(xy 108.928219 -78.12737) (xy 108.920395 -78.186796) (xy 108.90488 -78.244693) (xy 108.881941 -78.300069)
			(xy 108.85197 -78.351977) (xy 108.815479 -78.399528) (xy 108.773093 -78.441909) (xy 108.725538 -78.478395)
			(xy 108.673627 -78.508362) (xy 108.618249 -78.531295) (xy 108.560351 -78.546804) (xy 108.500924 -78.554622)
			(xy 108.470954 -78.555088) (xy 107.607354 -78.555088) (xy 107.577387 -78.554635) (xy 107.517966 -78.546807)
			(xy 107.460076 -78.53129) (xy 107.404706 -78.50835) (xy 107.352803 -78.478379) (xy 107.305256 -78.441891)
			(xy 107.262879 -78.399509) (xy 107.226395 -78.351958) (xy 107.19643 -78.300053) (xy 107.173496 -78.244681)
			(xy 107.157984 -78.186788) (xy 107.150162 -78.127367) (xy 1.524 -78.127367) (xy 1.524 -79.238094)
			(xy 227.9777 -79.238094) (xy 227.9777 -78.374494) (xy 227.97819 -78.344526) (xy 227.986013 -78.285104)
			(xy 228.001526 -78.227211) (xy 228.024462 -78.171838) (xy 228.054429 -78.119932) (xy 228.090916 -78.072382)
			(xy 228.133296 -78.030002) (xy 228.180846 -77.993515) (xy 228.232752 -77.963548) (xy 228.288125 -77.940612)
			(xy 228.346018 -77.925099) (xy 228.40544 -77.917276) (xy 228.465376 -77.917276) (xy 228.524798 -77.925099)
			(xy 228.582691 -77.940612) (xy 228.638064 -77.963548) (xy 228.68997 -77.993515) (xy 228.73752 -78.030002)
			(xy 228.7799 -78.072382) (xy 228.816387 -78.119932) (xy 228.83413 -78.150664) (xy 336.40703 -78.150664)
			(xy 336.40703 -78.090736) (xy 336.414852 -78.031319) (xy 336.430363 -77.973433) (xy 336.453297 -77.918066)
			(xy 336.483261 -77.866166) (xy 336.519743 -77.818621) (xy 336.562119 -77.776245) (xy 336.609664 -77.739762)
			(xy 336.661564 -77.709797) (xy 336.716931 -77.686864) (xy 336.774817 -77.671353) (xy 336.834234 -77.66353)
			(xy 336.864198 -77.66304) (xy 337.727798 -77.66304) (xy 337.75777 -77.663413) (xy 337.817202 -77.671237)
			(xy 337.875104 -77.686751) (xy 337.930486 -77.709691) (xy 337.982399 -77.739663) (xy 338.029957 -77.776155)
			(xy 338.072344 -77.818542) (xy 338.108836 -77.866099) (xy 338.138808 -77.918013) (xy 338.161748 -77.973394)
			(xy 338.177263 -78.031296) (xy 338.185087 -78.090728) (xy 338.185087 -78.150672) (xy 338.177263 -78.210104)
			(xy 338.161748 -78.268006) (xy 338.138808 -78.323387) (xy 338.108836 -78.375301) (xy 338.072344 -78.422858)
			(xy 338.029957 -78.465245) (xy 337.982399 -78.501737) (xy 337.930486 -78.531709) (xy 337.875104 -78.554649)
			(xy 337.817202 -78.570163) (xy 337.75777 -78.577987) (xy 337.727798 -78.578456) (xy 336.864198 -78.578456)
			(xy 336.834234 -78.57787) (xy 336.774817 -78.570047) (xy 336.716931 -78.554536) (xy 336.661564 -78.531603)
			(xy 336.609664 -78.501638) (xy 336.562119 -78.465155) (xy 336.519743 -78.422779) (xy 336.483261 -78.375234)
			(xy 336.453297 -78.323334) (xy 336.430363 -78.267967) (xy 336.414852 -78.210081) (xy 336.40703 -78.150664)
			(xy 228.83413 -78.150664) (xy 228.846354 -78.171838) (xy 228.86929 -78.227211) (xy 228.884803 -78.285104)
			(xy 228.892626 -78.344526) (xy 228.893116 -78.374494) (xy 228.893116 -79.238094) (xy 228.892626 -79.268062)
			(xy 228.884803 -79.327484) (xy 228.86929 -79.385377) (xy 228.846354 -79.44075) (xy 228.816387 -79.492656)
			(xy 228.7799 -79.540206) (xy 228.73752 -79.582586) (xy 228.68997 -79.619073) (xy 228.638064 -79.64904)
			(xy 228.582691 -79.671976) (xy 228.524798 -79.687489) (xy 228.465376 -79.695312) (xy 228.40544 -79.695312)
			(xy 228.346018 -79.687489) (xy 228.288125 -79.671976) (xy 228.232752 -79.64904) (xy 228.180846 -79.619073)
			(xy 228.133296 -79.582586) (xy 228.090916 -79.540206) (xy 228.054429 -79.492656) (xy 228.024462 -79.44075)
			(xy 228.001526 -79.385377) (xy 227.986013 -79.327484) (xy 227.97819 -79.268062) (xy 227.9777 -79.238094)
			(xy 1.524 -79.238094) (xy 1.524 -82.131662) (xy 1.524528 -82.162804) (xy 1.532692 -82.224552) (xy 1.54884 -82.284707)
			(xy 1.572698 -82.342242) (xy 1.603856 -82.396173) (xy 1.641783 -82.445579) (xy 1.663446 -82.467958)
			(xy 1.678178 -82.482944) (xy 1.678432 -82.483198) (xy 3.894875 -84.699856) (xy 13.541002 -84.699856)
			(xy 13.545006 -84.494668) (xy 13.557013 -84.289792) (xy 13.577004 -84.085541) (xy 13.604949 -83.882226)
			(xy 13.640805 -83.680155) (xy 13.684519 -83.479637) (xy 13.736022 -83.280978) (xy 13.795237 -83.084479)
			(xy 13.862073 -82.89044) (xy 13.936429 -82.699157) (xy 14.018192 -82.51092) (xy 14.107237 -82.326017)
			(xy 14.203428 -82.144729) (xy 14.306619 -81.967332) (xy 14.416653 -81.794095) (xy 14.533362 -81.625284)
			(xy 14.656568 -81.461155) (xy 14.786085 -81.301958) (xy 14.921714 -81.147936) (xy 15.063249 -80.999322)
			(xy 15.210474 -80.856344) (xy 15.363166 -80.719219) (xy 15.521092 -80.588155) (xy 15.684011 -80.463353)
			(xy 15.851676 -80.345003) (xy 16.02383 -80.233284) (xy 16.200212 -80.128367) (xy 16.380553 -80.030412)
			(xy 16.564579 -79.939568) (xy 16.752009 -79.855972) (xy 16.942558 -79.779753) (xy 17.135935 -79.711027)
			(xy 17.331847 -79.649898) (xy 17.529994 -79.596459) (xy 17.730076 -79.550792) (xy 17.931787 -79.512965)
			(xy 18.13482 -79.483038) (xy 18.338867 -79.461055) (xy 18.543616 -79.44705) (xy 18.748755 -79.441044)
			(xy 18.953972 -79.443046) (xy 19.158955 -79.453054) (xy 19.363392 -79.471051) (xy 19.56697 -79.497011)
			(xy 19.769381 -79.530894) (xy 19.970315 -79.572649) (xy 20.169468 -79.622212) (xy 20.366535 -79.679507)
			(xy 20.561217 -79.744447) (xy 20.753217 -79.816933) (xy 20.942242 -79.896856) (xy 21.128005 -79.984092)
			(xy 21.310223 -80.07851) (xy 21.488619 -80.179965) (xy 21.494277 -80.183482) (xy 237.540292 -80.183482)
			(xy 237.540292 -79.319882) (xy 237.540782 -79.289914) (xy 237.548605 -79.230492) (xy 237.564118 -79.172599)
			(xy 237.587054 -79.117226) (xy 237.617021 -79.06532) (xy 237.653508 -79.01777) (xy 237.695888 -78.97539)
			(xy 237.743438 -78.938903) (xy 237.795344 -78.908936) (xy 237.850717 -78.886) (xy 237.90861 -78.870487)
			(xy 237.968032 -78.862664) (xy 238.027968 -78.862664) (xy 238.08739 -78.870487) (xy 238.145283 -78.886)
			(xy 238.200656 -78.908936) (xy 238.207117 -78.912666) (xy 334.407009 -78.912666) (xy 334.407009 -78.852734)
			(xy 334.414832 -78.793315) (xy 334.430343 -78.735425) (xy 334.453278 -78.680055) (xy 334.483244 -78.628153)
			(xy 334.519729 -78.580606) (xy 334.562107 -78.538227) (xy 334.609654 -78.501743) (xy 334.661557 -78.471777)
			(xy 334.716927 -78.448843) (xy 334.774817 -78.433331) (xy 334.834236 -78.425509) (xy 334.864202 -78.42504)
			(xy 335.727802 -78.42504) (xy 335.757773 -78.425434) (xy 335.817201 -78.433258) (xy 335.8751 -78.448773)
			(xy 335.930479 -78.471711) (xy 335.982389 -78.501682) (xy 336.029944 -78.538172) (xy 336.072329 -78.580557)
			(xy 336.108819 -78.628112) (xy 336.13879 -78.680023) (xy 336.161728 -78.735402) (xy 336.177242 -78.793301)
			(xy 336.185066 -78.852729) (xy 336.185066 -78.912664) (xy 338.40703 -78.912664) (xy 338.40703 -78.852736)
			(xy 338.414852 -78.79332) (xy 338.430363 -78.735433) (xy 338.453296 -78.680067) (xy 338.48326 -78.628167)
			(xy 338.519742 -78.580622) (xy 338.562118 -78.538246) (xy 338.609662 -78.501763) (xy 338.661561 -78.471799)
			(xy 338.716928 -78.448865) (xy 338.774814 -78.433353) (xy 338.83423 -78.42553) (xy 338.864194 -78.42504)
			(xy 339.727794 -78.42504) (xy 339.757766 -78.425412) (xy 339.817199 -78.433236) (xy 339.875101 -78.44875)
			(xy 339.930483 -78.47169) (xy 339.982397 -78.501662) (xy 340.029955 -78.538153) (xy 340.072343 -78.580541)
			(xy 340.108835 -78.628098) (xy 340.138808 -78.680011) (xy 340.161748 -78.735393) (xy 340.177263 -78.793296)
			(xy 340.185087 -78.852728) (xy 340.185087 -78.912672) (xy 340.177263 -78.972104) (xy 340.161748 -79.030007)
			(xy 340.138808 -79.085389) (xy 340.108835 -79.137302) (xy 340.072343 -79.184859) (xy 340.029955 -79.227247)
			(xy 339.982397 -79.263738) (xy 339.930483 -79.29371) (xy 339.875101 -79.31665) (xy 339.817199 -79.332164)
			(xy 339.757766 -79.339988) (xy 339.727794 -79.340456) (xy 338.864194 -79.340456) (xy 338.83423 -79.33987)
			(xy 338.774814 -79.332047) (xy 338.716928 -79.316535) (xy 338.661561 -79.293601) (xy 338.609662 -79.263637)
			(xy 338.562118 -79.227154) (xy 338.519742 -79.184778) (xy 338.48326 -79.137233) (xy 338.453296 -79.085333)
			(xy 338.430363 -79.029967) (xy 338.414852 -78.97208) (xy 338.40703 -78.912664) (xy 336.185066 -78.912664)
			(xy 336.185066 -78.912671) (xy 336.177242 -78.972099) (xy 336.161728 -79.029998) (xy 336.13879 -79.085377)
			(xy 336.108819 -79.137288) (xy 336.072329 -79.184843) (xy 336.029944 -79.227228) (xy 335.982389 -79.263718)
			(xy 335.930479 -79.293689) (xy 335.8751 -79.316627) (xy 335.817201 -79.332142) (xy 335.757773 -79.339966)
			(xy 335.727802 -79.340456) (xy 334.864202 -79.340456) (xy 334.834236 -79.339891) (xy 334.774817 -79.332069)
			(xy 334.716927 -79.316557) (xy 334.661557 -79.293623) (xy 334.609654 -79.263657) (xy 334.562107 -79.227173)
			(xy 334.519729 -79.184794) (xy 334.483244 -79.137247) (xy 334.453278 -79.085345) (xy 334.430343 -79.029975)
			(xy 334.414832 -78.972085) (xy 334.407009 -78.912666) (xy 238.207117 -78.912666) (xy 238.252562 -78.938903)
			(xy 238.300112 -78.97539) (xy 238.342492 -79.01777) (xy 238.378979 -79.06532) (xy 238.408946 -79.117226)
			(xy 238.431882 -79.172599) (xy 238.447395 -79.230492) (xy 238.455218 -79.289914) (xy 238.455708 -79.319882)
			(xy 238.455708 -80.183482) (xy 238.455218 -80.21345) (xy 238.447395 -80.272872) (xy 238.431882 -80.330765)
			(xy 238.408946 -80.386138) (xy 238.378979 -80.438044) (xy 238.342492 -80.485594) (xy 238.300112 -80.527974)
			(xy 238.252562 -80.564461) (xy 238.200656 -80.594428) (xy 238.145283 -80.617364) (xy 238.08739 -80.632877)
			(xy 238.027968 -80.6407) (xy 237.968032 -80.6407) (xy 237.90861 -80.632877) (xy 237.850717 -80.617364)
			(xy 237.795344 -80.594428) (xy 237.743438 -80.564461) (xy 237.695888 -80.527974) (xy 237.653508 -80.485594)
			(xy 237.617021 -80.438044) (xy 237.587054 -80.386138) (xy 237.564118 -80.330765) (xy 237.548605 -80.272872)
			(xy 237.540782 -80.21345) (xy 237.540292 -80.183482) (xy 21.494277 -80.183482) (xy 21.66292 -80.288304)
			(xy 21.832862 -80.40336) (xy 21.998185 -80.52496) (xy 22.158638 -80.652917) (xy 22.313977 -80.787036)
			(xy 22.463964 -80.927115) (xy 22.608372 -81.072939) (xy 22.74698 -81.224285) (xy 22.879578 -81.380925)
			(xy 23.005964 -81.542619) (xy 23.125944 -81.709121) (xy 23.239337 -81.880177) (xy 23.34597 -82.055527)
			(xy 23.44568 -82.234904) (xy 23.538316 -82.418034) (xy 23.623736 -82.60464) (xy 23.70181 -82.794436)
			(xy 23.77242 -82.987134) (xy 23.835457 -83.18244) (xy 23.890827 -83.380056) (xy 23.938444 -83.579683)
			(xy 23.978236 -83.781015) (xy 24.010143 -83.983747) (xy 24.034116 -84.187569) (xy 24.050118 -84.392172)
			(xy 24.058125 -84.597242) (xy 24.058626 -84.699856) (xy 24.058125 -84.80247) (xy 24.050118 -85.00754)
			(xy 24.04871 -85.025538) (xy 44.856389 -85.025538) (xy 44.856389 -84.896398) (xy 44.864339 -84.767503)
			(xy 44.880209 -84.639343) (xy 44.903938 -84.512402) (xy 44.935437 -84.387163) (xy 44.974586 -84.2641)
			(xy 45.021237 -84.143681) (xy 45.075212 -84.026362) (xy 45.136307 -83.912588) (xy 45.20429 -83.802791)
			(xy 45.278904 -83.697388) (xy 45.359865 -83.596778) (xy 45.446865 -83.501343) (xy 45.539576 -83.411444)
			(xy 45.637646 -83.327423) (xy 45.740701 -83.249599) (xy 45.848352 -83.178267) (xy 45.960191 -83.113697)
			(xy 46.075792 -83.056135) (xy 46.194717 -83.005798) (xy 46.316516 -82.962878) (xy 46.440726 -82.927537)
			(xy 46.566875 -82.89991) (xy 46.694487 -82.880101) (xy 46.823076 -82.868185) (xy 46.952154 -82.864209)
			(xy 47.081232 -82.868185) (xy 47.209821 -82.880101) (xy 47.337433 -82.89991) (xy 47.463582 -82.927537)
			(xy 47.587792 -82.962878) (xy 47.709591 -83.005798) (xy 47.828516 -83.056135) (xy 47.944117 -83.113697)
			(xy 48.055956 -83.178267) (xy 48.163607 -83.249599) (xy 48.266662 -83.327423) (xy 48.303507 -83.35899)
			(xy 116.623592 -83.35899) (xy 116.623592 -82.49539) (xy 116.624082 -82.465422) (xy 116.631905 -82.406)
			(xy 116.647418 -82.348107) (xy 116.670354 -82.292734) (xy 116.700321 -82.240828) (xy 116.736808 -82.193278)
			(xy 116.779188 -82.150898) (xy 116.826738 -82.114411) (xy 116.878644 -82.084444) (xy 116.934017 -82.061508)
			(xy 116.99191 -82.045995) (xy 117.051332 -82.038172) (xy 117.111268 -82.038172) (xy 117.17069 -82.045995)
			(xy 117.228583 -82.061508) (xy 117.283956 -82.084444) (xy 117.335862 -82.114411) (xy 117.383412 -82.150898)
			(xy 117.425792 -82.193278) (xy 117.462279 -82.240828) (xy 117.492246 -82.292734) (xy 117.515182 -82.348107)
			(xy 117.530695 -82.406) (xy 117.538518 -82.465422) (xy 117.539008 -82.49539) (xy 117.539008 -83.35899)
			(xy 117.538875 -83.367118) (xy 232.68432 -83.367118) (xy 232.68432 -82.503518) (xy 232.68481 -82.47355)
			(xy 232.692633 -82.414128) (xy 232.708146 -82.356235) (xy 232.731082 -82.300862) (xy 232.761049 -82.248956)
			(xy 232.797536 -82.201406) (xy 232.839916 -82.159026) (xy 232.887466 -82.122539) (xy 232.939372 -82.092572)
			(xy 232.994745 -82.069636) (xy 233.052638 -82.054123) (xy 233.11206 -82.0463) (xy 233.171996 -82.0463)
			(xy 233.231418 -82.054123) (xy 233.289311 -82.069636) (xy 233.344684 -82.092572) (xy 233.39659 -82.122539)
			(xy 233.44414 -82.159026) (xy 233.48652 -82.201406) (xy 233.523007 -82.248956) (xy 233.552974 -82.300862)
			(xy 233.568014 -82.337171) (xy 238.132537 -82.337171) (xy 238.132537 -82.277229) (xy 238.140362 -82.217799)
			(xy 238.155876 -82.159898) (xy 238.178816 -82.104519) (xy 238.208788 -82.052607) (xy 238.24528 -82.005052)
			(xy 238.287667 -81.962667) (xy 238.335224 -81.926177) (xy 238.387137 -81.896207) (xy 238.442517 -81.87327)
			(xy 238.500418 -81.857758) (xy 238.559849 -81.849936) (xy 238.58982 -81.849468) (xy 239.45342 -81.849468)
			(xy 239.483385 -81.850007) (xy 239.542803 -81.857832) (xy 239.600691 -81.873345) (xy 239.656058 -81.896282)
			(xy 239.707959 -81.926248) (xy 239.755504 -81.962733) (xy 239.769238 -81.976468) (xy 273.798284 -81.976468)
			(xy 273.798284 -81.112868) (xy 273.798774 -81.0829) (xy 273.806597 -81.023478) (xy 273.82211 -80.965585)
			(xy 273.845046 -80.910212) (xy 273.875013 -80.858306) (xy 273.9115 -80.810756) (xy 273.95388 -80.768376)
			(xy 274.00143 -80.731889) (xy 274.053336 -80.701922) (xy 274.108709 -80.678986) (xy 274.166602 -80.663473)
			(xy 274.226024 -80.65565) (xy 274.28596 -80.65565) (xy 274.345382 -80.663473) (xy 274.403275 -80.678986)
			(xy 274.458648 -80.701922) (xy 274.510554 -80.731889) (xy 274.558104 -80.768376) (xy 274.600484 -80.810756)
			(xy 274.636971 -80.858306) (xy 274.666938 -80.910212) (xy 274.689874 -80.965585) (xy 274.705387 -81.023478)
			(xy 274.71321 -81.0829) (xy 274.7137 -81.112868) (xy 274.7137 -81.976468) (xy 274.71321 -82.006436)
			(xy 274.705387 -82.065858) (xy 274.689874 -82.123751) (xy 274.666938 -82.179124) (xy 274.636971 -82.23103)
			(xy 274.600484 -82.27858) (xy 274.558104 -82.32096) (xy 274.510554 -82.357447) (xy 274.458648 -82.387414)
			(xy 274.403275 -82.41035) (xy 274.345382 -82.425863) (xy 274.28596 -82.433686) (xy 274.226024 -82.433686)
			(xy 274.166602 -82.425863) (xy 274.108709 -82.41035) (xy 274.053336 -82.387414) (xy 274.00143 -82.357447)
			(xy 273.95388 -82.32096) (xy 273.9115 -82.27858) (xy 273.875013 -82.23103) (xy 273.845046 -82.179124)
			(xy 273.82211 -82.123751) (xy 273.806597 -82.065858) (xy 273.798774 -82.006436) (xy 273.798284 -81.976468)
			(xy 239.769238 -81.976468) (xy 239.79788 -82.005111) (xy 239.834363 -82.052658) (xy 239.864327 -82.10456)
			(xy 239.887261 -82.159928) (xy 239.902772 -82.217817) (xy 239.910594 -82.277235) (xy 239.910594 -82.337165)
			(xy 239.902772 -82.396583) (xy 239.887261 -82.454472) (xy 239.864327 -82.50984) (xy 239.834363 -82.561742)
			(xy 239.79788 -82.609289) (xy 239.755504 -82.651667) (xy 239.707959 -82.688152) (xy 239.656058 -82.718118)
			(xy 239.600691 -82.741055) (xy 239.542803 -82.756568) (xy 239.483385 -82.764393) (xy 239.45342 -82.764884)
			(xy 238.58982 -82.764884) (xy 238.559849 -82.764464) (xy 238.500418 -82.756642) (xy 238.442517 -82.74113)
			(xy 238.387137 -82.718193) (xy 238.335224 -82.688223) (xy 238.287667 -82.651733) (xy 238.24528 -82.609348)
			(xy 238.208788 -82.561793) (xy 238.178816 -82.509881) (xy 238.155876 -82.454502) (xy 238.140362 -82.396601)
			(xy 238.132537 -82.337171) (xy 233.568014 -82.337171) (xy 233.57591 -82.356235) (xy 233.591423 -82.414128)
			(xy 233.599246 -82.47355) (xy 233.599736 -82.503518) (xy 233.599736 -83.367118) (xy 233.599246 -83.397086)
			(xy 233.591423 -83.456508) (xy 233.57591 -83.514401) (xy 233.552974 -83.569774) (xy 233.523007 -83.62168)
			(xy 233.48652 -83.66923) (xy 233.44414 -83.71161) (xy 233.39659 -83.748097) (xy 233.344684 -83.778064)
			(xy 233.289311 -83.801) (xy 233.231418 -83.816513) (xy 233.171996 -83.824336) (xy 233.11206 -83.824336)
			(xy 233.052638 -83.816513) (xy 232.994745 -83.801) (xy 232.939372 -83.778064) (xy 232.887466 -83.748097)
			(xy 232.839916 -83.71161) (xy 232.797536 -83.66923) (xy 232.761049 -83.62168) (xy 232.731082 -83.569774)
			(xy 232.708146 -83.514401) (xy 232.692633 -83.456508) (xy 232.68481 -83.397086) (xy 232.68432 -83.367118)
			(xy 117.538875 -83.367118) (xy 117.538518 -83.388958) (xy 117.530695 -83.44838) (xy 117.515182 -83.506273)
			(xy 117.492246 -83.561646) (xy 117.462279 -83.613552) (xy 117.425792 -83.661102) (xy 117.383412 -83.703482)
			(xy 117.335862 -83.739969) (xy 117.283956 -83.769936) (xy 117.228583 -83.792872) (xy 117.17069 -83.808385)
			(xy 117.111268 -83.816208) (xy 117.051332 -83.816208) (xy 116.99191 -83.808385) (xy 116.934017 -83.792872)
			(xy 116.878644 -83.769936) (xy 116.826738 -83.739969) (xy 116.779188 -83.703482) (xy 116.736808 -83.661102)
			(xy 116.700321 -83.613552) (xy 116.670354 -83.561646) (xy 116.647418 -83.506273) (xy 116.631905 -83.44838)
			(xy 116.624082 -83.388958) (xy 116.623592 -83.35899) (xy 48.303507 -83.35899) (xy 48.364732 -83.411444)
			(xy 48.457443 -83.501343) (xy 48.544443 -83.596778) (xy 48.625404 -83.697388) (xy 48.700018 -83.802791)
			(xy 48.768001 -83.912588) (xy 48.829096 -84.026362) (xy 48.883071 -84.143681) (xy 48.929722 -84.2641)
			(xy 48.968871 -84.387163) (xy 49.00037 -84.512402) (xy 49.024099 -84.639343) (xy 49.039969 -84.767503)
			(xy 49.047919 -84.896398) (xy 49.048416 -84.960968) (xy 49.047919 -85.025538) (xy 49.039969 -85.154433)
			(xy 49.024099 -85.282593) (xy 49.009819 -85.358986) (xy 117.385592 -85.358986) (xy 117.385592 -84.495386)
			(xy 117.386082 -84.465418) (xy 117.393905 -84.405996) (xy 117.409418 -84.348103) (xy 117.432354 -84.29273)
			(xy 117.462321 -84.240824) (xy 117.498808 -84.193274) (xy 117.541188 -84.150894) (xy 117.588738 -84.114407)
			(xy 117.640644 -84.08444) (xy 117.696017 -84.061504) (xy 117.75391 -84.045991) (xy 117.813332 -84.038168)
			(xy 117.873268 -84.038168) (xy 117.93269 -84.045991) (xy 117.990583 -84.061504) (xy 118.045956 -84.08444)
			(xy 118.097862 -84.114407) (xy 118.145412 -84.150894) (xy 118.187792 -84.193274) (xy 118.224279 -84.240824)
			(xy 118.254246 -84.29273) (xy 118.277182 -84.348103) (xy 118.292695 -84.405996) (xy 118.300518 -84.465418)
			(xy 118.301008 -84.495386) (xy 118.301008 -85.358986) (xy 118.300518 -85.388954) (xy 118.292695 -85.448376)
			(xy 118.289959 -85.458587) (xy 232.264389 -85.458587) (xy 232.264389 -85.398613) (xy 232.272218 -85.339151)
			(xy 232.28774 -85.28122) (xy 232.310692 -85.225811) (xy 232.34068 -85.173871) (xy 232.377191 -85.126291)
			(xy 232.4196 -85.083883) (xy 232.467181 -85.047373) (xy 232.519122 -85.017387) (xy 232.574531 -84.994437)
			(xy 232.632463 -84.978915) (xy 232.691925 -84.971088) (xy 232.721912 -84.97062) (xy 233.585512 -84.97062)
			(xy 233.615495 -84.971147) (xy 233.674947 -84.978975) (xy 233.732868 -84.994497) (xy 233.788268 -85.017445)
			(xy 233.840199 -85.047429) (xy 233.887772 -85.083934) (xy 233.930174 -85.126337) (xy 233.963295 -85.169502)
			(xy 238.555276 -85.169502) (xy 238.555276 -84.305902) (xy 238.555766 -84.275918) (xy 238.563594 -84.216462)
			(xy 238.579115 -84.158537) (xy 238.602064 -84.103133) (xy 238.632048 -84.051199) (xy 238.668554 -84.003623)
			(xy 238.710959 -83.961218) (xy 238.758535 -83.924712) (xy 238.810469 -83.894728) (xy 238.865873 -83.871779)
			(xy 238.923798 -83.856258) (xy 238.983254 -83.84843) (xy 239.043222 -83.84843) (xy 239.102678 -83.856258)
			(xy 239.160603 -83.871779) (xy 239.216007 -83.894728) (xy 239.267941 -83.924712) (xy 239.315517 -83.961218)
			(xy 239.357922 -84.003623) (xy 239.394428 -84.051199) (xy 239.424412 -84.103133) (xy 239.447361 -84.158537)
			(xy 239.462882 -84.216462) (xy 239.46603 -84.24037) (xy 273.951192 -84.24037) (xy 273.951192 -83.37677)
			(xy 273.951682 -83.346786) (xy 273.95951 -83.28733) (xy 273.975031 -83.229405) (xy 273.99798 -83.174001)
			(xy 274.027964 -83.122067) (xy 274.06447 -83.074491) (xy 274.106875 -83.032086) (xy 274.154451 -82.99558)
			(xy 274.206385 -82.965596) (xy 274.261789 -82.942647) (xy 274.319714 -82.927126) (xy 274.37917 -82.919298)
			(xy 274.439138 -82.919298) (xy 274.498594 -82.927126) (xy 274.556519 -82.942647) (xy 274.611923 -82.965596)
			(xy 274.663857 -82.99558) (xy 274.711433 -83.032086) (xy 274.753838 -83.074491) (xy 274.790344 -83.122067)
			(xy 274.820328 -83.174001) (xy 274.843277 -83.229405) (xy 274.858798 -83.28733) (xy 274.866626 -83.346786)
			(xy 274.867116 -83.37677) (xy 274.867116 -84.144612) (xy 345.879928 -84.144612) (xy 345.879928 -83.281012)
			(xy 345.880418 -83.251028) (xy 345.888246 -83.191572) (xy 345.903767 -83.133647) (xy 345.926716 -83.078243)
			(xy 345.9567 -83.026309) (xy 345.993206 -82.978733) (xy 346.035611 -82.936328) (xy 346.083187 -82.899822)
			(xy 346.135121 -82.869838) (xy 346.190525 -82.846889) (xy 346.24845 -82.831368) (xy 346.307906 -82.82354)
			(xy 346.367874 -82.82354) (xy 346.42733 -82.831368) (xy 346.485255 -82.846889) (xy 346.540659 -82.869838)
			(xy 346.592593 -82.899822) (xy 346.640169 -82.936328) (xy 346.682574 -82.978733) (xy 346.71908 -83.026309)
			(xy 346.749064 -83.078243) (xy 346.772013 -83.133647) (xy 346.787534 -83.191572) (xy 346.795362 -83.251028)
			(xy 346.795852 -83.281012) (xy 346.795852 -84.144612) (xy 346.795362 -84.174596) (xy 346.787534 -84.234052)
			(xy 346.772013 -84.291977) (xy 346.749064 -84.347381) (xy 346.71908 -84.399315) (xy 346.682574 -84.446891)
			(xy 346.640169 -84.489296) (xy 346.592593 -84.525802) (xy 346.540659 -84.555786) (xy 346.485255 -84.578735)
			(xy 346.42733 -84.594256) (xy 346.367874 -84.602084) (xy 346.307906 -84.602084) (xy 346.24845 -84.594256)
			(xy 346.190525 -84.578735) (xy 346.135121 -84.555786) (xy 346.083187 -84.525802) (xy 346.035611 -84.489296)
			(xy 345.993206 -84.446891) (xy 345.9567 -84.399315) (xy 345.926716 -84.347381) (xy 345.903767 -84.291977)
			(xy 345.888246 -84.234052) (xy 345.880418 -84.174596) (xy 345.879928 -84.144612) (xy 274.867116 -84.144612)
			(xy 274.867116 -84.24037) (xy 274.866626 -84.270354) (xy 274.858798 -84.32981) (xy 274.843277 -84.387735)
			(xy 274.820328 -84.443139) (xy 274.790344 -84.495073) (xy 274.753838 -84.542649) (xy 274.711433 -84.585054)
			(xy 274.663857 -84.62156) (xy 274.611923 -84.651544) (xy 274.556519 -84.674493) (xy 274.498594 -84.690014)
			(xy 274.439138 -84.697842) (xy 274.37917 -84.697842) (xy 274.319714 -84.690014) (xy 274.261789 -84.674493)
			(xy 274.206385 -84.651544) (xy 274.154451 -84.62156) (xy 274.106875 -84.585054) (xy 274.06447 -84.542649)
			(xy 274.027964 -84.495073) (xy 273.99798 -84.443139) (xy 273.975031 -84.387735) (xy 273.95951 -84.32981)
			(xy 273.951682 -84.270354) (xy 273.951192 -84.24037) (xy 239.46603 -84.24037) (xy 239.47071 -84.275918)
			(xy 239.4712 -84.305902) (xy 239.4712 -84.699856) (xy 443.540904 -84.699856) (xy 443.544908 -84.494668)
			(xy 443.556915 -84.289792) (xy 443.576906 -84.085541) (xy 443.604851 -83.882226) (xy 443.640707 -83.680155)
			(xy 443.684421 -83.479637) (xy 443.735924 -83.280978) (xy 443.795139 -83.084479) (xy 443.861975 -82.89044)
			(xy 443.936331 -82.699157) (xy 444.018094 -82.51092) (xy 444.107139 -82.326017) (xy 444.20333 -82.144729)
			(xy 444.306521 -81.967332) (xy 444.416555 -81.794095) (xy 444.533264 -81.625284) (xy 444.65647 -81.461155)
			(xy 444.785987 -81.301958) (xy 444.921616 -81.147936) (xy 445.063151 -80.999322) (xy 445.210376 -80.856344)
			(xy 445.363068 -80.719219) (xy 445.520994 -80.588155) (xy 445.683913 -80.463353) (xy 445.851578 -80.345003)
			(xy 446.023732 -80.233284) (xy 446.200114 -80.128367) (xy 446.380455 -80.030412) (xy 446.564481 -79.939568)
			(xy 446.751911 -79.855972) (xy 446.94246 -79.779753) (xy 447.135837 -79.711027) (xy 447.331749 -79.649898)
			(xy 447.529896 -79.596459) (xy 447.729978 -79.550792) (xy 447.931689 -79.512965) (xy 448.134722 -79.483038)
			(xy 448.338769 -79.461055) (xy 448.543518 -79.44705) (xy 448.748657 -79.441044) (xy 448.953874 -79.443046)
			(xy 449.158857 -79.453054) (xy 449.363294 -79.471051) (xy 449.566872 -79.497011) (xy 449.769283 -79.530894)
			(xy 449.970217 -79.572649) (xy 450.16937 -79.622212) (xy 450.366437 -79.679507) (xy 450.561119 -79.744447)
			(xy 450.753119 -79.816933) (xy 450.942144 -79.896856) (xy 451.127907 -79.984092) (xy 451.310125 -80.07851)
			(xy 451.488521 -80.179965) (xy 451.662822 -80.288304) (xy 451.832764 -80.40336) (xy 451.998087 -80.52496)
			(xy 452.15854 -80.652917) (xy 452.313879 -80.787036) (xy 452.463866 -80.927115) (xy 452.608274 -81.072939)
			(xy 452.746882 -81.224285) (xy 452.87948 -81.380925) (xy 453.005866 -81.542619) (xy 453.125846 -81.709121)
			(xy 453.239239 -81.880177) (xy 453.345872 -82.055527) (xy 453.445582 -82.234904) (xy 453.538218 -82.418034)
			(xy 453.623638 -82.60464) (xy 453.701712 -82.794436) (xy 453.772322 -82.987134) (xy 453.835359 -83.18244)
			(xy 453.890729 -83.380056) (xy 453.938346 -83.579683) (xy 453.978138 -83.781015) (xy 454.010045 -83.983747)
			(xy 454.034018 -84.187569) (xy 454.05002 -84.392172) (xy 454.058027 -84.597242) (xy 454.058528 -84.699856)
			(xy 454.058027 -84.80247) (xy 454.05002 -85.00754) (xy 454.034018 -85.212143) (xy 454.010045 -85.415965)
			(xy 453.978138 -85.618697) (xy 453.938346 -85.820029) (xy 453.890729 -86.019656) (xy 453.835359 -86.217272)
			(xy 453.772322 -86.412578) (xy 453.701712 -86.605276) (xy 453.623638 -86.795072) (xy 453.538218 -86.981678)
			(xy 453.445582 -87.164808) (xy 453.345872 -87.344185) (xy 453.239239 -87.519535) (xy 453.125846 -87.690591)
			(xy 453.005866 -87.857093) (xy 452.87948 -88.018787) (xy 452.746882 -88.175427) (xy 452.608274 -88.326773)
			(xy 452.463866 -88.472597) (xy 452.313879 -88.612676) (xy 452.15854 -88.746795) (xy 451.998087 -88.874752)
			(xy 451.832764 -88.996352) (xy 451.662822 -89.111408) (xy 451.488521 -89.219747) (xy 451.310125 -89.321202)
			(xy 451.127907 -89.41562) (xy 450.942144 -89.502856) (xy 450.753119 -89.582779) (xy 450.561119 -89.655265)
			(xy 450.366437 -89.720205) (xy 450.16937 -89.7775) (xy 449.970217 -89.827063) (xy 449.769283 -89.868818)
			(xy 449.566872 -89.902701) (xy 449.363294 -89.928661) (xy 449.158857 -89.946658) (xy 448.953874 -89.956666)
			(xy 448.748657 -89.958668) (xy 448.543518 -89.952662) (xy 448.338769 -89.938657) (xy 448.134722 -89.916674)
			(xy 447.931689 -89.886747) (xy 447.729978 -89.84892) (xy 447.529896 -89.803253) (xy 447.331749 -89.749814)
			(xy 447.135837 -89.688685) (xy 446.94246 -89.619959) (xy 446.751911 -89.54374) (xy 446.564481 -89.460144)
			(xy 446.380455 -89.3693) (xy 446.200114 -89.271345) (xy 446.023732 -89.166428) (xy 445.851578 -89.054709)
			(xy 445.683913 -88.936359) (xy 445.520994 -88.811557) (xy 445.363068 -88.680493) (xy 445.210376 -88.543368)
			(xy 445.063151 -88.40039) (xy 444.921616 -88.251776) (xy 444.785987 -88.097754) (xy 444.65647 -87.938557)
			(xy 444.533264 -87.774428) (xy 444.416555 -87.605617) (xy 444.306521 -87.43238) (xy 444.20333 -87.254983)
			(xy 444.107139 -87.073695) (xy 444.018094 -86.888792) (xy 443.936331 -86.700555) (xy 443.861975 -86.509272)
			(xy 443.795139 -86.315233) (xy 443.735924 -86.118734) (xy 443.684421 -85.920075) (xy 443.640707 -85.719557)
			(xy 443.604851 -85.517486) (xy 443.576906 -85.314171) (xy 443.556915 -85.10992) (xy 443.544908 -84.905044)
			(xy 443.540904 -84.699856) (xy 239.4712 -84.699856) (xy 239.4712 -85.169502) (xy 239.47071 -85.199486)
			(xy 239.462882 -85.258942) (xy 239.447361 -85.316867) (xy 239.424412 -85.372271) (xy 239.394428 -85.424205)
			(xy 239.357922 -85.471781) (xy 239.315517 -85.514186) (xy 239.267941 -85.550692) (xy 239.216007 -85.580676)
			(xy 239.160603 -85.603625) (xy 239.102678 -85.619146) (xy 239.043222 -85.626974) (xy 238.983254 -85.626974)
			(xy 238.923798 -85.619146) (xy 238.865873 -85.603625) (xy 238.810469 -85.580676) (xy 238.758535 -85.550692)
			(xy 238.710959 -85.514186) (xy 238.668554 -85.471781) (xy 238.632048 -85.424205) (xy 238.602064 -85.372271)
			(xy 238.579115 -85.316867) (xy 238.563594 -85.258942) (xy 238.555766 -85.199486) (xy 238.555276 -85.169502)
			(xy 233.963295 -85.169502) (xy 233.966678 -85.173911) (xy 233.99666 -85.225842) (xy 234.019607 -85.281243)
			(xy 234.035127 -85.339165) (xy 234.042954 -85.398617) (xy 234.042954 -85.458583) (xy 234.035127 -85.518035)
			(xy 234.019607 -85.575957) (xy 233.99666 -85.631358) (xy 233.966678 -85.683289) (xy 233.930174 -85.730863)
			(xy 233.887772 -85.773266) (xy 233.840199 -85.809771) (xy 233.788268 -85.839755) (xy 233.732868 -85.862703)
			(xy 233.674947 -85.878225) (xy 233.615495 -85.886053) (xy 233.585512 -85.886544) (xy 232.721912 -85.886544)
			(xy 232.691925 -85.886112) (xy 232.632463 -85.878285) (xy 232.574531 -85.862763) (xy 232.519122 -85.839813)
			(xy 232.467181 -85.809827) (xy 232.4196 -85.773317) (xy 232.377191 -85.730909) (xy 232.34068 -85.683329)
			(xy 232.310692 -85.631389) (xy 232.28774 -85.57598) (xy 232.272218 -85.518049) (xy 232.264389 -85.458587)
			(xy 118.289959 -85.458587) (xy 118.277182 -85.506269) (xy 118.254246 -85.561642) (xy 118.224279 -85.613548)
			(xy 118.187792 -85.661098) (xy 118.145412 -85.703478) (xy 118.097862 -85.739965) (xy 118.045956 -85.769932)
			(xy 117.990583 -85.792868) (xy 117.93269 -85.808381) (xy 117.873268 -85.816204) (xy 117.813332 -85.816204)
			(xy 117.75391 -85.808381) (xy 117.696017 -85.792868) (xy 117.640644 -85.769932) (xy 117.588738 -85.739965)
			(xy 117.541188 -85.703478) (xy 117.498808 -85.661098) (xy 117.462321 -85.613548) (xy 117.432354 -85.561642)
			(xy 117.409418 -85.506269) (xy 117.393905 -85.448376) (xy 117.386082 -85.388954) (xy 117.385592 -85.358986)
			(xy 49.009819 -85.358986) (xy 49.00037 -85.409534) (xy 48.968871 -85.534773) (xy 48.929722 -85.657836)
			(xy 48.883071 -85.778255) (xy 48.829096 -85.895574) (xy 48.768001 -86.009348) (xy 48.700018 -86.119145)
			(xy 48.625404 -86.224548) (xy 48.544443 -86.325158) (xy 48.457443 -86.420593) (xy 48.364732 -86.510492)
			(xy 48.266662 -86.594513) (xy 48.163607 -86.672337) (xy 48.055956 -86.743669) (xy 47.944117 -86.808239)
			(xy 47.937853 -86.811358) (xy 99.84232 -86.811358) (xy 99.84232 -85.947758) (xy 99.84281 -85.917774)
			(xy 99.850638 -85.858318) (xy 99.866159 -85.800393) (xy 99.889108 -85.744989) (xy 99.919092 -85.693055)
			(xy 99.955598 -85.645479) (xy 99.998003 -85.603074) (xy 100.045579 -85.566568) (xy 100.097513 -85.536584)
			(xy 100.152917 -85.513635) (xy 100.210842 -85.498114) (xy 100.270298 -85.490286) (xy 100.330266 -85.490286)
			(xy 100.389722 -85.498114) (xy 100.447647 -85.513635) (xy 100.503051 -85.536584) (xy 100.554985 -85.566568)
			(xy 100.602561 -85.603074) (xy 100.644966 -85.645479) (xy 100.681472 -85.693055) (xy 100.711456 -85.744989)
			(xy 100.734405 -85.800393) (xy 100.749926 -85.858318) (xy 100.757754 -85.917774) (xy 100.758244 -85.947758)
			(xy 100.758244 -86.811358) (xy 100.757754 -86.841342) (xy 100.749926 -86.900798) (xy 100.734405 -86.958723)
			(xy 100.711456 -87.014127) (xy 100.681472 -87.066061) (xy 100.644966 -87.113637) (xy 100.602561 -87.156042)
			(xy 100.554985 -87.192548) (xy 100.503051 -87.222532) (xy 100.447647 -87.245481) (xy 100.389722 -87.261002)
			(xy 100.330266 -87.26883) (xy 100.270298 -87.26883) (xy 100.210842 -87.261002) (xy 100.152917 -87.245481)
			(xy 100.097513 -87.222532) (xy 100.045579 -87.192548) (xy 99.998003 -87.156042) (xy 99.955598 -87.113637)
			(xy 99.919092 -87.066061) (xy 99.889108 -87.014127) (xy 99.866159 -86.958723) (xy 99.850638 -86.900798)
			(xy 99.84281 -86.841342) (xy 99.84232 -86.811358) (xy 47.937853 -86.811358) (xy 47.828516 -86.865801)
			(xy 47.709591 -86.916138) (xy 47.587792 -86.959058) (xy 47.463582 -86.994399) (xy 47.337433 -87.022026)
			(xy 47.209821 -87.041835) (xy 47.081232 -87.053751) (xy 46.952154 -87.057728) (xy 46.823076 -87.053751)
			(xy 46.694487 -87.041835) (xy 46.566875 -87.022026) (xy 46.440726 -86.994399) (xy 46.316516 -86.959058)
			(xy 46.194717 -86.916138) (xy 46.075792 -86.865801) (xy 45.960191 -86.808239) (xy 45.848352 -86.743669)
			(xy 45.740701 -86.672337) (xy 45.637646 -86.594513) (xy 45.539576 -86.510492) (xy 45.446865 -86.420593)
			(xy 45.359865 -86.325158) (xy 45.278904 -86.224548) (xy 45.20429 -86.119145) (xy 45.136307 -86.009348)
			(xy 45.075212 -85.895574) (xy 45.021237 -85.778255) (xy 44.974586 -85.657836) (xy 44.935437 -85.534773)
			(xy 44.903938 -85.409534) (xy 44.880209 -85.282593) (xy 44.864339 -85.154433) (xy 44.856389 -85.025538)
			(xy 24.04871 -85.025538) (xy 24.034116 -85.212143) (xy 24.010143 -85.415965) (xy 23.978236 -85.618697)
			(xy 23.938444 -85.820029) (xy 23.890827 -86.019656) (xy 23.835457 -86.217272) (xy 23.77242 -86.412578)
			(xy 23.70181 -86.605276) (xy 23.623736 -86.795072) (xy 23.538316 -86.981678) (xy 23.44568 -87.164808)
			(xy 23.34597 -87.344185) (xy 23.336972 -87.358982) (xy 116.623592 -87.358982) (xy 116.623592 -86.495382)
			(xy 116.624082 -86.465414) (xy 116.631905 -86.405992) (xy 116.647418 -86.348099) (xy 116.670354 -86.292726)
			(xy 116.700321 -86.24082) (xy 116.736808 -86.19327) (xy 116.779188 -86.15089) (xy 116.826738 -86.114403)
			(xy 116.878644 -86.084436) (xy 116.934017 -86.0615) (xy 116.99191 -86.045987) (xy 117.051332 -86.038164)
			(xy 117.111268 -86.038164) (xy 117.17069 -86.045987) (xy 117.228583 -86.0615) (xy 117.283956 -86.084436)
			(xy 117.335862 -86.114403) (xy 117.383412 -86.15089) (xy 117.425792 -86.19327) (xy 117.462279 -86.24082)
			(xy 117.492246 -86.292726) (xy 117.515182 -86.348099) (xy 117.530695 -86.405992) (xy 117.538518 -86.465414)
			(xy 117.539008 -86.495382) (xy 117.539008 -87.358982) (xy 117.538518 -87.38895) (xy 117.531262 -87.444066)
			(xy 232.194882 -87.444066) (xy 232.194882 -87.384134) (xy 232.202704 -87.324714) (xy 232.218215 -87.266824)
			(xy 232.241149 -87.211454) (xy 232.271114 -87.15955) (xy 232.307596 -87.112002) (xy 232.349973 -87.069621)
			(xy 232.397519 -87.033135) (xy 232.44942 -87.003166) (xy 232.504788 -86.980227) (xy 232.562677 -86.964712)
			(xy 232.622096 -86.956884) (xy 232.652062 -86.956392) (xy 233.515662 -86.956392) (xy 233.545633 -86.956859)
			(xy 233.605062 -86.964678) (xy 233.662961 -86.980188) (xy 233.718341 -87.003123) (xy 233.770254 -87.033091)
			(xy 233.81781 -87.069578) (xy 233.860197 -87.111961) (xy 233.896688 -87.159515) (xy 233.92666 -87.211425)
			(xy 233.9496 -87.266803) (xy 233.965115 -87.324701) (xy 233.972939 -87.384129) (xy 233.972939 -87.416385)
			(xy 234.381521 -87.416385) (xy 234.381521 -87.356415) (xy 234.389349 -87.296959) (xy 234.40487 -87.239032)
			(xy 234.42782 -87.183628) (xy 234.457804 -87.131692) (xy 234.494312 -87.084115) (xy 234.536717 -87.04171)
			(xy 234.584294 -87.005203) (xy 234.636229 -86.975219) (xy 234.691634 -86.952269) (xy 234.749561 -86.936748)
			(xy 234.809017 -86.928921) (xy 234.839002 -86.928452) (xy 235.702602 -86.928452) (xy 235.732587 -86.928914)
			(xy 235.792044 -86.936742) (xy 235.849971 -86.952264) (xy 235.905376 -86.975214) (xy 235.957312 -87.005199)
			(xy 236.004889 -87.041707) (xy 236.047295 -87.084112) (xy 236.083802 -87.13169) (xy 236.113787 -87.183626)
			(xy 236.136737 -87.239031) (xy 236.152258 -87.296958) (xy 236.155843 -87.324184) (xy 330.477876 -87.324184)
			(xy 330.477876 -86.460584) (xy 330.478366 -86.430616) (xy 330.486189 -86.371194) (xy 330.501702 -86.313301)
			(xy 330.524638 -86.257928) (xy 330.554605 -86.206022) (xy 330.591092 -86.158472) (xy 330.633472 -86.116092)
			(xy 330.681022 -86.079605) (xy 330.732928 -86.049638) (xy 330.788301 -86.026702) (xy 330.846194 -86.011189)
			(xy 330.905616 -86.003366) (xy 330.965552 -86.003366) (xy 331.024974 -86.011189) (xy 331.082867 -86.026702)
			(xy 331.13824 -86.049638) (xy 331.190146 -86.079605) (xy 331.237696 -86.116092) (xy 331.266212 -86.144608)
			(xy 346.641928 -86.144608) (xy 346.641928 -85.281008) (xy 346.642418 -85.251024) (xy 346.650246 -85.191568)
			(xy 346.665767 -85.133643) (xy 346.688716 -85.078239) (xy 346.7187 -85.026305) (xy 346.755206 -84.978729)
			(xy 346.797611 -84.936324) (xy 346.845187 -84.899818) (xy 346.897121 -84.869834) (xy 346.952525 -84.846885)
			(xy 347.01045 -84.831364) (xy 347.069906 -84.823536) (xy 347.129874 -84.823536) (xy 347.18933 -84.831364)
			(xy 347.247255 -84.846885) (xy 347.302659 -84.869834) (xy 347.354593 -84.899818) (xy 347.402169 -84.936324)
			(xy 347.444574 -84.978729) (xy 347.48108 -85.026305) (xy 347.511064 -85.078239) (xy 347.534013 -85.133643)
			(xy 347.549534 -85.191568) (xy 347.557362 -85.251024) (xy 347.557852 -85.281008) (xy 347.557852 -86.144608)
			(xy 347.557362 -86.174592) (xy 347.549534 -86.234048) (xy 347.534013 -86.291973) (xy 347.511064 -86.347377)
			(xy 347.48108 -86.399311) (xy 347.444574 -86.446887) (xy 347.402169 -86.489292) (xy 347.354593 -86.525798)
			(xy 347.302659 -86.555782) (xy 347.247255 -86.578731) (xy 347.18933 -86.594252) (xy 347.129874 -86.60208)
			(xy 347.069906 -86.60208) (xy 347.01045 -86.594252) (xy 346.952525 -86.578731) (xy 346.897121 -86.555782)
			(xy 346.845187 -86.525798) (xy 346.797611 -86.489292) (xy 346.755206 -86.446887) (xy 346.7187 -86.399311)
			(xy 346.688716 -86.347377) (xy 346.665767 -86.291973) (xy 346.650246 -86.234048) (xy 346.642418 -86.174592)
			(xy 346.641928 -86.144608) (xy 331.266212 -86.144608) (xy 331.280076 -86.158472) (xy 331.316563 -86.206022)
			(xy 331.34653 -86.257928) (xy 331.369466 -86.313301) (xy 331.384979 -86.371194) (xy 331.392802 -86.430616)
			(xy 331.393292 -86.460584) (xy 331.393292 -87.324184) (xy 331.392802 -87.354152) (xy 331.384979 -87.413574)
			(xy 331.369466 -87.471467) (xy 331.34653 -87.52684) (xy 331.316563 -87.578746) (xy 331.280076 -87.626296)
			(xy 331.237696 -87.668676) (xy 331.190146 -87.705163) (xy 331.13824 -87.73513) (xy 331.082867 -87.758066)
			(xy 331.024974 -87.773579) (xy 330.965552 -87.781402) (xy 330.905616 -87.781402) (xy 330.846194 -87.773579)
			(xy 330.788301 -87.758066) (xy 330.732928 -87.73513) (xy 330.681022 -87.705163) (xy 330.633472 -87.668676)
			(xy 330.591092 -87.626296) (xy 330.554605 -87.578746) (xy 330.524638 -87.52684) (xy 330.501702 -87.471467)
			(xy 330.486189 -87.413574) (xy 330.478366 -87.354152) (xy 330.477876 -87.324184) (xy 236.155843 -87.324184)
			(xy 236.160086 -87.356415) (xy 236.160086 -87.416385) (xy 236.152258 -87.475842) (xy 236.136737 -87.533769)
			(xy 236.113787 -87.589174) (xy 236.083802 -87.64111) (xy 236.047295 -87.688688) (xy 236.004889 -87.731093)
			(xy 235.957312 -87.767601) (xy 235.905376 -87.797586) (xy 235.849971 -87.820536) (xy 235.792044 -87.836058)
			(xy 235.732587 -87.843886) (xy 235.702602 -87.844376) (xy 234.839002 -87.844376) (xy 234.809017 -87.843879)
			(xy 234.749561 -87.836052) (xy 234.691634 -87.820531) (xy 234.636229 -87.797581) (xy 234.584294 -87.767597)
			(xy 234.536717 -87.73109) (xy 234.494312 -87.688685) (xy 234.457804 -87.641108) (xy 234.42782 -87.589172)
			(xy 234.40487 -87.533768) (xy 234.389349 -87.475841) (xy 234.381521 -87.416385) (xy 233.972939 -87.416385)
			(xy 233.972939 -87.444071) (xy 233.965115 -87.503499) (xy 233.9496 -87.561397) (xy 233.92666 -87.616775)
			(xy 233.896688 -87.668685) (xy 233.860197 -87.716239) (xy 233.81781 -87.758622) (xy 233.770254 -87.795109)
			(xy 233.718341 -87.825077) (xy 233.662961 -87.848012) (xy 233.605062 -87.863522) (xy 233.545633 -87.871341)
			(xy 233.515662 -87.871808) (xy 232.652062 -87.871808) (xy 232.622096 -87.871316) (xy 232.562677 -87.863488)
			(xy 232.504788 -87.847973) (xy 232.44942 -87.825034) (xy 232.397519 -87.795065) (xy 232.349973 -87.758579)
			(xy 232.307596 -87.716198) (xy 232.271114 -87.66865) (xy 232.241149 -87.616746) (xy 232.218215 -87.561376)
			(xy 232.202704 -87.503486) (xy 232.194882 -87.444066) (xy 117.531262 -87.444066) (xy 117.530695 -87.448372)
			(xy 117.515182 -87.506265) (xy 117.492246 -87.561638) (xy 117.462279 -87.613544) (xy 117.425792 -87.661094)
			(xy 117.383412 -87.703474) (xy 117.335862 -87.739961) (xy 117.283956 -87.769928) (xy 117.228583 -87.792864)
			(xy 117.17069 -87.808377) (xy 117.111268 -87.8162) (xy 117.051332 -87.8162) (xy 116.99191 -87.808377)
			(xy 116.934017 -87.792864) (xy 116.878644 -87.769928) (xy 116.826738 -87.739961) (xy 116.779188 -87.703474)
			(xy 116.736808 -87.661094) (xy 116.700321 -87.613544) (xy 116.670354 -87.561638) (xy 116.647418 -87.506265)
			(xy 116.631905 -87.448372) (xy 116.624082 -87.38895) (xy 116.623592 -87.358982) (xy 23.336972 -87.358982)
			(xy 23.239337 -87.519535) (xy 23.125944 -87.690591) (xy 23.005964 -87.857093) (xy 22.889427 -88.006187)
			(xy 238.124409 -88.006187) (xy 238.124409 -87.946213) (xy 238.132238 -87.886751) (xy 238.147762 -87.82882)
			(xy 238.170714 -87.773411) (xy 238.200704 -87.721472) (xy 238.237216 -87.673892) (xy 238.279627 -87.631486)
			(xy 238.32721 -87.594978) (xy 238.379152 -87.564994) (xy 238.434563 -87.542047) (xy 238.492496 -87.526529)
			(xy 238.551959 -87.518706) (xy 238.581946 -87.51824) (xy 239.445546 -87.51824) (xy 239.475528 -87.518729)
			(xy 239.53498 -87.526561) (xy 239.5929 -87.542086) (xy 239.648299 -87.565038) (xy 239.700228 -87.595024)
			(xy 239.747799 -87.631531) (xy 239.790199 -87.673935) (xy 239.826701 -87.72151) (xy 239.856682 -87.773442)
			(xy 239.879628 -87.828843) (xy 239.895148 -87.886765) (xy 239.902974 -87.946217) (xy 239.902974 -88.006183)
			(xy 239.895148 -88.065635) (xy 239.879628 -88.123557) (xy 239.870911 -88.144604) (xy 345.879928 -88.144604)
			(xy 345.879928 -87.281004) (xy 345.880418 -87.25102) (xy 345.888246 -87.191564) (xy 345.903767 -87.133639)
			(xy 345.926716 -87.078235) (xy 345.9567 -87.026301) (xy 345.993206 -86.978725) (xy 346.035611 -86.93632)
			(xy 346.083187 -86.899814) (xy 346.135121 -86.86983) (xy 346.190525 -86.846881) (xy 346.24845 -86.83136)
			(xy 346.307906 -86.823532) (xy 346.367874 -86.823532) (xy 346.42733 -86.83136) (xy 346.485255 -86.846881)
			(xy 346.540659 -86.86983) (xy 346.592593 -86.899814) (xy 346.640169 -86.93632) (xy 346.682574 -86.978725)
			(xy 346.71908 -87.026301) (xy 346.749064 -87.078235) (xy 346.772013 -87.133639) (xy 346.787534 -87.191564)
			(xy 346.795362 -87.25102) (xy 346.795852 -87.281004) (xy 346.795852 -88.144604) (xy 346.795362 -88.174588)
			(xy 346.787534 -88.234044) (xy 346.772013 -88.291969) (xy 346.749064 -88.347373) (xy 346.71908 -88.399307)
			(xy 346.682574 -88.446883) (xy 346.640169 -88.489288) (xy 346.592593 -88.525794) (xy 346.540659 -88.555778)
			(xy 346.485255 -88.578727) (xy 346.42733 -88.594248) (xy 346.367874 -88.602076) (xy 346.307906 -88.602076)
			(xy 346.24845 -88.594248) (xy 346.190525 -88.578727) (xy 346.135121 -88.555778) (xy 346.083187 -88.525794)
			(xy 346.035611 -88.489288) (xy 345.993206 -88.446883) (xy 345.9567 -88.399307) (xy 345.926716 -88.347373)
			(xy 345.903767 -88.291969) (xy 345.888246 -88.234044) (xy 345.880418 -88.174588) (xy 345.879928 -88.144604)
			(xy 239.870911 -88.144604) (xy 239.856682 -88.178958) (xy 239.826701 -88.23089) (xy 239.790199 -88.278465)
			(xy 239.747799 -88.320869) (xy 239.700228 -88.357376) (xy 239.648299 -88.387362) (xy 239.5929 -88.410314)
			(xy 239.53498 -88.425839) (xy 239.475528 -88.433671) (xy 239.445546 -88.434164) (xy 238.581946 -88.434164)
			(xy 238.551959 -88.433694) (xy 238.492496 -88.425871) (xy 238.434563 -88.410353) (xy 238.379152 -88.387406)
			(xy 238.32721 -88.357422) (xy 238.279627 -88.320914) (xy 238.237216 -88.278508) (xy 238.200704 -88.230928)
			(xy 238.170714 -88.178989) (xy 238.147762 -88.12358) (xy 238.132238 -88.065649) (xy 238.124409 -88.006187)
			(xy 22.889427 -88.006187) (xy 22.879578 -88.018787) (xy 22.74698 -88.175427) (xy 22.608372 -88.326773)
			(xy 22.463964 -88.472597) (xy 22.313977 -88.612676) (xy 22.158638 -88.746795) (xy 21.998185 -88.874752)
			(xy 21.832862 -88.996352) (xy 21.66292 -89.111408) (xy 21.488619 -89.219747) (xy 21.310223 -89.321202)
			(xy 21.237319 -89.358978) (xy 117.385592 -89.358978) (xy 117.385592 -88.495378) (xy 117.386082 -88.46541)
			(xy 117.393905 -88.405988) (xy 117.409418 -88.348095) (xy 117.432354 -88.292722) (xy 117.462321 -88.240816)
			(xy 117.498808 -88.193266) (xy 117.541188 -88.150886) (xy 117.588738 -88.114399) (xy 117.640644 -88.084432)
			(xy 117.696017 -88.061496) (xy 117.75391 -88.045983) (xy 117.813332 -88.03816) (xy 117.873268 -88.03816)
			(xy 117.93269 -88.045983) (xy 117.990583 -88.061496) (xy 118.045956 -88.084432) (xy 118.097862 -88.114399)
			(xy 118.145412 -88.150886) (xy 118.187792 -88.193266) (xy 118.224279 -88.240816) (xy 118.254246 -88.292722)
			(xy 118.277182 -88.348095) (xy 118.292695 -88.405988) (xy 118.300518 -88.46541) (xy 118.301008 -88.495378)
			(xy 118.301008 -89.358978) (xy 118.300518 -89.388946) (xy 118.292695 -89.448368) (xy 118.277182 -89.506261)
			(xy 118.254246 -89.561634) (xy 118.224279 -89.61354) (xy 118.187792 -89.66109) (xy 118.145412 -89.70347)
			(xy 118.097862 -89.739957) (xy 118.045956 -89.769924) (xy 117.990583 -89.79286) (xy 117.93269 -89.808373)
			(xy 117.873268 -89.816196) (xy 117.813332 -89.816196) (xy 117.75391 -89.808373) (xy 117.696017 -89.79286)
			(xy 117.640644 -89.769924) (xy 117.588738 -89.739957) (xy 117.541188 -89.70347) (xy 117.498808 -89.66109)
			(xy 117.462321 -89.61354) (xy 117.432354 -89.561634) (xy 117.409418 -89.506261) (xy 117.393905 -89.448368)
			(xy 117.386082 -89.388946) (xy 117.385592 -89.358978) (xy 21.237319 -89.358978) (xy 21.128005 -89.41562)
			(xy 20.942242 -89.502856) (xy 20.753217 -89.582779) (xy 20.561217 -89.655265) (xy 20.366535 -89.720205)
			(xy 20.169468 -89.7775) (xy 19.970315 -89.827063) (xy 19.769381 -89.868818) (xy 19.56697 -89.902701)
			(xy 19.363392 -89.928661) (xy 19.158955 -89.946658) (xy 18.953972 -89.956666) (xy 18.748755 -89.958668)
			(xy 18.543616 -89.952662) (xy 18.338867 -89.938657) (xy 18.13482 -89.916674) (xy 17.931787 -89.886747)
			(xy 17.730076 -89.84892) (xy 17.529994 -89.803253) (xy 17.331847 -89.749814) (xy 17.135935 -89.688685)
			(xy 16.942558 -89.619959) (xy 16.752009 -89.54374) (xy 16.564579 -89.460144) (xy 16.380553 -89.3693)
			(xy 16.200212 -89.271345) (xy 16.02383 -89.166428) (xy 15.851676 -89.054709) (xy 15.684011 -88.936359)
			(xy 15.521092 -88.811557) (xy 15.363166 -88.680493) (xy 15.210474 -88.543368) (xy 15.063249 -88.40039)
			(xy 14.921714 -88.251776) (xy 14.786085 -88.097754) (xy 14.656568 -87.938557) (xy 14.533362 -87.774428)
			(xy 14.416653 -87.605617) (xy 14.306619 -87.43238) (xy 14.203428 -87.254983) (xy 14.107237 -87.073695)
			(xy 14.018192 -86.888792) (xy 13.936429 -86.700555) (xy 13.862073 -86.509272) (xy 13.795237 -86.315233)
			(xy 13.736022 -86.118734) (xy 13.684519 -85.920075) (xy 13.640805 -85.719557) (xy 13.604949 -85.517486)
			(xy 13.577004 -85.314171) (xy 13.557013 -85.10992) (xy 13.545006 -84.905044) (xy 13.541002 -84.699856)
			(xy 3.894875 -84.699856) (xy 4.291584 -85.096604) (xy 4.352388 -85.158117) (xy 4.468586 -85.286261)
			(xy 4.578355 -85.419953) (xy 4.681431 -85.558871) (xy 4.777564 -85.702681) (xy 4.866525 -85.851035)
			(xy 4.948097 -86.003576) (xy 5.022085 -86.159936) (xy 5.08831 -86.31974) (xy 5.146612 -86.4826) (xy 5.196852 -86.648126)
			(xy 5.238907 -86.815918) (xy 5.272678 -86.985572) (xy 5.298081 -87.156679) (xy 5.315056 -87.328826)
			(xy 5.323563 -87.501599) (xy 5.324094 -87.58809) (xy 5.324094 -90.1446) (xy 346.641928 -90.1446)
			(xy 346.641928 -89.281) (xy 346.642418 -89.251016) (xy 346.650246 -89.19156) (xy 346.665767 -89.133635)
			(xy 346.688716 -89.078231) (xy 346.7187 -89.026297) (xy 346.755206 -88.978721) (xy 346.797611 -88.936316)
			(xy 346.845187 -88.89981) (xy 346.897121 -88.869826) (xy 346.952525 -88.846877) (xy 347.01045 -88.831356)
			(xy 347.069906 -88.823528) (xy 347.129874 -88.823528) (xy 347.18933 -88.831356) (xy 347.247255 -88.846877)
			(xy 347.302659 -88.869826) (xy 347.354593 -88.89981) (xy 347.402169 -88.936316) (xy 347.444574 -88.978721)
			(xy 347.48108 -89.026297) (xy 347.511064 -89.078231) (xy 347.534013 -89.133635) (xy 347.549534 -89.19156)
			(xy 347.557362 -89.251016) (xy 347.557852 -89.281) (xy 347.557852 -90.1446) (xy 347.557362 -90.174584)
			(xy 347.549534 -90.23404) (xy 347.534013 -90.291965) (xy 347.511064 -90.347369) (xy 347.48108 -90.399303)
			(xy 347.444574 -90.446879) (xy 347.402169 -90.489284) (xy 347.354593 -90.52579) (xy 347.302659 -90.555774)
			(xy 347.247255 -90.578723) (xy 347.18933 -90.594244) (xy 347.129874 -90.602072) (xy 347.069906 -90.602072)
			(xy 347.01045 -90.594244) (xy 346.952525 -90.578723) (xy 346.897121 -90.555774) (xy 346.845187 -90.52579)
			(xy 346.797611 -90.489284) (xy 346.755206 -90.446879) (xy 346.7187 -90.399303) (xy 346.688716 -90.347369)
			(xy 346.665767 -90.291965) (xy 346.650246 -90.23404) (xy 346.642418 -90.174584) (xy 346.641928 -90.1446)
			(xy 5.324094 -90.1446) (xy 5.324094 -94.088485) (xy 109.149614 -94.088485) (xy 109.149614 -94.028515)
			(xy 109.157442 -93.969058) (xy 109.172963 -93.911131) (xy 109.195912 -93.855726) (xy 109.225897 -93.80379)
			(xy 109.262405 -93.756213) (xy 109.30481 -93.713807) (xy 109.352387 -93.6773) (xy 109.404322 -93.647314)
			(xy 109.459727 -93.624364) (xy 109.517654 -93.608843) (xy 109.577111 -93.601014) (xy 109.607096 -93.600524)
			(xy 110.470696 -93.600524) (xy 110.500681 -93.601021) (xy 110.560138 -93.608848) (xy 110.618064 -93.624369)
			(xy 110.673469 -93.647318) (xy 110.725405 -93.677303) (xy 110.772982 -93.71381) (xy 110.815388 -93.756215)
			(xy 110.851895 -93.803792) (xy 110.88188 -93.855727) (xy 110.90483 -93.911132) (xy 110.920351 -93.969058)
			(xy 110.928179 -94.028515) (xy 110.928179 -94.088485) (xy 110.920351 -94.147942) (xy 110.90483 -94.205868)
			(xy 110.88188 -94.261273) (xy 110.851895 -94.313208) (xy 110.815388 -94.360785) (xy 110.772982 -94.40319)
			(xy 110.725405 -94.439697) (xy 110.673469 -94.469682) (xy 110.618064 -94.492631) (xy 110.560138 -94.508152)
			(xy 110.500681 -94.515979) (xy 110.470696 -94.516448) (xy 109.607096 -94.516448) (xy 109.577111 -94.515986)
			(xy 109.517654 -94.508157) (xy 109.459727 -94.492636) (xy 109.404322 -94.469686) (xy 109.352387 -94.4397)
			(xy 109.30481 -94.403193) (xy 109.262405 -94.360787) (xy 109.225897 -94.31321) (xy 109.195912 -94.261274)
			(xy 109.172963 -94.205869) (xy 109.157442 -94.147942) (xy 109.149614 -94.088485) (xy 5.324094 -94.088485)
			(xy 5.324094 -95.214948) (xy 47.274494 -95.214948) (xy 47.278447 -95.123133) (xy 47.290279 -95.031997)
			(xy 47.309902 -94.942216) (xy 47.33717 -94.854454) (xy 47.371881 -94.769362) (xy 47.413779 -94.687568)
			(xy 47.462554 -94.609679) (xy 47.517843 -94.53627) (xy 47.579238 -94.467887) (xy 47.646285 -94.405035)
			(xy 47.718487 -94.348178) (xy 47.795308 -94.29774) (xy 47.876182 -94.254091) (xy 47.960508 -94.217557)
			(xy 48.047663 -94.188407) (xy 48.137001 -94.166857) (xy 48.227861 -94.153067) (xy 48.31957 -94.147139)
			(xy 48.411449 -94.149116) (xy 48.502818 -94.158984) (xy 48.593 -94.176671) (xy 48.681328 -94.202044)
			(xy 48.767148 -94.234917) (xy 48.849825 -94.275045) (xy 48.928745 -94.322132) (xy 49.003326 -94.37583)
			(xy 49.073015 -94.435739) (xy 49.137295 -94.501418) (xy 49.195692 -94.57238) (xy 49.247772 -94.648098)
			(xy 49.29315 -94.728014) (xy 49.33149 -94.811535) (xy 49.362508 -94.898042) (xy 49.385976 -94.986896)
			(xy 49.401717 -95.077438) (xy 49.409618 -95.168998) (xy 49.410112 -95.214948) (xy 71.639444 -95.214948)
			(xy 71.643397 -95.123133) (xy 71.655229 -95.031997) (xy 71.674852 -94.942216) (xy 71.70212 -94.854454)
			(xy 71.736831 -94.769362) (xy 71.778729 -94.687568) (xy 71.827504 -94.609679) (xy 71.882793 -94.53627)
			(xy 71.944188 -94.467887) (xy 72.011235 -94.405035) (xy 72.083437 -94.348178) (xy 72.160258 -94.29774)
			(xy 72.241132 -94.254091) (xy 72.325458 -94.217557) (xy 72.412613 -94.188407) (xy 72.501951 -94.166857)
			(xy 72.592811 -94.153067) (xy 72.68452 -94.147139) (xy 72.776399 -94.149116) (xy 72.867768 -94.158984)
			(xy 72.95795 -94.176671) (xy 73.046278 -94.202044) (xy 73.132098 -94.234917) (xy 73.214775 -94.275045)
			(xy 73.293695 -94.322132) (xy 73.368276 -94.37583) (xy 73.437965 -94.435739) (xy 73.502245 -94.501418)
			(xy 73.560642 -94.57238) (xy 73.612722 -94.648098) (xy 73.6581 -94.728014) (xy 73.69644 -94.811535)
			(xy 73.727458 -94.898042) (xy 73.750926 -94.986896) (xy 73.766667 -95.077438) (xy 73.774568 -95.168998)
			(xy 73.775062 -95.214948) (xy 73.774568 -95.260898) (xy 73.774517 -95.261486) (xy 163.375394 -95.261486)
			(xy 163.375394 -95.168314) (xy 163.383515 -95.075496) (xy 163.399694 -94.983738) (xy 163.423808 -94.893741)
			(xy 163.455675 -94.806187) (xy 163.495052 -94.721744) (xy 163.541638 -94.641054) (xy 163.595079 -94.564731)
			(xy 163.654969 -94.493357) (xy 163.720852 -94.427473) (xy 163.792226 -94.367583) (xy 163.868549 -94.314141)
			(xy 163.949238 -94.267554) (xy 164.033681 -94.228178) (xy 164.121235 -94.19631) (xy 164.211233 -94.172195)
			(xy 164.30299 -94.156015) (xy 164.395808 -94.147894) (xy 164.442394 -94.147386) (xy 164.442648 -94.147386)
			(xy 164.489237 -94.1478) (xy 164.582061 -94.155925) (xy 164.673824 -94.172109) (xy 164.763826 -94.196229)
			(xy 164.851385 -94.228101) (xy 164.935832 -94.267483) (xy 165.016526 -94.314074) (xy 165.092852 -94.367522)
			(xy 165.164229 -94.427418) (xy 165.230115 -94.493306) (xy 165.290008 -94.564687) (xy 165.343451 -94.641015)
			(xy 165.390039 -94.721711) (xy 165.429417 -94.80616) (xy 165.461286 -94.893719) (xy 165.485401 -94.983723)
			(xy 165.501581 -95.075487) (xy 165.509702 -95.168311) (xy 165.509702 -95.214948) (xy 187.739796 -95.214948)
			(xy 187.743748 -95.123155) (xy 187.755578 -95.032041) (xy 187.775195 -94.942281) (xy 187.802457 -94.85454)
			(xy 187.83716 -94.769468) (xy 187.879048 -94.687693) (xy 187.927811 -94.609822) (xy 187.983087 -94.536432)
			(xy 188.044468 -94.468065) (xy 188.111499 -94.405227) (xy 188.183683 -94.348385) (xy 188.260487 -94.297958)
			(xy 188.341341 -94.25432) (xy 188.425647 -94.217794) (xy 188.512781 -94.188651) (xy 188.602098 -94.167106)
			(xy 188.692936 -94.15332) (xy 188.784623 -94.147393) (xy 188.87648 -94.14937) (xy 188.967828 -94.159236)
			(xy 189.057988 -94.176918) (xy 189.146296 -94.202285) (xy 189.232095 -94.23515) (xy 189.314752 -94.275269)
			(xy 189.393654 -94.322345) (xy 189.468217 -94.376029) (xy 189.537889 -94.435925) (xy 189.602154 -94.501588)
			(xy 189.660537 -94.572532) (xy 189.712604 -94.648233) (xy 189.757972 -94.72813) (xy 189.796303 -94.81163)
			(xy 189.827314 -94.898117) (xy 189.850775 -94.98695) (xy 189.866514 -95.07747) (xy 189.874412 -95.169009)
			(xy 189.874906 -95.214948) (xy 189.874412 -95.260887) (xy 189.866514 -95.352426) (xy 189.850775 -95.442946)
			(xy 189.827314 -95.531779) (xy 189.796303 -95.618266) (xy 189.757972 -95.701766) (xy 189.712604 -95.781663)
			(xy 189.660537 -95.857364) (xy 189.602154 -95.928308) (xy 189.537889 -95.993971) (xy 189.468217 -96.053867)
			(xy 189.393654 -96.107551) (xy 189.314752 -96.154627) (xy 189.232095 -96.194746) (xy 189.146296 -96.227611)
			(xy 189.057988 -96.252978) (xy 188.967828 -96.27066) (xy 188.87648 -96.280526) (xy 188.784623 -96.282503)
			(xy 188.692936 -96.276576) (xy 188.602098 -96.26279) (xy 188.512781 -96.241245) (xy 188.425647 -96.212102)
			(xy 188.341341 -96.175576) (xy 188.260487 -96.131938) (xy 188.183683 -96.081511) (xy 188.111499 -96.024669)
			(xy 188.044468 -95.961831) (xy 187.983087 -95.893464) (xy 187.927811 -95.820074) (xy 187.879048 -95.742203)
			(xy 187.83716 -95.660428) (xy 187.802457 -95.575356) (xy 187.775195 -95.487615) (xy 187.755578 -95.397855)
			(xy 187.743748 -95.306741) (xy 187.739796 -95.214948) (xy 165.509702 -95.214948) (xy 165.509702 -95.261489)
			(xy 165.501581 -95.354313) (xy 165.485401 -95.446077) (xy 165.461286 -95.536081) (xy 165.429417 -95.62364)
			(xy 165.390039 -95.708089) (xy 165.343451 -95.788785) (xy 165.290008 -95.865113) (xy 165.230115 -95.936494)
			(xy 165.164229 -96.002382) (xy 165.092852 -96.062278) (xy 165.016526 -96.115726) (xy 164.935832 -96.162317)
			(xy 164.851385 -96.201699) (xy 164.763826 -96.233571) (xy 164.673824 -96.257691) (xy 164.582061 -96.273875)
			(xy 164.489237 -96.282) (xy 164.442648 -96.28251) (xy 164.442394 -96.28251) (xy 164.395808 -96.281906)
			(xy 164.30299 -96.273785) (xy 164.211233 -96.257605) (xy 164.121235 -96.23349) (xy 164.033681 -96.201622)
			(xy 163.949238 -96.162246) (xy 163.868549 -96.115659) (xy 163.792226 -96.062217) (xy 163.720852 -96.002327)
			(xy 163.654969 -95.936443) (xy 163.595079 -95.865069) (xy 163.541638 -95.788746) (xy 163.495052 -95.708056)
			(xy 163.455675 -95.623613) (xy 163.423808 -95.536059) (xy 163.399694 -95.446062) (xy 163.383515 -95.354304)
			(xy 163.375394 -95.261486) (xy 73.774517 -95.261486) (xy 73.766667 -95.352458) (xy 73.750926 -95.443)
			(xy 73.727458 -95.531854) (xy 73.69644 -95.618361) (xy 73.6581 -95.701882) (xy 73.612722 -95.781798)
			(xy 73.560642 -95.857516) (xy 73.502245 -95.928478) (xy 73.437965 -95.994157) (xy 73.368276 -96.054066)
			(xy 73.293695 -96.107764) (xy 73.214775 -96.154851) (xy 73.132098 -96.194979) (xy 73.046278 -96.227852)
			(xy 72.95795 -96.253225) (xy 72.867768 -96.270912) (xy 72.776399 -96.28078) (xy 72.68452 -96.282757)
			(xy 72.592811 -96.276829) (xy 72.501951 -96.263039) (xy 72.412613 -96.241489) (xy 72.325458 -96.212339)
			(xy 72.241132 -96.175805) (xy 72.160258 -96.132156) (xy 72.083437 -96.081718) (xy 72.011235 -96.024861)
			(xy 71.944188 -95.962009) (xy 71.882793 -95.893626) (xy 71.827504 -95.820217) (xy 71.778729 -95.742328)
			(xy 71.736831 -95.660534) (xy 71.70212 -95.575442) (xy 71.674852 -95.48768) (xy 71.655229 -95.397899)
			(xy 71.643397 -95.306763) (xy 71.639444 -95.214948) (xy 49.410112 -95.214948) (xy 49.409618 -95.260898)
			(xy 49.401717 -95.352458) (xy 49.385976 -95.443) (xy 49.362508 -95.531854) (xy 49.33149 -95.618361)
			(xy 49.29315 -95.701882) (xy 49.247772 -95.781798) (xy 49.195692 -95.857516) (xy 49.137295 -95.928478)
			(xy 49.073015 -95.994157) (xy 49.003326 -96.054066) (xy 48.928745 -96.107764) (xy 48.849825 -96.154851)
			(xy 48.767148 -96.194979) (xy 48.681328 -96.227852) (xy 48.593 -96.253225) (xy 48.502818 -96.270912)
			(xy 48.411449 -96.28078) (xy 48.31957 -96.282757) (xy 48.227861 -96.276829) (xy 48.137001 -96.263039)
			(xy 48.047663 -96.241489) (xy 47.960508 -96.212339) (xy 47.876182 -96.175805) (xy 47.795308 -96.132156)
			(xy 47.718487 -96.081718) (xy 47.646285 -96.024861) (xy 47.579238 -95.962009) (xy 47.517843 -95.893626)
			(xy 47.462554 -95.820217) (xy 47.413779 -95.742328) (xy 47.371881 -95.660534) (xy 47.33717 -95.575442)
			(xy 47.309902 -95.48768) (xy 47.290279 -95.397899) (xy 47.278447 -95.306763) (xy 47.274494 -95.214948)
			(xy 5.324094 -95.214948) (xy 5.324094 -98.700082) (xy 203.041004 -98.700082) (xy 203.045008 -98.494894)
			(xy 203.057015 -98.290018) (xy 203.077006 -98.085767) (xy 203.104951 -97.882452) (xy 203.140807 -97.680381)
			(xy 203.184521 -97.479863) (xy 203.236024 -97.281204) (xy 203.295239 -97.084705) (xy 203.362075 -96.890666)
			(xy 203.436431 -96.699383) (xy 203.518194 -96.511146) (xy 203.607239 -96.326243) (xy 203.70343 -96.144955)
			(xy 203.806621 -95.967558) (xy 203.916655 -95.794321) (xy 204.033364 -95.62551) (xy 204.15657 -95.461381)
			(xy 204.286087 -95.302184) (xy 204.421716 -95.148162) (xy 204.563251 -94.999548) (xy 204.710476 -94.85657)
			(xy 204.863168 -94.719445) (xy 205.021094 -94.588381) (xy 205.184013 -94.463579) (xy 205.351678 -94.345229)
			(xy 205.523832 -94.23351) (xy 205.700214 -94.128593) (xy 205.880555 -94.030638) (xy 206.064581 -93.939794)
			(xy 206.252011 -93.856198) (xy 206.44256 -93.779979) (xy 206.635937 -93.711253) (xy 206.831849 -93.650124)
			(xy 207.029996 -93.596685) (xy 207.230078 -93.551018) (xy 207.431789 -93.513191) (xy 207.634822 -93.483264)
			(xy 207.838869 -93.461281) (xy 208.043618 -93.447276) (xy 208.248757 -93.44127) (xy 208.453974 -93.443272)
			(xy 208.658957 -93.45328) (xy 208.863394 -93.471277) (xy 209.066972 -93.497237) (xy 209.269383 -93.53112)
			(xy 209.470317 -93.572875) (xy 209.66947 -93.622438) (xy 209.866537 -93.679733) (xy 210.061219 -93.744673)
			(xy 210.253219 -93.817159) (xy 210.442244 -93.897082) (xy 210.628007 -93.984318) (xy 210.810225 -94.078736)
			(xy 210.988621 -94.180191) (xy 211.162922 -94.28853) (xy 211.332864 -94.403586) (xy 211.498187 -94.525186)
			(xy 211.65864 -94.653143) (xy 211.813979 -94.787262) (xy 211.963966 -94.927341) (xy 212.108374 -95.073165)
			(xy 212.246982 -95.224511) (xy 212.37958 -95.381151) (xy 212.505966 -95.542845) (xy 212.625946 -95.709347)
			(xy 212.739339 -95.880403) (xy 212.845972 -96.055753) (xy 212.945682 -96.23513) (xy 213.038318 -96.41826)
			(xy 213.123738 -96.604866) (xy 213.201812 -96.794662) (xy 213.272422 -96.98736) (xy 213.335459 -97.182666)
			(xy 213.390829 -97.380282) (xy 213.438446 -97.579909) (xy 213.478238 -97.781241) (xy 213.510145 -97.983973)
			(xy 213.534118 -98.187795) (xy 213.55012 -98.392398) (xy 213.558127 -98.597468) (xy 213.558628 -98.700082)
			(xy 254.040902 -98.700082) (xy 254.044906 -98.494894) (xy 254.056913 -98.290018) (xy 254.076904 -98.085767)
			(xy 254.104849 -97.882452) (xy 254.140705 -97.680381) (xy 254.184419 -97.479863) (xy 254.235922 -97.281204)
			(xy 254.295137 -97.084705) (xy 254.361973 -96.890666) (xy 254.436329 -96.699383) (xy 254.518092 -96.511146)
			(xy 254.607137 -96.326243) (xy 254.703328 -96.144955) (xy 254.806519 -95.967558) (xy 254.916553 -95.794321)
			(xy 255.033262 -95.62551) (xy 255.156468 -95.461381) (xy 255.285985 -95.302184) (xy 255.421614 -95.148162)
			(xy 255.563149 -94.999548) (xy 255.710374 -94.85657) (xy 255.863066 -94.719445) (xy 256.020992 -94.588381)
			(xy 256.183911 -94.463579) (xy 256.351576 -94.345229) (xy 256.52373 -94.23351) (xy 256.700112 -94.128593)
			(xy 256.880453 -94.030638) (xy 257.064479 -93.939794) (xy 257.251909 -93.856198) (xy 257.442458 -93.779979)
			(xy 257.635835 -93.711253) (xy 257.831747 -93.650124) (xy 258.029894 -93.596685) (xy 258.229976 -93.551018)
			(xy 258.431687 -93.513191) (xy 258.63472 -93.483264) (xy 258.838767 -93.461281) (xy 259.043516 -93.447276)
			(xy 259.248655 -93.44127) (xy 259.453872 -93.443272) (xy 259.658855 -93.45328) (xy 259.863292 -93.471277)
			(xy 260.06687 -93.497237) (xy 260.269281 -93.53112) (xy 260.470215 -93.572875) (xy 260.669368 -93.622438)
			(xy 260.866435 -93.679733) (xy 261.061117 -93.744673) (xy 261.253117 -93.817159) (xy 261.442142 -93.897082)
			(xy 261.627905 -93.984318) (xy 261.810123 -94.078736) (xy 261.988519 -94.180191) (xy 262.16282 -94.28853)
			(xy 262.332762 -94.403586) (xy 262.498085 -94.525186) (xy 262.658538 -94.653143) (xy 262.813877 -94.787262)
			(xy 262.963864 -94.927341) (xy 263.108272 -95.073165) (xy 263.238122 -95.214948) (xy 279.474436 -95.214948)
			(xy 279.478389 -95.123133) (xy 279.490221 -95.031997) (xy 279.509844 -94.942216) (xy 279.537112 -94.854454)
			(xy 279.571823 -94.769362) (xy 279.613721 -94.687568) (xy 279.662496 -94.609679) (xy 279.717785 -94.53627)
			(xy 279.77918 -94.467887) (xy 279.846227 -94.405035) (xy 279.918429 -94.348178) (xy 279.99525 -94.29774)
			(xy 280.076124 -94.254091) (xy 280.16045 -94.217557) (xy 280.247605 -94.188407) (xy 280.336943 -94.166857)
			(xy 280.427803 -94.153067) (xy 280.519512 -94.147139) (xy 280.611391 -94.149116) (xy 280.70276 -94.158984)
			(xy 280.792942 -94.176671) (xy 280.88127 -94.202044) (xy 280.96709 -94.234917) (xy 281.049767 -94.275045)
			(xy 281.128687 -94.322132) (xy 281.203268 -94.37583) (xy 281.272957 -94.435739) (xy 281.337237 -94.501418)
			(xy 281.395634 -94.57238) (xy 281.447714 -94.648098) (xy 281.493092 -94.728014) (xy 281.531432 -94.811535)
			(xy 281.56245 -94.898042) (xy 281.585918 -94.986896) (xy 281.601659 -95.077438) (xy 281.60956 -95.168998)
			(xy 281.610054 -95.214948) (xy 303.839386 -95.214948) (xy 303.843339 -95.123133) (xy 303.855171 -95.031997)
			(xy 303.874794 -94.942216) (xy 303.902062 -94.854454) (xy 303.936773 -94.769362) (xy 303.978671 -94.687568)
			(xy 304.027446 -94.609679) (xy 304.082735 -94.53627) (xy 304.14413 -94.467887) (xy 304.211177 -94.405035)
			(xy 304.283379 -94.348178) (xy 304.3602 -94.29774) (xy 304.441074 -94.254091) (xy 304.5254 -94.217557)
			(xy 304.612555 -94.188407) (xy 304.701893 -94.166857) (xy 304.792753 -94.153067) (xy 304.884462 -94.147139)
			(xy 304.976341 -94.149116) (xy 305.06771 -94.158984) (xy 305.157892 -94.176671) (xy 305.24622 -94.202044)
			(xy 305.33204 -94.234917) (xy 305.414717 -94.275045) (xy 305.493637 -94.322132) (xy 305.568218 -94.37583)
			(xy 305.637907 -94.435739) (xy 305.702187 -94.501418) (xy 305.760584 -94.57238) (xy 305.812664 -94.648098)
			(xy 305.858042 -94.728014) (xy 305.896382 -94.811535) (xy 305.91874 -94.87389) (xy 338.405861 -94.87389)
			(xy 338.405861 -94.81391) (xy 338.413691 -94.754443) (xy 338.429215 -94.696507) (xy 338.45217 -94.641093)
			(xy 338.482161 -94.58915) (xy 338.518676 -94.541565) (xy 338.561089 -94.499155) (xy 338.608676 -94.462643)
			(xy 338.660622 -94.432655) (xy 338.716037 -94.409705) (xy 338.773975 -94.394184) (xy 338.833442 -94.386359)
			(xy 338.863432 -94.385892) (xy 339.727032 -94.385892) (xy 339.757012 -94.386476) (xy 339.816458 -94.394306)
			(xy 339.874374 -94.409828) (xy 339.929769 -94.432777) (xy 339.981694 -94.462759) (xy 340.029262 -94.499262)
			(xy 340.071659 -94.541662) (xy 340.108159 -94.589232) (xy 340.138137 -94.64116) (xy 340.161082 -94.696556)
			(xy 340.1766 -94.754473) (xy 340.184426 -94.81392) (xy 340.184426 -94.87388) (xy 340.1766 -94.933327)
			(xy 340.161082 -94.991244) (xy 340.138137 -95.04664) (xy 340.108159 -95.098568) (xy 340.071659 -95.146138)
			(xy 340.029262 -95.188538) (xy 339.994846 -95.214948) (xy 395.574534 -95.214948) (xy 395.578487 -95.123133)
			(xy 395.590319 -95.031997) (xy 395.609942 -94.942216) (xy 395.63721 -94.854454) (xy 395.671921 -94.769362)
			(xy 395.713819 -94.687568) (xy 395.762594 -94.609679) (xy 395.817883 -94.53627) (xy 395.879278 -94.467887)
			(xy 395.946325 -94.405035) (xy 396.018527 -94.348178) (xy 396.095348 -94.29774) (xy 396.176222 -94.254091)
			(xy 396.260548 -94.217557) (xy 396.347703 -94.188407) (xy 396.437041 -94.166857) (xy 396.527901 -94.153067)
			(xy 396.61961 -94.147139) (xy 396.711489 -94.149116) (xy 396.802858 -94.158984) (xy 396.89304 -94.176671)
			(xy 396.981368 -94.202044) (xy 397.067188 -94.234917) (xy 397.149865 -94.275045) (xy 397.228785 -94.322132)
			(xy 397.303366 -94.37583) (xy 397.373055 -94.435739) (xy 397.437335 -94.501418) (xy 397.495732 -94.57238)
			(xy 397.547812 -94.648098) (xy 397.59319 -94.728014) (xy 397.63153 -94.811535) (xy 397.662548 -94.898042)
			(xy 397.686016 -94.986896) (xy 397.701757 -95.077438) (xy 397.709658 -95.168998) (xy 397.710152 -95.214948)
			(xy 419.939484 -95.214948) (xy 419.943437 -95.123133) (xy 419.955269 -95.031997) (xy 419.974892 -94.942216)
			(xy 420.00216 -94.854454) (xy 420.036871 -94.769362) (xy 420.078769 -94.687568) (xy 420.127544 -94.609679)
			(xy 420.182833 -94.53627) (xy 420.244228 -94.467887) (xy 420.311275 -94.405035) (xy 420.383477 -94.348178)
			(xy 420.460298 -94.29774) (xy 420.541172 -94.254091) (xy 420.625498 -94.217557) (xy 420.712653 -94.188407)
			(xy 420.801991 -94.166857) (xy 420.892851 -94.153067) (xy 420.98456 -94.147139) (xy 421.076439 -94.149116)
			(xy 421.167808 -94.158984) (xy 421.25799 -94.176671) (xy 421.346318 -94.202044) (xy 421.432138 -94.234917)
			(xy 421.514815 -94.275045) (xy 421.593735 -94.322132) (xy 421.668316 -94.37583) (xy 421.738005 -94.435739)
			(xy 421.802285 -94.501418) (xy 421.860682 -94.57238) (xy 421.912762 -94.648098) (xy 421.95814 -94.728014)
			(xy 421.99648 -94.811535) (xy 422.027498 -94.898042) (xy 422.050966 -94.986896) (xy 422.066707 -95.077438)
			(xy 422.074608 -95.168998) (xy 422.075102 -95.214948) (xy 422.074608 -95.260898) (xy 422.066707 -95.352458)
			(xy 422.050966 -95.443) (xy 422.027498 -95.531854) (xy 421.99648 -95.618361) (xy 421.95814 -95.701882)
			(xy 421.912762 -95.781798) (xy 421.860682 -95.857516) (xy 421.802285 -95.928478) (xy 421.738005 -95.994157)
			(xy 421.668316 -96.054066) (xy 421.593735 -96.107764) (xy 421.514815 -96.154851) (xy 421.432138 -96.194979)
			(xy 421.346318 -96.227852) (xy 421.25799 -96.253225) (xy 421.167808 -96.270912) (xy 421.076439 -96.28078)
			(xy 420.98456 -96.282757) (xy 420.892851 -96.276829) (xy 420.801991 -96.263039) (xy 420.712653 -96.241489)
			(xy 420.625498 -96.212339) (xy 420.541172 -96.175805) (xy 420.460298 -96.132156) (xy 420.383477 -96.081718)
			(xy 420.311275 -96.024861) (xy 420.244228 -95.962009) (xy 420.182833 -95.893626) (xy 420.127544 -95.820217)
			(xy 420.078769 -95.742328) (xy 420.036871 -95.660534) (xy 420.00216 -95.575442) (xy 419.974892 -95.48768)
			(xy 419.955269 -95.397899) (xy 419.943437 -95.306763) (xy 419.939484 -95.214948) (xy 397.710152 -95.214948)
			(xy 397.709658 -95.260898) (xy 397.701757 -95.352458) (xy 397.686016 -95.443) (xy 397.662548 -95.531854)
			(xy 397.63153 -95.618361) (xy 397.59319 -95.701882) (xy 397.547812 -95.781798) (xy 397.495732 -95.857516)
			(xy 397.437335 -95.928478) (xy 397.373055 -95.994157) (xy 397.303366 -96.054066) (xy 397.228785 -96.107764)
			(xy 397.149865 -96.154851) (xy 397.067188 -96.194979) (xy 396.981368 -96.227852) (xy 396.89304 -96.253225)
			(xy 396.802858 -96.270912) (xy 396.711489 -96.28078) (xy 396.61961 -96.282757) (xy 396.527901 -96.276829)
			(xy 396.437041 -96.263039) (xy 396.347703 -96.241489) (xy 396.260548 -96.212339) (xy 396.176222 -96.175805)
			(xy 396.095348 -96.132156) (xy 396.018527 -96.081718) (xy 395.946325 -96.024861) (xy 395.879278 -95.962009)
			(xy 395.817883 -95.893626) (xy 395.762594 -95.820217) (xy 395.713819 -95.742328) (xy 395.671921 -95.660534)
			(xy 395.63721 -95.575442) (xy 395.609942 -95.48768) (xy 395.590319 -95.397899) (xy 395.578487 -95.306763)
			(xy 395.574534 -95.214948) (xy 339.994846 -95.214948) (xy 339.981694 -95.225041) (xy 339.929769 -95.255023)
			(xy 339.874374 -95.277972) (xy 339.816458 -95.293494) (xy 339.757012 -95.301324) (xy 339.727032 -95.301816)
			(xy 338.863432 -95.301816) (xy 338.833442 -95.301441) (xy 338.773975 -95.293616) (xy 338.716037 -95.278095)
			(xy 338.660622 -95.255145) (xy 338.608676 -95.225157) (xy 338.561089 -95.188645) (xy 338.518676 -95.146235)
			(xy 338.482161 -95.09865) (xy 338.45217 -95.046707) (xy 338.429215 -94.991293) (xy 338.413691 -94.933357)
			(xy 338.405861 -94.87389) (xy 305.91874 -94.87389) (xy 305.9274 -94.898042) (xy 305.950868 -94.986896)
			(xy 305.966609 -95.077438) (xy 305.97451 -95.168998) (xy 305.975004 -95.214948) (xy 305.97451 -95.260898)
			(xy 305.966609 -95.352458) (xy 305.950868 -95.443) (xy 305.9274 -95.531854) (xy 305.896382 -95.618361)
			(xy 305.858042 -95.701882) (xy 305.812664 -95.781798) (xy 305.760584 -95.857516) (xy 305.702187 -95.928478)
			(xy 305.637907 -95.994157) (xy 305.568218 -96.054066) (xy 305.493637 -96.107764) (xy 305.414717 -96.154851)
			(xy 305.33204 -96.194979) (xy 305.24622 -96.227852) (xy 305.157892 -96.253225) (xy 305.06771 -96.270912)
			(xy 304.976341 -96.28078) (xy 304.884462 -96.282757) (xy 304.792753 -96.276829) (xy 304.701893 -96.263039)
			(xy 304.612555 -96.241489) (xy 304.5254 -96.212339) (xy 304.441074 -96.175805) (xy 304.3602 -96.132156)
			(xy 304.283379 -96.081718) (xy 304.211177 -96.024861) (xy 304.14413 -95.962009) (xy 304.082735 -95.893626)
			(xy 304.027446 -95.820217) (xy 303.978671 -95.742328) (xy 303.936773 -95.660534) (xy 303.902062 -95.575442)
			(xy 303.874794 -95.48768) (xy 303.855171 -95.397899) (xy 303.843339 -95.306763) (xy 303.839386 -95.214948)
			(xy 281.610054 -95.214948) (xy 281.60956 -95.260898) (xy 281.601659 -95.352458) (xy 281.585918 -95.443)
			(xy 281.56245 -95.531854) (xy 281.531432 -95.618361) (xy 281.493092 -95.701882) (xy 281.447714 -95.781798)
			(xy 281.395634 -95.857516) (xy 281.337237 -95.928478) (xy 281.272957 -95.994157) (xy 281.203268 -96.054066)
			(xy 281.128687 -96.107764) (xy 281.049767 -96.154851) (xy 280.96709 -96.194979) (xy 280.88127 -96.227852)
			(xy 280.792942 -96.253225) (xy 280.70276 -96.270912) (xy 280.611391 -96.28078) (xy 280.519512 -96.282757)
			(xy 280.427803 -96.276829) (xy 280.336943 -96.263039) (xy 280.247605 -96.241489) (xy 280.16045 -96.212339)
			(xy 280.076124 -96.175805) (xy 279.99525 -96.132156) (xy 279.918429 -96.081718) (xy 279.846227 -96.024861)
			(xy 279.77918 -95.962009) (xy 279.717785 -95.893626) (xy 279.662496 -95.820217) (xy 279.613721 -95.742328)
			(xy 279.571823 -95.660534) (xy 279.537112 -95.575442) (xy 279.509844 -95.48768) (xy 279.490221 -95.397899)
			(xy 279.478389 -95.306763) (xy 279.474436 -95.214948) (xy 263.238122 -95.214948) (xy 263.24688 -95.224511)
			(xy 263.379478 -95.381151) (xy 263.505864 -95.542845) (xy 263.625844 -95.709347) (xy 263.739237 -95.880403)
			(xy 263.84587 -96.055753) (xy 263.94558 -96.23513) (xy 264.038216 -96.41826) (xy 264.123636 -96.604866)
			(xy 264.20171 -96.794662) (xy 264.27232 -96.98736) (xy 264.335357 -97.182666) (xy 264.390727 -97.380282)
			(xy 264.438344 -97.579909) (xy 264.478136 -97.781241) (xy 264.510043 -97.983973) (xy 264.534016 -98.187795)
			(xy 264.550018 -98.392398) (xy 264.558025 -98.597468) (xy 264.558526 -98.700082) (xy 264.558025 -98.802696)
			(xy 264.550018 -99.007766) (xy 264.534016 -99.212369) (xy 264.510043 -99.416191) (xy 264.478136 -99.618923)
			(xy 264.438344 -99.820255) (xy 264.390727 -100.019882) (xy 264.346465 -100.177854) (xy 269.509748 -100.177854)
			(xy 269.509748 -99.314254) (xy 269.510238 -99.28427) (xy 269.518066 -99.224814) (xy 269.533587 -99.166889)
			(xy 269.556536 -99.111485) (xy 269.58652 -99.059551) (xy 269.623026 -99.011975) (xy 269.665431 -98.96957)
			(xy 269.713007 -98.933064) (xy 269.764941 -98.90308) (xy 269.820345 -98.880131) (xy 269.87827 -98.86461)
			(xy 269.937726 -98.856782) (xy 269.997694 -98.856782) (xy 270.05715 -98.86461) (xy 270.115075 -98.880131)
			(xy 270.170479 -98.90308) (xy 270.222413 -98.933064) (xy 270.269989 -98.96957) (xy 270.312394 -99.011975)
			(xy 270.3489 -99.059551) (xy 270.378884 -99.111485) (xy 270.401833 -99.166889) (xy 270.417354 -99.224814)
			(xy 270.425182 -99.28427) (xy 270.425672 -99.314254) (xy 270.425672 -100.17633) (xy 285.8389 -100.17633)
			(xy 285.8389 -99.31273) (xy 285.83939 -99.282746) (xy 285.847218 -99.22329) (xy 285.862739 -99.165365)
			(xy 285.885688 -99.109961) (xy 285.915672 -99.058027) (xy 285.952178 -99.010451) (xy 285.994583 -98.968046)
			(xy 286.042159 -98.93154) (xy 286.094093 -98.901556) (xy 286.149497 -98.878607) (xy 286.207422 -98.863086)
			(xy 286.266878 -98.855258) (xy 286.326846 -98.855258) (xy 286.386302 -98.863086) (xy 286.444227 -98.878607)
			(xy 286.499631 -98.901556) (xy 286.551565 -98.93154) (xy 286.599141 -98.968046) (xy 286.641546 -99.010451)
			(xy 286.678052 -99.058027) (xy 286.708036 -99.109961) (xy 286.730985 -99.165365) (xy 286.746506 -99.22329)
			(xy 286.754334 -99.282746) (xy 286.754824 -99.31273) (xy 286.754824 -100.17633) (xy 286.754799 -100.177854)
			(xy 385.6101 -100.177854) (xy 385.6101 -99.314254) (xy 385.61059 -99.284286) (xy 385.618413 -99.224864)
			(xy 385.633926 -99.166971) (xy 385.656862 -99.111598) (xy 385.686829 -99.059692) (xy 385.723316 -99.012142)
			(xy 385.765696 -98.969762) (xy 385.813246 -98.933275) (xy 385.865152 -98.903308) (xy 385.920525 -98.880372)
			(xy 385.978418 -98.864859) (xy 386.03784 -98.857036) (xy 386.097776 -98.857036) (xy 386.157198 -98.864859)
			(xy 386.215091 -98.880372) (xy 386.270464 -98.903308) (xy 386.32237 -98.933275) (xy 386.36992 -98.969762)
			(xy 386.4123 -99.012142) (xy 386.448787 -99.059692) (xy 386.478754 -99.111598) (xy 386.50169 -99.166971)
			(xy 386.517203 -99.224864) (xy 386.525026 -99.284286) (xy 386.525516 -99.314254) (xy 386.525516 -100.17633)
			(xy 401.939252 -100.17633) (xy 401.939252 -99.31273) (xy 401.939742 -99.282762) (xy 401.947565 -99.22334)
			(xy 401.963078 -99.165447) (xy 401.986014 -99.110074) (xy 402.015981 -99.058168) (xy 402.052468 -99.010618)
			(xy 402.094848 -98.968238) (xy 402.142398 -98.931751) (xy 402.194304 -98.901784) (xy 402.249677 -98.878848)
			(xy 402.30757 -98.863335) (xy 402.366992 -98.855512) (xy 402.426928 -98.855512) (xy 402.48635 -98.863335)
			(xy 402.544243 -98.878848) (xy 402.599616 -98.901784) (xy 402.651522 -98.931751) (xy 402.699072 -98.968238)
			(xy 402.741452 -99.010618) (xy 402.777939 -99.058168) (xy 402.807906 -99.110074) (xy 402.830842 -99.165447)
			(xy 402.846355 -99.22334) (xy 402.854178 -99.282762) (xy 402.854668 -99.31273) (xy 402.854668 -100.17633)
			(xy 402.854178 -100.206298) (xy 402.846355 -100.26572) (xy 402.830842 -100.323613) (xy 402.807906 -100.378986)
			(xy 402.777939 -100.430892) (xy 402.741452 -100.478442) (xy 402.699072 -100.520822) (xy 402.651522 -100.557309)
			(xy 402.599616 -100.587276) (xy 402.544243 -100.610212) (xy 402.48635 -100.625725) (xy 402.426928 -100.633548)
			(xy 402.366992 -100.633548) (xy 402.30757 -100.625725) (xy 402.249677 -100.610212) (xy 402.194304 -100.587276)
			(xy 402.142398 -100.557309) (xy 402.094848 -100.520822) (xy 402.052468 -100.478442) (xy 402.015981 -100.430892)
			(xy 401.986014 -100.378986) (xy 401.963078 -100.323613) (xy 401.947565 -100.26572) (xy 401.939742 -100.206298)
			(xy 401.939252 -100.17633) (xy 386.525516 -100.17633) (xy 386.525516 -100.177854) (xy 386.525026 -100.207822)
			(xy 386.517203 -100.267244) (xy 386.50169 -100.325137) (xy 386.478754 -100.38051) (xy 386.448787 -100.432416)
			(xy 386.4123 -100.479966) (xy 386.36992 -100.522346) (xy 386.32237 -100.558833) (xy 386.270464 -100.5888)
			(xy 386.215091 -100.611736) (xy 386.157198 -100.627249) (xy 386.097776 -100.635072) (xy 386.03784 -100.635072)
			(xy 385.978418 -100.627249) (xy 385.920525 -100.611736) (xy 385.865152 -100.5888) (xy 385.813246 -100.558833)
			(xy 385.765696 -100.522346) (xy 385.723316 -100.479966) (xy 385.686829 -100.432416) (xy 385.656862 -100.38051)
			(xy 385.633926 -100.325137) (xy 385.618413 -100.267244) (xy 385.61059 -100.207822) (xy 385.6101 -100.177854)
			(xy 286.754799 -100.177854) (xy 286.754334 -100.206314) (xy 286.746506 -100.26577) (xy 286.730985 -100.323695)
			(xy 286.708036 -100.379099) (xy 286.678052 -100.431033) (xy 286.641546 -100.478609) (xy 286.599141 -100.521014)
			(xy 286.551565 -100.55752) (xy 286.499631 -100.587504) (xy 286.444227 -100.610453) (xy 286.386302 -100.625974)
			(xy 286.326846 -100.633802) (xy 286.266878 -100.633802) (xy 286.207422 -100.625974) (xy 286.149497 -100.610453)
			(xy 286.094093 -100.587504) (xy 286.042159 -100.55752) (xy 285.994583 -100.521014) (xy 285.952178 -100.478609)
			(xy 285.915672 -100.431033) (xy 285.885688 -100.379099) (xy 285.862739 -100.323695) (xy 285.847218 -100.26577)
			(xy 285.83939 -100.206314) (xy 285.8389 -100.17633) (xy 270.425672 -100.17633) (xy 270.425672 -100.177854)
			(xy 270.425182 -100.207838) (xy 270.417354 -100.267294) (xy 270.401833 -100.325219) (xy 270.378884 -100.380623)
			(xy 270.3489 -100.432557) (xy 270.312394 -100.480133) (xy 270.269989 -100.522538) (xy 270.222413 -100.559044)
			(xy 270.170479 -100.589028) (xy 270.115075 -100.611977) (xy 270.05715 -100.627498) (xy 269.997694 -100.635326)
			(xy 269.937726 -100.635326) (xy 269.87827 -100.627498) (xy 269.820345 -100.611977) (xy 269.764941 -100.589028)
			(xy 269.713007 -100.559044) (xy 269.665431 -100.522538) (xy 269.623026 -100.480133) (xy 269.58652 -100.432557)
			(xy 269.556536 -100.380623) (xy 269.533587 -100.325219) (xy 269.518066 -100.267294) (xy 269.510238 -100.207838)
			(xy 269.509748 -100.177854) (xy 264.346465 -100.177854) (xy 264.335357 -100.217498) (xy 264.27232 -100.412804)
			(xy 264.20171 -100.605502) (xy 264.123636 -100.795298) (xy 264.038216 -100.981904) (xy 263.94558 -101.165034)
			(xy 263.84587 -101.344411) (xy 263.739237 -101.519761) (xy 263.625844 -101.690817) (xy 263.505864 -101.857319)
			(xy 263.406609 -101.984302) (xy 267.47724 -101.984302) (xy 267.47724 -101.120702) (xy 267.47773 -101.090718)
			(xy 267.485558 -101.031262) (xy 267.501079 -100.973337) (xy 267.524028 -100.917933) (xy 267.554012 -100.865999)
			(xy 267.590518 -100.818423) (xy 267.632923 -100.776018) (xy 267.680499 -100.739512) (xy 267.732433 -100.709528)
			(xy 267.787837 -100.686579) (xy 267.845762 -100.671058) (xy 267.905218 -100.66323) (xy 267.965186 -100.66323)
			(xy 268.024642 -100.671058) (xy 268.082567 -100.686579) (xy 268.137971 -100.709528) (xy 268.189905 -100.739512)
			(xy 268.237481 -100.776018) (xy 268.279886 -100.818423) (xy 268.316392 -100.865999) (xy 268.346376 -100.917933)
			(xy 268.369325 -100.973337) (xy 268.384846 -101.031262) (xy 268.392674 -101.090718) (xy 268.393164 -101.120702)
			(xy 268.393164 -101.976428) (xy 283.9847 -101.976428) (xy 283.9847 -101.112828) (xy 283.98519 -101.082844)
			(xy 283.993018 -101.023388) (xy 284.008539 -100.965463) (xy 284.031488 -100.910059) (xy 284.061472 -100.858125)
			(xy 284.097978 -100.810549) (xy 284.140383 -100.768144) (xy 284.187959 -100.731638) (xy 284.239893 -100.701654)
			(xy 284.295297 -100.678705) (xy 284.353222 -100.663184) (xy 284.412678 -100.655356) (xy 284.472646 -100.655356)
			(xy 284.532102 -100.663184) (xy 284.590027 -100.678705) (xy 284.645431 -100.701654) (xy 284.697365 -100.731638)
			(xy 284.744941 -100.768144) (xy 284.787346 -100.810549) (xy 284.823852 -100.858125) (xy 284.853836 -100.910059)
			(xy 284.876785 -100.965463) (xy 284.892306 -101.023388) (xy 284.900134 -101.082844) (xy 284.900624 -101.112828)
			(xy 284.900624 -101.976428) (xy 284.900495 -101.984302) (xy 383.577592 -101.984302) (xy 383.577592 -101.120702)
			(xy 383.578082 -101.090734) (xy 383.585905 -101.031312) (xy 383.601418 -100.973419) (xy 383.624354 -100.918046)
			(xy 383.654321 -100.86614) (xy 383.690808 -100.81859) (xy 383.733188 -100.77621) (xy 383.780738 -100.739723)
			(xy 383.832644 -100.709756) (xy 383.888017 -100.68682) (xy 383.94591 -100.671307) (xy 384.005332 -100.663484)
			(xy 384.065268 -100.663484) (xy 384.12469 -100.671307) (xy 384.182583 -100.68682) (xy 384.237956 -100.709756)
			(xy 384.289862 -100.739723) (xy 384.337412 -100.77621) (xy 384.379792 -100.81859) (xy 384.416279 -100.86614)
			(xy 384.446246 -100.918046) (xy 384.469182 -100.973419) (xy 384.484695 -101.031312) (xy 384.492518 -101.090734)
			(xy 384.493008 -101.120702) (xy 384.493008 -101.976428) (xy 400.085052 -101.976428) (xy 400.085052 -101.112828)
			(xy 400.085542 -101.08286) (xy 400.093365 -101.023438) (xy 400.108878 -100.965545) (xy 400.131814 -100.910172)
			(xy 400.161781 -100.858266) (xy 400.198268 -100.810716) (xy 400.240648 -100.768336) (xy 400.288198 -100.731849)
			(xy 400.340104 -100.701882) (xy 400.395477 -100.678946) (xy 400.45337 -100.663433) (xy 400.512792 -100.65561)
			(xy 400.572728 -100.65561) (xy 400.63215 -100.663433) (xy 400.690043 -100.678946) (xy 400.745416 -100.701882)
			(xy 400.797322 -100.731849) (xy 400.844872 -100.768336) (xy 400.887252 -100.810716) (xy 400.923739 -100.858266)
			(xy 400.953706 -100.910172) (xy 400.976642 -100.965545) (xy 400.992155 -101.023438) (xy 400.999978 -101.08286)
			(xy 401.000468 -101.112828) (xy 401.000468 -101.976428) (xy 400.999978 -102.006396) (xy 400.992155 -102.065818)
			(xy 400.976642 -102.123711) (xy 400.953706 -102.179084) (xy 400.923739 -102.23099) (xy 400.887252 -102.27854)
			(xy 400.844872 -102.32092) (xy 400.797322 -102.357407) (xy 400.745416 -102.387374) (xy 400.690043 -102.41031)
			(xy 400.63215 -102.425823) (xy 400.572728 -102.433646) (xy 400.512792 -102.433646) (xy 400.45337 -102.425823)
			(xy 400.395477 -102.41031) (xy 400.340104 -102.387374) (xy 400.288198 -102.357407) (xy 400.240648 -102.32092)
			(xy 400.198268 -102.27854) (xy 400.161781 -102.23099) (xy 400.131814 -102.179084) (xy 400.108878 -102.123711)
			(xy 400.093365 -102.065818) (xy 400.085542 -102.006396) (xy 400.085052 -101.976428) (xy 384.493008 -101.976428)
			(xy 384.493008 -101.984302) (xy 384.492518 -102.01427) (xy 384.484695 -102.073692) (xy 384.469182 -102.131585)
			(xy 384.446246 -102.186958) (xy 384.416279 -102.238864) (xy 384.379792 -102.286414) (xy 384.337412 -102.328794)
			(xy 384.289862 -102.365281) (xy 384.237956 -102.395248) (xy 384.182583 -102.418184) (xy 384.12469 -102.433697)
			(xy 384.065268 -102.44152) (xy 384.005332 -102.44152) (xy 383.94591 -102.433697) (xy 383.888017 -102.418184)
			(xy 383.832644 -102.395248) (xy 383.780738 -102.365281) (xy 383.733188 -102.328794) (xy 383.690808 -102.286414)
			(xy 383.654321 -102.238864) (xy 383.624354 -102.186958) (xy 383.601418 -102.131585) (xy 383.585905 -102.073692)
			(xy 383.578082 -102.01427) (xy 383.577592 -101.984302) (xy 284.900495 -101.984302) (xy 284.900134 -102.006412)
			(xy 284.892306 -102.065868) (xy 284.876785 -102.123793) (xy 284.853836 -102.179197) (xy 284.823852 -102.231131)
			(xy 284.787346 -102.278707) (xy 284.744941 -102.321112) (xy 284.697365 -102.357618) (xy 284.645431 -102.387602)
			(xy 284.590027 -102.410551) (xy 284.532102 -102.426072) (xy 284.472646 -102.4339) (xy 284.412678 -102.4339)
			(xy 284.353222 -102.426072) (xy 284.295297 -102.410551) (xy 284.239893 -102.387602) (xy 284.187959 -102.357618)
			(xy 284.140383 -102.321112) (xy 284.097978 -102.278707) (xy 284.061472 -102.231131) (xy 284.031488 -102.179197)
			(xy 284.008539 -102.123793) (xy 283.993018 -102.065868) (xy 283.98519 -102.006412) (xy 283.9847 -101.976428)
			(xy 268.393164 -101.976428) (xy 268.393164 -101.984302) (xy 268.392674 -102.014286) (xy 268.384846 -102.073742)
			(xy 268.369325 -102.131667) (xy 268.346376 -102.187071) (xy 268.316392 -102.239005) (xy 268.279886 -102.286581)
			(xy 268.237481 -102.328986) (xy 268.189905 -102.365492) (xy 268.137971 -102.395476) (xy 268.082567 -102.418425)
			(xy 268.024642 -102.433946) (xy 267.965186 -102.441774) (xy 267.905218 -102.441774) (xy 267.845762 -102.433946)
			(xy 267.787837 -102.418425) (xy 267.732433 -102.395476) (xy 267.680499 -102.365492) (xy 267.632923 -102.328986)
			(xy 267.590518 -102.286581) (xy 267.554012 -102.239005) (xy 267.524028 -102.187071) (xy 267.501079 -102.131667)
			(xy 267.485558 -102.073742) (xy 267.47773 -102.014286) (xy 267.47724 -101.984302) (xy 263.406609 -101.984302)
			(xy 263.379478 -102.019013) (xy 263.24688 -102.175653) (xy 263.108272 -102.326999) (xy 262.963864 -102.472823)
			(xy 262.813877 -102.612902) (xy 262.658538 -102.747021) (xy 262.498085 -102.874978) (xy 262.332762 -102.996578)
			(xy 262.16282 -103.111634) (xy 261.988519 -103.219973) (xy 261.810123 -103.321428) (xy 261.627905 -103.415846)
			(xy 261.442142 -103.503082) (xy 261.253117 -103.583005) (xy 261.061117 -103.655491) (xy 260.866435 -103.720431)
			(xy 260.669368 -103.777726) (xy 260.669087 -103.777796) (xy 269.509748 -103.777796) (xy 269.509748 -102.914196)
			(xy 269.510238 -102.884212) (xy 269.518066 -102.824756) (xy 269.533587 -102.766831) (xy 269.556536 -102.711427)
			(xy 269.58652 -102.659493) (xy 269.623026 -102.611917) (xy 269.665431 -102.569512) (xy 269.713007 -102.533006)
			(xy 269.764941 -102.503022) (xy 269.820345 -102.480073) (xy 269.87827 -102.464552) (xy 269.937726 -102.456724)
			(xy 269.997694 -102.456724) (xy 270.05715 -102.464552) (xy 270.115075 -102.480073) (xy 270.170479 -102.503022)
			(xy 270.222413 -102.533006) (xy 270.269989 -102.569512) (xy 270.312394 -102.611917) (xy 270.3489 -102.659493)
			(xy 270.378884 -102.711427) (xy 270.401833 -102.766831) (xy 270.417354 -102.824756) (xy 270.425182 -102.884212)
			(xy 270.425672 -102.914196) (xy 270.425672 -103.776272) (xy 285.8389 -103.776272) (xy 285.8389 -102.912672)
			(xy 285.83939 -102.882688) (xy 285.847218 -102.823232) (xy 285.862739 -102.765307) (xy 285.885688 -102.709903)
			(xy 285.915672 -102.657969) (xy 285.952178 -102.610393) (xy 285.994583 -102.567988) (xy 286.042159 -102.531482)
			(xy 286.094093 -102.501498) (xy 286.149497 -102.478549) (xy 286.207422 -102.463028) (xy 286.266878 -102.4552)
			(xy 286.326846 -102.4552) (xy 286.386302 -102.463028) (xy 286.444227 -102.478549) (xy 286.499631 -102.501498)
			(xy 286.551565 -102.531482) (xy 286.599141 -102.567988) (xy 286.641546 -102.610393) (xy 286.678052 -102.657969)
			(xy 286.708036 -102.709903) (xy 286.730985 -102.765307) (xy 286.746506 -102.823232) (xy 286.754334 -102.882688)
			(xy 286.754824 -102.912672) (xy 286.754824 -103.776272) (xy 286.754799 -103.777796) (xy 385.6101 -103.777796)
			(xy 385.6101 -102.914196) (xy 385.61059 -102.884228) (xy 385.618413 -102.824806) (xy 385.633926 -102.766913)
			(xy 385.656862 -102.71154) (xy 385.686829 -102.659634) (xy 385.723316 -102.612084) (xy 385.765696 -102.569704)
			(xy 385.813246 -102.533217) (xy 385.865152 -102.50325) (xy 385.920525 -102.480314) (xy 385.978418 -102.464801)
			(xy 386.03784 -102.456978) (xy 386.097776 -102.456978) (xy 386.157198 -102.464801) (xy 386.215091 -102.480314)
			(xy 386.270464 -102.50325) (xy 386.32237 -102.533217) (xy 386.36992 -102.569704) (xy 386.4123 -102.612084)
			(xy 386.448787 -102.659634) (xy 386.478754 -102.71154) (xy 386.50169 -102.766913) (xy 386.517203 -102.824806)
			(xy 386.525026 -102.884228) (xy 386.525516 -102.914196) (xy 386.525516 -103.776272) (xy 401.939252 -103.776272)
			(xy 401.939252 -102.912672) (xy 401.939742 -102.882704) (xy 401.947565 -102.823282) (xy 401.963078 -102.765389)
			(xy 401.986014 -102.710016) (xy 402.015981 -102.65811) (xy 402.052468 -102.61056) (xy 402.094848 -102.56818)
			(xy 402.142398 -102.531693) (xy 402.194304 -102.501726) (xy 402.249677 -102.47879) (xy 402.30757 -102.463277)
			(xy 402.366992 -102.455454) (xy 402.426928 -102.455454) (xy 402.48635 -102.463277) (xy 402.544243 -102.47879)
			(xy 402.599616 -102.501726) (xy 402.651522 -102.531693) (xy 402.699072 -102.56818) (xy 402.741452 -102.61056)
			(xy 402.777939 -102.65811) (xy 402.807906 -102.710016) (xy 402.830842 -102.765389) (xy 402.846355 -102.823282)
			(xy 402.854178 -102.882704) (xy 402.854668 -102.912672) (xy 402.854668 -103.776272) (xy 402.854178 -103.80624)
			(xy 402.846355 -103.865662) (xy 402.830842 -103.923555) (xy 402.807906 -103.978928) (xy 402.777939 -104.030834)
			(xy 402.741452 -104.078384) (xy 402.699072 -104.120764) (xy 402.651522 -104.157251) (xy 402.599616 -104.187218)
			(xy 402.544243 -104.210154) (xy 402.48635 -104.225667) (xy 402.426928 -104.23349) (xy 402.366992 -104.23349)
			(xy 402.30757 -104.225667) (xy 402.249677 -104.210154) (xy 402.194304 -104.187218) (xy 402.142398 -104.157251)
			(xy 402.094848 -104.120764) (xy 402.052468 -104.078384) (xy 402.015981 -104.030834) (xy 401.986014 -103.978928)
			(xy 401.963078 -103.923555) (xy 401.947565 -103.865662) (xy 401.939742 -103.80624) (xy 401.939252 -103.776272)
			(xy 386.525516 -103.776272) (xy 386.525516 -103.777796) (xy 386.525026 -103.807764) (xy 386.517203 -103.867186)
			(xy 386.50169 -103.925079) (xy 386.478754 -103.980452) (xy 386.448787 -104.032358) (xy 386.4123 -104.079908)
			(xy 386.36992 -104.122288) (xy 386.32237 -104.158775) (xy 386.270464 -104.188742) (xy 386.215091 -104.211678)
			(xy 386.157198 -104.227191) (xy 386.097776 -104.235014) (xy 386.03784 -104.235014) (xy 385.978418 -104.227191)
			(xy 385.920525 -104.211678) (xy 385.865152 -104.188742) (xy 385.813246 -104.158775) (xy 385.765696 -104.122288)
			(xy 385.723316 -104.079908) (xy 385.686829 -104.032358) (xy 385.656862 -103.980452) (xy 385.633926 -103.925079)
			(xy 385.618413 -103.867186) (xy 385.61059 -103.807764) (xy 385.6101 -103.777796) (xy 286.754799 -103.777796)
			(xy 286.754334 -103.806256) (xy 286.746506 -103.865712) (xy 286.730985 -103.923637) (xy 286.708036 -103.979041)
			(xy 286.678052 -104.030975) (xy 286.641546 -104.078551) (xy 286.599141 -104.120956) (xy 286.551565 -104.157462)
			(xy 286.499631 -104.187446) (xy 286.444227 -104.210395) (xy 286.386302 -104.225916) (xy 286.326846 -104.233744)
			(xy 286.266878 -104.233744) (xy 286.207422 -104.225916) (xy 286.149497 -104.210395) (xy 286.094093 -104.187446)
			(xy 286.042159 -104.157462) (xy 285.994583 -104.120956) (xy 285.952178 -104.078551) (xy 285.915672 -104.030975)
			(xy 285.885688 -103.979041) (xy 285.862739 -103.923637) (xy 285.847218 -103.865712) (xy 285.83939 -103.806256)
			(xy 285.8389 -103.776272) (xy 270.425672 -103.776272) (xy 270.425672 -103.777796) (xy 270.425182 -103.80778)
			(xy 270.417354 -103.867236) (xy 270.401833 -103.925161) (xy 270.378884 -103.980565) (xy 270.3489 -104.032499)
			(xy 270.312394 -104.080075) (xy 270.269989 -104.12248) (xy 270.222413 -104.158986) (xy 270.170479 -104.18897)
			(xy 270.115075 -104.211919) (xy 270.05715 -104.22744) (xy 269.997694 -104.235268) (xy 269.937726 -104.235268)
			(xy 269.87827 -104.22744) (xy 269.820345 -104.211919) (xy 269.764941 -104.18897) (xy 269.713007 -104.158986)
			(xy 269.665431 -104.12248) (xy 269.623026 -104.080075) (xy 269.58652 -104.032499) (xy 269.556536 -103.980565)
			(xy 269.533587 -103.925161) (xy 269.518066 -103.867236) (xy 269.510238 -103.80778) (xy 269.509748 -103.777796)
			(xy 260.669087 -103.777796) (xy 260.470215 -103.827289) (xy 260.269281 -103.869044) (xy 260.06687 -103.902927)
			(xy 259.863292 -103.928887) (xy 259.658855 -103.946884) (xy 259.453872 -103.956892) (xy 259.248655 -103.958894)
			(xy 259.043516 -103.952888) (xy 258.838767 -103.938883) (xy 258.63472 -103.9169) (xy 258.431687 -103.886973)
			(xy 258.229976 -103.849146) (xy 258.029894 -103.803479) (xy 257.831747 -103.75004) (xy 257.635835 -103.688911)
			(xy 257.442458 -103.620185) (xy 257.251909 -103.543966) (xy 257.064479 -103.46037) (xy 256.880453 -103.369526)
			(xy 256.700112 -103.271571) (xy 256.52373 -103.166654) (xy 256.351576 -103.054935) (xy 256.183911 -102.936585)
			(xy 256.020992 -102.811783) (xy 255.863066 -102.680719) (xy 255.710374 -102.543594) (xy 255.563149 -102.400616)
			(xy 255.421614 -102.252002) (xy 255.285985 -102.09798) (xy 255.156468 -101.938783) (xy 255.033262 -101.774654)
			(xy 254.916553 -101.605843) (xy 254.806519 -101.432606) (xy 254.703328 -101.255209) (xy 254.607137 -101.073921)
			(xy 254.518092 -100.889018) (xy 254.436329 -100.700781) (xy 254.361973 -100.509498) (xy 254.295137 -100.315459)
			(xy 254.235922 -100.11896) (xy 254.184419 -99.920301) (xy 254.140705 -99.719783) (xy 254.104849 -99.517712)
			(xy 254.076904 -99.314397) (xy 254.056913 -99.110146) (xy 254.044906 -98.90527) (xy 254.040902 -98.700082)
			(xy 213.558628 -98.700082) (xy 213.558127 -98.802696) (xy 213.55012 -99.007766) (xy 213.534118 -99.212369)
			(xy 213.510145 -99.416191) (xy 213.478238 -99.618923) (xy 213.438446 -99.820255) (xy 213.390829 -100.019882)
			(xy 213.335459 -100.217498) (xy 213.272422 -100.412804) (xy 213.201812 -100.605502) (xy 213.123738 -100.795298)
			(xy 213.038318 -100.981904) (xy 212.945682 -101.165034) (xy 212.845972 -101.344411) (xy 212.739339 -101.519761)
			(xy 212.625946 -101.690817) (xy 212.505966 -101.857319) (xy 212.37958 -102.019013) (xy 212.246982 -102.175653)
			(xy 212.108374 -102.326999) (xy 211.963966 -102.472823) (xy 211.813979 -102.612902) (xy 211.65864 -102.747021)
			(xy 211.498187 -102.874978) (xy 211.332864 -102.996578) (xy 211.162922 -103.111634) (xy 210.988621 -103.219973)
			(xy 210.810225 -103.321428) (xy 210.628007 -103.415846) (xy 210.442244 -103.503082) (xy 210.253219 -103.583005)
			(xy 210.061219 -103.655491) (xy 209.866537 -103.720431) (xy 209.66947 -103.777726) (xy 209.470317 -103.827289)
			(xy 209.269383 -103.869044) (xy 209.066972 -103.902927) (xy 208.863394 -103.928887) (xy 208.658957 -103.946884)
			(xy 208.453974 -103.956892) (xy 208.248757 -103.958894) (xy 208.043618 -103.952888) (xy 207.838869 -103.938883)
			(xy 207.634822 -103.9169) (xy 207.431789 -103.886973) (xy 207.230078 -103.849146) (xy 207.029996 -103.803479)
			(xy 206.831849 -103.75004) (xy 206.635937 -103.688911) (xy 206.44256 -103.620185) (xy 206.252011 -103.543966)
			(xy 206.064581 -103.46037) (xy 205.880555 -103.369526) (xy 205.700214 -103.271571) (xy 205.523832 -103.166654)
			(xy 205.351678 -103.054935) (xy 205.184013 -102.936585) (xy 205.021094 -102.811783) (xy 204.863168 -102.680719)
			(xy 204.710476 -102.543594) (xy 204.563251 -102.400616) (xy 204.421716 -102.252002) (xy 204.286087 -102.09798)
			(xy 204.15657 -101.938783) (xy 204.033364 -101.774654) (xy 203.916655 -101.605843) (xy 203.806621 -101.432606)
			(xy 203.70343 -101.255209) (xy 203.607239 -101.073921) (xy 203.518194 -100.889018) (xy 203.436431 -100.700781)
			(xy 203.362075 -100.509498) (xy 203.295239 -100.315459) (xy 203.236024 -100.11896) (xy 203.184521 -99.920301)
			(xy 203.140807 -99.719783) (xy 203.104951 -99.517712) (xy 203.077006 -99.314397) (xy 203.057015 -99.110146)
			(xy 203.045008 -98.90527) (xy 203.041004 -98.700082) (xy 5.324094 -98.700082) (xy 5.324094 -100.177854)
			(xy 37.31006 -100.177854) (xy 37.31006 -99.314254) (xy 37.31055 -99.284286) (xy 37.318373 -99.224864)
			(xy 37.333886 -99.166971) (xy 37.356822 -99.111598) (xy 37.386789 -99.059692) (xy 37.423276 -99.012142)
			(xy 37.465656 -98.969762) (xy 37.513206 -98.933275) (xy 37.565112 -98.903308) (xy 37.620485 -98.880372)
			(xy 37.678378 -98.864859) (xy 37.7378 -98.857036) (xy 37.797736 -98.857036) (xy 37.857158 -98.864859)
			(xy 37.915051 -98.880372) (xy 37.970424 -98.903308) (xy 38.02233 -98.933275) (xy 38.06988 -98.969762)
			(xy 38.11226 -99.012142) (xy 38.148747 -99.059692) (xy 38.178714 -99.111598) (xy 38.20165 -99.166971)
			(xy 38.217163 -99.224864) (xy 38.224986 -99.284286) (xy 38.225476 -99.314254) (xy 38.225476 -100.17633)
			(xy 53.639212 -100.17633) (xy 53.639212 -99.31273) (xy 53.639702 -99.282762) (xy 53.647525 -99.22334)
			(xy 53.663038 -99.165447) (xy 53.685974 -99.110074) (xy 53.715941 -99.058168) (xy 53.752428 -99.010618)
			(xy 53.794808 -98.968238) (xy 53.842358 -98.931751) (xy 53.894264 -98.901784) (xy 53.949637 -98.878848)
			(xy 54.00753 -98.863335) (xy 54.066952 -98.855512) (xy 54.126888 -98.855512) (xy 54.18631 -98.863335)
			(xy 54.244203 -98.878848) (xy 54.299576 -98.901784) (xy 54.351482 -98.931751) (xy 54.399032 -98.968238)
			(xy 54.441412 -99.010618) (xy 54.477899 -99.058168) (xy 54.507866 -99.110074) (xy 54.530802 -99.165447)
			(xy 54.546315 -99.22334) (xy 54.554138 -99.282762) (xy 54.554628 -99.31273) (xy 54.554628 -100.17633)
			(xy 54.554603 -100.177854) (xy 153.409904 -100.177854) (xy 153.409904 -99.314254) (xy 153.410394 -99.28427)
			(xy 153.418222 -99.224814) (xy 153.433743 -99.166889) (xy 153.456692 -99.111485) (xy 153.486676 -99.059551)
			(xy 153.523182 -99.011975) (xy 153.565587 -98.96957) (xy 153.613163 -98.933064) (xy 153.665097 -98.90308)
			(xy 153.720501 -98.880131) (xy 153.778426 -98.86461) (xy 153.837882 -98.856782) (xy 153.89785 -98.856782)
			(xy 153.957306 -98.86461) (xy 154.015231 -98.880131) (xy 154.070635 -98.90308) (xy 154.122569 -98.933064)
			(xy 154.170145 -98.96957) (xy 154.21255 -99.011975) (xy 154.249056 -99.059551) (xy 154.27904 -99.111485)
			(xy 154.301989 -99.166889) (xy 154.31751 -99.224814) (xy 154.325338 -99.28427) (xy 154.325828 -99.314254)
			(xy 154.325828 -100.17633) (xy 169.739056 -100.17633) (xy 169.739056 -99.31273) (xy 169.739546 -99.282746)
			(xy 169.747374 -99.22329) (xy 169.762895 -99.165365) (xy 169.785844 -99.109961) (xy 169.815828 -99.058027)
			(xy 169.852334 -99.010451) (xy 169.894739 -98.968046) (xy 169.942315 -98.93154) (xy 169.994249 -98.901556)
			(xy 170.049653 -98.878607) (xy 170.107578 -98.863086) (xy 170.167034 -98.855258) (xy 170.227002 -98.855258)
			(xy 170.286458 -98.863086) (xy 170.344383 -98.878607) (xy 170.399787 -98.901556) (xy 170.451721 -98.93154)
			(xy 170.499297 -98.968046) (xy 170.541702 -99.010451) (xy 170.578208 -99.058027) (xy 170.608192 -99.109961)
			(xy 170.631141 -99.165365) (xy 170.646662 -99.22329) (xy 170.65449 -99.282746) (xy 170.65498 -99.31273)
			(xy 170.65498 -100.17633) (xy 170.65449 -100.206314) (xy 170.646662 -100.26577) (xy 170.631141 -100.323695)
			(xy 170.608192 -100.379099) (xy 170.578208 -100.431033) (xy 170.541702 -100.478609) (xy 170.499297 -100.521014)
			(xy 170.451721 -100.55752) (xy 170.399787 -100.587504) (xy 170.344383 -100.610453) (xy 170.286458 -100.625974)
			(xy 170.227002 -100.633802) (xy 170.167034 -100.633802) (xy 170.107578 -100.625974) (xy 170.049653 -100.610453)
			(xy 169.994249 -100.587504) (xy 169.942315 -100.55752) (xy 169.894739 -100.521014) (xy 169.852334 -100.478609)
			(xy 169.815828 -100.431033) (xy 169.785844 -100.379099) (xy 169.762895 -100.323695) (xy 169.747374 -100.26577)
			(xy 169.739546 -100.206314) (xy 169.739056 -100.17633) (xy 154.325828 -100.17633) (xy 154.325828 -100.177854)
			(xy 154.325338 -100.207838) (xy 154.31751 -100.267294) (xy 154.301989 -100.325219) (xy 154.27904 -100.380623)
			(xy 154.249056 -100.432557) (xy 154.21255 -100.480133) (xy 154.170145 -100.522538) (xy 154.122569 -100.559044)
			(xy 154.070635 -100.589028) (xy 154.015231 -100.611977) (xy 153.957306 -100.627498) (xy 153.89785 -100.635326)
			(xy 153.837882 -100.635326) (xy 153.778426 -100.627498) (xy 153.720501 -100.611977) (xy 153.665097 -100.589028)
			(xy 153.613163 -100.559044) (xy 153.565587 -100.522538) (xy 153.523182 -100.480133) (xy 153.486676 -100.432557)
			(xy 153.456692 -100.380623) (xy 153.433743 -100.325219) (xy 153.418222 -100.267294) (xy 153.410394 -100.207838)
			(xy 153.409904 -100.177854) (xy 54.554603 -100.177854) (xy 54.554138 -100.206298) (xy 54.546315 -100.26572)
			(xy 54.530802 -100.323613) (xy 54.507866 -100.378986) (xy 54.477899 -100.430892) (xy 54.441412 -100.478442)
			(xy 54.399032 -100.520822) (xy 54.351482 -100.557309) (xy 54.299576 -100.587276) (xy 54.244203 -100.610212)
			(xy 54.18631 -100.625725) (xy 54.126888 -100.633548) (xy 54.066952 -100.633548) (xy 54.00753 -100.625725)
			(xy 53.949637 -100.610212) (xy 53.894264 -100.587276) (xy 53.842358 -100.557309) (xy 53.794808 -100.520822)
			(xy 53.752428 -100.478442) (xy 53.715941 -100.430892) (xy 53.685974 -100.378986) (xy 53.663038 -100.323613)
			(xy 53.647525 -100.26572) (xy 53.639702 -100.206298) (xy 53.639212 -100.17633) (xy 38.225476 -100.17633)
			(xy 38.225476 -100.177854) (xy 38.224986 -100.207822) (xy 38.217163 -100.267244) (xy 38.20165 -100.325137)
			(xy 38.178714 -100.38051) (xy 38.148747 -100.432416) (xy 38.11226 -100.479966) (xy 38.06988 -100.522346)
			(xy 38.02233 -100.558833) (xy 37.970424 -100.5888) (xy 37.915051 -100.611736) (xy 37.857158 -100.627249)
			(xy 37.797736 -100.635072) (xy 37.7378 -100.635072) (xy 37.678378 -100.627249) (xy 37.620485 -100.611736)
			(xy 37.565112 -100.5888) (xy 37.513206 -100.558833) (xy 37.465656 -100.522346) (xy 37.423276 -100.479966)
			(xy 37.386789 -100.432416) (xy 37.356822 -100.38051) (xy 37.333886 -100.325137) (xy 37.318373 -100.267244)
			(xy 37.31055 -100.207822) (xy 37.31006 -100.177854) (xy 5.324094 -100.177854) (xy 5.324094 -101.984302)
			(xy 35.277552 -101.984302) (xy 35.277552 -101.120702) (xy 35.278042 -101.090734) (xy 35.285865 -101.031312)
			(xy 35.301378 -100.973419) (xy 35.324314 -100.918046) (xy 35.354281 -100.86614) (xy 35.390768 -100.81859)
			(xy 35.433148 -100.77621) (xy 35.480698 -100.739723) (xy 35.532604 -100.709756) (xy 35.587977 -100.68682)
			(xy 35.64587 -100.671307) (xy 35.705292 -100.663484) (xy 35.765228 -100.663484) (xy 35.82465 -100.671307)
			(xy 35.882543 -100.68682) (xy 35.937916 -100.709756) (xy 35.989822 -100.739723) (xy 36.037372 -100.77621)
			(xy 36.079752 -100.81859) (xy 36.116239 -100.86614) (xy 36.146206 -100.918046) (xy 36.169142 -100.973419)
			(xy 36.184655 -101.031312) (xy 36.192478 -101.090734) (xy 36.192968 -101.120702) (xy 36.192968 -101.976428)
			(xy 51.785012 -101.976428) (xy 51.785012 -101.112828) (xy 51.785502 -101.08286) (xy 51.793325 -101.023438)
			(xy 51.808838 -100.965545) (xy 51.831774 -100.910172) (xy 51.861741 -100.858266) (xy 51.898228 -100.810716)
			(xy 51.940608 -100.768336) (xy 51.988158 -100.731849) (xy 52.040064 -100.701882) (xy 52.095437 -100.678946)
			(xy 52.15333 -100.663433) (xy 52.212752 -100.65561) (xy 52.272688 -100.65561) (xy 52.33211 -100.663433)
			(xy 52.390003 -100.678946) (xy 52.445376 -100.701882) (xy 52.497282 -100.731849) (xy 52.544832 -100.768336)
			(xy 52.587212 -100.810716) (xy 52.623699 -100.858266) (xy 52.653666 -100.910172) (xy 52.676602 -100.965545)
			(xy 52.692115 -101.023438) (xy 52.699938 -101.08286) (xy 52.700428 -101.112828) (xy 52.700428 -101.976428)
			(xy 52.700299 -101.984302) (xy 151.377396 -101.984302) (xy 151.377396 -101.120702) (xy 151.377886 -101.090718)
			(xy 151.385714 -101.031262) (xy 151.401235 -100.973337) (xy 151.424184 -100.917933) (xy 151.454168 -100.865999)
			(xy 151.490674 -100.818423) (xy 151.533079 -100.776018) (xy 151.580655 -100.739512) (xy 151.632589 -100.709528)
			(xy 151.687993 -100.686579) (xy 151.745918 -100.671058) (xy 151.805374 -100.66323) (xy 151.865342 -100.66323)
			(xy 151.924798 -100.671058) (xy 151.982723 -100.686579) (xy 152.038127 -100.709528) (xy 152.090061 -100.739512)
			(xy 152.137637 -100.776018) (xy 152.180042 -100.818423) (xy 152.216548 -100.865999) (xy 152.246532 -100.917933)
			(xy 152.269481 -100.973337) (xy 152.285002 -101.031262) (xy 152.29283 -101.090718) (xy 152.29332 -101.120702)
			(xy 152.29332 -101.976428) (xy 167.884856 -101.976428) (xy 167.884856 -101.112828) (xy 167.885346 -101.082844)
			(xy 167.893174 -101.023388) (xy 167.908695 -100.965463) (xy 167.931644 -100.910059) (xy 167.961628 -100.858125)
			(xy 167.998134 -100.810549) (xy 168.040539 -100.768144) (xy 168.088115 -100.731638) (xy 168.140049 -100.701654)
			(xy 168.195453 -100.678705) (xy 168.253378 -100.663184) (xy 168.312834 -100.655356) (xy 168.372802 -100.655356)
			(xy 168.432258 -100.663184) (xy 168.490183 -100.678705) (xy 168.545587 -100.701654) (xy 168.597521 -100.731638)
			(xy 168.645097 -100.768144) (xy 168.687502 -100.810549) (xy 168.724008 -100.858125) (xy 168.753992 -100.910059)
			(xy 168.776941 -100.965463) (xy 168.792462 -101.023388) (xy 168.80029 -101.082844) (xy 168.80078 -101.112828)
			(xy 168.80078 -101.976428) (xy 168.80029 -102.006412) (xy 168.792462 -102.065868) (xy 168.776941 -102.123793)
			(xy 168.753992 -102.179197) (xy 168.724008 -102.231131) (xy 168.687502 -102.278707) (xy 168.645097 -102.321112)
			(xy 168.597521 -102.357618) (xy 168.545587 -102.387602) (xy 168.490183 -102.410551) (xy 168.432258 -102.426072)
			(xy 168.372802 -102.4339) (xy 168.312834 -102.4339) (xy 168.253378 -102.426072) (xy 168.195453 -102.410551)
			(xy 168.140049 -102.387602) (xy 168.088115 -102.357618) (xy 168.040539 -102.321112) (xy 167.998134 -102.278707)
			(xy 167.961628 -102.231131) (xy 167.931644 -102.179197) (xy 167.908695 -102.123793) (xy 167.893174 -102.065868)
			(xy 167.885346 -102.006412) (xy 167.884856 -101.976428) (xy 152.29332 -101.976428) (xy 152.29332 -101.984302)
			(xy 152.29283 -102.014286) (xy 152.285002 -102.073742) (xy 152.269481 -102.131667) (xy 152.246532 -102.187071)
			(xy 152.216548 -102.239005) (xy 152.180042 -102.286581) (xy 152.137637 -102.328986) (xy 152.090061 -102.365492)
			(xy 152.038127 -102.395476) (xy 151.982723 -102.418425) (xy 151.924798 -102.433946) (xy 151.865342 -102.441774)
			(xy 151.805374 -102.441774) (xy 151.745918 -102.433946) (xy 151.687993 -102.418425) (xy 151.632589 -102.395476)
			(xy 151.580655 -102.365492) (xy 151.533079 -102.328986) (xy 151.490674 -102.286581) (xy 151.454168 -102.239005)
			(xy 151.424184 -102.187071) (xy 151.401235 -102.131667) (xy 151.385714 -102.073742) (xy 151.377886 -102.014286)
			(xy 151.377396 -101.984302) (xy 52.700299 -101.984302) (xy 52.699938 -102.006396) (xy 52.692115 -102.065818)
			(xy 52.676602 -102.123711) (xy 52.653666 -102.179084) (xy 52.623699 -102.23099) (xy 52.587212 -102.27854)
			(xy 52.544832 -102.32092) (xy 52.497282 -102.357407) (xy 52.445376 -102.387374) (xy 52.390003 -102.41031)
			(xy 52.33211 -102.425823) (xy 52.272688 -102.433646) (xy 52.212752 -102.433646) (xy 52.15333 -102.425823)
			(xy 52.095437 -102.41031) (xy 52.040064 -102.387374) (xy 51.988158 -102.357407) (xy 51.940608 -102.32092)
			(xy 51.898228 -102.27854) (xy 51.861741 -102.23099) (xy 51.831774 -102.179084) (xy 51.808838 -102.123711)
			(xy 51.793325 -102.065818) (xy 51.785502 -102.006396) (xy 51.785012 -101.976428) (xy 36.192968 -101.976428)
			(xy 36.192968 -101.984302) (xy 36.192478 -102.01427) (xy 36.184655 -102.073692) (xy 36.169142 -102.131585)
			(xy 36.146206 -102.186958) (xy 36.116239 -102.238864) (xy 36.079752 -102.286414) (xy 36.037372 -102.328794)
			(xy 35.989822 -102.365281) (xy 35.937916 -102.395248) (xy 35.882543 -102.418184) (xy 35.82465 -102.433697)
			(xy 35.765228 -102.44152) (xy 35.705292 -102.44152) (xy 35.64587 -102.433697) (xy 35.587977 -102.418184)
			(xy 35.532604 -102.395248) (xy 35.480698 -102.365281) (xy 35.433148 -102.328794) (xy 35.390768 -102.286414)
			(xy 35.354281 -102.238864) (xy 35.324314 -102.186958) (xy 35.301378 -102.131585) (xy 35.285865 -102.073692)
			(xy 35.278042 -102.01427) (xy 35.277552 -101.984302) (xy 5.324094 -101.984302) (xy 5.324094 -103.777796)
			(xy 37.31006 -103.777796) (xy 37.31006 -102.914196) (xy 37.31055 -102.884228) (xy 37.318373 -102.824806)
			(xy 37.333886 -102.766913) (xy 37.356822 -102.71154) (xy 37.386789 -102.659634) (xy 37.423276 -102.612084)
			(xy 37.465656 -102.569704) (xy 37.513206 -102.533217) (xy 37.565112 -102.50325) (xy 37.620485 -102.480314)
			(xy 37.678378 -102.464801) (xy 37.7378 -102.456978) (xy 37.797736 -102.456978) (xy 37.857158 -102.464801)
			(xy 37.915051 -102.480314) (xy 37.970424 -102.50325) (xy 38.02233 -102.533217) (xy 38.06988 -102.569704)
			(xy 38.11226 -102.612084) (xy 38.148747 -102.659634) (xy 38.178714 -102.71154) (xy 38.20165 -102.766913)
			(xy 38.217163 -102.824806) (xy 38.224986 -102.884228) (xy 38.225476 -102.914196) (xy 38.225476 -103.776272)
			(xy 53.639212 -103.776272) (xy 53.639212 -102.912672) (xy 53.639702 -102.882704) (xy 53.647525 -102.823282)
			(xy 53.663038 -102.765389) (xy 53.685974 -102.710016) (xy 53.715941 -102.65811) (xy 53.752428 -102.61056)
			(xy 53.794808 -102.56818) (xy 53.842358 -102.531693) (xy 53.894264 -102.501726) (xy 53.949637 -102.47879)
			(xy 54.00753 -102.463277) (xy 54.066952 -102.455454) (xy 54.126888 -102.455454) (xy 54.18631 -102.463277)
			(xy 54.244203 -102.47879) (xy 54.299576 -102.501726) (xy 54.351482 -102.531693) (xy 54.399032 -102.56818)
			(xy 54.441412 -102.61056) (xy 54.477899 -102.65811) (xy 54.507866 -102.710016) (xy 54.530802 -102.765389)
			(xy 54.546315 -102.823282) (xy 54.554138 -102.882704) (xy 54.554628 -102.912672) (xy 54.554628 -103.776272)
			(xy 54.554603 -103.777796) (xy 153.409904 -103.777796) (xy 153.409904 -102.914196) (xy 153.410394 -102.884212)
			(xy 153.418222 -102.824756) (xy 153.433743 -102.766831) (xy 153.456692 -102.711427) (xy 153.486676 -102.659493)
			(xy 153.523182 -102.611917) (xy 153.565587 -102.569512) (xy 153.613163 -102.533006) (xy 153.665097 -102.503022)
			(xy 153.720501 -102.480073) (xy 153.778426 -102.464552) (xy 153.837882 -102.456724) (xy 153.89785 -102.456724)
			(xy 153.957306 -102.464552) (xy 154.015231 -102.480073) (xy 154.070635 -102.503022) (xy 154.122569 -102.533006)
			(xy 154.170145 -102.569512) (xy 154.21255 -102.611917) (xy 154.249056 -102.659493) (xy 154.27904 -102.711427)
			(xy 154.301989 -102.766831) (xy 154.31751 -102.824756) (xy 154.325338 -102.884212) (xy 154.325828 -102.914196)
			(xy 154.325828 -103.776272) (xy 169.739056 -103.776272) (xy 169.739056 -102.912672) (xy 169.739546 -102.882688)
			(xy 169.747374 -102.823232) (xy 169.762895 -102.765307) (xy 169.785844 -102.709903) (xy 169.815828 -102.657969)
			(xy 169.852334 -102.610393) (xy 169.894739 -102.567988) (xy 169.942315 -102.531482) (xy 169.994249 -102.501498)
			(xy 170.049653 -102.478549) (xy 170.107578 -102.463028) (xy 170.167034 -102.4552) (xy 170.227002 -102.4552)
			(xy 170.286458 -102.463028) (xy 170.344383 -102.478549) (xy 170.399787 -102.501498) (xy 170.451721 -102.531482)
			(xy 170.499297 -102.567988) (xy 170.541702 -102.610393) (xy 170.578208 -102.657969) (xy 170.608192 -102.709903)
			(xy 170.631141 -102.765307) (xy 170.646662 -102.823232) (xy 170.65449 -102.882688) (xy 170.65498 -102.912672)
			(xy 170.65498 -103.776272) (xy 170.65449 -103.806256) (xy 170.646662 -103.865712) (xy 170.631141 -103.923637)
			(xy 170.608192 -103.979041) (xy 170.578208 -104.030975) (xy 170.541702 -104.078551) (xy 170.499297 -104.120956)
			(xy 170.451721 -104.157462) (xy 170.399787 -104.187446) (xy 170.344383 -104.210395) (xy 170.286458 -104.225916)
			(xy 170.227002 -104.233744) (xy 170.167034 -104.233744) (xy 170.107578 -104.225916) (xy 170.049653 -104.210395)
			(xy 169.994249 -104.187446) (xy 169.942315 -104.157462) (xy 169.894739 -104.120956) (xy 169.852334 -104.078551)
			(xy 169.815828 -104.030975) (xy 169.785844 -103.979041) (xy 169.762895 -103.923637) (xy 169.747374 -103.865712)
			(xy 169.739546 -103.806256) (xy 169.739056 -103.776272) (xy 154.325828 -103.776272) (xy 154.325828 -103.777796)
			(xy 154.325338 -103.80778) (xy 154.31751 -103.867236) (xy 154.301989 -103.925161) (xy 154.27904 -103.980565)
			(xy 154.249056 -104.032499) (xy 154.21255 -104.080075) (xy 154.170145 -104.12248) (xy 154.122569 -104.158986)
			(xy 154.070635 -104.18897) (xy 154.015231 -104.211919) (xy 153.957306 -104.22744) (xy 153.89785 -104.235268)
			(xy 153.837882 -104.235268) (xy 153.778426 -104.22744) (xy 153.720501 -104.211919) (xy 153.665097 -104.18897)
			(xy 153.613163 -104.158986) (xy 153.565587 -104.12248) (xy 153.523182 -104.080075) (xy 153.486676 -104.032499)
			(xy 153.456692 -103.980565) (xy 153.433743 -103.925161) (xy 153.418222 -103.867236) (xy 153.410394 -103.80778)
			(xy 153.409904 -103.777796) (xy 54.554603 -103.777796) (xy 54.554138 -103.80624) (xy 54.546315 -103.865662)
			(xy 54.530802 -103.923555) (xy 54.507866 -103.978928) (xy 54.477899 -104.030834) (xy 54.441412 -104.078384)
			(xy 54.399032 -104.120764) (xy 54.351482 -104.157251) (xy 54.299576 -104.187218) (xy 54.244203 -104.210154)
			(xy 54.18631 -104.225667) (xy 54.126888 -104.23349) (xy 54.066952 -104.23349) (xy 54.00753 -104.225667)
			(xy 53.949637 -104.210154) (xy 53.894264 -104.187218) (xy 53.842358 -104.157251) (xy 53.794808 -104.120764)
			(xy 53.752428 -104.078384) (xy 53.715941 -104.030834) (xy 53.685974 -103.978928) (xy 53.663038 -103.923555)
			(xy 53.647525 -103.865662) (xy 53.639702 -103.80624) (xy 53.639212 -103.776272) (xy 38.225476 -103.776272)
			(xy 38.225476 -103.777796) (xy 38.224986 -103.807764) (xy 38.217163 -103.867186) (xy 38.20165 -103.925079)
			(xy 38.178714 -103.980452) (xy 38.148747 -104.032358) (xy 38.11226 -104.079908) (xy 38.06988 -104.122288)
			(xy 38.02233 -104.158775) (xy 37.970424 -104.188742) (xy 37.915051 -104.211678) (xy 37.857158 -104.227191)
			(xy 37.797736 -104.235014) (xy 37.7378 -104.235014) (xy 37.678378 -104.227191) (xy 37.620485 -104.211678)
			(xy 37.565112 -104.188742) (xy 37.513206 -104.158775) (xy 37.465656 -104.122288) (xy 37.423276 -104.079908)
			(xy 37.386789 -104.032358) (xy 37.356822 -103.980452) (xy 37.333886 -103.925079) (xy 37.318373 -103.867186)
			(xy 37.31055 -103.807764) (xy 37.31006 -103.777796) (xy 5.324094 -103.777796) (xy 5.324094 -105.584498)
			(xy 34.667952 -105.584498) (xy 34.667952 -104.720898) (xy 34.668442 -104.69093) (xy 34.676265 -104.631508)
			(xy 34.691778 -104.573615) (xy 34.714714 -104.518242) (xy 34.744681 -104.466336) (xy 34.781168 -104.418786)
			(xy 34.823548 -104.376406) (xy 34.871098 -104.339919) (xy 34.923004 -104.309952) (xy 34.978377 -104.287016)
			(xy 35.03627 -104.271503) (xy 35.095692 -104.26368) (xy 35.155628 -104.26368) (xy 35.21505 -104.271503)
			(xy 35.272943 -104.287016) (xy 35.328316 -104.309952) (xy 35.380222 -104.339919) (xy 35.427772 -104.376406)
			(xy 35.470152 -104.418786) (xy 35.506639 -104.466336) (xy 35.536606 -104.518242) (xy 35.559542 -104.573615)
			(xy 35.575055 -104.631508) (xy 35.582878 -104.69093) (xy 35.583368 -104.720898) (xy 35.583368 -105.57637)
			(xy 51.785012 -105.57637) (xy 51.785012 -104.71277) (xy 51.785502 -104.682802) (xy 51.793325 -104.62338)
			(xy 51.808838 -104.565487) (xy 51.831774 -104.510114) (xy 51.861741 -104.458208) (xy 51.898228 -104.410658)
			(xy 51.940608 -104.368278) (xy 51.988158 -104.331791) (xy 52.040064 -104.301824) (xy 52.095437 -104.278888)
			(xy 52.15333 -104.263375) (xy 52.212752 -104.255552) (xy 52.272688 -104.255552) (xy 52.33211 -104.263375)
			(xy 52.390003 -104.278888) (xy 52.445376 -104.301824) (xy 52.497282 -104.331791) (xy 52.544832 -104.368278)
			(xy 52.587212 -104.410658) (xy 52.623699 -104.458208) (xy 52.653666 -104.510114) (xy 52.676602 -104.565487)
			(xy 52.692115 -104.62338) (xy 52.699938 -104.682802) (xy 52.700428 -104.71277) (xy 52.700428 -105.57637)
			(xy 52.700295 -105.584498) (xy 150.767796 -105.584498) (xy 150.767796 -104.720898) (xy 150.768286 -104.690914)
			(xy 150.776114 -104.631458) (xy 150.791635 -104.573533) (xy 150.814584 -104.518129) (xy 150.844568 -104.466195)
			(xy 150.881074 -104.418619) (xy 150.923479 -104.376214) (xy 150.971055 -104.339708) (xy 151.022989 -104.309724)
			(xy 151.078393 -104.286775) (xy 151.136318 -104.271254) (xy 151.195774 -104.263426) (xy 151.255742 -104.263426)
			(xy 151.315198 -104.271254) (xy 151.373123 -104.286775) (xy 151.428527 -104.309724) (xy 151.480461 -104.339708)
			(xy 151.528037 -104.376214) (xy 151.570442 -104.418619) (xy 151.606948 -104.466195) (xy 151.636932 -104.518129)
			(xy 151.659881 -104.573533) (xy 151.675402 -104.631458) (xy 151.68323 -104.690914) (xy 151.68372 -104.720898)
			(xy 151.68372 -105.57637) (xy 167.884856 -105.57637) (xy 167.884856 -104.71277) (xy 167.885346 -104.682786)
			(xy 167.893174 -104.62333) (xy 167.908695 -104.565405) (xy 167.931644 -104.510001) (xy 167.961628 -104.458067)
			(xy 167.998134 -104.410491) (xy 168.040539 -104.368086) (xy 168.088115 -104.33158) (xy 168.140049 -104.301596)
			(xy 168.195453 -104.278647) (xy 168.253378 -104.263126) (xy 168.312834 -104.255298) (xy 168.372802 -104.255298)
			(xy 168.432258 -104.263126) (xy 168.490183 -104.278647) (xy 168.545587 -104.301596) (xy 168.597521 -104.33158)
			(xy 168.645097 -104.368086) (xy 168.687502 -104.410491) (xy 168.724008 -104.458067) (xy 168.753992 -104.510001)
			(xy 168.776941 -104.565405) (xy 168.792462 -104.62333) (xy 168.80029 -104.682786) (xy 168.80078 -104.71277)
			(xy 168.80078 -105.57637) (xy 168.800647 -105.584498) (xy 266.86764 -105.584498) (xy 266.86764 -104.720898)
			(xy 266.86813 -104.690914) (xy 266.875958 -104.631458) (xy 266.891479 -104.573533) (xy 266.914428 -104.518129)
			(xy 266.944412 -104.466195) (xy 266.980918 -104.418619) (xy 267.023323 -104.376214) (xy 267.070899 -104.339708)
			(xy 267.122833 -104.309724) (xy 267.178237 -104.286775) (xy 267.236162 -104.271254) (xy 267.295618 -104.263426)
			(xy 267.355586 -104.263426) (xy 267.415042 -104.271254) (xy 267.472967 -104.286775) (xy 267.528371 -104.309724)
			(xy 267.580305 -104.339708) (xy 267.627881 -104.376214) (xy 267.670286 -104.418619) (xy 267.706792 -104.466195)
			(xy 267.736776 -104.518129) (xy 267.759725 -104.573533) (xy 267.775246 -104.631458) (xy 267.783074 -104.690914)
			(xy 267.783564 -104.720898) (xy 267.783564 -105.57637) (xy 283.9847 -105.57637) (xy 283.9847 -104.71277)
			(xy 283.98519 -104.682786) (xy 283.993018 -104.62333) (xy 284.008539 -104.565405) (xy 284.031488 -104.510001)
			(xy 284.061472 -104.458067) (xy 284.097978 -104.410491) (xy 284.140383 -104.368086) (xy 284.187959 -104.33158)
			(xy 284.239893 -104.301596) (xy 284.295297 -104.278647) (xy 284.353222 -104.263126) (xy 284.412678 -104.255298)
			(xy 284.472646 -104.255298) (xy 284.532102 -104.263126) (xy 284.590027 -104.278647) (xy 284.645431 -104.301596)
			(xy 284.697365 -104.33158) (xy 284.744941 -104.368086) (xy 284.787346 -104.410491) (xy 284.823852 -104.458067)
			(xy 284.853836 -104.510001) (xy 284.876785 -104.565405) (xy 284.892306 -104.62333) (xy 284.900134 -104.682786)
			(xy 284.900624 -104.71277) (xy 284.900624 -105.57637) (xy 284.900491 -105.584498) (xy 382.967992 -105.584498)
			(xy 382.967992 -104.720898) (xy 382.968482 -104.69093) (xy 382.976305 -104.631508) (xy 382.991818 -104.573615)
			(xy 383.014754 -104.518242) (xy 383.044721 -104.466336) (xy 383.081208 -104.418786) (xy 383.123588 -104.376406)
			(xy 383.171138 -104.339919) (xy 383.223044 -104.309952) (xy 383.278417 -104.287016) (xy 383.33631 -104.271503)
			(xy 383.395732 -104.26368) (xy 383.455668 -104.26368) (xy 383.51509 -104.271503) (xy 383.572983 -104.287016)
			(xy 383.628356 -104.309952) (xy 383.680262 -104.339919) (xy 383.727812 -104.376406) (xy 383.770192 -104.418786)
			(xy 383.806679 -104.466336) (xy 383.836646 -104.518242) (xy 383.859582 -104.573615) (xy 383.875095 -104.631508)
			(xy 383.882918 -104.69093) (xy 383.883408 -104.720898) (xy 383.883408 -105.57637) (xy 400.085052 -105.57637)
			(xy 400.085052 -104.71277) (xy 400.085542 -104.682802) (xy 400.093365 -104.62338) (xy 400.108878 -104.565487)
			(xy 400.131814 -104.510114) (xy 400.161781 -104.458208) (xy 400.198268 -104.410658) (xy 400.240648 -104.368278)
			(xy 400.288198 -104.331791) (xy 400.340104 -104.301824) (xy 400.395477 -104.278888) (xy 400.45337 -104.263375)
			(xy 400.512792 -104.255552) (xy 400.572728 -104.255552) (xy 400.63215 -104.263375) (xy 400.690043 -104.278888)
			(xy 400.745416 -104.301824) (xy 400.797322 -104.331791) (xy 400.844872 -104.368278) (xy 400.887252 -104.410658)
			(xy 400.923739 -104.458208) (xy 400.953706 -104.510114) (xy 400.976642 -104.565487) (xy 400.992155 -104.62338)
			(xy 400.999978 -104.682802) (xy 401.000468 -104.71277) (xy 401.000468 -105.57637) (xy 400.999978 -105.606338)
			(xy 400.992155 -105.66576) (xy 400.976642 -105.723653) (xy 400.953706 -105.779026) (xy 400.923739 -105.830932)
			(xy 400.887252 -105.878482) (xy 400.844872 -105.920862) (xy 400.797322 -105.957349) (xy 400.745416 -105.987316)
			(xy 400.690043 -106.010252) (xy 400.63215 -106.025765) (xy 400.572728 -106.033588) (xy 400.512792 -106.033588)
			(xy 400.45337 -106.025765) (xy 400.395477 -106.010252) (xy 400.340104 -105.987316) (xy 400.288198 -105.957349)
			(xy 400.240648 -105.920862) (xy 400.198268 -105.878482) (xy 400.161781 -105.830932) (xy 400.131814 -105.779026)
			(xy 400.108878 -105.723653) (xy 400.093365 -105.66576) (xy 400.085542 -105.606338) (xy 400.085052 -105.57637)
			(xy 383.883408 -105.57637) (xy 383.883408 -105.584498) (xy 383.882918 -105.614466) (xy 383.875095 -105.673888)
			(xy 383.859582 -105.731781) (xy 383.836646 -105.787154) (xy 383.806679 -105.83906) (xy 383.770192 -105.88661)
			(xy 383.727812 -105.92899) (xy 383.680262 -105.965477) (xy 383.628356 -105.995444) (xy 383.572983 -106.01838)
			(xy 383.51509 -106.033893) (xy 383.455668 -106.041716) (xy 383.395732 -106.041716) (xy 383.33631 -106.033893)
			(xy 383.278417 -106.01838) (xy 383.223044 -105.995444) (xy 383.171138 -105.965477) (xy 383.123588 -105.92899)
			(xy 383.081208 -105.88661) (xy 383.044721 -105.83906) (xy 383.014754 -105.787154) (xy 382.991818 -105.731781)
			(xy 382.976305 -105.673888) (xy 382.968482 -105.614466) (xy 382.967992 -105.584498) (xy 284.900491 -105.584498)
			(xy 284.900134 -105.606354) (xy 284.892306 -105.66581) (xy 284.876785 -105.723735) (xy 284.853836 -105.779139)
			(xy 284.823852 -105.831073) (xy 284.787346 -105.878649) (xy 284.744941 -105.921054) (xy 284.697365 -105.95756)
			(xy 284.645431 -105.987544) (xy 284.590027 -106.010493) (xy 284.532102 -106.026014) (xy 284.472646 -106.033842)
			(xy 284.412678 -106.033842) (xy 284.353222 -106.026014) (xy 284.295297 -106.010493) (xy 284.239893 -105.987544)
			(xy 284.187959 -105.95756) (xy 284.140383 -105.921054) (xy 284.097978 -105.878649) (xy 284.061472 -105.831073)
			(xy 284.031488 -105.779139) (xy 284.008539 -105.723735) (xy 283.993018 -105.66581) (xy 283.98519 -105.606354)
			(xy 283.9847 -105.57637) (xy 267.783564 -105.57637) (xy 267.783564 -105.584498) (xy 267.783074 -105.614482)
			(xy 267.775246 -105.673938) (xy 267.759725 -105.731863) (xy 267.736776 -105.787267) (xy 267.706792 -105.839201)
			(xy 267.670286 -105.886777) (xy 267.627881 -105.929182) (xy 267.580305 -105.965688) (xy 267.528371 -105.995672)
			(xy 267.472967 -106.018621) (xy 267.415042 -106.034142) (xy 267.355586 -106.04197) (xy 267.295618 -106.04197)
			(xy 267.236162 -106.034142) (xy 267.178237 -106.018621) (xy 267.122833 -105.995672) (xy 267.070899 -105.965688)
			(xy 267.023323 -105.929182) (xy 266.980918 -105.886777) (xy 266.944412 -105.839201) (xy 266.914428 -105.787267)
			(xy 266.891479 -105.731863) (xy 266.875958 -105.673938) (xy 266.86813 -105.614482) (xy 266.86764 -105.584498)
			(xy 168.800647 -105.584498) (xy 168.80029 -105.606354) (xy 168.792462 -105.66581) (xy 168.776941 -105.723735)
			(xy 168.753992 -105.779139) (xy 168.724008 -105.831073) (xy 168.687502 -105.878649) (xy 168.645097 -105.921054)
			(xy 168.597521 -105.95756) (xy 168.545587 -105.987544) (xy 168.490183 -106.010493) (xy 168.432258 -106.026014)
			(xy 168.372802 -106.033842) (xy 168.312834 -106.033842) (xy 168.253378 -106.026014) (xy 168.195453 -106.010493)
			(xy 168.140049 -105.987544) (xy 168.088115 -105.95756) (xy 168.040539 -105.921054) (xy 167.998134 -105.878649)
			(xy 167.961628 -105.831073) (xy 167.931644 -105.779139) (xy 167.908695 -105.723735) (xy 167.893174 -105.66581)
			(xy 167.885346 -105.606354) (xy 167.884856 -105.57637) (xy 151.68372 -105.57637) (xy 151.68372 -105.584498)
			(xy 151.68323 -105.614482) (xy 151.675402 -105.673938) (xy 151.659881 -105.731863) (xy 151.636932 -105.787267)
			(xy 151.606948 -105.839201) (xy 151.570442 -105.886777) (xy 151.528037 -105.929182) (xy 151.480461 -105.965688)
			(xy 151.428527 -105.995672) (xy 151.373123 -106.018621) (xy 151.315198 -106.034142) (xy 151.255742 -106.04197)
			(xy 151.195774 -106.04197) (xy 151.136318 -106.034142) (xy 151.078393 -106.018621) (xy 151.022989 -105.995672)
			(xy 150.971055 -105.965688) (xy 150.923479 -105.929182) (xy 150.881074 -105.886777) (xy 150.844568 -105.839201)
			(xy 150.814584 -105.787267) (xy 150.791635 -105.731863) (xy 150.776114 -105.673938) (xy 150.768286 -105.614482)
			(xy 150.767796 -105.584498) (xy 52.700295 -105.584498) (xy 52.699938 -105.606338) (xy 52.692115 -105.66576)
			(xy 52.676602 -105.723653) (xy 52.653666 -105.779026) (xy 52.623699 -105.830932) (xy 52.587212 -105.878482)
			(xy 52.544832 -105.920862) (xy 52.497282 -105.957349) (xy 52.445376 -105.987316) (xy 52.390003 -106.010252)
			(xy 52.33211 -106.025765) (xy 52.272688 -106.033588) (xy 52.212752 -106.033588) (xy 52.15333 -106.025765)
			(xy 52.095437 -106.010252) (xy 52.040064 -105.987316) (xy 51.988158 -105.957349) (xy 51.940608 -105.920862)
			(xy 51.898228 -105.878482) (xy 51.861741 -105.830932) (xy 51.831774 -105.779026) (xy 51.808838 -105.723653)
			(xy 51.793325 -105.66576) (xy 51.785502 -105.606338) (xy 51.785012 -105.57637) (xy 35.583368 -105.57637)
			(xy 35.583368 -105.584498) (xy 35.582878 -105.614466) (xy 35.575055 -105.673888) (xy 35.559542 -105.731781)
			(xy 35.536606 -105.787154) (xy 35.506639 -105.83906) (xy 35.470152 -105.88661) (xy 35.427772 -105.92899)
			(xy 35.380222 -105.965477) (xy 35.328316 -105.995444) (xy 35.272943 -106.01838) (xy 35.21505 -106.033893)
			(xy 35.155628 -106.041716) (xy 35.095692 -106.041716) (xy 35.03627 -106.033893) (xy 34.978377 -106.01838)
			(xy 34.923004 -105.995444) (xy 34.871098 -105.965477) (xy 34.823548 -105.92899) (xy 34.781168 -105.88661)
			(xy 34.744681 -105.83906) (xy 34.714714 -105.787154) (xy 34.691778 -105.731781) (xy 34.676265 -105.673888)
			(xy 34.668442 -105.614466) (xy 34.667952 -105.584498) (xy 5.324094 -105.584498) (xy 5.324094 -107.377738)
			(xy 37.31006 -107.377738) (xy 37.31006 -106.514138) (xy 37.31055 -106.48417) (xy 37.318373 -106.424748)
			(xy 37.333886 -106.366855) (xy 37.356822 -106.311482) (xy 37.386789 -106.259576) (xy 37.423276 -106.212026)
			(xy 37.465656 -106.169646) (xy 37.513206 -106.133159) (xy 37.565112 -106.103192) (xy 37.620485 -106.080256)
			(xy 37.678378 -106.064743) (xy 37.7378 -106.05692) (xy 37.797736 -106.05692) (xy 37.857158 -106.064743)
			(xy 37.915051 -106.080256) (xy 37.970424 -106.103192) (xy 38.02233 -106.133159) (xy 38.06988 -106.169646)
			(xy 38.11226 -106.212026) (xy 38.148747 -106.259576) (xy 38.178714 -106.311482) (xy 38.20165 -106.366855)
			(xy 38.217163 -106.424748) (xy 38.224986 -106.48417) (xy 38.225476 -106.514138) (xy 38.225476 -107.376214)
			(xy 53.639212 -107.376214) (xy 53.639212 -106.512614) (xy 53.639702 -106.482646) (xy 53.647525 -106.423224)
			(xy 53.663038 -106.365331) (xy 53.685974 -106.309958) (xy 53.715941 -106.258052) (xy 53.752428 -106.210502)
			(xy 53.794808 -106.168122) (xy 53.842358 -106.131635) (xy 53.894264 -106.101668) (xy 53.949637 -106.078732)
			(xy 54.00753 -106.063219) (xy 54.066952 -106.055396) (xy 54.126888 -106.055396) (xy 54.18631 -106.063219)
			(xy 54.244203 -106.078732) (xy 54.299576 -106.101668) (xy 54.351482 -106.131635) (xy 54.399032 -106.168122)
			(xy 54.441412 -106.210502) (xy 54.477899 -106.258052) (xy 54.507866 -106.309958) (xy 54.530802 -106.365331)
			(xy 54.546315 -106.423224) (xy 54.554138 -106.482646) (xy 54.554628 -106.512614) (xy 54.554628 -107.376214)
			(xy 54.554603 -107.377738) (xy 153.409904 -107.377738) (xy 153.409904 -106.514138) (xy 153.410394 -106.484154)
			(xy 153.418222 -106.424698) (xy 153.433743 -106.366773) (xy 153.456692 -106.311369) (xy 153.486676 -106.259435)
			(xy 153.523182 -106.211859) (xy 153.565587 -106.169454) (xy 153.613163 -106.132948) (xy 153.665097 -106.102964)
			(xy 153.720501 -106.080015) (xy 153.778426 -106.064494) (xy 153.837882 -106.056666) (xy 153.89785 -106.056666)
			(xy 153.957306 -106.064494) (xy 154.015231 -106.080015) (xy 154.070635 -106.102964) (xy 154.122569 -106.132948)
			(xy 154.170145 -106.169454) (xy 154.21255 -106.211859) (xy 154.249056 -106.259435) (xy 154.27904 -106.311369)
			(xy 154.301989 -106.366773) (xy 154.31751 -106.424698) (xy 154.325338 -106.484154) (xy 154.325828 -106.514138)
			(xy 154.325828 -107.376214) (xy 169.739056 -107.376214) (xy 169.739056 -106.512614) (xy 169.739546 -106.48263)
			(xy 169.747374 -106.423174) (xy 169.762895 -106.365249) (xy 169.785844 -106.309845) (xy 169.815828 -106.257911)
			(xy 169.852334 -106.210335) (xy 169.894739 -106.16793) (xy 169.942315 -106.131424) (xy 169.994249 -106.10144)
			(xy 170.049653 -106.078491) (xy 170.107578 -106.06297) (xy 170.167034 -106.055142) (xy 170.227002 -106.055142)
			(xy 170.286458 -106.06297) (xy 170.344383 -106.078491) (xy 170.399787 -106.10144) (xy 170.451721 -106.131424)
			(xy 170.499297 -106.16793) (xy 170.541702 -106.210335) (xy 170.578208 -106.257911) (xy 170.608192 -106.309845)
			(xy 170.631141 -106.365249) (xy 170.646662 -106.423174) (xy 170.65449 -106.48263) (xy 170.65498 -106.512614)
			(xy 170.65498 -107.376214) (xy 170.654955 -107.377738) (xy 269.509748 -107.377738) (xy 269.509748 -106.514138)
			(xy 269.510238 -106.484154) (xy 269.518066 -106.424698) (xy 269.533587 -106.366773) (xy 269.556536 -106.311369)
			(xy 269.58652 -106.259435) (xy 269.623026 -106.211859) (xy 269.665431 -106.169454) (xy 269.713007 -106.132948)
			(xy 269.764941 -106.102964) (xy 269.820345 -106.080015) (xy 269.87827 -106.064494) (xy 269.937726 -106.056666)
			(xy 269.997694 -106.056666) (xy 270.05715 -106.064494) (xy 270.115075 -106.080015) (xy 270.170479 -106.102964)
			(xy 270.222413 -106.132948) (xy 270.269989 -106.169454) (xy 270.312394 -106.211859) (xy 270.3489 -106.259435)
			(xy 270.378884 -106.311369) (xy 270.401833 -106.366773) (xy 270.417354 -106.424698) (xy 270.425182 -106.484154)
			(xy 270.425672 -106.514138) (xy 270.425672 -107.376214) (xy 285.8389 -107.376214) (xy 285.8389 -106.512614)
			(xy 285.83939 -106.48263) (xy 285.847218 -106.423174) (xy 285.862739 -106.365249) (xy 285.885688 -106.309845)
			(xy 285.915672 -106.257911) (xy 285.952178 -106.210335) (xy 285.994583 -106.16793) (xy 286.042159 -106.131424)
			(xy 286.094093 -106.10144) (xy 286.149497 -106.078491) (xy 286.207422 -106.06297) (xy 286.266878 -106.055142)
			(xy 286.326846 -106.055142) (xy 286.386302 -106.06297) (xy 286.444227 -106.078491) (xy 286.499631 -106.10144)
			(xy 286.551565 -106.131424) (xy 286.599141 -106.16793) (xy 286.641546 -106.210335) (xy 286.678052 -106.257911)
			(xy 286.708036 -106.309845) (xy 286.730985 -106.365249) (xy 286.746506 -106.423174) (xy 286.754334 -106.48263)
			(xy 286.754824 -106.512614) (xy 286.754824 -107.376214) (xy 286.754799 -107.377738) (xy 385.6101 -107.377738)
			(xy 385.6101 -106.514138) (xy 385.61059 -106.48417) (xy 385.618413 -106.424748) (xy 385.633926 -106.366855)
			(xy 385.656862 -106.311482) (xy 385.686829 -106.259576) (xy 385.723316 -106.212026) (xy 385.765696 -106.169646)
			(xy 385.813246 -106.133159) (xy 385.865152 -106.103192) (xy 385.920525 -106.080256) (xy 385.978418 -106.064743)
			(xy 386.03784 -106.05692) (xy 386.097776 -106.05692) (xy 386.157198 -106.064743) (xy 386.215091 -106.080256)
			(xy 386.270464 -106.103192) (xy 386.32237 -106.133159) (xy 386.36992 -106.169646) (xy 386.4123 -106.212026)
			(xy 386.448787 -106.259576) (xy 386.478754 -106.311482) (xy 386.50169 -106.366855) (xy 386.517203 -106.424748)
			(xy 386.525026 -106.48417) (xy 386.525516 -106.514138) (xy 386.525516 -107.376214) (xy 401.939252 -107.376214)
			(xy 401.939252 -106.512614) (xy 401.939742 -106.482646) (xy 401.947565 -106.423224) (xy 401.963078 -106.365331)
			(xy 401.986014 -106.309958) (xy 402.015981 -106.258052) (xy 402.052468 -106.210502) (xy 402.094848 -106.168122)
			(xy 402.142398 -106.131635) (xy 402.194304 -106.101668) (xy 402.249677 -106.078732) (xy 402.30757 -106.063219)
			(xy 402.366992 -106.055396) (xy 402.426928 -106.055396) (xy 402.48635 -106.063219) (xy 402.544243 -106.078732)
			(xy 402.599616 -106.101668) (xy 402.651522 -106.131635) (xy 402.699072 -106.168122) (xy 402.741452 -106.210502)
			(xy 402.777939 -106.258052) (xy 402.807906 -106.309958) (xy 402.830842 -106.365331) (xy 402.846355 -106.423224)
			(xy 402.854178 -106.482646) (xy 402.854668 -106.512614) (xy 402.854668 -107.376214) (xy 402.854178 -107.406182)
			(xy 402.846355 -107.465604) (xy 402.830842 -107.523497) (xy 402.807906 -107.57887) (xy 402.777939 -107.630776)
			(xy 402.741452 -107.678326) (xy 402.699072 -107.720706) (xy 402.651522 -107.757193) (xy 402.599616 -107.78716)
			(xy 402.544243 -107.810096) (xy 402.48635 -107.825609) (xy 402.426928 -107.833432) (xy 402.366992 -107.833432)
			(xy 402.30757 -107.825609) (xy 402.249677 -107.810096) (xy 402.194304 -107.78716) (xy 402.142398 -107.757193)
			(xy 402.094848 -107.720706) (xy 402.052468 -107.678326) (xy 402.015981 -107.630776) (xy 401.986014 -107.57887)
			(xy 401.963078 -107.523497) (xy 401.947565 -107.465604) (xy 401.939742 -107.406182) (xy 401.939252 -107.376214)
			(xy 386.525516 -107.376214) (xy 386.525516 -107.377738) (xy 386.525026 -107.407706) (xy 386.517203 -107.467128)
			(xy 386.50169 -107.525021) (xy 386.478754 -107.580394) (xy 386.448787 -107.6323) (xy 386.4123 -107.67985)
			(xy 386.36992 -107.72223) (xy 386.32237 -107.758717) (xy 386.270464 -107.788684) (xy 386.215091 -107.81162)
			(xy 386.157198 -107.827133) (xy 386.097776 -107.834956) (xy 386.03784 -107.834956) (xy 385.978418 -107.827133)
			(xy 385.920525 -107.81162) (xy 385.865152 -107.788684) (xy 385.813246 -107.758717) (xy 385.765696 -107.72223)
			(xy 385.723316 -107.67985) (xy 385.686829 -107.6323) (xy 385.656862 -107.580394) (xy 385.633926 -107.525021)
			(xy 385.618413 -107.467128) (xy 385.61059 -107.407706) (xy 385.6101 -107.377738) (xy 286.754799 -107.377738)
			(xy 286.754334 -107.406198) (xy 286.746506 -107.465654) (xy 286.730985 -107.523579) (xy 286.708036 -107.578983)
			(xy 286.678052 -107.630917) (xy 286.641546 -107.678493) (xy 286.599141 -107.720898) (xy 286.551565 -107.757404)
			(xy 286.499631 -107.787388) (xy 286.444227 -107.810337) (xy 286.386302 -107.825858) (xy 286.326846 -107.833686)
			(xy 286.266878 -107.833686) (xy 286.207422 -107.825858) (xy 286.149497 -107.810337) (xy 286.094093 -107.787388)
			(xy 286.042159 -107.757404) (xy 285.994583 -107.720898) (xy 285.952178 -107.678493) (xy 285.915672 -107.630917)
			(xy 285.885688 -107.578983) (xy 285.862739 -107.523579) (xy 285.847218 -107.465654) (xy 285.83939 -107.406198)
			(xy 285.8389 -107.376214) (xy 270.425672 -107.376214) (xy 270.425672 -107.377738) (xy 270.425182 -107.407722)
			(xy 270.417354 -107.467178) (xy 270.401833 -107.525103) (xy 270.378884 -107.580507) (xy 270.3489 -107.632441)
			(xy 270.312394 -107.680017) (xy 270.269989 -107.722422) (xy 270.222413 -107.758928) (xy 270.170479 -107.788912)
			(xy 270.115075 -107.811861) (xy 270.05715 -107.827382) (xy 269.997694 -107.83521) (xy 269.937726 -107.83521)
			(xy 269.87827 -107.827382) (xy 269.820345 -107.811861) (xy 269.764941 -107.788912) (xy 269.713007 -107.758928)
			(xy 269.665431 -107.722422) (xy 269.623026 -107.680017) (xy 269.58652 -107.632441) (xy 269.556536 -107.580507)
			(xy 269.533587 -107.525103) (xy 269.518066 -107.467178) (xy 269.510238 -107.407722) (xy 269.509748 -107.377738)
			(xy 170.654955 -107.377738) (xy 170.65449 -107.406198) (xy 170.646662 -107.465654) (xy 170.631141 -107.523579)
			(xy 170.608192 -107.578983) (xy 170.578208 -107.630917) (xy 170.541702 -107.678493) (xy 170.499297 -107.720898)
			(xy 170.451721 -107.757404) (xy 170.399787 -107.787388) (xy 170.344383 -107.810337) (xy 170.286458 -107.825858)
			(xy 170.227002 -107.833686) (xy 170.167034 -107.833686) (xy 170.107578 -107.825858) (xy 170.049653 -107.810337)
			(xy 169.994249 -107.787388) (xy 169.942315 -107.757404) (xy 169.894739 -107.720898) (xy 169.852334 -107.678493)
			(xy 169.815828 -107.630917) (xy 169.785844 -107.578983) (xy 169.762895 -107.523579) (xy 169.747374 -107.465654)
			(xy 169.739546 -107.406198) (xy 169.739056 -107.376214) (xy 154.325828 -107.376214) (xy 154.325828 -107.377738)
			(xy 154.325338 -107.407722) (xy 154.31751 -107.467178) (xy 154.301989 -107.525103) (xy 154.27904 -107.580507)
			(xy 154.249056 -107.632441) (xy 154.21255 -107.680017) (xy 154.170145 -107.722422) (xy 154.122569 -107.758928)
			(xy 154.070635 -107.788912) (xy 154.015231 -107.811861) (xy 153.957306 -107.827382) (xy 153.89785 -107.83521)
			(xy 153.837882 -107.83521) (xy 153.778426 -107.827382) (xy 153.720501 -107.811861) (xy 153.665097 -107.788912)
			(xy 153.613163 -107.758928) (xy 153.565587 -107.722422) (xy 153.523182 -107.680017) (xy 153.486676 -107.632441)
			(xy 153.456692 -107.580507) (xy 153.433743 -107.525103) (xy 153.418222 -107.467178) (xy 153.410394 -107.407722)
			(xy 153.409904 -107.377738) (xy 54.554603 -107.377738) (xy 54.554138 -107.406182) (xy 54.546315 -107.465604)
			(xy 54.530802 -107.523497) (xy 54.507866 -107.57887) (xy 54.477899 -107.630776) (xy 54.441412 -107.678326)
			(xy 54.399032 -107.720706) (xy 54.351482 -107.757193) (xy 54.299576 -107.78716) (xy 54.244203 -107.810096)
			(xy 54.18631 -107.825609) (xy 54.126888 -107.833432) (xy 54.066952 -107.833432) (xy 54.00753 -107.825609)
			(xy 53.949637 -107.810096) (xy 53.894264 -107.78716) (xy 53.842358 -107.757193) (xy 53.794808 -107.720706)
			(xy 53.752428 -107.678326) (xy 53.715941 -107.630776) (xy 53.685974 -107.57887) (xy 53.663038 -107.523497)
			(xy 53.647525 -107.465604) (xy 53.639702 -107.406182) (xy 53.639212 -107.376214) (xy 38.225476 -107.376214)
			(xy 38.225476 -107.377738) (xy 38.224986 -107.407706) (xy 38.217163 -107.467128) (xy 38.20165 -107.525021)
			(xy 38.178714 -107.580394) (xy 38.148747 -107.6323) (xy 38.11226 -107.67985) (xy 38.06988 -107.72223)
			(xy 38.02233 -107.758717) (xy 37.970424 -107.788684) (xy 37.915051 -107.81162) (xy 37.857158 -107.827133)
			(xy 37.797736 -107.834956) (xy 37.7378 -107.834956) (xy 37.678378 -107.827133) (xy 37.620485 -107.81162)
			(xy 37.565112 -107.788684) (xy 37.513206 -107.758717) (xy 37.465656 -107.72223) (xy 37.423276 -107.67985)
			(xy 37.386789 -107.6323) (xy 37.356822 -107.580394) (xy 37.333886 -107.525021) (xy 37.318373 -107.467128)
			(xy 37.31055 -107.407706) (xy 37.31006 -107.377738) (xy 5.324094 -107.377738) (xy 5.324094 -109.18444)
			(xy 34.667952 -109.18444) (xy 34.667952 -108.32084) (xy 34.668442 -108.290872) (xy 34.676265 -108.23145)
			(xy 34.691778 -108.173557) (xy 34.714714 -108.118184) (xy 34.744681 -108.066278) (xy 34.781168 -108.018728)
			(xy 34.823548 -107.976348) (xy 34.871098 -107.939861) (xy 34.923004 -107.909894) (xy 34.978377 -107.886958)
			(xy 35.03627 -107.871445) (xy 35.095692 -107.863622) (xy 35.155628 -107.863622) (xy 35.21505 -107.871445)
			(xy 35.272943 -107.886958) (xy 35.328316 -107.909894) (xy 35.380222 -107.939861) (xy 35.427772 -107.976348)
			(xy 35.470152 -108.018728) (xy 35.506639 -108.066278) (xy 35.536606 -108.118184) (xy 35.559542 -108.173557)
			(xy 35.575055 -108.23145) (xy 35.582878 -108.290872) (xy 35.583368 -108.32084) (xy 35.583368 -109.176312)
			(xy 51.785012 -109.176312) (xy 51.785012 -108.312712) (xy 51.785502 -108.282744) (xy 51.793325 -108.223322)
			(xy 51.808838 -108.165429) (xy 51.831774 -108.110056) (xy 51.861741 -108.05815) (xy 51.898228 -108.0106)
			(xy 51.940608 -107.96822) (xy 51.988158 -107.931733) (xy 52.040064 -107.901766) (xy 52.095437 -107.87883)
			(xy 52.15333 -107.863317) (xy 52.212752 -107.855494) (xy 52.272688 -107.855494) (xy 52.33211 -107.863317)
			(xy 52.390003 -107.87883) (xy 52.445376 -107.901766) (xy 52.497282 -107.931733) (xy 52.544832 -107.96822)
			(xy 52.587212 -108.0106) (xy 52.623699 -108.05815) (xy 52.653666 -108.110056) (xy 52.676602 -108.165429)
			(xy 52.692115 -108.223322) (xy 52.699938 -108.282744) (xy 52.700428 -108.312712) (xy 52.700428 -109.176312)
			(xy 52.700295 -109.18444) (xy 150.767796 -109.18444) (xy 150.767796 -108.32084) (xy 150.768286 -108.290856)
			(xy 150.776114 -108.2314) (xy 150.791635 -108.173475) (xy 150.814584 -108.118071) (xy 150.844568 -108.066137)
			(xy 150.881074 -108.018561) (xy 150.923479 -107.976156) (xy 150.971055 -107.93965) (xy 151.022989 -107.909666)
			(xy 151.078393 -107.886717) (xy 151.136318 -107.871196) (xy 151.195774 -107.863368) (xy 151.255742 -107.863368)
			(xy 151.315198 -107.871196) (xy 151.373123 -107.886717) (xy 151.428527 -107.909666) (xy 151.480461 -107.93965)
			(xy 151.528037 -107.976156) (xy 151.570442 -108.018561) (xy 151.606948 -108.066137) (xy 151.636932 -108.118071)
			(xy 151.659881 -108.173475) (xy 151.675402 -108.2314) (xy 151.68323 -108.290856) (xy 151.68372 -108.32084)
			(xy 151.68372 -109.176312) (xy 167.884856 -109.176312) (xy 167.884856 -108.312712) (xy 167.885346 -108.282728)
			(xy 167.893174 -108.223272) (xy 167.908695 -108.165347) (xy 167.931644 -108.109943) (xy 167.961628 -108.058009)
			(xy 167.998134 -108.010433) (xy 168.040539 -107.968028) (xy 168.088115 -107.931522) (xy 168.140049 -107.901538)
			(xy 168.195453 -107.878589) (xy 168.253378 -107.863068) (xy 168.312834 -107.85524) (xy 168.372802 -107.85524)
			(xy 168.432258 -107.863068) (xy 168.490183 -107.878589) (xy 168.545587 -107.901538) (xy 168.597521 -107.931522)
			(xy 168.645097 -107.968028) (xy 168.687502 -108.010433) (xy 168.724008 -108.058009) (xy 168.753992 -108.109943)
			(xy 168.776941 -108.165347) (xy 168.792462 -108.223272) (xy 168.80029 -108.282728) (xy 168.80078 -108.312712)
			(xy 168.80078 -109.176312) (xy 168.800647 -109.18444) (xy 266.86764 -109.18444) (xy 266.86764 -108.32084)
			(xy 266.86813 -108.290856) (xy 266.875958 -108.2314) (xy 266.891479 -108.173475) (xy 266.914428 -108.118071)
			(xy 266.944412 -108.066137) (xy 266.980918 -108.018561) (xy 267.023323 -107.976156) (xy 267.070899 -107.93965)
			(xy 267.122833 -107.909666) (xy 267.178237 -107.886717) (xy 267.236162 -107.871196) (xy 267.295618 -107.863368)
			(xy 267.355586 -107.863368) (xy 267.415042 -107.871196) (xy 267.472967 -107.886717) (xy 267.528371 -107.909666)
			(xy 267.580305 -107.93965) (xy 267.627881 -107.976156) (xy 267.670286 -108.018561) (xy 267.706792 -108.066137)
			(xy 267.736776 -108.118071) (xy 267.759725 -108.173475) (xy 267.775246 -108.2314) (xy 267.783074 -108.290856)
			(xy 267.783564 -108.32084) (xy 267.783564 -109.176312) (xy 283.9847 -109.176312) (xy 283.9847 -108.312712)
			(xy 283.98519 -108.282728) (xy 283.993018 -108.223272) (xy 284.008539 -108.165347) (xy 284.031488 -108.109943)
			(xy 284.061472 -108.058009) (xy 284.097978 -108.010433) (xy 284.140383 -107.968028) (xy 284.187959 -107.931522)
			(xy 284.239893 -107.901538) (xy 284.295297 -107.878589) (xy 284.353222 -107.863068) (xy 284.412678 -107.85524)
			(xy 284.472646 -107.85524) (xy 284.532102 -107.863068) (xy 284.590027 -107.878589) (xy 284.645431 -107.901538)
			(xy 284.697365 -107.931522) (xy 284.744941 -107.968028) (xy 284.787346 -108.010433) (xy 284.823852 -108.058009)
			(xy 284.853836 -108.109943) (xy 284.876785 -108.165347) (xy 284.892306 -108.223272) (xy 284.900134 -108.282728)
			(xy 284.900624 -108.312712) (xy 284.900624 -109.176312) (xy 284.900491 -109.18444) (xy 382.967992 -109.18444)
			(xy 382.967992 -108.32084) (xy 382.968482 -108.290872) (xy 382.976305 -108.23145) (xy 382.991818 -108.173557)
			(xy 383.014754 -108.118184) (xy 383.044721 -108.066278) (xy 383.081208 -108.018728) (xy 383.123588 -107.976348)
			(xy 383.171138 -107.939861) (xy 383.223044 -107.909894) (xy 383.278417 -107.886958) (xy 383.33631 -107.871445)
			(xy 383.395732 -107.863622) (xy 383.455668 -107.863622) (xy 383.51509 -107.871445) (xy 383.572983 -107.886958)
			(xy 383.628356 -107.909894) (xy 383.680262 -107.939861) (xy 383.727812 -107.976348) (xy 383.770192 -108.018728)
			(xy 383.806679 -108.066278) (xy 383.836646 -108.118184) (xy 383.859582 -108.173557) (xy 383.875095 -108.23145)
			(xy 383.882918 -108.290872) (xy 383.883408 -108.32084) (xy 383.883408 -109.176312) (xy 400.085052 -109.176312)
			(xy 400.085052 -108.312712) (xy 400.085542 -108.282744) (xy 400.093365 -108.223322) (xy 400.108878 -108.165429)
			(xy 400.131814 -108.110056) (xy 400.161781 -108.05815) (xy 400.198268 -108.0106) (xy 400.240648 -107.96822)
			(xy 400.288198 -107.931733) (xy 400.340104 -107.901766) (xy 400.395477 -107.87883) (xy 400.45337 -107.863317)
			(xy 400.512792 -107.855494) (xy 400.572728 -107.855494) (xy 400.63215 -107.863317) (xy 400.690043 -107.87883)
			(xy 400.745416 -107.901766) (xy 400.797322 -107.931733) (xy 400.844872 -107.96822) (xy 400.887252 -108.0106)
			(xy 400.923739 -108.05815) (xy 400.953706 -108.110056) (xy 400.976642 -108.165429) (xy 400.992155 -108.223322)
			(xy 400.999978 -108.282744) (xy 401.000468 -108.312712) (xy 401.000468 -109.176312) (xy 400.999978 -109.20628)
			(xy 400.992155 -109.265702) (xy 400.976642 -109.323595) (xy 400.953706 -109.378968) (xy 400.923739 -109.430874)
			(xy 400.887252 -109.478424) (xy 400.844872 -109.520804) (xy 400.797322 -109.557291) (xy 400.745416 -109.587258)
			(xy 400.690043 -109.610194) (xy 400.63215 -109.625707) (xy 400.572728 -109.63353) (xy 400.512792 -109.63353)
			(xy 400.45337 -109.625707) (xy 400.395477 -109.610194) (xy 400.340104 -109.587258) (xy 400.288198 -109.557291)
			(xy 400.240648 -109.520804) (xy 400.198268 -109.478424) (xy 400.161781 -109.430874) (xy 400.131814 -109.378968)
			(xy 400.108878 -109.323595) (xy 400.093365 -109.265702) (xy 400.085542 -109.20628) (xy 400.085052 -109.176312)
			(xy 383.883408 -109.176312) (xy 383.883408 -109.18444) (xy 383.882918 -109.214408) (xy 383.875095 -109.27383)
			(xy 383.859582 -109.331723) (xy 383.836646 -109.387096) (xy 383.806679 -109.439002) (xy 383.770192 -109.486552)
			(xy 383.727812 -109.528932) (xy 383.680262 -109.565419) (xy 383.628356 -109.595386) (xy 383.572983 -109.618322)
			(xy 383.51509 -109.633835) (xy 383.455668 -109.641658) (xy 383.395732 -109.641658) (xy 383.33631 -109.633835)
			(xy 383.278417 -109.618322) (xy 383.223044 -109.595386) (xy 383.171138 -109.565419) (xy 383.123588 -109.528932)
			(xy 383.081208 -109.486552) (xy 383.044721 -109.439002) (xy 383.014754 -109.387096) (xy 382.991818 -109.331723)
			(xy 382.976305 -109.27383) (xy 382.968482 -109.214408) (xy 382.967992 -109.18444) (xy 284.900491 -109.18444)
			(xy 284.900134 -109.206296) (xy 284.892306 -109.265752) (xy 284.876785 -109.323677) (xy 284.853836 -109.379081)
			(xy 284.823852 -109.431015) (xy 284.787346 -109.478591) (xy 284.744941 -109.520996) (xy 284.697365 -109.557502)
			(xy 284.645431 -109.587486) (xy 284.590027 -109.610435) (xy 284.532102 -109.625956) (xy 284.472646 -109.633784)
			(xy 284.412678 -109.633784) (xy 284.353222 -109.625956) (xy 284.295297 -109.610435) (xy 284.239893 -109.587486)
			(xy 284.187959 -109.557502) (xy 284.140383 -109.520996) (xy 284.097978 -109.478591) (xy 284.061472 -109.431015)
			(xy 284.031488 -109.379081) (xy 284.008539 -109.323677) (xy 283.993018 -109.265752) (xy 283.98519 -109.206296)
			(xy 283.9847 -109.176312) (xy 267.783564 -109.176312) (xy 267.783564 -109.18444) (xy 267.783074 -109.214424)
			(xy 267.775246 -109.27388) (xy 267.759725 -109.331805) (xy 267.736776 -109.387209) (xy 267.706792 -109.439143)
			(xy 267.670286 -109.486719) (xy 267.627881 -109.529124) (xy 267.580305 -109.56563) (xy 267.528371 -109.595614)
			(xy 267.472967 -109.618563) (xy 267.415042 -109.634084) (xy 267.355586 -109.641912) (xy 267.295618 -109.641912)
			(xy 267.236162 -109.634084) (xy 267.178237 -109.618563) (xy 267.122833 -109.595614) (xy 267.070899 -109.56563)
			(xy 267.023323 -109.529124) (xy 266.980918 -109.486719) (xy 266.944412 -109.439143) (xy 266.914428 -109.387209)
			(xy 266.891479 -109.331805) (xy 266.875958 -109.27388) (xy 266.86813 -109.214424) (xy 266.86764 -109.18444)
			(xy 168.800647 -109.18444) (xy 168.80029 -109.206296) (xy 168.792462 -109.265752) (xy 168.776941 -109.323677)
			(xy 168.753992 -109.379081) (xy 168.724008 -109.431015) (xy 168.687502 -109.478591) (xy 168.645097 -109.520996)
			(xy 168.597521 -109.557502) (xy 168.545587 -109.587486) (xy 168.490183 -109.610435) (xy 168.432258 -109.625956)
			(xy 168.372802 -109.633784) (xy 168.312834 -109.633784) (xy 168.253378 -109.625956) (xy 168.195453 -109.610435)
			(xy 168.140049 -109.587486) (xy 168.088115 -109.557502) (xy 168.040539 -109.520996) (xy 167.998134 -109.478591)
			(xy 167.961628 -109.431015) (xy 167.931644 -109.379081) (xy 167.908695 -109.323677) (xy 167.893174 -109.265752)
			(xy 167.885346 -109.206296) (xy 167.884856 -109.176312) (xy 151.68372 -109.176312) (xy 151.68372 -109.18444)
			(xy 151.68323 -109.214424) (xy 151.675402 -109.27388) (xy 151.659881 -109.331805) (xy 151.636932 -109.387209)
			(xy 151.606948 -109.439143) (xy 151.570442 -109.486719) (xy 151.528037 -109.529124) (xy 151.480461 -109.56563)
			(xy 151.428527 -109.595614) (xy 151.373123 -109.618563) (xy 151.315198 -109.634084) (xy 151.255742 -109.641912)
			(xy 151.195774 -109.641912) (xy 151.136318 -109.634084) (xy 151.078393 -109.618563) (xy 151.022989 -109.595614)
			(xy 150.971055 -109.56563) (xy 150.923479 -109.529124) (xy 150.881074 -109.486719) (xy 150.844568 -109.439143)
			(xy 150.814584 -109.387209) (xy 150.791635 -109.331805) (xy 150.776114 -109.27388) (xy 150.768286 -109.214424)
			(xy 150.767796 -109.18444) (xy 52.700295 -109.18444) (xy 52.699938 -109.20628) (xy 52.692115 -109.265702)
			(xy 52.676602 -109.323595) (xy 52.653666 -109.378968) (xy 52.623699 -109.430874) (xy 52.587212 -109.478424)
			(xy 52.544832 -109.520804) (xy 52.497282 -109.557291) (xy 52.445376 -109.587258) (xy 52.390003 -109.610194)
			(xy 52.33211 -109.625707) (xy 52.272688 -109.63353) (xy 52.212752 -109.63353) (xy 52.15333 -109.625707)
			(xy 52.095437 -109.610194) (xy 52.040064 -109.587258) (xy 51.988158 -109.557291) (xy 51.940608 -109.520804)
			(xy 51.898228 -109.478424) (xy 51.861741 -109.430874) (xy 51.831774 -109.378968) (xy 51.808838 -109.323595)
			(xy 51.793325 -109.265702) (xy 51.785502 -109.20628) (xy 51.785012 -109.176312) (xy 35.583368 -109.176312)
			(xy 35.583368 -109.18444) (xy 35.582878 -109.214408) (xy 35.575055 -109.27383) (xy 35.559542 -109.331723)
			(xy 35.536606 -109.387096) (xy 35.506639 -109.439002) (xy 35.470152 -109.486552) (xy 35.427772 -109.528932)
			(xy 35.380222 -109.565419) (xy 35.328316 -109.595386) (xy 35.272943 -109.618322) (xy 35.21505 -109.633835)
			(xy 35.155628 -109.641658) (xy 35.095692 -109.641658) (xy 35.03627 -109.633835) (xy 34.978377 -109.618322)
			(xy 34.923004 -109.595386) (xy 34.871098 -109.565419) (xy 34.823548 -109.528932) (xy 34.781168 -109.486552)
			(xy 34.744681 -109.439002) (xy 34.714714 -109.387096) (xy 34.691778 -109.331723) (xy 34.676265 -109.27383)
			(xy 34.668442 -109.214408) (xy 34.667952 -109.18444) (xy 5.324094 -109.18444) (xy 5.324094 -110.977934)
			(xy 37.31006 -110.977934) (xy 37.31006 -110.114334) (xy 37.31055 -110.084366) (xy 37.318373 -110.024944)
			(xy 37.333886 -109.967051) (xy 37.356822 -109.911678) (xy 37.386789 -109.859772) (xy 37.423276 -109.812222)
			(xy 37.465656 -109.769842) (xy 37.513206 -109.733355) (xy 37.565112 -109.703388) (xy 37.620485 -109.680452)
			(xy 37.678378 -109.664939) (xy 37.7378 -109.657116) (xy 37.797736 -109.657116) (xy 37.857158 -109.664939)
			(xy 37.915051 -109.680452) (xy 37.970424 -109.703388) (xy 38.02233 -109.733355) (xy 38.06988 -109.769842)
			(xy 38.11226 -109.812222) (xy 38.148747 -109.859772) (xy 38.178714 -109.911678) (xy 38.20165 -109.967051)
			(xy 38.217163 -110.024944) (xy 38.224986 -110.084366) (xy 38.225476 -110.114334) (xy 38.225476 -110.97641)
			(xy 53.639212 -110.97641) (xy 53.639212 -110.11281) (xy 53.639702 -110.082842) (xy 53.647525 -110.02342)
			(xy 53.663038 -109.965527) (xy 53.685974 -109.910154) (xy 53.715941 -109.858248) (xy 53.752428 -109.810698)
			(xy 53.794808 -109.768318) (xy 53.842358 -109.731831) (xy 53.894264 -109.701864) (xy 53.949637 -109.678928)
			(xy 54.00753 -109.663415) (xy 54.066952 -109.655592) (xy 54.126888 -109.655592) (xy 54.18631 -109.663415)
			(xy 54.244203 -109.678928) (xy 54.299576 -109.701864) (xy 54.351482 -109.731831) (xy 54.399032 -109.768318)
			(xy 54.441412 -109.810698) (xy 54.477899 -109.858248) (xy 54.507866 -109.910154) (xy 54.530802 -109.965527)
			(xy 54.546315 -110.02342) (xy 54.554138 -110.082842) (xy 54.554628 -110.11281) (xy 54.554628 -110.97641)
			(xy 54.554603 -110.977934) (xy 153.409904 -110.977934) (xy 153.409904 -110.114334) (xy 153.410394 -110.08435)
			(xy 153.418222 -110.024894) (xy 153.433743 -109.966969) (xy 153.456692 -109.911565) (xy 153.486676 -109.859631)
			(xy 153.523182 -109.812055) (xy 153.565587 -109.76965) (xy 153.613163 -109.733144) (xy 153.665097 -109.70316)
			(xy 153.720501 -109.680211) (xy 153.778426 -109.66469) (xy 153.837882 -109.656862) (xy 153.89785 -109.656862)
			(xy 153.957306 -109.66469) (xy 154.015231 -109.680211) (xy 154.070635 -109.70316) (xy 154.122569 -109.733144)
			(xy 154.170145 -109.76965) (xy 154.21255 -109.812055) (xy 154.249056 -109.859631) (xy 154.27904 -109.911565)
			(xy 154.301989 -109.966969) (xy 154.31751 -110.024894) (xy 154.325338 -110.08435) (xy 154.325828 -110.114334)
			(xy 154.325828 -110.97641) (xy 169.739056 -110.97641) (xy 169.739056 -110.11281) (xy 169.739546 -110.082826)
			(xy 169.747374 -110.02337) (xy 169.762895 -109.965445) (xy 169.785844 -109.910041) (xy 169.815828 -109.858107)
			(xy 169.852334 -109.810531) (xy 169.894739 -109.768126) (xy 169.942315 -109.73162) (xy 169.994249 -109.701636)
			(xy 170.049653 -109.678687) (xy 170.107578 -109.663166) (xy 170.167034 -109.655338) (xy 170.227002 -109.655338)
			(xy 170.286458 -109.663166) (xy 170.344383 -109.678687) (xy 170.399787 -109.701636) (xy 170.451721 -109.73162)
			(xy 170.499297 -109.768126) (xy 170.541702 -109.810531) (xy 170.578208 -109.858107) (xy 170.608192 -109.910041)
			(xy 170.631141 -109.965445) (xy 170.646662 -110.02337) (xy 170.65449 -110.082826) (xy 170.65498 -110.11281)
			(xy 170.65498 -110.97641) (xy 170.654955 -110.977934) (xy 269.509748 -110.977934) (xy 269.509748 -110.114334)
			(xy 269.510238 -110.08435) (xy 269.518066 -110.024894) (xy 269.533587 -109.966969) (xy 269.556536 -109.911565)
			(xy 269.58652 -109.859631) (xy 269.623026 -109.812055) (xy 269.665431 -109.76965) (xy 269.713007 -109.733144)
			(xy 269.764941 -109.70316) (xy 269.820345 -109.680211) (xy 269.87827 -109.66469) (xy 269.937726 -109.656862)
			(xy 269.997694 -109.656862) (xy 270.05715 -109.66469) (xy 270.115075 -109.680211) (xy 270.170479 -109.70316)
			(xy 270.222413 -109.733144) (xy 270.269989 -109.76965) (xy 270.312394 -109.812055) (xy 270.3489 -109.859631)
			(xy 270.378884 -109.911565) (xy 270.401833 -109.966969) (xy 270.417354 -110.024894) (xy 270.425182 -110.08435)
			(xy 270.425672 -110.114334) (xy 270.425672 -110.97641) (xy 285.8389 -110.97641) (xy 285.8389 -110.11281)
			(xy 285.83939 -110.082826) (xy 285.847218 -110.02337) (xy 285.862739 -109.965445) (xy 285.885688 -109.910041)
			(xy 285.915672 -109.858107) (xy 285.952178 -109.810531) (xy 285.994583 -109.768126) (xy 286.042159 -109.73162)
			(xy 286.094093 -109.701636) (xy 286.149497 -109.678687) (xy 286.207422 -109.663166) (xy 286.266878 -109.655338)
			(xy 286.326846 -109.655338) (xy 286.386302 -109.663166) (xy 286.444227 -109.678687) (xy 286.499631 -109.701636)
			(xy 286.551565 -109.73162) (xy 286.599141 -109.768126) (xy 286.641546 -109.810531) (xy 286.678052 -109.858107)
			(xy 286.708036 -109.910041) (xy 286.730985 -109.965445) (xy 286.746506 -110.02337) (xy 286.754334 -110.082826)
			(xy 286.754824 -110.11281) (xy 286.754824 -110.97641) (xy 286.754799 -110.977934) (xy 385.6101 -110.977934)
			(xy 385.6101 -110.114334) (xy 385.61059 -110.084366) (xy 385.618413 -110.024944) (xy 385.633926 -109.967051)
			(xy 385.656862 -109.911678) (xy 385.686829 -109.859772) (xy 385.723316 -109.812222) (xy 385.765696 -109.769842)
			(xy 385.813246 -109.733355) (xy 385.865152 -109.703388) (xy 385.920525 -109.680452) (xy 385.978418 -109.664939)
			(xy 386.03784 -109.657116) (xy 386.097776 -109.657116) (xy 386.157198 -109.664939) (xy 386.215091 -109.680452)
			(xy 386.270464 -109.703388) (xy 386.32237 -109.733355) (xy 386.36992 -109.769842) (xy 386.4123 -109.812222)
			(xy 386.448787 -109.859772) (xy 386.478754 -109.911678) (xy 386.50169 -109.967051) (xy 386.517203 -110.024944)
			(xy 386.525026 -110.084366) (xy 386.525516 -110.114334) (xy 386.525516 -110.97641) (xy 401.939252 -110.97641)
			(xy 401.939252 -110.11281) (xy 401.939742 -110.082842) (xy 401.947565 -110.02342) (xy 401.963078 -109.965527)
			(xy 401.986014 -109.910154) (xy 402.015981 -109.858248) (xy 402.052468 -109.810698) (xy 402.094848 -109.768318)
			(xy 402.142398 -109.731831) (xy 402.194304 -109.701864) (xy 402.249677 -109.678928) (xy 402.30757 -109.663415)
			(xy 402.366992 -109.655592) (xy 402.426928 -109.655592) (xy 402.48635 -109.663415) (xy 402.544243 -109.678928)
			(xy 402.599616 -109.701864) (xy 402.651522 -109.731831) (xy 402.699072 -109.768318) (xy 402.741452 -109.810698)
			(xy 402.777939 -109.858248) (xy 402.807906 -109.910154) (xy 402.830842 -109.965527) (xy 402.846355 -110.02342)
			(xy 402.854178 -110.082842) (xy 402.854668 -110.11281) (xy 402.854668 -110.97641) (xy 402.854178 -111.006378)
			(xy 402.846355 -111.0658) (xy 402.830842 -111.123693) (xy 402.807906 -111.179066) (xy 402.777939 -111.230972)
			(xy 402.741452 -111.278522) (xy 402.699072 -111.320902) (xy 402.651522 -111.357389) (xy 402.599616 -111.387356)
			(xy 402.544243 -111.410292) (xy 402.48635 -111.425805) (xy 402.426928 -111.433628) (xy 402.366992 -111.433628)
			(xy 402.30757 -111.425805) (xy 402.249677 -111.410292) (xy 402.194304 -111.387356) (xy 402.142398 -111.357389)
			(xy 402.094848 -111.320902) (xy 402.052468 -111.278522) (xy 402.015981 -111.230972) (xy 401.986014 -111.179066)
			(xy 401.963078 -111.123693) (xy 401.947565 -111.0658) (xy 401.939742 -111.006378) (xy 401.939252 -110.97641)
			(xy 386.525516 -110.97641) (xy 386.525516 -110.977934) (xy 386.525026 -111.007902) (xy 386.517203 -111.067324)
			(xy 386.50169 -111.125217) (xy 386.478754 -111.18059) (xy 386.448787 -111.232496) (xy 386.4123 -111.280046)
			(xy 386.36992 -111.322426) (xy 386.32237 -111.358913) (xy 386.270464 -111.38888) (xy 386.215091 -111.411816)
			(xy 386.157198 -111.427329) (xy 386.097776 -111.435152) (xy 386.03784 -111.435152) (xy 385.978418 -111.427329)
			(xy 385.920525 -111.411816) (xy 385.865152 -111.38888) (xy 385.813246 -111.358913) (xy 385.765696 -111.322426)
			(xy 385.723316 -111.280046) (xy 385.686829 -111.232496) (xy 385.656862 -111.18059) (xy 385.633926 -111.125217)
			(xy 385.618413 -111.067324) (xy 385.61059 -111.007902) (xy 385.6101 -110.977934) (xy 286.754799 -110.977934)
			(xy 286.754334 -111.006394) (xy 286.746506 -111.06585) (xy 286.730985 -111.123775) (xy 286.708036 -111.179179)
			(xy 286.678052 -111.231113) (xy 286.641546 -111.278689) (xy 286.599141 -111.321094) (xy 286.551565 -111.3576)
			(xy 286.499631 -111.387584) (xy 286.444227 -111.410533) (xy 286.386302 -111.426054) (xy 286.326846 -111.433882)
			(xy 286.266878 -111.433882) (xy 286.207422 -111.426054) (xy 286.149497 -111.410533) (xy 286.094093 -111.387584)
			(xy 286.042159 -111.3576) (xy 285.994583 -111.321094) (xy 285.952178 -111.278689) (xy 285.915672 -111.231113)
			(xy 285.885688 -111.179179) (xy 285.862739 -111.123775) (xy 285.847218 -111.06585) (xy 285.83939 -111.006394)
			(xy 285.8389 -110.97641) (xy 270.425672 -110.97641) (xy 270.425672 -110.977934) (xy 270.425182 -111.007918)
			(xy 270.417354 -111.067374) (xy 270.401833 -111.125299) (xy 270.378884 -111.180703) (xy 270.3489 -111.232637)
			(xy 270.312394 -111.280213) (xy 270.269989 -111.322618) (xy 270.222413 -111.359124) (xy 270.170479 -111.389108)
			(xy 270.115075 -111.412057) (xy 270.05715 -111.427578) (xy 269.997694 -111.435406) (xy 269.937726 -111.435406)
			(xy 269.87827 -111.427578) (xy 269.820345 -111.412057) (xy 269.764941 -111.389108) (xy 269.713007 -111.359124)
			(xy 269.665431 -111.322618) (xy 269.623026 -111.280213) (xy 269.58652 -111.232637) (xy 269.556536 -111.180703)
			(xy 269.533587 -111.125299) (xy 269.518066 -111.067374) (xy 269.510238 -111.007918) (xy 269.509748 -110.977934)
			(xy 170.654955 -110.977934) (xy 170.65449 -111.006394) (xy 170.646662 -111.06585) (xy 170.631141 -111.123775)
			(xy 170.608192 -111.179179) (xy 170.578208 -111.231113) (xy 170.541702 -111.278689) (xy 170.499297 -111.321094)
			(xy 170.451721 -111.3576) (xy 170.399787 -111.387584) (xy 170.344383 -111.410533) (xy 170.286458 -111.426054)
			(xy 170.227002 -111.433882) (xy 170.167034 -111.433882) (xy 170.107578 -111.426054) (xy 170.049653 -111.410533)
			(xy 169.994249 -111.387584) (xy 169.942315 -111.3576) (xy 169.894739 -111.321094) (xy 169.852334 -111.278689)
			(xy 169.815828 -111.231113) (xy 169.785844 -111.179179) (xy 169.762895 -111.123775) (xy 169.747374 -111.06585)
			(xy 169.739546 -111.006394) (xy 169.739056 -110.97641) (xy 154.325828 -110.97641) (xy 154.325828 -110.977934)
			(xy 154.325338 -111.007918) (xy 154.31751 -111.067374) (xy 154.301989 -111.125299) (xy 154.27904 -111.180703)
			(xy 154.249056 -111.232637) (xy 154.21255 -111.280213) (xy 154.170145 -111.322618) (xy 154.122569 -111.359124)
			(xy 154.070635 -111.389108) (xy 154.015231 -111.412057) (xy 153.957306 -111.427578) (xy 153.89785 -111.435406)
			(xy 153.837882 -111.435406) (xy 153.778426 -111.427578) (xy 153.720501 -111.412057) (xy 153.665097 -111.389108)
			(xy 153.613163 -111.359124) (xy 153.565587 -111.322618) (xy 153.523182 -111.280213) (xy 153.486676 -111.232637)
			(xy 153.456692 -111.180703) (xy 153.433743 -111.125299) (xy 153.418222 -111.067374) (xy 153.410394 -111.007918)
			(xy 153.409904 -110.977934) (xy 54.554603 -110.977934) (xy 54.554138 -111.006378) (xy 54.546315 -111.0658)
			(xy 54.530802 -111.123693) (xy 54.507866 -111.179066) (xy 54.477899 -111.230972) (xy 54.441412 -111.278522)
			(xy 54.399032 -111.320902) (xy 54.351482 -111.357389) (xy 54.299576 -111.387356) (xy 54.244203 -111.410292)
			(xy 54.18631 -111.425805) (xy 54.126888 -111.433628) (xy 54.066952 -111.433628) (xy 54.00753 -111.425805)
			(xy 53.949637 -111.410292) (xy 53.894264 -111.387356) (xy 53.842358 -111.357389) (xy 53.794808 -111.320902)
			(xy 53.752428 -111.278522) (xy 53.715941 -111.230972) (xy 53.685974 -111.179066) (xy 53.663038 -111.123693)
			(xy 53.647525 -111.0658) (xy 53.639702 -111.006378) (xy 53.639212 -110.97641) (xy 38.225476 -110.97641)
			(xy 38.225476 -110.977934) (xy 38.224986 -111.007902) (xy 38.217163 -111.067324) (xy 38.20165 -111.125217)
			(xy 38.178714 -111.18059) (xy 38.148747 -111.232496) (xy 38.11226 -111.280046) (xy 38.06988 -111.322426)
			(xy 38.02233 -111.358913) (xy 37.970424 -111.38888) (xy 37.915051 -111.411816) (xy 37.857158 -111.427329)
			(xy 37.797736 -111.435152) (xy 37.7378 -111.435152) (xy 37.678378 -111.427329) (xy 37.620485 -111.411816)
			(xy 37.565112 -111.38888) (xy 37.513206 -111.358913) (xy 37.465656 -111.322426) (xy 37.423276 -111.280046)
			(xy 37.386789 -111.232496) (xy 37.356822 -111.18059) (xy 37.333886 -111.125217) (xy 37.318373 -111.067324)
			(xy 37.31055 -111.007902) (xy 37.31006 -110.977934) (xy 5.324094 -110.977934) (xy 5.324094 -112.784382)
			(xy 34.667952 -112.784382) (xy 34.667952 -111.920782) (xy 34.668442 -111.890814) (xy 34.676265 -111.831392)
			(xy 34.691778 -111.773499) (xy 34.714714 -111.718126) (xy 34.744681 -111.66622) (xy 34.781168 -111.61867)
			(xy 34.823548 -111.57629) (xy 34.871098 -111.539803) (xy 34.923004 -111.509836) (xy 34.978377 -111.4869)
			(xy 35.03627 -111.471387) (xy 35.095692 -111.463564) (xy 35.155628 -111.463564) (xy 35.21505 -111.471387)
			(xy 35.272943 -111.4869) (xy 35.328316 -111.509836) (xy 35.380222 -111.539803) (xy 35.427772 -111.57629)
			(xy 35.470152 -111.61867) (xy 35.506639 -111.66622) (xy 35.536606 -111.718126) (xy 35.559542 -111.773499)
			(xy 35.575055 -111.831392) (xy 35.582878 -111.890814) (xy 35.583368 -111.920782) (xy 35.583368 -112.776508)
			(xy 51.785012 -112.776508) (xy 51.785012 -111.912908) (xy 51.785502 -111.88294) (xy 51.793325 -111.823518)
			(xy 51.808838 -111.765625) (xy 51.831774 -111.710252) (xy 51.861741 -111.658346) (xy 51.898228 -111.610796)
			(xy 51.940608 -111.568416) (xy 51.988158 -111.531929) (xy 52.040064 -111.501962) (xy 52.095437 -111.479026)
			(xy 52.15333 -111.463513) (xy 52.212752 -111.45569) (xy 52.272688 -111.45569) (xy 52.33211 -111.463513)
			(xy 52.390003 -111.479026) (xy 52.445376 -111.501962) (xy 52.497282 -111.531929) (xy 52.544832 -111.568416)
			(xy 52.587212 -111.610796) (xy 52.623699 -111.658346) (xy 52.653666 -111.710252) (xy 52.676602 -111.765625)
			(xy 52.692115 -111.823518) (xy 52.699938 -111.88294) (xy 52.700428 -111.912908) (xy 52.700428 -112.776508)
			(xy 52.700299 -112.784382) (xy 150.767796 -112.784382) (xy 150.767796 -111.920782) (xy 150.768286 -111.890798)
			(xy 150.776114 -111.831342) (xy 150.791635 -111.773417) (xy 150.814584 -111.718013) (xy 150.844568 -111.666079)
			(xy 150.881074 -111.618503) (xy 150.923479 -111.576098) (xy 150.971055 -111.539592) (xy 151.022989 -111.509608)
			(xy 151.078393 -111.486659) (xy 151.136318 -111.471138) (xy 151.195774 -111.46331) (xy 151.255742 -111.46331)
			(xy 151.315198 -111.471138) (xy 151.373123 -111.486659) (xy 151.428527 -111.509608) (xy 151.480461 -111.539592)
			(xy 151.528037 -111.576098) (xy 151.570442 -111.618503) (xy 151.606948 -111.666079) (xy 151.636932 -111.718013)
			(xy 151.659881 -111.773417) (xy 151.675402 -111.831342) (xy 151.68323 -111.890798) (xy 151.68372 -111.920782)
			(xy 151.68372 -112.776508) (xy 167.884856 -112.776508) (xy 167.884856 -111.912908) (xy 167.885346 -111.882924)
			(xy 167.893174 -111.823468) (xy 167.908695 -111.765543) (xy 167.931644 -111.710139) (xy 167.961628 -111.658205)
			(xy 167.998134 -111.610629) (xy 168.040539 -111.568224) (xy 168.088115 -111.531718) (xy 168.140049 -111.501734)
			(xy 168.195453 -111.478785) (xy 168.253378 -111.463264) (xy 168.312834 -111.455436) (xy 168.372802 -111.455436)
			(xy 168.432258 -111.463264) (xy 168.490183 -111.478785) (xy 168.545587 -111.501734) (xy 168.597521 -111.531718)
			(xy 168.645097 -111.568224) (xy 168.687502 -111.610629) (xy 168.724008 -111.658205) (xy 168.753992 -111.710139)
			(xy 168.776941 -111.765543) (xy 168.792462 -111.823468) (xy 168.80029 -111.882924) (xy 168.80078 -111.912908)
			(xy 168.80078 -112.776508) (xy 168.800651 -112.784382) (xy 266.86764 -112.784382) (xy 266.86764 -111.920782)
			(xy 266.86813 -111.890798) (xy 266.875958 -111.831342) (xy 266.891479 -111.773417) (xy 266.914428 -111.718013)
			(xy 266.944412 -111.666079) (xy 266.980918 -111.618503) (xy 267.023323 -111.576098) (xy 267.070899 -111.539592)
			(xy 267.122833 -111.509608) (xy 267.178237 -111.486659) (xy 267.236162 -111.471138) (xy 267.295618 -111.46331)
			(xy 267.355586 -111.46331) (xy 267.415042 -111.471138) (xy 267.472967 -111.486659) (xy 267.528371 -111.509608)
			(xy 267.580305 -111.539592) (xy 267.627881 -111.576098) (xy 267.670286 -111.618503) (xy 267.706792 -111.666079)
			(xy 267.736776 -111.718013) (xy 267.759725 -111.773417) (xy 267.775246 -111.831342) (xy 267.783074 -111.890798)
			(xy 267.783564 -111.920782) (xy 267.783564 -112.776508) (xy 283.9847 -112.776508) (xy 283.9847 -111.912908)
			(xy 283.98519 -111.882924) (xy 283.993018 -111.823468) (xy 284.008539 -111.765543) (xy 284.031488 -111.710139)
			(xy 284.061472 -111.658205) (xy 284.097978 -111.610629) (xy 284.140383 -111.568224) (xy 284.187959 -111.531718)
			(xy 284.239893 -111.501734) (xy 284.295297 -111.478785) (xy 284.353222 -111.463264) (xy 284.412678 -111.455436)
			(xy 284.472646 -111.455436) (xy 284.532102 -111.463264) (xy 284.590027 -111.478785) (xy 284.645431 -111.501734)
			(xy 284.697365 -111.531718) (xy 284.744941 -111.568224) (xy 284.787346 -111.610629) (xy 284.823852 -111.658205)
			(xy 284.853836 -111.710139) (xy 284.876785 -111.765543) (xy 284.892306 -111.823468) (xy 284.900134 -111.882924)
			(xy 284.900624 -111.912908) (xy 284.900624 -112.776508) (xy 284.900495 -112.784382) (xy 382.967992 -112.784382)
			(xy 382.967992 -111.920782) (xy 382.968482 -111.890814) (xy 382.976305 -111.831392) (xy 382.991818 -111.773499)
			(xy 383.014754 -111.718126) (xy 383.044721 -111.66622) (xy 383.081208 -111.61867) (xy 383.123588 -111.57629)
			(xy 383.171138 -111.539803) (xy 383.223044 -111.509836) (xy 383.278417 -111.4869) (xy 383.33631 -111.471387)
			(xy 383.395732 -111.463564) (xy 383.455668 -111.463564) (xy 383.51509 -111.471387) (xy 383.572983 -111.4869)
			(xy 383.628356 -111.509836) (xy 383.680262 -111.539803) (xy 383.727812 -111.57629) (xy 383.770192 -111.61867)
			(xy 383.806679 -111.66622) (xy 383.836646 -111.718126) (xy 383.859582 -111.773499) (xy 383.875095 -111.831392)
			(xy 383.882918 -111.890814) (xy 383.883408 -111.920782) (xy 383.883408 -112.776508) (xy 400.085052 -112.776508)
			(xy 400.085052 -111.912908) (xy 400.085542 -111.88294) (xy 400.093365 -111.823518) (xy 400.108878 -111.765625)
			(xy 400.131814 -111.710252) (xy 400.161781 -111.658346) (xy 400.198268 -111.610796) (xy 400.240648 -111.568416)
			(xy 400.288198 -111.531929) (xy 400.340104 -111.501962) (xy 400.395477 -111.479026) (xy 400.45337 -111.463513)
			(xy 400.512792 -111.45569) (xy 400.572728 -111.45569) (xy 400.63215 -111.463513) (xy 400.690043 -111.479026)
			(xy 400.745416 -111.501962) (xy 400.797322 -111.531929) (xy 400.844872 -111.568416) (xy 400.887252 -111.610796)
			(xy 400.923739 -111.658346) (xy 400.953706 -111.710252) (xy 400.976642 -111.765625) (xy 400.992155 -111.823518)
			(xy 400.999978 -111.88294) (xy 401.000468 -111.912908) (xy 401.000468 -112.776508) (xy 400.999978 -112.806476)
			(xy 400.992155 -112.865898) (xy 400.976642 -112.923791) (xy 400.953706 -112.979164) (xy 400.923739 -113.03107)
			(xy 400.887252 -113.07862) (xy 400.844872 -113.121) (xy 400.797322 -113.157487) (xy 400.745416 -113.187454)
			(xy 400.690043 -113.21039) (xy 400.63215 -113.225903) (xy 400.572728 -113.233726) (xy 400.512792 -113.233726)
			(xy 400.45337 -113.225903) (xy 400.395477 -113.21039) (xy 400.340104 -113.187454) (xy 400.288198 -113.157487)
			(xy 400.240648 -113.121) (xy 400.198268 -113.07862) (xy 400.161781 -113.03107) (xy 400.131814 -112.979164)
			(xy 400.108878 -112.923791) (xy 400.093365 -112.865898) (xy 400.085542 -112.806476) (xy 400.085052 -112.776508)
			(xy 383.883408 -112.776508) (xy 383.883408 -112.784382) (xy 383.882918 -112.81435) (xy 383.875095 -112.873772)
			(xy 383.859582 -112.931665) (xy 383.836646 -112.987038) (xy 383.806679 -113.038944) (xy 383.770192 -113.086494)
			(xy 383.727812 -113.128874) (xy 383.680262 -113.165361) (xy 383.628356 -113.195328) (xy 383.572983 -113.218264)
			(xy 383.51509 -113.233777) (xy 383.455668 -113.2416) (xy 383.395732 -113.2416) (xy 383.33631 -113.233777)
			(xy 383.278417 -113.218264) (xy 383.223044 -113.195328) (xy 383.171138 -113.165361) (xy 383.123588 -113.128874)
			(xy 383.081208 -113.086494) (xy 383.044721 -113.038944) (xy 383.014754 -112.987038) (xy 382.991818 -112.931665)
			(xy 382.976305 -112.873772) (xy 382.968482 -112.81435) (xy 382.967992 -112.784382) (xy 284.900495 -112.784382)
			(xy 284.900134 -112.806492) (xy 284.892306 -112.865948) (xy 284.876785 -112.923873) (xy 284.853836 -112.979277)
			(xy 284.823852 -113.031211) (xy 284.787346 -113.078787) (xy 284.744941 -113.121192) (xy 284.697365 -113.157698)
			(xy 284.645431 -113.187682) (xy 284.590027 -113.210631) (xy 284.532102 -113.226152) (xy 284.472646 -113.23398)
			(xy 284.412678 -113.23398) (xy 284.353222 -113.226152) (xy 284.295297 -113.210631) (xy 284.239893 -113.187682)
			(xy 284.187959 -113.157698) (xy 284.140383 -113.121192) (xy 284.097978 -113.078787) (xy 284.061472 -113.031211)
			(xy 284.031488 -112.979277) (xy 284.008539 -112.923873) (xy 283.993018 -112.865948) (xy 283.98519 -112.806492)
			(xy 283.9847 -112.776508) (xy 267.783564 -112.776508) (xy 267.783564 -112.784382) (xy 267.783074 -112.814366)
			(xy 267.775246 -112.873822) (xy 267.759725 -112.931747) (xy 267.736776 -112.987151) (xy 267.706792 -113.039085)
			(xy 267.670286 -113.086661) (xy 267.627881 -113.129066) (xy 267.580305 -113.165572) (xy 267.528371 -113.195556)
			(xy 267.472967 -113.218505) (xy 267.415042 -113.234026) (xy 267.355586 -113.241854) (xy 267.295618 -113.241854)
			(xy 267.236162 -113.234026) (xy 267.178237 -113.218505) (xy 267.122833 -113.195556) (xy 267.070899 -113.165572)
			(xy 267.023323 -113.129066) (xy 266.980918 -113.086661) (xy 266.944412 -113.039085) (xy 266.914428 -112.987151)
			(xy 266.891479 -112.931747) (xy 266.875958 -112.873822) (xy 266.86813 -112.814366) (xy 266.86764 -112.784382)
			(xy 168.800651 -112.784382) (xy 168.80029 -112.806492) (xy 168.792462 -112.865948) (xy 168.776941 -112.923873)
			(xy 168.753992 -112.979277) (xy 168.724008 -113.031211) (xy 168.687502 -113.078787) (xy 168.645097 -113.121192)
			(xy 168.597521 -113.157698) (xy 168.545587 -113.187682) (xy 168.490183 -113.210631) (xy 168.432258 -113.226152)
			(xy 168.372802 -113.23398) (xy 168.312834 -113.23398) (xy 168.253378 -113.226152) (xy 168.195453 -113.210631)
			(xy 168.140049 -113.187682) (xy 168.088115 -113.157698) (xy 168.040539 -113.121192) (xy 167.998134 -113.078787)
			(xy 167.961628 -113.031211) (xy 167.931644 -112.979277) (xy 167.908695 -112.923873) (xy 167.893174 -112.865948)
			(xy 167.885346 -112.806492) (xy 167.884856 -112.776508) (xy 151.68372 -112.776508) (xy 151.68372 -112.784382)
			(xy 151.68323 -112.814366) (xy 151.675402 -112.873822) (xy 151.659881 -112.931747) (xy 151.636932 -112.987151)
			(xy 151.606948 -113.039085) (xy 151.570442 -113.086661) (xy 151.528037 -113.129066) (xy 151.480461 -113.165572)
			(xy 151.428527 -113.195556) (xy 151.373123 -113.218505) (xy 151.315198 -113.234026) (xy 151.255742 -113.241854)
			(xy 151.195774 -113.241854) (xy 151.136318 -113.234026) (xy 151.078393 -113.218505) (xy 151.022989 -113.195556)
			(xy 150.971055 -113.165572) (xy 150.923479 -113.129066) (xy 150.881074 -113.086661) (xy 150.844568 -113.039085)
			(xy 150.814584 -112.987151) (xy 150.791635 -112.931747) (xy 150.776114 -112.873822) (xy 150.768286 -112.814366)
			(xy 150.767796 -112.784382) (xy 52.700299 -112.784382) (xy 52.699938 -112.806476) (xy 52.692115 -112.865898)
			(xy 52.676602 -112.923791) (xy 52.653666 -112.979164) (xy 52.623699 -113.03107) (xy 52.587212 -113.07862)
			(xy 52.544832 -113.121) (xy 52.497282 -113.157487) (xy 52.445376 -113.187454) (xy 52.390003 -113.21039)
			(xy 52.33211 -113.225903) (xy 52.272688 -113.233726) (xy 52.212752 -113.233726) (xy 52.15333 -113.225903)
			(xy 52.095437 -113.21039) (xy 52.040064 -113.187454) (xy 51.988158 -113.157487) (xy 51.940608 -113.121)
			(xy 51.898228 -113.07862) (xy 51.861741 -113.03107) (xy 51.831774 -112.979164) (xy 51.808838 -112.923791)
			(xy 51.793325 -112.865898) (xy 51.785502 -112.806476) (xy 51.785012 -112.776508) (xy 35.583368 -112.776508)
			(xy 35.583368 -112.784382) (xy 35.582878 -112.81435) (xy 35.575055 -112.873772) (xy 35.559542 -112.931665)
			(xy 35.536606 -112.987038) (xy 35.506639 -113.038944) (xy 35.470152 -113.086494) (xy 35.427772 -113.128874)
			(xy 35.380222 -113.165361) (xy 35.328316 -113.195328) (xy 35.272943 -113.218264) (xy 35.21505 -113.233777)
			(xy 35.155628 -113.2416) (xy 35.095692 -113.2416) (xy 35.03627 -113.233777) (xy 34.978377 -113.218264)
			(xy 34.923004 -113.195328) (xy 34.871098 -113.165361) (xy 34.823548 -113.128874) (xy 34.781168 -113.086494)
			(xy 34.744681 -113.038944) (xy 34.714714 -112.987038) (xy 34.691778 -112.931665) (xy 34.676265 -112.873772)
			(xy 34.668442 -112.81435) (xy 34.667952 -112.784382) (xy 5.324094 -112.784382) (xy 5.324094 -117.758718)
			(xy 74.474832 -117.758718) (xy 74.474832 -116.895118) (xy 74.475322 -116.865134) (xy 74.48315 -116.805678)
			(xy 74.498671 -116.747753) (xy 74.52162 -116.692349) (xy 74.551604 -116.640415) (xy 74.58811 -116.592839)
			(xy 74.630515 -116.550434) (xy 74.678091 -116.513928) (xy 74.730025 -116.483944) (xy 74.785429 -116.460995)
			(xy 74.843354 -116.445474) (xy 74.90281 -116.437646) (xy 74.962778 -116.437646) (xy 75.022234 -116.445474)
			(xy 75.080159 -116.460995) (xy 75.135563 -116.483944) (xy 75.187497 -116.513928) (xy 75.235073 -116.550434)
			(xy 75.277478 -116.592839) (xy 75.313984 -116.640415) (xy 75.343968 -116.692349) (xy 75.366917 -116.747753)
			(xy 75.382438 -116.805678) (xy 75.390266 -116.865134) (xy 75.390756 -116.895118) (xy 75.390756 -117.758718)
			(xy 190.574676 -117.758718) (xy 190.574676 -116.895118) (xy 190.575166 -116.865134) (xy 190.582994 -116.805678)
			(xy 190.598515 -116.747753) (xy 190.621464 -116.692349) (xy 190.651448 -116.640415) (xy 190.687954 -116.592839)
			(xy 190.730359 -116.550434) (xy 190.777935 -116.513928) (xy 190.829869 -116.483944) (xy 190.885273 -116.460995)
			(xy 190.943198 -116.445474) (xy 191.002654 -116.437646) (xy 191.062622 -116.437646) (xy 191.122078 -116.445474)
			(xy 191.180003 -116.460995) (xy 191.235407 -116.483944) (xy 191.287341 -116.513928) (xy 191.334917 -116.550434)
			(xy 191.377322 -116.592839) (xy 191.413828 -116.640415) (xy 191.443812 -116.692349) (xy 191.466761 -116.747753)
			(xy 191.482282 -116.805678) (xy 191.49011 -116.865134) (xy 191.4906 -116.895118) (xy 191.4906 -117.758718)
			(xy 306.675028 -117.758718) (xy 306.675028 -116.895118) (xy 306.675518 -116.86515) (xy 306.683341 -116.805728)
			(xy 306.698854 -116.747835) (xy 306.72179 -116.692462) (xy 306.751757 -116.640556) (xy 306.788244 -116.593006)
			(xy 306.830624 -116.550626) (xy 306.878174 -116.514139) (xy 306.93008 -116.484172) (xy 306.985453 -116.461236)
			(xy 307.043346 -116.445723) (xy 307.102768 -116.4379) (xy 307.162704 -116.4379) (xy 307.222126 -116.445723)
			(xy 307.280019 -116.461236) (xy 307.335392 -116.484172) (xy 307.387298 -116.514139) (xy 307.434848 -116.550626)
			(xy 307.477228 -116.593006) (xy 307.513715 -116.640556) (xy 307.543682 -116.692462) (xy 307.566618 -116.747835)
			(xy 307.582131 -116.805728) (xy 307.589954 -116.86515) (xy 307.590444 -116.895118) (xy 307.590444 -117.758718)
			(xy 307.590436 -117.759226) (xy 422.774872 -117.759226) (xy 422.774872 -116.895626) (xy 422.775362 -116.865642)
			(xy 422.78319 -116.806186) (xy 422.798711 -116.748261) (xy 422.82166 -116.692857) (xy 422.851644 -116.640923)
			(xy 422.88815 -116.593347) (xy 422.930555 -116.550942) (xy 422.978131 -116.514436) (xy 423.030065 -116.484452)
			(xy 423.085469 -116.461503) (xy 423.143394 -116.445982) (xy 423.20285 -116.438154) (xy 423.262818 -116.438154)
			(xy 423.322274 -116.445982) (xy 423.380199 -116.461503) (xy 423.435603 -116.484452) (xy 423.487537 -116.514436)
			(xy 423.535113 -116.550942) (xy 423.577518 -116.593347) (xy 423.614024 -116.640923) (xy 423.644008 -116.692857)
			(xy 423.666957 -116.748261) (xy 423.682478 -116.806186) (xy 423.690306 -116.865642) (xy 423.690796 -116.895626)
			(xy 423.690796 -117.759226) (xy 423.690306 -117.78921) (xy 423.682478 -117.848666) (xy 423.666957 -117.906591)
			(xy 423.644008 -117.961995) (xy 423.614024 -118.013929) (xy 423.577518 -118.061505) (xy 423.535113 -118.10391)
			(xy 423.487537 -118.140416) (xy 423.435603 -118.1704) (xy 423.380199 -118.193349) (xy 423.322274 -118.20887)
			(xy 423.262818 -118.216698) (xy 423.20285 -118.216698) (xy 423.143394 -118.20887) (xy 423.085469 -118.193349)
			(xy 423.030065 -118.1704) (xy 422.978131 -118.140416) (xy 422.930555 -118.10391) (xy 422.88815 -118.061505)
			(xy 422.851644 -118.013929) (xy 422.82166 -117.961995) (xy 422.798711 -117.906591) (xy 422.78319 -117.848666)
			(xy 422.775362 -117.78921) (xy 422.774872 -117.759226) (xy 307.590436 -117.759226) (xy 307.589954 -117.788686)
			(xy 307.582131 -117.848108) (xy 307.566618 -117.906001) (xy 307.543682 -117.961374) (xy 307.513715 -118.01328)
			(xy 307.477228 -118.06083) (xy 307.434848 -118.10321) (xy 307.387298 -118.139697) (xy 307.335392 -118.169664)
			(xy 307.280019 -118.1926) (xy 307.222126 -118.208113) (xy 307.162704 -118.215936) (xy 307.102768 -118.215936)
			(xy 307.043346 -118.208113) (xy 306.985453 -118.1926) (xy 306.93008 -118.169664) (xy 306.878174 -118.139697)
			(xy 306.830624 -118.10321) (xy 306.788244 -118.06083) (xy 306.751757 -118.01328) (xy 306.72179 -117.961374)
			(xy 306.698854 -117.906001) (xy 306.683341 -117.848108) (xy 306.675518 -117.788686) (xy 306.675028 -117.758718)
			(xy 191.4906 -117.758718) (xy 191.49011 -117.788702) (xy 191.482282 -117.848158) (xy 191.466761 -117.906083)
			(xy 191.443812 -117.961487) (xy 191.413828 -118.013421) (xy 191.377322 -118.060997) (xy 191.334917 -118.103402)
			(xy 191.287341 -118.139908) (xy 191.235407 -118.169892) (xy 191.180003 -118.192841) (xy 191.122078 -118.208362)
			(xy 191.062622 -118.21619) (xy 191.002654 -118.21619) (xy 190.943198 -118.208362) (xy 190.885273 -118.192841)
			(xy 190.829869 -118.169892) (xy 190.777935 -118.139908) (xy 190.730359 -118.103402) (xy 190.687954 -118.060997)
			(xy 190.651448 -118.013421) (xy 190.621464 -117.961487) (xy 190.598515 -117.906083) (xy 190.582994 -117.848158)
			(xy 190.575166 -117.788702) (xy 190.574676 -117.758718) (xy 75.390756 -117.758718) (xy 75.390266 -117.788702)
			(xy 75.382438 -117.848158) (xy 75.366917 -117.906083) (xy 75.343968 -117.961487) (xy 75.313984 -118.013421)
			(xy 75.277478 -118.060997) (xy 75.235073 -118.103402) (xy 75.187497 -118.139908) (xy 75.135563 -118.169892)
			(xy 75.080159 -118.192841) (xy 75.022234 -118.208362) (xy 74.962778 -118.21619) (xy 74.90281 -118.21619)
			(xy 74.843354 -118.208362) (xy 74.785429 -118.192841) (xy 74.730025 -118.169892) (xy 74.678091 -118.139908)
			(xy 74.630515 -118.103402) (xy 74.58811 -118.060997) (xy 74.551604 -118.013421) (xy 74.52162 -117.961487)
			(xy 74.498671 -117.906083) (xy 74.48315 -117.848158) (xy 74.475322 -117.788702) (xy 74.474832 -117.758718)
			(xy 5.324094 -117.758718) (xy 5.324094 -120.087898) (xy 34.667952 -120.087898) (xy 34.667952 -119.224298)
			(xy 34.668442 -119.19433) (xy 34.676265 -119.134908) (xy 34.691778 -119.077015) (xy 34.714714 -119.021642)
			(xy 34.744681 -118.969736) (xy 34.781168 -118.922186) (xy 34.823548 -118.879806) (xy 34.871098 -118.843319)
			(xy 34.923004 -118.813352) (xy 34.978377 -118.790416) (xy 35.03627 -118.774903) (xy 35.095692 -118.76708)
			(xy 35.155628 -118.76708) (xy 35.21505 -118.774903) (xy 35.272943 -118.790416) (xy 35.328316 -118.813352)
			(xy 35.380222 -118.843319) (xy 35.427772 -118.879806) (xy 35.470152 -118.922186) (xy 35.506639 -118.969736)
			(xy 35.536606 -119.021642) (xy 35.559542 -119.077015) (xy 35.575055 -119.134908) (xy 35.582878 -119.19433)
			(xy 35.583368 -119.224298) (xy 35.583368 -120.086374) (xy 53.639212 -120.086374) (xy 53.639212 -119.222774)
			(xy 53.639702 -119.192806) (xy 53.647525 -119.133384) (xy 53.663038 -119.075491) (xy 53.685974 -119.020118)
			(xy 53.715941 -118.968212) (xy 53.752428 -118.920662) (xy 53.794808 -118.878282) (xy 53.842358 -118.841795)
			(xy 53.894264 -118.811828) (xy 53.949637 -118.788892) (xy 54.00753 -118.773379) (xy 54.066952 -118.765556)
			(xy 54.126888 -118.765556) (xy 54.18631 -118.773379) (xy 54.244203 -118.788892) (xy 54.299576 -118.811828)
			(xy 54.351482 -118.841795) (xy 54.399032 -118.878282) (xy 54.441412 -118.920662) (xy 54.477899 -118.968212)
			(xy 54.507866 -119.020118) (xy 54.530802 -119.075491) (xy 54.546315 -119.133384) (xy 54.554138 -119.192806)
			(xy 54.554628 -119.222774) (xy 54.554628 -119.567198) (xy 66.599308 -119.567198) (xy 66.599308 -118.703598)
			(xy 66.599798 -118.673614) (xy 66.607626 -118.614158) (xy 66.623147 -118.556233) (xy 66.646096 -118.500829)
			(xy 66.67608 -118.448895) (xy 66.712586 -118.401319) (xy 66.754991 -118.358914) (xy 66.802567 -118.322408)
			(xy 66.854501 -118.292424) (xy 66.909905 -118.269475) (xy 66.96783 -118.253954) (xy 67.027286 -118.246126)
			(xy 67.087254 -118.246126) (xy 67.14671 -118.253954) (xy 67.204635 -118.269475) (xy 67.260039 -118.292424)
			(xy 67.311973 -118.322408) (xy 67.359549 -118.358914) (xy 67.401954 -118.401319) (xy 67.43846 -118.448895)
			(xy 67.468444 -118.500829) (xy 67.491393 -118.556233) (xy 67.506914 -118.614158) (xy 67.514742 -118.673614)
			(xy 67.515232 -118.703598) (xy 67.515232 -119.55907) (xy 81.07426 -119.55907) (xy 81.07426 -118.69547)
			(xy 81.07475 -118.665486) (xy 81.082578 -118.60603) (xy 81.098099 -118.548105) (xy 81.121048 -118.492701)
			(xy 81.151032 -118.440767) (xy 81.187538 -118.393191) (xy 81.229943 -118.350786) (xy 81.277519 -118.31428)
			(xy 81.329453 -118.284296) (xy 81.384857 -118.261347) (xy 81.442782 -118.245826) (xy 81.502238 -118.237998)
			(xy 81.562206 -118.237998) (xy 81.621662 -118.245826) (xy 81.679587 -118.261347) (xy 81.734991 -118.284296)
			(xy 81.786925 -118.31428) (xy 81.834501 -118.350786) (xy 81.876906 -118.393191) (xy 81.913412 -118.440767)
			(xy 81.943396 -118.492701) (xy 81.966345 -118.548105) (xy 81.981866 -118.60603) (xy 81.989694 -118.665486)
			(xy 81.990184 -118.69547) (xy 81.990184 -119.55907) (xy 81.989694 -119.589054) (xy 81.981866 -119.64851)
			(xy 81.966345 -119.706435) (xy 81.943396 -119.761839) (xy 81.913412 -119.813773) (xy 81.876906 -119.861349)
			(xy 81.834501 -119.903754) (xy 81.786925 -119.94026) (xy 81.734991 -119.970244) (xy 81.679587 -119.993193)
			(xy 81.621662 -120.008714) (xy 81.562206 -120.016542) (xy 81.502238 -120.016542) (xy 81.442782 -120.008714)
			(xy 81.384857 -119.993193) (xy 81.329453 -119.970244) (xy 81.277519 -119.94026) (xy 81.229943 -119.903754)
			(xy 81.187538 -119.861349) (xy 81.151032 -119.813773) (xy 81.121048 -119.761839) (xy 81.098099 -119.706435)
			(xy 81.082578 -119.64851) (xy 81.07475 -119.589054) (xy 81.07426 -119.55907) (xy 67.515232 -119.55907)
			(xy 67.515232 -119.567198) (xy 67.514742 -119.597182) (xy 67.506914 -119.656638) (xy 67.491393 -119.714563)
			(xy 67.468444 -119.769967) (xy 67.43846 -119.821901) (xy 67.401954 -119.869477) (xy 67.359549 -119.911882)
			(xy 67.311973 -119.948388) (xy 67.260039 -119.978372) (xy 67.204635 -120.001321) (xy 67.14671 -120.016842)
			(xy 67.087254 -120.02467) (xy 67.027286 -120.02467) (xy 66.96783 -120.016842) (xy 66.909905 -120.001321)
			(xy 66.854501 -119.978372) (xy 66.802567 -119.948388) (xy 66.754991 -119.911882) (xy 66.712586 -119.869477)
			(xy 66.67608 -119.821901) (xy 66.646096 -119.769967) (xy 66.623147 -119.714563) (xy 66.607626 -119.656638)
			(xy 66.599798 -119.597182) (xy 66.599308 -119.567198) (xy 54.554628 -119.567198) (xy 54.554628 -120.086374)
			(xy 54.554138 -120.116342) (xy 54.546315 -120.175764) (xy 54.530802 -120.233657) (xy 54.507866 -120.28903)
			(xy 54.477899 -120.340936) (xy 54.441412 -120.388486) (xy 54.399032 -120.430866) (xy 54.351482 -120.467353)
			(xy 54.299576 -120.49732) (xy 54.244203 -120.520256) (xy 54.18631 -120.535769) (xy 54.126888 -120.543592)
			(xy 54.066952 -120.543592) (xy 54.00753 -120.535769) (xy 53.949637 -120.520256) (xy 53.894264 -120.49732)
			(xy 53.842358 -120.467353) (xy 53.794808 -120.430866) (xy 53.752428 -120.388486) (xy 53.715941 -120.340936)
			(xy 53.685974 -120.28903) (xy 53.663038 -120.233657) (xy 53.647525 -120.175764) (xy 53.639702 -120.116342)
			(xy 53.639212 -120.086374) (xy 35.583368 -120.086374) (xy 35.583368 -120.087898) (xy 35.582878 -120.117866)
			(xy 35.575055 -120.177288) (xy 35.559542 -120.235181) (xy 35.536606 -120.290554) (xy 35.506639 -120.34246)
			(xy 35.470152 -120.39001) (xy 35.427772 -120.43239) (xy 35.380222 -120.468877) (xy 35.328316 -120.498844)
			(xy 35.272943 -120.52178) (xy 35.21505 -120.537293) (xy 35.155628 -120.545116) (xy 35.095692 -120.545116)
			(xy 35.03627 -120.537293) (xy 34.978377 -120.52178) (xy 34.923004 -120.498844) (xy 34.871098 -120.468877)
			(xy 34.823548 -120.43239) (xy 34.781168 -120.39001) (xy 34.744681 -120.34246) (xy 34.714714 -120.290554)
			(xy 34.691778 -120.235181) (xy 34.676265 -120.177288) (xy 34.668442 -120.117866) (xy 34.667952 -120.087898)
			(xy 5.324094 -120.087898) (xy 5.324094 -121.894346) (xy 37.31006 -121.894346) (xy 37.31006 -121.030746)
			(xy 37.31055 -121.000778) (xy 37.318373 -120.941356) (xy 37.333886 -120.883463) (xy 37.356822 -120.82809)
			(xy 37.386789 -120.776184) (xy 37.423276 -120.728634) (xy 37.465656 -120.686254) (xy 37.513206 -120.649767)
			(xy 37.565112 -120.6198) (xy 37.620485 -120.596864) (xy 37.678378 -120.581351) (xy 37.7378 -120.573528)
			(xy 37.797736 -120.573528) (xy 37.857158 -120.581351) (xy 37.915051 -120.596864) (xy 37.970424 -120.6198)
			(xy 38.02233 -120.649767) (xy 38.06988 -120.686254) (xy 38.11226 -120.728634) (xy 38.148747 -120.776184)
			(xy 38.178714 -120.82809) (xy 38.20165 -120.883463) (xy 38.217163 -120.941356) (xy 38.224986 -121.000778)
			(xy 38.225476 -121.030746) (xy 38.225476 -121.886472) (xy 51.785012 -121.886472) (xy 51.785012 -121.022872)
			(xy 51.785502 -120.992904) (xy 51.793325 -120.933482) (xy 51.808838 -120.875589) (xy 51.831774 -120.820216)
			(xy 51.861741 -120.76831) (xy 51.898228 -120.72076) (xy 51.940608 -120.67838) (xy 51.988158 -120.641893)
			(xy 52.040064 -120.611926) (xy 52.095437 -120.58899) (xy 52.15333 -120.573477) (xy 52.212752 -120.565654)
			(xy 52.272688 -120.565654) (xy 52.33211 -120.573477) (xy 52.390003 -120.58899) (xy 52.445376 -120.611926)
			(xy 52.497282 -120.641893) (xy 52.544832 -120.67838) (xy 52.587212 -120.72076) (xy 52.623699 -120.76831)
			(xy 52.653666 -120.820216) (xy 52.676602 -120.875589) (xy 52.692115 -120.933482) (xy 52.699938 -120.992904)
			(xy 52.700428 -121.022872) (xy 52.700428 -121.367296) (xy 64.745108 -121.367296) (xy 64.745108 -120.503696)
			(xy 64.745598 -120.473712) (xy 64.753426 -120.414256) (xy 64.768947 -120.356331) (xy 64.791896 -120.300927)
			(xy 64.82188 -120.248993) (xy 64.858386 -120.201417) (xy 64.900791 -120.159012) (xy 64.948367 -120.122506)
			(xy 65.000301 -120.092522) (xy 65.055705 -120.069573) (xy 65.11363 -120.054052) (xy 65.173086 -120.046224)
			(xy 65.233054 -120.046224) (xy 65.29251 -120.054052) (xy 65.350435 -120.069573) (xy 65.405839 -120.092522)
			(xy 65.457773 -120.122506) (xy 65.505349 -120.159012) (xy 65.547754 -120.201417) (xy 65.58426 -120.248993)
			(xy 65.614244 -120.300927) (xy 65.637193 -120.356331) (xy 65.652714 -120.414256) (xy 65.660542 -120.473712)
			(xy 65.661032 -120.503696) (xy 65.661032 -121.365772) (xy 83.716368 -121.365772) (xy 83.716368 -120.502172)
			(xy 83.716858 -120.472188) (xy 83.724686 -120.412732) (xy 83.740207 -120.354807) (xy 83.763156 -120.299403)
			(xy 83.79314 -120.247469) (xy 83.829646 -120.199893) (xy 83.872051 -120.157488) (xy 83.919627 -120.120982)
			(xy 83.971561 -120.090998) (xy 84.026965 -120.068049) (xy 84.08489 -120.052528) (xy 84.144346 -120.0447)
			(xy 84.204314 -120.0447) (xy 84.26377 -120.052528) (xy 84.321695 -120.068049) (xy 84.369615 -120.087898)
			(xy 150.767796 -120.087898) (xy 150.767796 -119.224298) (xy 150.768286 -119.194314) (xy 150.776114 -119.134858)
			(xy 150.791635 -119.076933) (xy 150.814584 -119.021529) (xy 150.844568 -118.969595) (xy 150.881074 -118.922019)
			(xy 150.923479 -118.879614) (xy 150.971055 -118.843108) (xy 151.022989 -118.813124) (xy 151.078393 -118.790175)
			(xy 151.136318 -118.774654) (xy 151.195774 -118.766826) (xy 151.255742 -118.766826) (xy 151.315198 -118.774654)
			(xy 151.373123 -118.790175) (xy 151.428527 -118.813124) (xy 151.480461 -118.843108) (xy 151.528037 -118.879614)
			(xy 151.570442 -118.922019) (xy 151.606948 -118.969595) (xy 151.636932 -119.021529) (xy 151.659881 -119.076933)
			(xy 151.675402 -119.134858) (xy 151.68323 -119.194314) (xy 151.68372 -119.224298) (xy 151.68372 -120.086374)
			(xy 169.739056 -120.086374) (xy 169.739056 -119.222774) (xy 169.739546 -119.19279) (xy 169.747374 -119.133334)
			(xy 169.762895 -119.075409) (xy 169.785844 -119.020005) (xy 169.815828 -118.968071) (xy 169.852334 -118.920495)
			(xy 169.894739 -118.87809) (xy 169.942315 -118.841584) (xy 169.994249 -118.8116) (xy 170.049653 -118.788651)
			(xy 170.107578 -118.77313) (xy 170.167034 -118.765302) (xy 170.227002 -118.765302) (xy 170.286458 -118.77313)
			(xy 170.344383 -118.788651) (xy 170.399787 -118.8116) (xy 170.451721 -118.841584) (xy 170.499297 -118.87809)
			(xy 170.541702 -118.920495) (xy 170.578208 -118.968071) (xy 170.608192 -119.020005) (xy 170.631141 -119.075409)
			(xy 170.646662 -119.133334) (xy 170.65449 -119.19279) (xy 170.65498 -119.222774) (xy 170.65498 -119.567198)
			(xy 182.69966 -119.567198) (xy 182.69966 -118.703598) (xy 182.70015 -118.67363) (xy 182.707973 -118.614208)
			(xy 182.723486 -118.556315) (xy 182.746422 -118.500942) (xy 182.776389 -118.449036) (xy 182.812876 -118.401486)
			(xy 182.855256 -118.359106) (xy 182.902806 -118.322619) (xy 182.954712 -118.292652) (xy 183.010085 -118.269716)
			(xy 183.067978 -118.254203) (xy 183.1274 -118.24638) (xy 183.187336 -118.24638) (xy 183.246758 -118.254203)
			(xy 183.304651 -118.269716) (xy 183.360024 -118.292652) (xy 183.41193 -118.322619) (xy 183.45948 -118.359106)
			(xy 183.50186 -118.401486) (xy 183.538347 -118.449036) (xy 183.568314 -118.500942) (xy 183.59125 -118.556315)
			(xy 183.606763 -118.614208) (xy 183.614586 -118.67363) (xy 183.615076 -118.703598) (xy 183.615076 -119.559324)
			(xy 197.174612 -119.559324) (xy 197.174612 -118.695724) (xy 197.175102 -118.665756) (xy 197.182925 -118.606334)
			(xy 197.198438 -118.548441) (xy 197.221374 -118.493068) (xy 197.251341 -118.441162) (xy 197.287828 -118.393612)
			(xy 197.330208 -118.351232) (xy 197.377758 -118.314745) (xy 197.429664 -118.284778) (xy 197.485037 -118.261842)
			(xy 197.54293 -118.246329) (xy 197.602352 -118.238506) (xy 197.662288 -118.238506) (xy 197.72171 -118.246329)
			(xy 197.779603 -118.261842) (xy 197.834976 -118.284778) (xy 197.886882 -118.314745) (xy 197.934432 -118.351232)
			(xy 197.976812 -118.393612) (xy 198.013299 -118.441162) (xy 198.043266 -118.493068) (xy 198.066202 -118.548441)
			(xy 198.081715 -118.606334) (xy 198.089538 -118.665756) (xy 198.090028 -118.695724) (xy 198.090028 -119.559324)
			(xy 198.089538 -119.589292) (xy 198.081715 -119.648714) (xy 198.066202 -119.706607) (xy 198.043266 -119.76198)
			(xy 198.013299 -119.813886) (xy 197.976812 -119.861436) (xy 197.934432 -119.903816) (xy 197.886882 -119.940303)
			(xy 197.834976 -119.97027) (xy 197.779603 -119.993206) (xy 197.72171 -120.008719) (xy 197.662288 -120.016542)
			(xy 197.602352 -120.016542) (xy 197.54293 -120.008719) (xy 197.485037 -119.993206) (xy 197.429664 -119.97027)
			(xy 197.377758 -119.940303) (xy 197.330208 -119.903816) (xy 197.287828 -119.861436) (xy 197.251341 -119.813886)
			(xy 197.221374 -119.76198) (xy 197.198438 -119.706607) (xy 197.182925 -119.648714) (xy 197.175102 -119.589292)
			(xy 197.174612 -119.559324) (xy 183.615076 -119.559324) (xy 183.615076 -119.567198) (xy 183.614586 -119.597166)
			(xy 183.606763 -119.656588) (xy 183.59125 -119.714481) (xy 183.568314 -119.769854) (xy 183.538347 -119.82176)
			(xy 183.50186 -119.86931) (xy 183.45948 -119.91169) (xy 183.41193 -119.948177) (xy 183.360024 -119.978144)
			(xy 183.304651 -120.00108) (xy 183.246758 -120.016593) (xy 183.187336 -120.024416) (xy 183.1274 -120.024416)
			(xy 183.067978 -120.016593) (xy 183.010085 -120.00108) (xy 182.954712 -119.978144) (xy 182.902806 -119.948177)
			(xy 182.855256 -119.91169) (xy 182.812876 -119.86931) (xy 182.776389 -119.82176) (xy 182.746422 -119.769854)
			(xy 182.723486 -119.714481) (xy 182.707973 -119.656588) (xy 182.70015 -119.597166) (xy 182.69966 -119.567198)
			(xy 170.65498 -119.567198) (xy 170.65498 -120.086374) (xy 170.65449 -120.116358) (xy 170.646662 -120.175814)
			(xy 170.631141 -120.233739) (xy 170.608192 -120.289143) (xy 170.578208 -120.341077) (xy 170.541702 -120.388653)
			(xy 170.499297 -120.431058) (xy 170.451721 -120.467564) (xy 170.399787 -120.497548) (xy 170.344383 -120.520497)
			(xy 170.286458 -120.536018) (xy 170.227002 -120.543846) (xy 170.167034 -120.543846) (xy 170.107578 -120.536018)
			(xy 170.049653 -120.520497) (xy 169.994249 -120.497548) (xy 169.942315 -120.467564) (xy 169.894739 -120.431058)
			(xy 169.852334 -120.388653) (xy 169.815828 -120.341077) (xy 169.785844 -120.289143) (xy 169.762895 -120.233739)
			(xy 169.747374 -120.175814) (xy 169.739546 -120.116358) (xy 169.739056 -120.086374) (xy 151.68372 -120.086374)
			(xy 151.68372 -120.087898) (xy 151.68323 -120.117882) (xy 151.675402 -120.177338) (xy 151.659881 -120.235263)
			(xy 151.636932 -120.290667) (xy 151.606948 -120.342601) (xy 151.570442 -120.390177) (xy 151.528037 -120.432582)
			(xy 151.480461 -120.469088) (xy 151.428527 -120.499072) (xy 151.373123 -120.522021) (xy 151.315198 -120.537542)
			(xy 151.255742 -120.54537) (xy 151.195774 -120.54537) (xy 151.136318 -120.537542) (xy 151.078393 -120.522021)
			(xy 151.022989 -120.499072) (xy 150.971055 -120.469088) (xy 150.923479 -120.432582) (xy 150.881074 -120.390177)
			(xy 150.844568 -120.342601) (xy 150.814584 -120.290667) (xy 150.791635 -120.235263) (xy 150.776114 -120.177338)
			(xy 150.768286 -120.117882) (xy 150.767796 -120.087898) (xy 84.369615 -120.087898) (xy 84.377099 -120.090998)
			(xy 84.429033 -120.120982) (xy 84.476609 -120.157488) (xy 84.519014 -120.199893) (xy 84.55552 -120.247469)
			(xy 84.585504 -120.299403) (xy 84.608453 -120.354807) (xy 84.623974 -120.412732) (xy 84.631802 -120.472188)
			(xy 84.632292 -120.502172) (xy 84.632292 -121.365772) (xy 84.631802 -121.395756) (xy 84.623974 -121.455212)
			(xy 84.608453 -121.513137) (xy 84.585504 -121.568541) (xy 84.55552 -121.620475) (xy 84.519014 -121.668051)
			(xy 84.476609 -121.710456) (xy 84.429033 -121.746962) (xy 84.377099 -121.776946) (xy 84.321695 -121.799895)
			(xy 84.26377 -121.815416) (xy 84.204314 -121.823244) (xy 84.144346 -121.823244) (xy 84.08489 -121.815416)
			(xy 84.026965 -121.799895) (xy 83.971561 -121.776946) (xy 83.919627 -121.746962) (xy 83.872051 -121.710456)
			(xy 83.829646 -121.668051) (xy 83.79314 -121.620475) (xy 83.763156 -121.568541) (xy 83.740207 -121.513137)
			(xy 83.724686 -121.455212) (xy 83.716858 -121.395756) (xy 83.716368 -121.365772) (xy 65.661032 -121.365772)
			(xy 65.661032 -121.367296) (xy 65.660542 -121.39728) (xy 65.652714 -121.456736) (xy 65.637193 -121.514661)
			(xy 65.614244 -121.570065) (xy 65.58426 -121.621999) (xy 65.547754 -121.669575) (xy 65.505349 -121.71198)
			(xy 65.457773 -121.748486) (xy 65.405839 -121.77847) (xy 65.350435 -121.801419) (xy 65.29251 -121.81694)
			(xy 65.233054 -121.824768) (xy 65.173086 -121.824768) (xy 65.11363 -121.81694) (xy 65.055705 -121.801419)
			(xy 65.000301 -121.77847) (xy 64.948367 -121.748486) (xy 64.900791 -121.71198) (xy 64.858386 -121.669575)
			(xy 64.82188 -121.621999) (xy 64.791896 -121.570065) (xy 64.768947 -121.514661) (xy 64.753426 -121.456736)
			(xy 64.745598 -121.39728) (xy 64.745108 -121.367296) (xy 52.700428 -121.367296) (xy 52.700428 -121.886472)
			(xy 52.699938 -121.91644) (xy 52.692115 -121.975862) (xy 52.676602 -122.033755) (xy 52.653666 -122.089128)
			(xy 52.623699 -122.141034) (xy 52.587212 -122.188584) (xy 52.544832 -122.230964) (xy 52.497282 -122.267451)
			(xy 52.445376 -122.297418) (xy 52.390003 -122.320354) (xy 52.33211 -122.335867) (xy 52.272688 -122.34369)
			(xy 52.212752 -122.34369) (xy 52.15333 -122.335867) (xy 52.095437 -122.320354) (xy 52.040064 -122.297418)
			(xy 51.988158 -122.267451) (xy 51.940608 -122.230964) (xy 51.898228 -122.188584) (xy 51.861741 -122.141034)
			(xy 51.831774 -122.089128) (xy 51.808838 -122.033755) (xy 51.793325 -121.975862) (xy 51.785502 -121.91644)
			(xy 51.785012 -121.886472) (xy 38.225476 -121.886472) (xy 38.225476 -121.894346) (xy 38.224986 -121.924314)
			(xy 38.217163 -121.983736) (xy 38.20165 -122.041629) (xy 38.178714 -122.097002) (xy 38.148747 -122.148908)
			(xy 38.11226 -122.196458) (xy 38.06988 -122.238838) (xy 38.02233 -122.275325) (xy 37.970424 -122.305292)
			(xy 37.915051 -122.328228) (xy 37.857158 -122.343741) (xy 37.797736 -122.351564) (xy 37.7378 -122.351564)
			(xy 37.678378 -122.343741) (xy 37.620485 -122.328228) (xy 37.565112 -122.305292) (xy 37.513206 -122.275325)
			(xy 37.465656 -122.238838) (xy 37.423276 -122.196458) (xy 37.386789 -122.148908) (xy 37.356822 -122.097002)
			(xy 37.333886 -122.041629) (xy 37.318373 -121.983736) (xy 37.31055 -121.924314) (xy 37.31006 -121.894346)
			(xy 5.324094 -121.894346) (xy 5.324094 -123.68784) (xy 34.667952 -123.68784) (xy 34.667952 -122.82424)
			(xy 34.668442 -122.794272) (xy 34.676265 -122.73485) (xy 34.691778 -122.676957) (xy 34.714714 -122.621584)
			(xy 34.744681 -122.569678) (xy 34.781168 -122.522128) (xy 34.823548 -122.479748) (xy 34.871098 -122.443261)
			(xy 34.923004 -122.413294) (xy 34.978377 -122.390358) (xy 35.03627 -122.374845) (xy 35.095692 -122.367022)
			(xy 35.155628 -122.367022) (xy 35.21505 -122.374845) (xy 35.272943 -122.390358) (xy 35.328316 -122.413294)
			(xy 35.380222 -122.443261) (xy 35.427772 -122.479748) (xy 35.470152 -122.522128) (xy 35.506639 -122.569678)
			(xy 35.536606 -122.621584) (xy 35.559542 -122.676957) (xy 35.575055 -122.73485) (xy 35.582878 -122.794272)
			(xy 35.583368 -122.82424) (xy 35.583368 -123.686316) (xy 53.639212 -123.686316) (xy 53.639212 -122.822716)
			(xy 53.639702 -122.792748) (xy 53.647525 -122.733326) (xy 53.663038 -122.675433) (xy 53.685974 -122.62006)
			(xy 53.715941 -122.568154) (xy 53.752428 -122.520604) (xy 53.794808 -122.478224) (xy 53.842358 -122.441737)
			(xy 53.894264 -122.41177) (xy 53.949637 -122.388834) (xy 54.00753 -122.373321) (xy 54.066952 -122.365498)
			(xy 54.126888 -122.365498) (xy 54.18631 -122.373321) (xy 54.244203 -122.388834) (xy 54.299576 -122.41177)
			(xy 54.351482 -122.441737) (xy 54.399032 -122.478224) (xy 54.441412 -122.520604) (xy 54.477899 -122.568154)
			(xy 54.507866 -122.62006) (xy 54.530802 -122.675433) (xy 54.546315 -122.733326) (xy 54.554138 -122.792748)
			(xy 54.554628 -122.822716) (xy 54.554628 -123.16714) (xy 66.599308 -123.16714) (xy 66.599308 -122.30354)
			(xy 66.599798 -122.273556) (xy 66.607626 -122.2141) (xy 66.623147 -122.156175) (xy 66.646096 -122.100771)
			(xy 66.67608 -122.048837) (xy 66.712586 -122.001261) (xy 66.754991 -121.958856) (xy 66.802567 -121.92235)
			(xy 66.854501 -121.892366) (xy 66.909905 -121.869417) (xy 66.96783 -121.853896) (xy 67.027286 -121.846068)
			(xy 67.087254 -121.846068) (xy 67.14671 -121.853896) (xy 67.204635 -121.869417) (xy 67.260039 -121.892366)
			(xy 67.311973 -121.92235) (xy 67.359549 -121.958856) (xy 67.401954 -122.001261) (xy 67.43846 -122.048837)
			(xy 67.468444 -122.100771) (xy 67.491393 -122.156175) (xy 67.506914 -122.2141) (xy 67.514742 -122.273556)
			(xy 67.515232 -122.30354) (xy 67.515232 -123.159266) (xy 81.07426 -123.159266) (xy 81.07426 -122.295666)
			(xy 81.07475 -122.265682) (xy 81.082578 -122.206226) (xy 81.098099 -122.148301) (xy 81.121048 -122.092897)
			(xy 81.151032 -122.040963) (xy 81.187538 -121.993387) (xy 81.229943 -121.950982) (xy 81.277519 -121.914476)
			(xy 81.329453 -121.884492) (xy 81.384857 -121.861543) (xy 81.442782 -121.846022) (xy 81.502238 -121.838194)
			(xy 81.562206 -121.838194) (xy 81.621662 -121.846022) (xy 81.679587 -121.861543) (xy 81.734991 -121.884492)
			(xy 81.752059 -121.894346) (xy 153.409904 -121.894346) (xy 153.409904 -121.030746) (xy 153.410394 -121.000762)
			(xy 153.418222 -120.941306) (xy 153.433743 -120.883381) (xy 153.456692 -120.827977) (xy 153.486676 -120.776043)
			(xy 153.523182 -120.728467) (xy 153.565587 -120.686062) (xy 153.613163 -120.649556) (xy 153.665097 -120.619572)
			(xy 153.720501 -120.596623) (xy 153.778426 -120.581102) (xy 153.837882 -120.573274) (xy 153.89785 -120.573274)
			(xy 153.957306 -120.581102) (xy 154.015231 -120.596623) (xy 154.070635 -120.619572) (xy 154.122569 -120.649556)
			(xy 154.170145 -120.686062) (xy 154.21255 -120.728467) (xy 154.249056 -120.776043) (xy 154.27904 -120.827977)
			(xy 154.301989 -120.883381) (xy 154.31751 -120.941306) (xy 154.325338 -121.000762) (xy 154.325828 -121.030746)
			(xy 154.325828 -121.886472) (xy 167.884856 -121.886472) (xy 167.884856 -121.022872) (xy 167.885346 -120.992888)
			(xy 167.893174 -120.933432) (xy 167.908695 -120.875507) (xy 167.931644 -120.820103) (xy 167.961628 -120.768169)
			(xy 167.998134 -120.720593) (xy 168.040539 -120.678188) (xy 168.088115 -120.641682) (xy 168.140049 -120.611698)
			(xy 168.195453 -120.588749) (xy 168.253378 -120.573228) (xy 168.312834 -120.5654) (xy 168.372802 -120.5654)
			(xy 168.432258 -120.573228) (xy 168.490183 -120.588749) (xy 168.545587 -120.611698) (xy 168.597521 -120.641682)
			(xy 168.645097 -120.678188) (xy 168.687502 -120.720593) (xy 168.724008 -120.768169) (xy 168.753992 -120.820103)
			(xy 168.776941 -120.875507) (xy 168.792462 -120.933432) (xy 168.80029 -120.992888) (xy 168.80078 -121.022872)
			(xy 168.80078 -121.367296) (xy 180.84546 -121.367296) (xy 180.84546 -120.503696) (xy 180.84595 -120.473728)
			(xy 180.853773 -120.414306) (xy 180.869286 -120.356413) (xy 180.892222 -120.30104) (xy 180.922189 -120.249134)
			(xy 180.958676 -120.201584) (xy 181.001056 -120.159204) (xy 181.048606 -120.122717) (xy 181.100512 -120.09275)
			(xy 181.155885 -120.069814) (xy 181.213778 -120.054301) (xy 181.2732 -120.046478) (xy 181.333136 -120.046478)
			(xy 181.392558 -120.054301) (xy 181.450451 -120.069814) (xy 181.505824 -120.09275) (xy 181.55773 -120.122717)
			(xy 181.60528 -120.159204) (xy 181.64766 -120.201584) (xy 181.684147 -120.249134) (xy 181.714114 -120.30104)
			(xy 181.73705 -120.356413) (xy 181.752563 -120.414306) (xy 181.760386 -120.473728) (xy 181.760876 -120.503696)
			(xy 181.760876 -121.365772) (xy 199.81672 -121.365772) (xy 199.81672 -120.502172) (xy 199.81721 -120.472204)
			(xy 199.825033 -120.412782) (xy 199.840546 -120.354889) (xy 199.863482 -120.299516) (xy 199.893449 -120.24761)
			(xy 199.929936 -120.20006) (xy 199.972316 -120.15768) (xy 200.019866 -120.121193) (xy 200.071772 -120.091226)
			(xy 200.127145 -120.06829) (xy 200.185038 -120.052777) (xy 200.24446 -120.044954) (xy 200.304396 -120.044954)
			(xy 200.363818 -120.052777) (xy 200.421711 -120.06829) (xy 200.469049 -120.087898) (xy 266.86764 -120.087898)
			(xy 266.86764 -119.224298) (xy 266.86813 -119.194314) (xy 266.875958 -119.134858) (xy 266.891479 -119.076933)
			(xy 266.914428 -119.021529) (xy 266.944412 -118.969595) (xy 266.980918 -118.922019) (xy 267.023323 -118.879614)
			(xy 267.070899 -118.843108) (xy 267.122833 -118.813124) (xy 267.178237 -118.790175) (xy 267.236162 -118.774654)
			(xy 267.295618 -118.766826) (xy 267.355586 -118.766826) (xy 267.415042 -118.774654) (xy 267.472967 -118.790175)
			(xy 267.528371 -118.813124) (xy 267.580305 -118.843108) (xy 267.627881 -118.879614) (xy 267.670286 -118.922019)
			(xy 267.706792 -118.969595) (xy 267.736776 -119.021529) (xy 267.759725 -119.076933) (xy 267.775246 -119.134858)
			(xy 267.783074 -119.194314) (xy 267.783564 -119.224298) (xy 267.783564 -120.086374) (xy 285.8389 -120.086374)
			(xy 285.8389 -119.222774) (xy 285.83939 -119.19279) (xy 285.847218 -119.133334) (xy 285.862739 -119.075409)
			(xy 285.885688 -119.020005) (xy 285.915672 -118.968071) (xy 285.952178 -118.920495) (xy 285.994583 -118.87809)
			(xy 286.042159 -118.841584) (xy 286.094093 -118.8116) (xy 286.149497 -118.788651) (xy 286.207422 -118.77313)
			(xy 286.266878 -118.765302) (xy 286.326846 -118.765302) (xy 286.386302 -118.77313) (xy 286.444227 -118.788651)
			(xy 286.499631 -118.8116) (xy 286.551565 -118.841584) (xy 286.599141 -118.87809) (xy 286.641546 -118.920495)
			(xy 286.678052 -118.968071) (xy 286.708036 -119.020005) (xy 286.730985 -119.075409) (xy 286.746506 -119.133334)
			(xy 286.754334 -119.19279) (xy 286.754824 -119.222774) (xy 286.754824 -119.567198) (xy 298.799504 -119.567198)
			(xy 298.799504 -118.703598) (xy 298.799994 -118.67363) (xy 298.807817 -118.614208) (xy 298.82333 -118.556315)
			(xy 298.846266 -118.500942) (xy 298.876233 -118.449036) (xy 298.91272 -118.401486) (xy 298.9551 -118.359106)
			(xy 299.00265 -118.322619) (xy 299.054556 -118.292652) (xy 299.109929 -118.269716) (xy 299.167822 -118.254203)
			(xy 299.227244 -118.24638) (xy 299.28718 -118.24638) (xy 299.346602 -118.254203) (xy 299.404495 -118.269716)
			(xy 299.459868 -118.292652) (xy 299.511774 -118.322619) (xy 299.559324 -118.359106) (xy 299.601704 -118.401486)
			(xy 299.638191 -118.449036) (xy 299.668158 -118.500942) (xy 299.691094 -118.556315) (xy 299.706607 -118.614208)
			(xy 299.71443 -118.67363) (xy 299.71492 -118.703598) (xy 299.71492 -119.559324) (xy 313.274456 -119.559324)
			(xy 313.274456 -118.695724) (xy 313.274946 -118.665756) (xy 313.282769 -118.606334) (xy 313.298282 -118.548441)
			(xy 313.321218 -118.493068) (xy 313.351185 -118.441162) (xy 313.387672 -118.393612) (xy 313.430052 -118.351232)
			(xy 313.477602 -118.314745) (xy 313.529508 -118.284778) (xy 313.584881 -118.261842) (xy 313.642774 -118.246329)
			(xy 313.702196 -118.238506) (xy 313.762132 -118.238506) (xy 313.821554 -118.246329) (xy 313.879447 -118.261842)
			(xy 313.93482 -118.284778) (xy 313.986726 -118.314745) (xy 314.034276 -118.351232) (xy 314.076656 -118.393612)
			(xy 314.113143 -118.441162) (xy 314.14311 -118.493068) (xy 314.166046 -118.548441) (xy 314.181559 -118.606334)
			(xy 314.189382 -118.665756) (xy 314.189872 -118.695724) (xy 314.189872 -119.559324) (xy 314.189382 -119.589292)
			(xy 314.181559 -119.648714) (xy 314.166046 -119.706607) (xy 314.14311 -119.76198) (xy 314.113143 -119.813886)
			(xy 314.076656 -119.861436) (xy 314.034276 -119.903816) (xy 313.986726 -119.940303) (xy 313.93482 -119.97027)
			(xy 313.879447 -119.993206) (xy 313.821554 -120.008719) (xy 313.762132 -120.016542) (xy 313.702196 -120.016542)
			(xy 313.642774 -120.008719) (xy 313.584881 -119.993206) (xy 313.529508 -119.97027) (xy 313.477602 -119.940303)
			(xy 313.430052 -119.903816) (xy 313.387672 -119.861436) (xy 313.351185 -119.813886) (xy 313.321218 -119.76198)
			(xy 313.298282 -119.706607) (xy 313.282769 -119.648714) (xy 313.274946 -119.589292) (xy 313.274456 -119.559324)
			(xy 299.71492 -119.559324) (xy 299.71492 -119.567198) (xy 299.71443 -119.597166) (xy 299.706607 -119.656588)
			(xy 299.691094 -119.714481) (xy 299.668158 -119.769854) (xy 299.638191 -119.82176) (xy 299.601704 -119.86931)
			(xy 299.559324 -119.91169) (xy 299.511774 -119.948177) (xy 299.459868 -119.978144) (xy 299.404495 -120.00108)
			(xy 299.346602 -120.016593) (xy 299.28718 -120.024416) (xy 299.227244 -120.024416) (xy 299.167822 -120.016593)
			(xy 299.109929 -120.00108) (xy 299.054556 -119.978144) (xy 299.00265 -119.948177) (xy 298.9551 -119.91169)
			(xy 298.91272 -119.86931) (xy 298.876233 -119.82176) (xy 298.846266 -119.769854) (xy 298.82333 -119.714481)
			(xy 298.807817 -119.656588) (xy 298.799994 -119.597166) (xy 298.799504 -119.567198) (xy 286.754824 -119.567198)
			(xy 286.754824 -120.086374) (xy 286.754334 -120.116358) (xy 286.746506 -120.175814) (xy 286.730985 -120.233739)
			(xy 286.708036 -120.289143) (xy 286.678052 -120.341077) (xy 286.641546 -120.388653) (xy 286.599141 -120.431058)
			(xy 286.551565 -120.467564) (xy 286.499631 -120.497548) (xy 286.444227 -120.520497) (xy 286.386302 -120.536018)
			(xy 286.326846 -120.543846) (xy 286.266878 -120.543846) (xy 286.207422 -120.536018) (xy 286.149497 -120.520497)
			(xy 286.094093 -120.497548) (xy 286.042159 -120.467564) (xy 285.994583 -120.431058) (xy 285.952178 -120.388653)
			(xy 285.915672 -120.341077) (xy 285.885688 -120.289143) (xy 285.862739 -120.233739) (xy 285.847218 -120.175814)
			(xy 285.83939 -120.116358) (xy 285.8389 -120.086374) (xy 267.783564 -120.086374) (xy 267.783564 -120.087898)
			(xy 267.783074 -120.117882) (xy 267.775246 -120.177338) (xy 267.759725 -120.235263) (xy 267.736776 -120.290667)
			(xy 267.706792 -120.342601) (xy 267.670286 -120.390177) (xy 267.627881 -120.432582) (xy 267.580305 -120.469088)
			(xy 267.528371 -120.499072) (xy 267.472967 -120.522021) (xy 267.415042 -120.537542) (xy 267.355586 -120.54537)
			(xy 267.295618 -120.54537) (xy 267.236162 -120.537542) (xy 267.178237 -120.522021) (xy 267.122833 -120.499072)
			(xy 267.070899 -120.469088) (xy 267.023323 -120.432582) (xy 266.980918 -120.390177) (xy 266.944412 -120.342601)
			(xy 266.914428 -120.290667) (xy 266.891479 -120.235263) (xy 266.875958 -120.177338) (xy 266.86813 -120.117882)
			(xy 266.86764 -120.087898) (xy 200.469049 -120.087898) (xy 200.477084 -120.091226) (xy 200.52899 -120.121193)
			(xy 200.57654 -120.15768) (xy 200.61892 -120.20006) (xy 200.655407 -120.24761) (xy 200.685374 -120.299516)
			(xy 200.70831 -120.354889) (xy 200.723823 -120.412782) (xy 200.731646 -120.472204) (xy 200.732136 -120.502172)
			(xy 200.732136 -121.365772) (xy 200.731646 -121.39574) (xy 200.723823 -121.455162) (xy 200.70831 -121.513055)
			(xy 200.685374 -121.568428) (xy 200.655407 -121.620334) (xy 200.61892 -121.667884) (xy 200.57654 -121.710264)
			(xy 200.52899 -121.746751) (xy 200.477084 -121.776718) (xy 200.421711 -121.799654) (xy 200.363818 -121.815167)
			(xy 200.304396 -121.82299) (xy 200.24446 -121.82299) (xy 200.185038 -121.815167) (xy 200.127145 -121.799654)
			(xy 200.071772 -121.776718) (xy 200.019866 -121.746751) (xy 199.972316 -121.710264) (xy 199.929936 -121.667884)
			(xy 199.893449 -121.620334) (xy 199.863482 -121.568428) (xy 199.840546 -121.513055) (xy 199.825033 -121.455162)
			(xy 199.81721 -121.39574) (xy 199.81672 -121.365772) (xy 181.760876 -121.365772) (xy 181.760876 -121.367296)
			(xy 181.760386 -121.397264) (xy 181.752563 -121.456686) (xy 181.73705 -121.514579) (xy 181.714114 -121.569952)
			(xy 181.684147 -121.621858) (xy 181.64766 -121.669408) (xy 181.60528 -121.711788) (xy 181.55773 -121.748275)
			(xy 181.505824 -121.778242) (xy 181.450451 -121.801178) (xy 181.392558 -121.816691) (xy 181.333136 -121.824514)
			(xy 181.2732 -121.824514) (xy 181.213778 -121.816691) (xy 181.155885 -121.801178) (xy 181.100512 -121.778242)
			(xy 181.048606 -121.748275) (xy 181.001056 -121.711788) (xy 180.958676 -121.669408) (xy 180.922189 -121.621858)
			(xy 180.892222 -121.569952) (xy 180.869286 -121.514579) (xy 180.853773 -121.456686) (xy 180.84595 -121.397264)
			(xy 180.84546 -121.367296) (xy 168.80078 -121.367296) (xy 168.80078 -121.886472) (xy 168.80029 -121.916456)
			(xy 168.792462 -121.975912) (xy 168.776941 -122.033837) (xy 168.753992 -122.089241) (xy 168.724008 -122.141175)
			(xy 168.687502 -122.188751) (xy 168.645097 -122.231156) (xy 168.597521 -122.267662) (xy 168.545587 -122.297646)
			(xy 168.490183 -122.320595) (xy 168.432258 -122.336116) (xy 168.372802 -122.343944) (xy 168.312834 -122.343944)
			(xy 168.253378 -122.336116) (xy 168.195453 -122.320595) (xy 168.140049 -122.297646) (xy 168.088115 -122.267662)
			(xy 168.040539 -122.231156) (xy 167.998134 -122.188751) (xy 167.961628 -122.141175) (xy 167.931644 -122.089241)
			(xy 167.908695 -122.033837) (xy 167.893174 -121.975912) (xy 167.885346 -121.916456) (xy 167.884856 -121.886472)
			(xy 154.325828 -121.886472) (xy 154.325828 -121.894346) (xy 154.325338 -121.92433) (xy 154.31751 -121.983786)
			(xy 154.301989 -122.041711) (xy 154.27904 -122.097115) (xy 154.249056 -122.149049) (xy 154.21255 -122.196625)
			(xy 154.170145 -122.23903) (xy 154.122569 -122.275536) (xy 154.070635 -122.30552) (xy 154.015231 -122.328469)
			(xy 153.957306 -122.34399) (xy 153.89785 -122.351818) (xy 153.837882 -122.351818) (xy 153.778426 -122.34399)
			(xy 153.720501 -122.328469) (xy 153.665097 -122.30552) (xy 153.613163 -122.275536) (xy 153.565587 -122.23903)
			(xy 153.523182 -122.196625) (xy 153.486676 -122.149049) (xy 153.456692 -122.097115) (xy 153.433743 -122.041711)
			(xy 153.418222 -121.983786) (xy 153.410394 -121.92433) (xy 153.409904 -121.894346) (xy 81.752059 -121.894346)
			(xy 81.786925 -121.914476) (xy 81.834501 -121.950982) (xy 81.876906 -121.993387) (xy 81.913412 -122.040963)
			(xy 81.943396 -122.092897) (xy 81.966345 -122.148301) (xy 81.981866 -122.206226) (xy 81.989694 -122.265682)
			(xy 81.990184 -122.295666) (xy 81.990184 -123.159266) (xy 81.989694 -123.18925) (xy 81.981866 -123.248706)
			(xy 81.966345 -123.306631) (xy 81.943396 -123.362035) (xy 81.913412 -123.413969) (xy 81.876906 -123.461545)
			(xy 81.834501 -123.50395) (xy 81.786925 -123.540456) (xy 81.734991 -123.57044) (xy 81.679587 -123.593389)
			(xy 81.621662 -123.60891) (xy 81.562206 -123.616738) (xy 81.502238 -123.616738) (xy 81.442782 -123.60891)
			(xy 81.384857 -123.593389) (xy 81.329453 -123.57044) (xy 81.277519 -123.540456) (xy 81.229943 -123.50395)
			(xy 81.187538 -123.461545) (xy 81.151032 -123.413969) (xy 81.121048 -123.362035) (xy 81.098099 -123.306631)
			(xy 81.082578 -123.248706) (xy 81.07475 -123.18925) (xy 81.07426 -123.159266) (xy 67.515232 -123.159266)
			(xy 67.515232 -123.16714) (xy 67.514742 -123.197124) (xy 67.506914 -123.25658) (xy 67.491393 -123.314505)
			(xy 67.468444 -123.369909) (xy 67.43846 -123.421843) (xy 67.401954 -123.469419) (xy 67.359549 -123.511824)
			(xy 67.311973 -123.54833) (xy 67.260039 -123.578314) (xy 67.204635 -123.601263) (xy 67.14671 -123.616784)
			(xy 67.087254 -123.624612) (xy 67.027286 -123.624612) (xy 66.96783 -123.616784) (xy 66.909905 -123.601263)
			(xy 66.854501 -123.578314) (xy 66.802567 -123.54833) (xy 66.754991 -123.511824) (xy 66.712586 -123.469419)
			(xy 66.67608 -123.421843) (xy 66.646096 -123.369909) (xy 66.623147 -123.314505) (xy 66.607626 -123.25658)
			(xy 66.599798 -123.197124) (xy 66.599308 -123.16714) (xy 54.554628 -123.16714) (xy 54.554628 -123.686316)
			(xy 54.554138 -123.716284) (xy 54.546315 -123.775706) (xy 54.530802 -123.833599) (xy 54.507866 -123.888972)
			(xy 54.477899 -123.940878) (xy 54.441412 -123.988428) (xy 54.399032 -124.030808) (xy 54.351482 -124.067295)
			(xy 54.299576 -124.097262) (xy 54.244203 -124.120198) (xy 54.18631 -124.135711) (xy 54.126888 -124.143534)
			(xy 54.066952 -124.143534) (xy 54.00753 -124.135711) (xy 53.949637 -124.120198) (xy 53.894264 -124.097262)
			(xy 53.842358 -124.067295) (xy 53.794808 -124.030808) (xy 53.752428 -123.988428) (xy 53.715941 -123.940878)
			(xy 53.685974 -123.888972) (xy 53.663038 -123.833599) (xy 53.647525 -123.775706) (xy 53.639702 -123.716284)
			(xy 53.639212 -123.686316) (xy 35.583368 -123.686316) (xy 35.583368 -123.68784) (xy 35.582878 -123.717808)
			(xy 35.575055 -123.77723) (xy 35.559542 -123.835123) (xy 35.536606 -123.890496) (xy 35.506639 -123.942402)
			(xy 35.470152 -123.989952) (xy 35.427772 -124.032332) (xy 35.380222 -124.068819) (xy 35.328316 -124.098786)
			(xy 35.272943 -124.121722) (xy 35.21505 -124.137235) (xy 35.155628 -124.145058) (xy 35.095692 -124.145058)
			(xy 35.03627 -124.137235) (xy 34.978377 -124.121722) (xy 34.923004 -124.098786) (xy 34.871098 -124.068819)
			(xy 34.823548 -124.032332) (xy 34.781168 -123.989952) (xy 34.744681 -123.942402) (xy 34.714714 -123.890496)
			(xy 34.691778 -123.835123) (xy 34.676265 -123.77723) (xy 34.668442 -123.717808) (xy 34.667952 -123.68784)
			(xy 5.324094 -123.68784) (xy 5.324094 -125.494542) (xy 37.31006 -125.494542) (xy 37.31006 -124.630942)
			(xy 37.31055 -124.600974) (xy 37.318373 -124.541552) (xy 37.333886 -124.483659) (xy 37.356822 -124.428286)
			(xy 37.386789 -124.37638) (xy 37.423276 -124.32883) (xy 37.465656 -124.28645) (xy 37.513206 -124.249963)
			(xy 37.565112 -124.219996) (xy 37.620485 -124.19706) (xy 37.678378 -124.181547) (xy 37.7378 -124.173724)
			(xy 37.797736 -124.173724) (xy 37.857158 -124.181547) (xy 37.915051 -124.19706) (xy 37.970424 -124.219996)
			(xy 38.02233 -124.249963) (xy 38.06988 -124.28645) (xy 38.11226 -124.32883) (xy 38.148747 -124.37638)
			(xy 38.178714 -124.428286) (xy 38.20165 -124.483659) (xy 38.217163 -124.541552) (xy 38.224986 -124.600974)
			(xy 38.225476 -124.630942) (xy 38.225476 -125.486414) (xy 51.785012 -125.486414) (xy 51.785012 -124.622814)
			(xy 51.785502 -124.592846) (xy 51.793325 -124.533424) (xy 51.808838 -124.475531) (xy 51.831774 -124.420158)
			(xy 51.861741 -124.368252) (xy 51.898228 -124.320702) (xy 51.940608 -124.278322) (xy 51.988158 -124.241835)
			(xy 52.040064 -124.211868) (xy 52.095437 -124.188932) (xy 52.15333 -124.173419) (xy 52.212752 -124.165596)
			(xy 52.272688 -124.165596) (xy 52.33211 -124.173419) (xy 52.390003 -124.188932) (xy 52.445376 -124.211868)
			(xy 52.497282 -124.241835) (xy 52.544832 -124.278322) (xy 52.587212 -124.320702) (xy 52.623699 -124.368252)
			(xy 52.653666 -124.420158) (xy 52.676602 -124.475531) (xy 52.692115 -124.533424) (xy 52.699938 -124.592846)
			(xy 52.700428 -124.622814) (xy 52.700428 -124.967238) (xy 64.745108 -124.967238) (xy 64.745108 -124.103638)
			(xy 64.745598 -124.073654) (xy 64.753426 -124.014198) (xy 64.768947 -123.956273) (xy 64.791896 -123.900869)
			(xy 64.82188 -123.848935) (xy 64.858386 -123.801359) (xy 64.900791 -123.758954) (xy 64.948367 -123.722448)
			(xy 65.000301 -123.692464) (xy 65.055705 -123.669515) (xy 65.11363 -123.653994) (xy 65.173086 -123.646166)
			(xy 65.233054 -123.646166) (xy 65.29251 -123.653994) (xy 65.350435 -123.669515) (xy 65.405839 -123.692464)
			(xy 65.457773 -123.722448) (xy 65.505349 -123.758954) (xy 65.547754 -123.801359) (xy 65.58426 -123.848935)
			(xy 65.614244 -123.900869) (xy 65.637193 -123.956273) (xy 65.652714 -124.014198) (xy 65.660542 -124.073654)
			(xy 65.661032 -124.103638) (xy 65.661032 -124.965714) (xy 83.716368 -124.965714) (xy 83.716368 -124.102114)
			(xy 83.716858 -124.07213) (xy 83.724686 -124.012674) (xy 83.740207 -123.954749) (xy 83.763156 -123.899345)
			(xy 83.79314 -123.847411) (xy 83.829646 -123.799835) (xy 83.872051 -123.75743) (xy 83.919627 -123.720924)
			(xy 83.971561 -123.69094) (xy 84.026965 -123.667991) (xy 84.08489 -123.65247) (xy 84.144346 -123.644642)
			(xy 84.204314 -123.644642) (xy 84.26377 -123.65247) (xy 84.321695 -123.667991) (xy 84.369615 -123.68784)
			(xy 150.767796 -123.68784) (xy 150.767796 -122.82424) (xy 150.768286 -122.794256) (xy 150.776114 -122.7348)
			(xy 150.791635 -122.676875) (xy 150.814584 -122.621471) (xy 150.844568 -122.569537) (xy 150.881074 -122.521961)
			(xy 150.923479 -122.479556) (xy 150.971055 -122.44305) (xy 151.022989 -122.413066) (xy 151.078393 -122.390117)
			(xy 151.136318 -122.374596) (xy 151.195774 -122.366768) (xy 151.255742 -122.366768) (xy 151.315198 -122.374596)
			(xy 151.373123 -122.390117) (xy 151.428527 -122.413066) (xy 151.480461 -122.44305) (xy 151.528037 -122.479556)
			(xy 151.570442 -122.521961) (xy 151.606948 -122.569537) (xy 151.636932 -122.621471) (xy 151.659881 -122.676875)
			(xy 151.675402 -122.7348) (xy 151.68323 -122.794256) (xy 151.68372 -122.82424) (xy 151.68372 -123.686316)
			(xy 169.739056 -123.686316) (xy 169.739056 -122.822716) (xy 169.739546 -122.792732) (xy 169.747374 -122.733276)
			(xy 169.762895 -122.675351) (xy 169.785844 -122.619947) (xy 169.815828 -122.568013) (xy 169.852334 -122.520437)
			(xy 169.894739 -122.478032) (xy 169.942315 -122.441526) (xy 169.994249 -122.411542) (xy 170.049653 -122.388593)
			(xy 170.107578 -122.373072) (xy 170.167034 -122.365244) (xy 170.227002 -122.365244) (xy 170.286458 -122.373072)
			(xy 170.344383 -122.388593) (xy 170.399787 -122.411542) (xy 170.451721 -122.441526) (xy 170.499297 -122.478032)
			(xy 170.541702 -122.520437) (xy 170.578208 -122.568013) (xy 170.608192 -122.619947) (xy 170.631141 -122.675351)
			(xy 170.646662 -122.733276) (xy 170.65449 -122.792732) (xy 170.65498 -122.822716) (xy 170.65498 -123.16714)
			(xy 182.69966 -123.16714) (xy 182.69966 -122.30354) (xy 182.70015 -122.273572) (xy 182.707973 -122.21415)
			(xy 182.723486 -122.156257) (xy 182.746422 -122.100884) (xy 182.776389 -122.048978) (xy 182.812876 -122.001428)
			(xy 182.855256 -121.959048) (xy 182.902806 -121.922561) (xy 182.954712 -121.892594) (xy 183.010085 -121.869658)
			(xy 183.067978 -121.854145) (xy 183.1274 -121.846322) (xy 183.187336 -121.846322) (xy 183.246758 -121.854145)
			(xy 183.304651 -121.869658) (xy 183.360024 -121.892594) (xy 183.41193 -121.922561) (xy 183.45948 -121.959048)
			(xy 183.50186 -122.001428) (xy 183.538347 -122.048978) (xy 183.568314 -122.100884) (xy 183.59125 -122.156257)
			(xy 183.606763 -122.21415) (xy 183.614586 -122.273572) (xy 183.615076 -122.30354) (xy 183.615076 -123.159266)
			(xy 197.174612 -123.159266) (xy 197.174612 -122.295666) (xy 197.175102 -122.265698) (xy 197.182925 -122.206276)
			(xy 197.198438 -122.148383) (xy 197.221374 -122.09301) (xy 197.251341 -122.041104) (xy 197.287828 -121.993554)
			(xy 197.330208 -121.951174) (xy 197.377758 -121.914687) (xy 197.429664 -121.88472) (xy 197.485037 -121.861784)
			(xy 197.54293 -121.846271) (xy 197.602352 -121.838448) (xy 197.662288 -121.838448) (xy 197.72171 -121.846271)
			(xy 197.779603 -121.861784) (xy 197.834976 -121.88472) (xy 197.851649 -121.894346) (xy 269.509748 -121.894346)
			(xy 269.509748 -121.030746) (xy 269.510238 -121.000762) (xy 269.518066 -120.941306) (xy 269.533587 -120.883381)
			(xy 269.556536 -120.827977) (xy 269.58652 -120.776043) (xy 269.623026 -120.728467) (xy 269.665431 -120.686062)
			(xy 269.713007 -120.649556) (xy 269.764941 -120.619572) (xy 269.820345 -120.596623) (xy 269.87827 -120.581102)
			(xy 269.937726 -120.573274) (xy 269.997694 -120.573274) (xy 270.05715 -120.581102) (xy 270.115075 -120.596623)
			(xy 270.170479 -120.619572) (xy 270.222413 -120.649556) (xy 270.269989 -120.686062) (xy 270.312394 -120.728467)
			(xy 270.3489 -120.776043) (xy 270.378884 -120.827977) (xy 270.401833 -120.883381) (xy 270.417354 -120.941306)
			(xy 270.425182 -121.000762) (xy 270.425672 -121.030746) (xy 270.425672 -121.886472) (xy 283.9847 -121.886472)
			(xy 283.9847 -121.022872) (xy 283.98519 -120.992888) (xy 283.993018 -120.933432) (xy 284.008539 -120.875507)
			(xy 284.031488 -120.820103) (xy 284.061472 -120.768169) (xy 284.097978 -120.720593) (xy 284.140383 -120.678188)
			(xy 284.187959 -120.641682) (xy 284.239893 -120.611698) (xy 284.295297 -120.588749) (xy 284.353222 -120.573228)
			(xy 284.412678 -120.5654) (xy 284.472646 -120.5654) (xy 284.532102 -120.573228) (xy 284.590027 -120.588749)
			(xy 284.645431 -120.611698) (xy 284.697365 -120.641682) (xy 284.744941 -120.678188) (xy 284.787346 -120.720593)
			(xy 284.823852 -120.768169) (xy 284.853836 -120.820103) (xy 284.876785 -120.875507) (xy 284.892306 -120.933432)
			(xy 284.900134 -120.992888) (xy 284.900624 -121.022872) (xy 284.900624 -121.367296) (xy 296.945304 -121.367296)
			(xy 296.945304 -120.503696) (xy 296.945794 -120.473728) (xy 296.953617 -120.414306) (xy 296.96913 -120.356413)
			(xy 296.992066 -120.30104) (xy 297.022033 -120.249134) (xy 297.05852 -120.201584) (xy 297.1009 -120.159204)
			(xy 297.14845 -120.122717) (xy 297.200356 -120.09275) (xy 297.255729 -120.069814) (xy 297.313622 -120.054301)
			(xy 297.373044 -120.046478) (xy 297.43298 -120.046478) (xy 297.492402 -120.054301) (xy 297.550295 -120.069814)
			(xy 297.605668 -120.09275) (xy 297.657574 -120.122717) (xy 297.705124 -120.159204) (xy 297.747504 -120.201584)
			(xy 297.783991 -120.249134) (xy 297.813958 -120.30104) (xy 297.836894 -120.356413) (xy 297.852407 -120.414306)
			(xy 297.86023 -120.473728) (xy 297.86072 -120.503696) (xy 297.86072 -121.365772) (xy 315.916564 -121.365772)
			(xy 315.916564 -120.502172) (xy 315.917054 -120.472204) (xy 315.924877 -120.412782) (xy 315.94039 -120.354889)
			(xy 315.963326 -120.299516) (xy 315.993293 -120.24761) (xy 316.02978 -120.20006) (xy 316.07216 -120.15768)
			(xy 316.11971 -120.121193) (xy 316.171616 -120.091226) (xy 316.226989 -120.06829) (xy 316.284882 -120.052777)
			(xy 316.344304 -120.044954) (xy 316.40424 -120.044954) (xy 316.463662 -120.052777) (xy 316.521555 -120.06829)
			(xy 316.568893 -120.087898) (xy 382.967992 -120.087898) (xy 382.967992 -119.224298) (xy 382.968482 -119.19433)
			(xy 382.976305 -119.134908) (xy 382.991818 -119.077015) (xy 383.014754 -119.021642) (xy 383.044721 -118.969736)
			(xy 383.081208 -118.922186) (xy 383.123588 -118.879806) (xy 383.171138 -118.843319) (xy 383.223044 -118.813352)
			(xy 383.278417 -118.790416) (xy 383.33631 -118.774903) (xy 383.395732 -118.76708) (xy 383.455668 -118.76708)
			(xy 383.51509 -118.774903) (xy 383.572983 -118.790416) (xy 383.628356 -118.813352) (xy 383.680262 -118.843319)
			(xy 383.727812 -118.879806) (xy 383.770192 -118.922186) (xy 383.806679 -118.969736) (xy 383.836646 -119.021642)
			(xy 383.859582 -119.077015) (xy 383.875095 -119.134908) (xy 383.882918 -119.19433) (xy 383.883408 -119.224298)
			(xy 383.883408 -120.086374) (xy 401.939252 -120.086374) (xy 401.939252 -119.222774) (xy 401.939742 -119.192806)
			(xy 401.947565 -119.133384) (xy 401.963078 -119.075491) (xy 401.986014 -119.020118) (xy 402.015981 -118.968212)
			(xy 402.052468 -118.920662) (xy 402.094848 -118.878282) (xy 402.142398 -118.841795) (xy 402.194304 -118.811828)
			(xy 402.249677 -118.788892) (xy 402.30757 -118.773379) (xy 402.366992 -118.765556) (xy 402.426928 -118.765556)
			(xy 402.48635 -118.773379) (xy 402.544243 -118.788892) (xy 402.599616 -118.811828) (xy 402.651522 -118.841795)
			(xy 402.699072 -118.878282) (xy 402.741452 -118.920662) (xy 402.777939 -118.968212) (xy 402.807906 -119.020118)
			(xy 402.830842 -119.075491) (xy 402.846355 -119.133384) (xy 402.854178 -119.192806) (xy 402.854668 -119.222774)
			(xy 402.854668 -119.567198) (xy 414.899348 -119.567198) (xy 414.899348 -118.703598) (xy 414.899838 -118.673614)
			(xy 414.907666 -118.614158) (xy 414.923187 -118.556233) (xy 414.946136 -118.500829) (xy 414.97612 -118.448895)
			(xy 415.012626 -118.401319) (xy 415.055031 -118.358914) (xy 415.102607 -118.322408) (xy 415.154541 -118.292424)
			(xy 415.209945 -118.269475) (xy 415.26787 -118.253954) (xy 415.327326 -118.246126) (xy 415.387294 -118.246126)
			(xy 415.44675 -118.253954) (xy 415.504675 -118.269475) (xy 415.560079 -118.292424) (xy 415.612013 -118.322408)
			(xy 415.659589 -118.358914) (xy 415.701994 -118.401319) (xy 415.7385 -118.448895) (xy 415.768484 -118.500829)
			(xy 415.791433 -118.556233) (xy 415.806954 -118.614158) (xy 415.814782 -118.673614) (xy 415.815272 -118.703598)
			(xy 415.815272 -119.559324) (xy 429.3743 -119.559324) (xy 429.3743 -118.695724) (xy 429.37479 -118.66574)
			(xy 429.382618 -118.606284) (xy 429.398139 -118.548359) (xy 429.421088 -118.492955) (xy 429.451072 -118.441021)
			(xy 429.487578 -118.393445) (xy 429.529983 -118.35104) (xy 429.577559 -118.314534) (xy 429.629493 -118.28455)
			(xy 429.684897 -118.261601) (xy 429.742822 -118.24608) (xy 429.802278 -118.238252) (xy 429.862246 -118.238252)
			(xy 429.921702 -118.24608) (xy 429.979627 -118.261601) (xy 430.035031 -118.28455) (xy 430.086965 -118.314534)
			(xy 430.134541 -118.35104) (xy 430.176946 -118.393445) (xy 430.213452 -118.441021) (xy 430.243436 -118.492955)
			(xy 430.266385 -118.548359) (xy 430.281906 -118.606284) (xy 430.289734 -118.66574) (xy 430.290224 -118.695724)
			(xy 430.290224 -119.559324) (xy 430.289734 -119.589308) (xy 430.281906 -119.648764) (xy 430.266385 -119.706689)
			(xy 430.243436 -119.762093) (xy 430.213452 -119.814027) (xy 430.176946 -119.861603) (xy 430.134541 -119.904008)
			(xy 430.086965 -119.940514) (xy 430.035031 -119.970498) (xy 429.979627 -119.993447) (xy 429.921702 -120.008968)
			(xy 429.862246 -120.016796) (xy 429.802278 -120.016796) (xy 429.742822 -120.008968) (xy 429.684897 -119.993447)
			(xy 429.629493 -119.970498) (xy 429.577559 -119.940514) (xy 429.529983 -119.904008) (xy 429.487578 -119.861603)
			(xy 429.451072 -119.814027) (xy 429.421088 -119.762093) (xy 429.398139 -119.706689) (xy 429.382618 -119.648764)
			(xy 429.37479 -119.589308) (xy 429.3743 -119.559324) (xy 415.815272 -119.559324) (xy 415.815272 -119.567198)
			(xy 415.814782 -119.597182) (xy 415.806954 -119.656638) (xy 415.791433 -119.714563) (xy 415.768484 -119.769967)
			(xy 415.7385 -119.821901) (xy 415.701994 -119.869477) (xy 415.659589 -119.911882) (xy 415.612013 -119.948388)
			(xy 415.560079 -119.978372) (xy 415.504675 -120.001321) (xy 415.44675 -120.016842) (xy 415.387294 -120.02467)
			(xy 415.327326 -120.02467) (xy 415.26787 -120.016842) (xy 415.209945 -120.001321) (xy 415.154541 -119.978372)
			(xy 415.102607 -119.948388) (xy 415.055031 -119.911882) (xy 415.012626 -119.869477) (xy 414.97612 -119.821901)
			(xy 414.946136 -119.769967) (xy 414.923187 -119.714563) (xy 414.907666 -119.656638) (xy 414.899838 -119.597182)
			(xy 414.899348 -119.567198) (xy 402.854668 -119.567198) (xy 402.854668 -120.086374) (xy 402.854178 -120.116342)
			(xy 402.846355 -120.175764) (xy 402.830842 -120.233657) (xy 402.807906 -120.28903) (xy 402.777939 -120.340936)
			(xy 402.741452 -120.388486) (xy 402.699072 -120.430866) (xy 402.651522 -120.467353) (xy 402.599616 -120.49732)
			(xy 402.544243 -120.520256) (xy 402.48635 -120.535769) (xy 402.426928 -120.543592) (xy 402.366992 -120.543592)
			(xy 402.30757 -120.535769) (xy 402.249677 -120.520256) (xy 402.194304 -120.49732) (xy 402.142398 -120.467353)
			(xy 402.094848 -120.430866) (xy 402.052468 -120.388486) (xy 402.015981 -120.340936) (xy 401.986014 -120.28903)
			(xy 401.963078 -120.233657) (xy 401.947565 -120.175764) (xy 401.939742 -120.116342) (xy 401.939252 -120.086374)
			(xy 383.883408 -120.086374) (xy 383.883408 -120.087898) (xy 383.882918 -120.117866) (xy 383.875095 -120.177288)
			(xy 383.859582 -120.235181) (xy 383.836646 -120.290554) (xy 383.806679 -120.34246) (xy 383.770192 -120.39001)
			(xy 383.727812 -120.43239) (xy 383.680262 -120.468877) (xy 383.628356 -120.498844) (xy 383.572983 -120.52178)
			(xy 383.51509 -120.537293) (xy 383.455668 -120.545116) (xy 383.395732 -120.545116) (xy 383.33631 -120.537293)
			(xy 383.278417 -120.52178) (xy 383.223044 -120.498844) (xy 383.171138 -120.468877) (xy 383.123588 -120.43239)
			(xy 383.081208 -120.39001) (xy 383.044721 -120.34246) (xy 383.014754 -120.290554) (xy 382.991818 -120.235181)
			(xy 382.976305 -120.177288) (xy 382.968482 -120.117866) (xy 382.967992 -120.087898) (xy 316.568893 -120.087898)
			(xy 316.576928 -120.091226) (xy 316.628834 -120.121193) (xy 316.676384 -120.15768) (xy 316.718764 -120.20006)
			(xy 316.755251 -120.24761) (xy 316.785218 -120.299516) (xy 316.808154 -120.354889) (xy 316.823667 -120.412782)
			(xy 316.83149 -120.472204) (xy 316.83198 -120.502172) (xy 316.83198 -121.365772) (xy 316.83149 -121.39574)
			(xy 316.823667 -121.455162) (xy 316.808154 -121.513055) (xy 316.785218 -121.568428) (xy 316.755251 -121.620334)
			(xy 316.718764 -121.667884) (xy 316.676384 -121.710264) (xy 316.628834 -121.746751) (xy 316.576928 -121.776718)
			(xy 316.521555 -121.799654) (xy 316.463662 -121.815167) (xy 316.40424 -121.82299) (xy 316.344304 -121.82299)
			(xy 316.284882 -121.815167) (xy 316.226989 -121.799654) (xy 316.171616 -121.776718) (xy 316.11971 -121.746751)
			(xy 316.07216 -121.710264) (xy 316.02978 -121.667884) (xy 315.993293 -121.620334) (xy 315.963326 -121.568428)
			(xy 315.94039 -121.513055) (xy 315.924877 -121.455162) (xy 315.917054 -121.39574) (xy 315.916564 -121.365772)
			(xy 297.86072 -121.365772) (xy 297.86072 -121.367296) (xy 297.86023 -121.397264) (xy 297.852407 -121.456686)
			(xy 297.836894 -121.514579) (xy 297.813958 -121.569952) (xy 297.783991 -121.621858) (xy 297.747504 -121.669408)
			(xy 297.705124 -121.711788) (xy 297.657574 -121.748275) (xy 297.605668 -121.778242) (xy 297.550295 -121.801178)
			(xy 297.492402 -121.816691) (xy 297.43298 -121.824514) (xy 297.373044 -121.824514) (xy 297.313622 -121.816691)
			(xy 297.255729 -121.801178) (xy 297.200356 -121.778242) (xy 297.14845 -121.748275) (xy 297.1009 -121.711788)
			(xy 297.05852 -121.669408) (xy 297.022033 -121.621858) (xy 296.992066 -121.569952) (xy 296.96913 -121.514579)
			(xy 296.953617 -121.456686) (xy 296.945794 -121.397264) (xy 296.945304 -121.367296) (xy 284.900624 -121.367296)
			(xy 284.900624 -121.886472) (xy 284.900134 -121.916456) (xy 284.892306 -121.975912) (xy 284.876785 -122.033837)
			(xy 284.853836 -122.089241) (xy 284.823852 -122.141175) (xy 284.787346 -122.188751) (xy 284.744941 -122.231156)
			(xy 284.697365 -122.267662) (xy 284.645431 -122.297646) (xy 284.590027 -122.320595) (xy 284.532102 -122.336116)
			(xy 284.472646 -122.343944) (xy 284.412678 -122.343944) (xy 284.353222 -122.336116) (xy 284.295297 -122.320595)
			(xy 284.239893 -122.297646) (xy 284.187959 -122.267662) (xy 284.140383 -122.231156) (xy 284.097978 -122.188751)
			(xy 284.061472 -122.141175) (xy 284.031488 -122.089241) (xy 284.008539 -122.033837) (xy 283.993018 -121.975912)
			(xy 283.98519 -121.916456) (xy 283.9847 -121.886472) (xy 270.425672 -121.886472) (xy 270.425672 -121.894346)
			(xy 270.425182 -121.92433) (xy 270.417354 -121.983786) (xy 270.401833 -122.041711) (xy 270.378884 -122.097115)
			(xy 270.3489 -122.149049) (xy 270.312394 -122.196625) (xy 270.269989 -122.23903) (xy 270.222413 -122.275536)
			(xy 270.170479 -122.30552) (xy 270.115075 -122.328469) (xy 270.05715 -122.34399) (xy 269.997694 -122.351818)
			(xy 269.937726 -122.351818) (xy 269.87827 -122.34399) (xy 269.820345 -122.328469) (xy 269.764941 -122.30552)
			(xy 269.713007 -122.275536) (xy 269.665431 -122.23903) (xy 269.623026 -122.196625) (xy 269.58652 -122.149049)
			(xy 269.556536 -122.097115) (xy 269.533587 -122.041711) (xy 269.518066 -121.983786) (xy 269.510238 -121.92433)
			(xy 269.509748 -121.894346) (xy 197.851649 -121.894346) (xy 197.886882 -121.914687) (xy 197.934432 -121.951174)
			(xy 197.976812 -121.993554) (xy 198.013299 -122.041104) (xy 198.043266 -122.09301) (xy 198.066202 -122.148383)
			(xy 198.081715 -122.206276) (xy 198.089538 -122.265698) (xy 198.090028 -122.295666) (xy 198.090028 -123.159266)
			(xy 198.089538 -123.189234) (xy 198.081715 -123.248656) (xy 198.066202 -123.306549) (xy 198.043266 -123.361922)
			(xy 198.013299 -123.413828) (xy 197.976812 -123.461378) (xy 197.934432 -123.503758) (xy 197.886882 -123.540245)
			(xy 197.834976 -123.570212) (xy 197.779603 -123.593148) (xy 197.72171 -123.608661) (xy 197.662288 -123.616484)
			(xy 197.602352 -123.616484) (xy 197.54293 -123.608661) (xy 197.485037 -123.593148) (xy 197.429664 -123.570212)
			(xy 197.377758 -123.540245) (xy 197.330208 -123.503758) (xy 197.287828 -123.461378) (xy 197.251341 -123.413828)
			(xy 197.221374 -123.361922) (xy 197.198438 -123.306549) (xy 197.182925 -123.248656) (xy 197.175102 -123.189234)
			(xy 197.174612 -123.159266) (xy 183.615076 -123.159266) (xy 183.615076 -123.16714) (xy 183.614586 -123.197108)
			(xy 183.606763 -123.25653) (xy 183.59125 -123.314423) (xy 183.568314 -123.369796) (xy 183.538347 -123.421702)
			(xy 183.50186 -123.469252) (xy 183.45948 -123.511632) (xy 183.41193 -123.548119) (xy 183.360024 -123.578086)
			(xy 183.304651 -123.601022) (xy 183.246758 -123.616535) (xy 183.187336 -123.624358) (xy 183.1274 -123.624358)
			(xy 183.067978 -123.616535) (xy 183.010085 -123.601022) (xy 182.954712 -123.578086) (xy 182.902806 -123.548119)
			(xy 182.855256 -123.511632) (xy 182.812876 -123.469252) (xy 182.776389 -123.421702) (xy 182.746422 -123.369796)
			(xy 182.723486 -123.314423) (xy 182.707973 -123.25653) (xy 182.70015 -123.197108) (xy 182.69966 -123.16714)
			(xy 170.65498 -123.16714) (xy 170.65498 -123.686316) (xy 170.65449 -123.7163) (xy 170.646662 -123.775756)
			(xy 170.631141 -123.833681) (xy 170.608192 -123.889085) (xy 170.578208 -123.941019) (xy 170.541702 -123.988595)
			(xy 170.499297 -124.031) (xy 170.451721 -124.067506) (xy 170.399787 -124.09749) (xy 170.344383 -124.120439)
			(xy 170.286458 -124.13596) (xy 170.227002 -124.143788) (xy 170.167034 -124.143788) (xy 170.107578 -124.13596)
			(xy 170.049653 -124.120439) (xy 169.994249 -124.09749) (xy 169.942315 -124.067506) (xy 169.894739 -124.031)
			(xy 169.852334 -123.988595) (xy 169.815828 -123.941019) (xy 169.785844 -123.889085) (xy 169.762895 -123.833681)
			(xy 169.747374 -123.775756) (xy 169.739546 -123.7163) (xy 169.739056 -123.686316) (xy 151.68372 -123.686316)
			(xy 151.68372 -123.68784) (xy 151.68323 -123.717824) (xy 151.675402 -123.77728) (xy 151.659881 -123.835205)
			(xy 151.636932 -123.890609) (xy 151.606948 -123.942543) (xy 151.570442 -123.990119) (xy 151.528037 -124.032524)
			(xy 151.480461 -124.06903) (xy 151.428527 -124.099014) (xy 151.373123 -124.121963) (xy 151.315198 -124.137484)
			(xy 151.255742 -124.145312) (xy 151.195774 -124.145312) (xy 151.136318 -124.137484) (xy 151.078393 -124.121963)
			(xy 151.022989 -124.099014) (xy 150.971055 -124.06903) (xy 150.923479 -124.032524) (xy 150.881074 -123.990119)
			(xy 150.844568 -123.942543) (xy 150.814584 -123.890609) (xy 150.791635 -123.835205) (xy 150.776114 -123.77728)
			(xy 150.768286 -123.717824) (xy 150.767796 -123.68784) (xy 84.369615 -123.68784) (xy 84.377099 -123.69094)
			(xy 84.429033 -123.720924) (xy 84.476609 -123.75743) (xy 84.519014 -123.799835) (xy 84.55552 -123.847411)
			(xy 84.585504 -123.899345) (xy 84.608453 -123.954749) (xy 84.623974 -124.012674) (xy 84.631802 -124.07213)
			(xy 84.632292 -124.102114) (xy 84.632292 -124.965714) (xy 84.631802 -124.995698) (xy 84.623974 -125.055154)
			(xy 84.608453 -125.113079) (xy 84.585504 -125.168483) (xy 84.55552 -125.220417) (xy 84.519014 -125.267993)
			(xy 84.476609 -125.310398) (xy 84.429033 -125.346904) (xy 84.377099 -125.376888) (xy 84.321695 -125.399837)
			(xy 84.26377 -125.415358) (xy 84.204314 -125.423186) (xy 84.144346 -125.423186) (xy 84.08489 -125.415358)
			(xy 84.026965 -125.399837) (xy 83.971561 -125.376888) (xy 83.919627 -125.346904) (xy 83.872051 -125.310398)
			(xy 83.829646 -125.267993) (xy 83.79314 -125.220417) (xy 83.763156 -125.168483) (xy 83.740207 -125.113079)
			(xy 83.724686 -125.055154) (xy 83.716858 -124.995698) (xy 83.716368 -124.965714) (xy 65.661032 -124.965714)
			(xy 65.661032 -124.967238) (xy 65.660542 -124.997222) (xy 65.652714 -125.056678) (xy 65.637193 -125.114603)
			(xy 65.614244 -125.170007) (xy 65.58426 -125.221941) (xy 65.547754 -125.269517) (xy 65.505349 -125.311922)
			(xy 65.457773 -125.348428) (xy 65.405839 -125.378412) (xy 65.350435 -125.401361) (xy 65.29251 -125.416882)
			(xy 65.233054 -125.42471) (xy 65.173086 -125.42471) (xy 65.11363 -125.416882) (xy 65.055705 -125.401361)
			(xy 65.000301 -125.378412) (xy 64.948367 -125.348428) (xy 64.900791 -125.311922) (xy 64.858386 -125.269517)
			(xy 64.82188 -125.221941) (xy 64.791896 -125.170007) (xy 64.768947 -125.114603) (xy 64.753426 -125.056678)
			(xy 64.745598 -124.997222) (xy 64.745108 -124.967238) (xy 52.700428 -124.967238) (xy 52.700428 -125.486414)
			(xy 52.700295 -125.494542) (xy 153.409904 -125.494542) (xy 153.409904 -124.630942) (xy 153.410394 -124.600958)
			(xy 153.418222 -124.541502) (xy 153.433743 -124.483577) (xy 153.456692 -124.428173) (xy 153.486676 -124.376239)
			(xy 153.523182 -124.328663) (xy 153.565587 -124.286258) (xy 153.613163 -124.249752) (xy 153.665097 -124.219768)
			(xy 153.720501 -124.196819) (xy 153.778426 -124.181298) (xy 153.837882 -124.17347) (xy 153.89785 -124.17347)
			(xy 153.957306 -124.181298) (xy 154.015231 -124.196819) (xy 154.070635 -124.219768) (xy 154.122569 -124.249752)
			(xy 154.170145 -124.286258) (xy 154.21255 -124.328663) (xy 154.249056 -124.376239) (xy 154.27904 -124.428173)
			(xy 154.301989 -124.483577) (xy 154.31751 -124.541502) (xy 154.325338 -124.600958) (xy 154.325828 -124.630942)
			(xy 154.325828 -125.486414) (xy 167.884856 -125.486414) (xy 167.884856 -124.622814) (xy 167.885346 -124.59283)
			(xy 167.893174 -124.533374) (xy 167.908695 -124.475449) (xy 167.931644 -124.420045) (xy 167.961628 -124.368111)
			(xy 167.998134 -124.320535) (xy 168.040539 -124.27813) (xy 168.088115 -124.241624) (xy 168.140049 -124.21164)
			(xy 168.195453 -124.188691) (xy 168.253378 -124.17317) (xy 168.312834 -124.165342) (xy 168.372802 -124.165342)
			(xy 168.432258 -124.17317) (xy 168.490183 -124.188691) (xy 168.545587 -124.21164) (xy 168.597521 -124.241624)
			(xy 168.645097 -124.27813) (xy 168.687502 -124.320535) (xy 168.724008 -124.368111) (xy 168.753992 -124.420045)
			(xy 168.776941 -124.475449) (xy 168.792462 -124.533374) (xy 168.80029 -124.59283) (xy 168.80078 -124.622814)
			(xy 168.80078 -124.967238) (xy 180.84546 -124.967238) (xy 180.84546 -124.103638) (xy 180.84595 -124.07367)
			(xy 180.853773 -124.014248) (xy 180.869286 -123.956355) (xy 180.892222 -123.900982) (xy 180.922189 -123.849076)
			(xy 180.958676 -123.801526) (xy 181.001056 -123.759146) (xy 181.048606 -123.722659) (xy 181.100512 -123.692692)
			(xy 181.155885 -123.669756) (xy 181.213778 -123.654243) (xy 181.2732 -123.64642) (xy 181.333136 -123.64642)
			(xy 181.392558 -123.654243) (xy 181.450451 -123.669756) (xy 181.505824 -123.692692) (xy 181.55773 -123.722659)
			(xy 181.60528 -123.759146) (xy 181.64766 -123.801526) (xy 181.684147 -123.849076) (xy 181.714114 -123.900982)
			(xy 181.73705 -123.956355) (xy 181.752563 -124.014248) (xy 181.760386 -124.07367) (xy 181.760876 -124.103638)
			(xy 181.760876 -124.965714) (xy 199.81672 -124.965714) (xy 199.81672 -124.102114) (xy 199.81721 -124.072146)
			(xy 199.825033 -124.012724) (xy 199.840546 -123.954831) (xy 199.863482 -123.899458) (xy 199.893449 -123.847552)
			(xy 199.929936 -123.800002) (xy 199.972316 -123.757622) (xy 200.019866 -123.721135) (xy 200.071772 -123.691168)
			(xy 200.127145 -123.668232) (xy 200.185038 -123.652719) (xy 200.24446 -123.644896) (xy 200.304396 -123.644896)
			(xy 200.363818 -123.652719) (xy 200.421711 -123.668232) (xy 200.469049 -123.68784) (xy 266.86764 -123.68784)
			(xy 266.86764 -122.82424) (xy 266.86813 -122.794256) (xy 266.875958 -122.7348) (xy 266.891479 -122.676875)
			(xy 266.914428 -122.621471) (xy 266.944412 -122.569537) (xy 266.980918 -122.521961) (xy 267.023323 -122.479556)
			(xy 267.070899 -122.44305) (xy 267.122833 -122.413066) (xy 267.178237 -122.390117) (xy 267.236162 -122.374596)
			(xy 267.295618 -122.366768) (xy 267.355586 -122.366768) (xy 267.415042 -122.374596) (xy 267.472967 -122.390117)
			(xy 267.528371 -122.413066) (xy 267.580305 -122.44305) (xy 267.627881 -122.479556) (xy 267.670286 -122.521961)
			(xy 267.706792 -122.569537) (xy 267.736776 -122.621471) (xy 267.759725 -122.676875) (xy 267.775246 -122.7348)
			(xy 267.783074 -122.794256) (xy 267.783564 -122.82424) (xy 267.783564 -123.686316) (xy 285.8389 -123.686316)
			(xy 285.8389 -122.822716) (xy 285.83939 -122.792732) (xy 285.847218 -122.733276) (xy 285.862739 -122.675351)
			(xy 285.885688 -122.619947) (xy 285.915672 -122.568013) (xy 285.952178 -122.520437) (xy 285.994583 -122.478032)
			(xy 286.042159 -122.441526) (xy 286.094093 -122.411542) (xy 286.149497 -122.388593) (xy 286.207422 -122.373072)
			(xy 286.266878 -122.365244) (xy 286.326846 -122.365244) (xy 286.386302 -122.373072) (xy 286.444227 -122.388593)
			(xy 286.499631 -122.411542) (xy 286.551565 -122.441526) (xy 286.599141 -122.478032) (xy 286.641546 -122.520437)
			(xy 286.678052 -122.568013) (xy 286.708036 -122.619947) (xy 286.730985 -122.675351) (xy 286.746506 -122.733276)
			(xy 286.754334 -122.792732) (xy 286.754824 -122.822716) (xy 286.754824 -123.16714) (xy 298.799504 -123.16714)
			(xy 298.799504 -122.30354) (xy 298.799994 -122.273572) (xy 298.807817 -122.21415) (xy 298.82333 -122.156257)
			(xy 298.846266 -122.100884) (xy 298.876233 -122.048978) (xy 298.91272 -122.001428) (xy 298.9551 -121.959048)
			(xy 299.00265 -121.922561) (xy 299.054556 -121.892594) (xy 299.109929 -121.869658) (xy 299.167822 -121.854145)
			(xy 299.227244 -121.846322) (xy 299.28718 -121.846322) (xy 299.346602 -121.854145) (xy 299.404495 -121.869658)
			(xy 299.459868 -121.892594) (xy 299.511774 -121.922561) (xy 299.559324 -121.959048) (xy 299.601704 -122.001428)
			(xy 299.638191 -122.048978) (xy 299.668158 -122.100884) (xy 299.691094 -122.156257) (xy 299.706607 -122.21415)
			(xy 299.71443 -122.273572) (xy 299.71492 -122.30354) (xy 299.71492 -123.159266) (xy 313.274456 -123.159266)
			(xy 313.274456 -122.295666) (xy 313.274946 -122.265698) (xy 313.282769 -122.206276) (xy 313.298282 -122.148383)
			(xy 313.321218 -122.09301) (xy 313.351185 -122.041104) (xy 313.387672 -121.993554) (xy 313.430052 -121.951174)
			(xy 313.477602 -121.914687) (xy 313.529508 -121.88472) (xy 313.584881 -121.861784) (xy 313.642774 -121.846271)
			(xy 313.702196 -121.838448) (xy 313.762132 -121.838448) (xy 313.821554 -121.846271) (xy 313.879447 -121.861784)
			(xy 313.93482 -121.88472) (xy 313.951493 -121.894346) (xy 385.6101 -121.894346) (xy 385.6101 -121.030746)
			(xy 385.61059 -121.000778) (xy 385.618413 -120.941356) (xy 385.633926 -120.883463) (xy 385.656862 -120.82809)
			(xy 385.686829 -120.776184) (xy 385.723316 -120.728634) (xy 385.765696 -120.686254) (xy 385.813246 -120.649767)
			(xy 385.865152 -120.6198) (xy 385.920525 -120.596864) (xy 385.978418 -120.581351) (xy 386.03784 -120.573528)
			(xy 386.097776 -120.573528) (xy 386.157198 -120.581351) (xy 386.215091 -120.596864) (xy 386.270464 -120.6198)
			(xy 386.32237 -120.649767) (xy 386.36992 -120.686254) (xy 386.4123 -120.728634) (xy 386.448787 -120.776184)
			(xy 386.478754 -120.82809) (xy 386.50169 -120.883463) (xy 386.517203 -120.941356) (xy 386.525026 -121.000778)
			(xy 386.525516 -121.030746) (xy 386.525516 -121.886472) (xy 400.085052 -121.886472) (xy 400.085052 -121.022872)
			(xy 400.085542 -120.992904) (xy 400.093365 -120.933482) (xy 400.108878 -120.875589) (xy 400.131814 -120.820216)
			(xy 400.161781 -120.76831) (xy 400.198268 -120.72076) (xy 400.240648 -120.67838) (xy 400.288198 -120.641893)
			(xy 400.340104 -120.611926) (xy 400.395477 -120.58899) (xy 400.45337 -120.573477) (xy 400.512792 -120.565654)
			(xy 400.572728 -120.565654) (xy 400.63215 -120.573477) (xy 400.690043 -120.58899) (xy 400.745416 -120.611926)
			(xy 400.797322 -120.641893) (xy 400.844872 -120.67838) (xy 400.887252 -120.72076) (xy 400.923739 -120.76831)
			(xy 400.953706 -120.820216) (xy 400.976642 -120.875589) (xy 400.992155 -120.933482) (xy 400.999978 -120.992904)
			(xy 401.000468 -121.022872) (xy 401.000468 -121.367296) (xy 413.045148 -121.367296) (xy 413.045148 -120.503696)
			(xy 413.045638 -120.473712) (xy 413.053466 -120.414256) (xy 413.068987 -120.356331) (xy 413.091936 -120.300927)
			(xy 413.12192 -120.248993) (xy 413.158426 -120.201417) (xy 413.200831 -120.159012) (xy 413.248407 -120.122506)
			(xy 413.300341 -120.092522) (xy 413.355745 -120.069573) (xy 413.41367 -120.054052) (xy 413.473126 -120.046224)
			(xy 413.533094 -120.046224) (xy 413.59255 -120.054052) (xy 413.650475 -120.069573) (xy 413.705879 -120.092522)
			(xy 413.757813 -120.122506) (xy 413.805389 -120.159012) (xy 413.847794 -120.201417) (xy 413.8843 -120.248993)
			(xy 413.914284 -120.300927) (xy 413.937233 -120.356331) (xy 413.952754 -120.414256) (xy 413.960582 -120.473712)
			(xy 413.961072 -120.503696) (xy 413.961072 -121.365772) (xy 432.016408 -121.365772) (xy 432.016408 -120.502172)
			(xy 432.016898 -120.472188) (xy 432.024726 -120.412732) (xy 432.040247 -120.354807) (xy 432.063196 -120.299403)
			(xy 432.09318 -120.247469) (xy 432.129686 -120.199893) (xy 432.172091 -120.157488) (xy 432.219667 -120.120982)
			(xy 432.271601 -120.090998) (xy 432.327005 -120.068049) (xy 432.38493 -120.052528) (xy 432.444386 -120.0447)
			(xy 432.504354 -120.0447) (xy 432.56381 -120.052528) (xy 432.621735 -120.068049) (xy 432.677139 -120.090998)
			(xy 432.729073 -120.120982) (xy 432.776649 -120.157488) (xy 432.819054 -120.199893) (xy 432.85556 -120.247469)
			(xy 432.885544 -120.299403) (xy 432.908493 -120.354807) (xy 432.924014 -120.412732) (xy 432.931842 -120.472188)
			(xy 432.932332 -120.502172) (xy 432.932332 -121.365772) (xy 432.931842 -121.395756) (xy 432.924014 -121.455212)
			(xy 432.908493 -121.513137) (xy 432.885544 -121.568541) (xy 432.85556 -121.620475) (xy 432.819054 -121.668051)
			(xy 432.776649 -121.710456) (xy 432.729073 -121.746962) (xy 432.677139 -121.776946) (xy 432.621735 -121.799895)
			(xy 432.56381 -121.815416) (xy 432.504354 -121.823244) (xy 432.444386 -121.823244) (xy 432.38493 -121.815416)
			(xy 432.327005 -121.799895) (xy 432.271601 -121.776946) (xy 432.219667 -121.746962) (xy 432.172091 -121.710456)
			(xy 432.129686 -121.668051) (xy 432.09318 -121.620475) (xy 432.063196 -121.568541) (xy 432.040247 -121.513137)
			(xy 432.024726 -121.455212) (xy 432.016898 -121.395756) (xy 432.016408 -121.365772) (xy 413.961072 -121.365772)
			(xy 413.961072 -121.367296) (xy 413.960582 -121.39728) (xy 413.952754 -121.456736) (xy 413.937233 -121.514661)
			(xy 413.914284 -121.570065) (xy 413.8843 -121.621999) (xy 413.847794 -121.669575) (xy 413.805389 -121.71198)
			(xy 413.757813 -121.748486) (xy 413.705879 -121.77847) (xy 413.650475 -121.801419) (xy 413.59255 -121.81694)
			(xy 413.533094 -121.824768) (xy 413.473126 -121.824768) (xy 413.41367 -121.81694) (xy 413.355745 -121.801419)
			(xy 413.300341 -121.77847) (xy 413.248407 -121.748486) (xy 413.200831 -121.71198) (xy 413.158426 -121.669575)
			(xy 413.12192 -121.621999) (xy 413.091936 -121.570065) (xy 413.068987 -121.514661) (xy 413.053466 -121.456736)
			(xy 413.045638 -121.39728) (xy 413.045148 -121.367296) (xy 401.000468 -121.367296) (xy 401.000468 -121.886472)
			(xy 400.999978 -121.91644) (xy 400.992155 -121.975862) (xy 400.976642 -122.033755) (xy 400.953706 -122.089128)
			(xy 400.923739 -122.141034) (xy 400.887252 -122.188584) (xy 400.844872 -122.230964) (xy 400.797322 -122.267451)
			(xy 400.745416 -122.297418) (xy 400.690043 -122.320354) (xy 400.63215 -122.335867) (xy 400.572728 -122.34369)
			(xy 400.512792 -122.34369) (xy 400.45337 -122.335867) (xy 400.395477 -122.320354) (xy 400.340104 -122.297418)
			(xy 400.288198 -122.267451) (xy 400.240648 -122.230964) (xy 400.198268 -122.188584) (xy 400.161781 -122.141034)
			(xy 400.131814 -122.089128) (xy 400.108878 -122.033755) (xy 400.093365 -121.975862) (xy 400.085542 -121.91644)
			(xy 400.085052 -121.886472) (xy 386.525516 -121.886472) (xy 386.525516 -121.894346) (xy 386.525026 -121.924314)
			(xy 386.517203 -121.983736) (xy 386.50169 -122.041629) (xy 386.478754 -122.097002) (xy 386.448787 -122.148908)
			(xy 386.4123 -122.196458) (xy 386.36992 -122.238838) (xy 386.32237 -122.275325) (xy 386.270464 -122.305292)
			(xy 386.215091 -122.328228) (xy 386.157198 -122.343741) (xy 386.097776 -122.351564) (xy 386.03784 -122.351564)
			(xy 385.978418 -122.343741) (xy 385.920525 -122.328228) (xy 385.865152 -122.305292) (xy 385.813246 -122.275325)
			(xy 385.765696 -122.238838) (xy 385.723316 -122.196458) (xy 385.686829 -122.148908) (xy 385.656862 -122.097002)
			(xy 385.633926 -122.041629) (xy 385.618413 -121.983736) (xy 385.61059 -121.924314) (xy 385.6101 -121.894346)
			(xy 313.951493 -121.894346) (xy 313.986726 -121.914687) (xy 314.034276 -121.951174) (xy 314.076656 -121.993554)
			(xy 314.113143 -122.041104) (xy 314.14311 -122.09301) (xy 314.166046 -122.148383) (xy 314.181559 -122.206276)
			(xy 314.189382 -122.265698) (xy 314.189872 -122.295666) (xy 314.189872 -123.159266) (xy 314.189382 -123.189234)
			(xy 314.181559 -123.248656) (xy 314.166046 -123.306549) (xy 314.14311 -123.361922) (xy 314.113143 -123.413828)
			(xy 314.076656 -123.461378) (xy 314.034276 -123.503758) (xy 313.986726 -123.540245) (xy 313.93482 -123.570212)
			(xy 313.879447 -123.593148) (xy 313.821554 -123.608661) (xy 313.762132 -123.616484) (xy 313.702196 -123.616484)
			(xy 313.642774 -123.608661) (xy 313.584881 -123.593148) (xy 313.529508 -123.570212) (xy 313.477602 -123.540245)
			(xy 313.430052 -123.503758) (xy 313.387672 -123.461378) (xy 313.351185 -123.413828) (xy 313.321218 -123.361922)
			(xy 313.298282 -123.306549) (xy 313.282769 -123.248656) (xy 313.274946 -123.189234) (xy 313.274456 -123.159266)
			(xy 299.71492 -123.159266) (xy 299.71492 -123.16714) (xy 299.71443 -123.197108) (xy 299.706607 -123.25653)
			(xy 299.691094 -123.314423) (xy 299.668158 -123.369796) (xy 299.638191 -123.421702) (xy 299.601704 -123.469252)
			(xy 299.559324 -123.511632) (xy 299.511774 -123.548119) (xy 299.459868 -123.578086) (xy 299.404495 -123.601022)
			(xy 299.346602 -123.616535) (xy 299.28718 -123.624358) (xy 299.227244 -123.624358) (xy 299.167822 -123.616535)
			(xy 299.109929 -123.601022) (xy 299.054556 -123.578086) (xy 299.00265 -123.548119) (xy 298.9551 -123.511632)
			(xy 298.91272 -123.469252) (xy 298.876233 -123.421702) (xy 298.846266 -123.369796) (xy 298.82333 -123.314423)
			(xy 298.807817 -123.25653) (xy 298.799994 -123.197108) (xy 298.799504 -123.16714) (xy 286.754824 -123.16714)
			(xy 286.754824 -123.686316) (xy 286.754334 -123.7163) (xy 286.746506 -123.775756) (xy 286.730985 -123.833681)
			(xy 286.708036 -123.889085) (xy 286.678052 -123.941019) (xy 286.641546 -123.988595) (xy 286.599141 -124.031)
			(xy 286.551565 -124.067506) (xy 286.499631 -124.09749) (xy 286.444227 -124.120439) (xy 286.386302 -124.13596)
			(xy 286.326846 -124.143788) (xy 286.266878 -124.143788) (xy 286.207422 -124.13596) (xy 286.149497 -124.120439)
			(xy 286.094093 -124.09749) (xy 286.042159 -124.067506) (xy 285.994583 -124.031) (xy 285.952178 -123.988595)
			(xy 285.915672 -123.941019) (xy 285.885688 -123.889085) (xy 285.862739 -123.833681) (xy 285.847218 -123.775756)
			(xy 285.83939 -123.7163) (xy 285.8389 -123.686316) (xy 267.783564 -123.686316) (xy 267.783564 -123.68784)
			(xy 267.783074 -123.717824) (xy 267.775246 -123.77728) (xy 267.759725 -123.835205) (xy 267.736776 -123.890609)
			(xy 267.706792 -123.942543) (xy 267.670286 -123.990119) (xy 267.627881 -124.032524) (xy 267.580305 -124.06903)
			(xy 267.528371 -124.099014) (xy 267.472967 -124.121963) (xy 267.415042 -124.137484) (xy 267.355586 -124.145312)
			(xy 267.295618 -124.145312) (xy 267.236162 -124.137484) (xy 267.178237 -124.121963) (xy 267.122833 -124.099014)
			(xy 267.070899 -124.06903) (xy 267.023323 -124.032524) (xy 266.980918 -123.990119) (xy 266.944412 -123.942543)
			(xy 266.914428 -123.890609) (xy 266.891479 -123.835205) (xy 266.875958 -123.77728) (xy 266.86813 -123.717824)
			(xy 266.86764 -123.68784) (xy 200.469049 -123.68784) (xy 200.477084 -123.691168) (xy 200.52899 -123.721135)
			(xy 200.57654 -123.757622) (xy 200.61892 -123.800002) (xy 200.655407 -123.847552) (xy 200.685374 -123.899458)
			(xy 200.70831 -123.954831) (xy 200.723823 -124.012724) (xy 200.731646 -124.072146) (xy 200.732136 -124.102114)
			(xy 200.732136 -124.965714) (xy 200.731646 -124.995682) (xy 200.723823 -125.055104) (xy 200.70831 -125.112997)
			(xy 200.685374 -125.16837) (xy 200.655407 -125.220276) (xy 200.61892 -125.267826) (xy 200.57654 -125.310206)
			(xy 200.52899 -125.346693) (xy 200.477084 -125.37666) (xy 200.421711 -125.399596) (xy 200.363818 -125.415109)
			(xy 200.304396 -125.422932) (xy 200.24446 -125.422932) (xy 200.185038 -125.415109) (xy 200.127145 -125.399596)
			(xy 200.071772 -125.37666) (xy 200.019866 -125.346693) (xy 199.972316 -125.310206) (xy 199.929936 -125.267826)
			(xy 199.893449 -125.220276) (xy 199.863482 -125.16837) (xy 199.840546 -125.112997) (xy 199.825033 -125.055104)
			(xy 199.81721 -124.995682) (xy 199.81672 -124.965714) (xy 181.760876 -124.965714) (xy 181.760876 -124.967238)
			(xy 181.760386 -124.997206) (xy 181.752563 -125.056628) (xy 181.73705 -125.114521) (xy 181.714114 -125.169894)
			(xy 181.684147 -125.2218) (xy 181.64766 -125.26935) (xy 181.60528 -125.31173) (xy 181.55773 -125.348217)
			(xy 181.505824 -125.378184) (xy 181.450451 -125.40112) (xy 181.392558 -125.416633) (xy 181.333136 -125.424456)
			(xy 181.2732 -125.424456) (xy 181.213778 -125.416633) (xy 181.155885 -125.40112) (xy 181.100512 -125.378184)
			(xy 181.048606 -125.348217) (xy 181.001056 -125.31173) (xy 180.958676 -125.26935) (xy 180.922189 -125.2218)
			(xy 180.892222 -125.169894) (xy 180.869286 -125.114521) (xy 180.853773 -125.056628) (xy 180.84595 -124.997206)
			(xy 180.84546 -124.967238) (xy 168.80078 -124.967238) (xy 168.80078 -125.486414) (xy 168.800647 -125.494542)
			(xy 269.509748 -125.494542) (xy 269.509748 -124.630942) (xy 269.510238 -124.600958) (xy 269.518066 -124.541502)
			(xy 269.533587 -124.483577) (xy 269.556536 -124.428173) (xy 269.58652 -124.376239) (xy 269.623026 -124.328663)
			(xy 269.665431 -124.286258) (xy 269.713007 -124.249752) (xy 269.764941 -124.219768) (xy 269.820345 -124.196819)
			(xy 269.87827 -124.181298) (xy 269.937726 -124.17347) (xy 269.997694 -124.17347) (xy 270.05715 -124.181298)
			(xy 270.115075 -124.196819) (xy 270.170479 -124.219768) (xy 270.222413 -124.249752) (xy 270.269989 -124.286258)
			(xy 270.312394 -124.328663) (xy 270.3489 -124.376239) (xy 270.378884 -124.428173) (xy 270.401833 -124.483577)
			(xy 270.417354 -124.541502) (xy 270.425182 -124.600958) (xy 270.425672 -124.630942) (xy 270.425672 -125.486414)
			(xy 283.9847 -125.486414) (xy 283.9847 -124.622814) (xy 283.98519 -124.59283) (xy 283.993018 -124.533374)
			(xy 284.008539 -124.475449) (xy 284.031488 -124.420045) (xy 284.061472 -124.368111) (xy 284.097978 -124.320535)
			(xy 284.140383 -124.27813) (xy 284.187959 -124.241624) (xy 284.239893 -124.21164) (xy 284.295297 -124.188691)
			(xy 284.353222 -124.17317) (xy 284.412678 -124.165342) (xy 284.472646 -124.165342) (xy 284.532102 -124.17317)
			(xy 284.590027 -124.188691) (xy 284.645431 -124.21164) (xy 284.697365 -124.241624) (xy 284.744941 -124.27813)
			(xy 284.787346 -124.320535) (xy 284.823852 -124.368111) (xy 284.853836 -124.420045) (xy 284.876785 -124.475449)
			(xy 284.892306 -124.533374) (xy 284.900134 -124.59283) (xy 284.900624 -124.622814) (xy 284.900624 -124.967238)
			(xy 296.945304 -124.967238) (xy 296.945304 -124.103638) (xy 296.945794 -124.07367) (xy 296.953617 -124.014248)
			(xy 296.96913 -123.956355) (xy 296.992066 -123.900982) (xy 297.022033 -123.849076) (xy 297.05852 -123.801526)
			(xy 297.1009 -123.759146) (xy 297.14845 -123.722659) (xy 297.200356 -123.692692) (xy 297.255729 -123.669756)
			(xy 297.313622 -123.654243) (xy 297.373044 -123.64642) (xy 297.43298 -123.64642) (xy 297.492402 -123.654243)
			(xy 297.550295 -123.669756) (xy 297.605668 -123.692692) (xy 297.657574 -123.722659) (xy 297.705124 -123.759146)
			(xy 297.747504 -123.801526) (xy 297.783991 -123.849076) (xy 297.813958 -123.900982) (xy 297.836894 -123.956355)
			(xy 297.852407 -124.014248) (xy 297.86023 -124.07367) (xy 297.86072 -124.103638) (xy 297.86072 -124.965714)
			(xy 315.916564 -124.965714) (xy 315.916564 -124.102114) (xy 315.917054 -124.072146) (xy 315.924877 -124.012724)
			(xy 315.94039 -123.954831) (xy 315.963326 -123.899458) (xy 315.993293 -123.847552) (xy 316.02978 -123.800002)
			(xy 316.07216 -123.757622) (xy 316.11971 -123.721135) (xy 316.171616 -123.691168) (xy 316.226989 -123.668232)
			(xy 316.284882 -123.652719) (xy 316.344304 -123.644896) (xy 316.40424 -123.644896) (xy 316.463662 -123.652719)
			(xy 316.521555 -123.668232) (xy 316.568893 -123.68784) (xy 382.967992 -123.68784) (xy 382.967992 -122.82424)
			(xy 382.968482 -122.794272) (xy 382.976305 -122.73485) (xy 382.991818 -122.676957) (xy 383.014754 -122.621584)
			(xy 383.044721 -122.569678) (xy 383.081208 -122.522128) (xy 383.123588 -122.479748) (xy 383.171138 -122.443261)
			(xy 383.223044 -122.413294) (xy 383.278417 -122.390358) (xy 383.33631 -122.374845) (xy 383.395732 -122.367022)
			(xy 383.455668 -122.367022) (xy 383.51509 -122.374845) (xy 383.572983 -122.390358) (xy 383.628356 -122.413294)
			(xy 383.680262 -122.443261) (xy 383.727812 -122.479748) (xy 383.770192 -122.522128) (xy 383.806679 -122.569678)
			(xy 383.836646 -122.621584) (xy 383.859582 -122.676957) (xy 383.875095 -122.73485) (xy 383.882918 -122.794272)
			(xy 383.883408 -122.82424) (xy 383.883408 -123.686316) (xy 401.939252 -123.686316) (xy 401.939252 -122.822716)
			(xy 401.939742 -122.792748) (xy 401.947565 -122.733326) (xy 401.963078 -122.675433) (xy 401.986014 -122.62006)
			(xy 402.015981 -122.568154) (xy 402.052468 -122.520604) (xy 402.094848 -122.478224) (xy 402.142398 -122.441737)
			(xy 402.194304 -122.41177) (xy 402.249677 -122.388834) (xy 402.30757 -122.373321) (xy 402.366992 -122.365498)
			(xy 402.426928 -122.365498) (xy 402.48635 -122.373321) (xy 402.544243 -122.388834) (xy 402.599616 -122.41177)
			(xy 402.651522 -122.441737) (xy 402.699072 -122.478224) (xy 402.741452 -122.520604) (xy 402.777939 -122.568154)
			(xy 402.807906 -122.62006) (xy 402.830842 -122.675433) (xy 402.846355 -122.733326) (xy 402.854178 -122.792748)
			(xy 402.854668 -122.822716) (xy 402.854668 -123.16714) (xy 414.899348 -123.16714) (xy 414.899348 -122.30354)
			(xy 414.899838 -122.273556) (xy 414.907666 -122.2141) (xy 414.923187 -122.156175) (xy 414.946136 -122.100771)
			(xy 414.97612 -122.048837) (xy 415.012626 -122.001261) (xy 415.055031 -121.958856) (xy 415.102607 -121.92235)
			(xy 415.154541 -121.892366) (xy 415.209945 -121.869417) (xy 415.26787 -121.853896) (xy 415.327326 -121.846068)
			(xy 415.387294 -121.846068) (xy 415.44675 -121.853896) (xy 415.504675 -121.869417) (xy 415.560079 -121.892366)
			(xy 415.612013 -121.92235) (xy 415.659589 -121.958856) (xy 415.701994 -122.001261) (xy 415.7385 -122.048837)
			(xy 415.768484 -122.100771) (xy 415.791433 -122.156175) (xy 415.806954 -122.2141) (xy 415.814782 -122.273556)
			(xy 415.815272 -122.30354) (xy 415.815272 -123.159266) (xy 429.3743 -123.159266) (xy 429.3743 -122.295666)
			(xy 429.37479 -122.265682) (xy 429.382618 -122.206226) (xy 429.398139 -122.148301) (xy 429.421088 -122.092897)
			(xy 429.451072 -122.040963) (xy 429.487578 -121.993387) (xy 429.529983 -121.950982) (xy 429.577559 -121.914476)
			(xy 429.629493 -121.884492) (xy 429.684897 -121.861543) (xy 429.742822 -121.846022) (xy 429.802278 -121.838194)
			(xy 429.862246 -121.838194) (xy 429.921702 -121.846022) (xy 429.979627 -121.861543) (xy 430.035031 -121.884492)
			(xy 430.086965 -121.914476) (xy 430.134541 -121.950982) (xy 430.176946 -121.993387) (xy 430.213452 -122.040963)
			(xy 430.243436 -122.092897) (xy 430.266385 -122.148301) (xy 430.281906 -122.206226) (xy 430.289734 -122.265682)
			(xy 430.290224 -122.295666) (xy 430.290224 -123.159266) (xy 430.289734 -123.18925) (xy 430.281906 -123.248706)
			(xy 430.266385 -123.306631) (xy 430.243436 -123.362035) (xy 430.213452 -123.413969) (xy 430.176946 -123.461545)
			(xy 430.134541 -123.50395) (xy 430.086965 -123.540456) (xy 430.035031 -123.57044) (xy 429.979627 -123.593389)
			(xy 429.921702 -123.60891) (xy 429.862246 -123.616738) (xy 429.802278 -123.616738) (xy 429.742822 -123.60891)
			(xy 429.684897 -123.593389) (xy 429.629493 -123.57044) (xy 429.577559 -123.540456) (xy 429.529983 -123.50395)
			(xy 429.487578 -123.461545) (xy 429.451072 -123.413969) (xy 429.421088 -123.362035) (xy 429.398139 -123.306631)
			(xy 429.382618 -123.248706) (xy 429.37479 -123.18925) (xy 429.3743 -123.159266) (xy 415.815272 -123.159266)
			(xy 415.815272 -123.16714) (xy 415.814782 -123.197124) (xy 415.806954 -123.25658) (xy 415.791433 -123.314505)
			(xy 415.768484 -123.369909) (xy 415.7385 -123.421843) (xy 415.701994 -123.469419) (xy 415.659589 -123.511824)
			(xy 415.612013 -123.54833) (xy 415.560079 -123.578314) (xy 415.504675 -123.601263) (xy 415.44675 -123.616784)
			(xy 415.387294 -123.624612) (xy 415.327326 -123.624612) (xy 415.26787 -123.616784) (xy 415.209945 -123.601263)
			(xy 415.154541 -123.578314) (xy 415.102607 -123.54833) (xy 415.055031 -123.511824) (xy 415.012626 -123.469419)
			(xy 414.97612 -123.421843) (xy 414.946136 -123.369909) (xy 414.923187 -123.314505) (xy 414.907666 -123.25658)
			(xy 414.899838 -123.197124) (xy 414.899348 -123.16714) (xy 402.854668 -123.16714) (xy 402.854668 -123.686316)
			(xy 402.854178 -123.716284) (xy 402.846355 -123.775706) (xy 402.830842 -123.833599) (xy 402.807906 -123.888972)
			(xy 402.777939 -123.940878) (xy 402.741452 -123.988428) (xy 402.699072 -124.030808) (xy 402.651522 -124.067295)
			(xy 402.599616 -124.097262) (xy 402.544243 -124.120198) (xy 402.48635 -124.135711) (xy 402.426928 -124.143534)
			(xy 402.366992 -124.143534) (xy 402.30757 -124.135711) (xy 402.249677 -124.120198) (xy 402.194304 -124.097262)
			(xy 402.142398 -124.067295) (xy 402.094848 -124.030808) (xy 402.052468 -123.988428) (xy 402.015981 -123.940878)
			(xy 401.986014 -123.888972) (xy 401.963078 -123.833599) (xy 401.947565 -123.775706) (xy 401.939742 -123.716284)
			(xy 401.939252 -123.686316) (xy 383.883408 -123.686316) (xy 383.883408 -123.68784) (xy 383.882918 -123.717808)
			(xy 383.875095 -123.77723) (xy 383.859582 -123.835123) (xy 383.836646 -123.890496) (xy 383.806679 -123.942402)
			(xy 383.770192 -123.989952) (xy 383.727812 -124.032332) (xy 383.680262 -124.068819) (xy 383.628356 -124.098786)
			(xy 383.572983 -124.121722) (xy 383.51509 -124.137235) (xy 383.455668 -124.145058) (xy 383.395732 -124.145058)
			(xy 383.33631 -124.137235) (xy 383.278417 -124.121722) (xy 383.223044 -124.098786) (xy 383.171138 -124.068819)
			(xy 383.123588 -124.032332) (xy 383.081208 -123.989952) (xy 383.044721 -123.942402) (xy 383.014754 -123.890496)
			(xy 382.991818 -123.835123) (xy 382.976305 -123.77723) (xy 382.968482 -123.717808) (xy 382.967992 -123.68784)
			(xy 316.568893 -123.68784) (xy 316.576928 -123.691168) (xy 316.628834 -123.721135) (xy 316.676384 -123.757622)
			(xy 316.718764 -123.800002) (xy 316.755251 -123.847552) (xy 316.785218 -123.899458) (xy 316.808154 -123.954831)
			(xy 316.823667 -124.012724) (xy 316.83149 -124.072146) (xy 316.83198 -124.102114) (xy 316.83198 -124.965714)
			(xy 316.83149 -124.995682) (xy 316.823667 -125.055104) (xy 316.808154 -125.112997) (xy 316.785218 -125.16837)
			(xy 316.755251 -125.220276) (xy 316.718764 -125.267826) (xy 316.676384 -125.310206) (xy 316.628834 -125.346693)
			(xy 316.576928 -125.37666) (xy 316.521555 -125.399596) (xy 316.463662 -125.415109) (xy 316.40424 -125.422932)
			(xy 316.344304 -125.422932) (xy 316.284882 -125.415109) (xy 316.226989 -125.399596) (xy 316.171616 -125.37666)
			(xy 316.11971 -125.346693) (xy 316.07216 -125.310206) (xy 316.02978 -125.267826) (xy 315.993293 -125.220276)
			(xy 315.963326 -125.16837) (xy 315.94039 -125.112997) (xy 315.924877 -125.055104) (xy 315.917054 -124.995682)
			(xy 315.916564 -124.965714) (xy 297.86072 -124.965714) (xy 297.86072 -124.967238) (xy 297.86023 -124.997206)
			(xy 297.852407 -125.056628) (xy 297.836894 -125.114521) (xy 297.813958 -125.169894) (xy 297.783991 -125.2218)
			(xy 297.747504 -125.26935) (xy 297.705124 -125.31173) (xy 297.657574 -125.348217) (xy 297.605668 -125.378184)
			(xy 297.550295 -125.40112) (xy 297.492402 -125.416633) (xy 297.43298 -125.424456) (xy 297.373044 -125.424456)
			(xy 297.313622 -125.416633) (xy 297.255729 -125.40112) (xy 297.200356 -125.378184) (xy 297.14845 -125.348217)
			(xy 297.1009 -125.31173) (xy 297.05852 -125.26935) (xy 297.022033 -125.2218) (xy 296.992066 -125.169894)
			(xy 296.96913 -125.114521) (xy 296.953617 -125.056628) (xy 296.945794 -124.997206) (xy 296.945304 -124.967238)
			(xy 284.900624 -124.967238) (xy 284.900624 -125.486414) (xy 284.900491 -125.494542) (xy 385.6101 -125.494542)
			(xy 385.6101 -124.630942) (xy 385.61059 -124.600974) (xy 385.618413 -124.541552) (xy 385.633926 -124.483659)
			(xy 385.656862 -124.428286) (xy 385.686829 -124.37638) (xy 385.723316 -124.32883) (xy 385.765696 -124.28645)
			(xy 385.813246 -124.249963) (xy 385.865152 -124.219996) (xy 385.920525 -124.19706) (xy 385.978418 -124.181547)
			(xy 386.03784 -124.173724) (xy 386.097776 -124.173724) (xy 386.157198 -124.181547) (xy 386.215091 -124.19706)
			(xy 386.270464 -124.219996) (xy 386.32237 -124.249963) (xy 386.36992 -124.28645) (xy 386.4123 -124.32883)
			(xy 386.448787 -124.37638) (xy 386.478754 -124.428286) (xy 386.50169 -124.483659) (xy 386.517203 -124.541552)
			(xy 386.525026 -124.600974) (xy 386.525516 -124.630942) (xy 386.525516 -125.486414) (xy 400.085052 -125.486414)
			(xy 400.085052 -124.622814) (xy 400.085542 -124.592846) (xy 400.093365 -124.533424) (xy 400.108878 -124.475531)
			(xy 400.131814 -124.420158) (xy 400.161781 -124.368252) (xy 400.198268 -124.320702) (xy 400.240648 -124.278322)
			(xy 400.288198 -124.241835) (xy 400.340104 -124.211868) (xy 400.395477 -124.188932) (xy 400.45337 -124.173419)
			(xy 400.512792 -124.165596) (xy 400.572728 -124.165596) (xy 400.63215 -124.173419) (xy 400.690043 -124.188932)
			(xy 400.745416 -124.211868) (xy 400.797322 -124.241835) (xy 400.844872 -124.278322) (xy 400.887252 -124.320702)
			(xy 400.923739 -124.368252) (xy 400.953706 -124.420158) (xy 400.976642 -124.475531) (xy 400.992155 -124.533424)
			(xy 400.999978 -124.592846) (xy 401.000468 -124.622814) (xy 401.000468 -124.967238) (xy 413.045148 -124.967238)
			(xy 413.045148 -124.103638) (xy 413.045638 -124.073654) (xy 413.053466 -124.014198) (xy 413.068987 -123.956273)
			(xy 413.091936 -123.900869) (xy 413.12192 -123.848935) (xy 413.158426 -123.801359) (xy 413.200831 -123.758954)
			(xy 413.248407 -123.722448) (xy 413.300341 -123.692464) (xy 413.355745 -123.669515) (xy 413.41367 -123.653994)
			(xy 413.473126 -123.646166) (xy 413.533094 -123.646166) (xy 413.59255 -123.653994) (xy 413.650475 -123.669515)
			(xy 413.705879 -123.692464) (xy 413.757813 -123.722448) (xy 413.805389 -123.758954) (xy 413.847794 -123.801359)
			(xy 413.8843 -123.848935) (xy 413.914284 -123.900869) (xy 413.937233 -123.956273) (xy 413.952754 -124.014198)
			(xy 413.960582 -124.073654) (xy 413.961072 -124.103638) (xy 413.961072 -124.965714) (xy 432.016408 -124.965714)
			(xy 432.016408 -124.102114) (xy 432.016898 -124.07213) (xy 432.024726 -124.012674) (xy 432.040247 -123.954749)
			(xy 432.063196 -123.899345) (xy 432.09318 -123.847411) (xy 432.129686 -123.799835) (xy 432.172091 -123.75743)
			(xy 432.219667 -123.720924) (xy 432.271601 -123.69094) (xy 432.327005 -123.667991) (xy 432.38493 -123.65247)
			(xy 432.444386 -123.644642) (xy 432.504354 -123.644642) (xy 432.56381 -123.65247) (xy 432.621735 -123.667991)
			(xy 432.677139 -123.69094) (xy 432.729073 -123.720924) (xy 432.776649 -123.75743) (xy 432.819054 -123.799835)
			(xy 432.85556 -123.847411) (xy 432.885544 -123.899345) (xy 432.908493 -123.954749) (xy 432.924014 -124.012674)
			(xy 432.931842 -124.07213) (xy 432.932332 -124.102114) (xy 432.932332 -124.965714) (xy 432.931842 -124.995698)
			(xy 432.924014 -125.055154) (xy 432.908493 -125.113079) (xy 432.885544 -125.168483) (xy 432.85556 -125.220417)
			(xy 432.819054 -125.267993) (xy 432.776649 -125.310398) (xy 432.729073 -125.346904) (xy 432.677139 -125.376888)
			(xy 432.621735 -125.399837) (xy 432.56381 -125.415358) (xy 432.504354 -125.423186) (xy 432.444386 -125.423186)
			(xy 432.38493 -125.415358) (xy 432.327005 -125.399837) (xy 432.271601 -125.376888) (xy 432.219667 -125.346904)
			(xy 432.172091 -125.310398) (xy 432.129686 -125.267993) (xy 432.09318 -125.220417) (xy 432.063196 -125.168483)
			(xy 432.040247 -125.113079) (xy 432.024726 -125.055154) (xy 432.016898 -124.995698) (xy 432.016408 -124.965714)
			(xy 413.961072 -124.965714) (xy 413.961072 -124.967238) (xy 413.960582 -124.997222) (xy 413.952754 -125.056678)
			(xy 413.937233 -125.114603) (xy 413.914284 -125.170007) (xy 413.8843 -125.221941) (xy 413.847794 -125.269517)
			(xy 413.805389 -125.311922) (xy 413.757813 -125.348428) (xy 413.705879 -125.378412) (xy 413.650475 -125.401361)
			(xy 413.59255 -125.416882) (xy 413.533094 -125.42471) (xy 413.473126 -125.42471) (xy 413.41367 -125.416882)
			(xy 413.355745 -125.401361) (xy 413.300341 -125.378412) (xy 413.248407 -125.348428) (xy 413.200831 -125.311922)
			(xy 413.158426 -125.269517) (xy 413.12192 -125.221941) (xy 413.091936 -125.170007) (xy 413.068987 -125.114603)
			(xy 413.053466 -125.056678) (xy 413.045638 -124.997222) (xy 413.045148 -124.967238) (xy 401.000468 -124.967238)
			(xy 401.000468 -125.486414) (xy 400.999978 -125.516382) (xy 400.992155 -125.575804) (xy 400.976642 -125.633697)
			(xy 400.953706 -125.68907) (xy 400.923739 -125.740976) (xy 400.887252 -125.788526) (xy 400.844872 -125.830906)
			(xy 400.797322 -125.867393) (xy 400.745416 -125.89736) (xy 400.690043 -125.920296) (xy 400.63215 -125.935809)
			(xy 400.572728 -125.943632) (xy 400.512792 -125.943632) (xy 400.45337 -125.935809) (xy 400.395477 -125.920296)
			(xy 400.340104 -125.89736) (xy 400.288198 -125.867393) (xy 400.240648 -125.830906) (xy 400.198268 -125.788526)
			(xy 400.161781 -125.740976) (xy 400.131814 -125.68907) (xy 400.108878 -125.633697) (xy 400.093365 -125.575804)
			(xy 400.085542 -125.516382) (xy 400.085052 -125.486414) (xy 386.525516 -125.486414) (xy 386.525516 -125.494542)
			(xy 386.525026 -125.52451) (xy 386.517203 -125.583932) (xy 386.50169 -125.641825) (xy 386.478754 -125.697198)
			(xy 386.448787 -125.749104) (xy 386.4123 -125.796654) (xy 386.36992 -125.839034) (xy 386.32237 -125.875521)
			(xy 386.270464 -125.905488) (xy 386.215091 -125.928424) (xy 386.157198 -125.943937) (xy 386.097776 -125.95176)
			(xy 386.03784 -125.95176) (xy 385.978418 -125.943937) (xy 385.920525 -125.928424) (xy 385.865152 -125.905488)
			(xy 385.813246 -125.875521) (xy 385.765696 -125.839034) (xy 385.723316 -125.796654) (xy 385.686829 -125.749104)
			(xy 385.656862 -125.697198) (xy 385.633926 -125.641825) (xy 385.618413 -125.583932) (xy 385.61059 -125.52451)
			(xy 385.6101 -125.494542) (xy 284.900491 -125.494542) (xy 284.900134 -125.516398) (xy 284.892306 -125.575854)
			(xy 284.876785 -125.633779) (xy 284.853836 -125.689183) (xy 284.823852 -125.741117) (xy 284.787346 -125.788693)
			(xy 284.744941 -125.831098) (xy 284.697365 -125.867604) (xy 284.645431 -125.897588) (xy 284.590027 -125.920537)
			(xy 284.532102 -125.936058) (xy 284.472646 -125.943886) (xy 284.412678 -125.943886) (xy 284.353222 -125.936058)
			(xy 284.295297 -125.920537) (xy 284.239893 -125.897588) (xy 284.187959 -125.867604) (xy 284.140383 -125.831098)
			(xy 284.097978 -125.788693) (xy 284.061472 -125.741117) (xy 284.031488 -125.689183) (xy 284.008539 -125.633779)
			(xy 283.993018 -125.575854) (xy 283.98519 -125.516398) (xy 283.9847 -125.486414) (xy 270.425672 -125.486414)
			(xy 270.425672 -125.494542) (xy 270.425182 -125.524526) (xy 270.417354 -125.583982) (xy 270.401833 -125.641907)
			(xy 270.378884 -125.697311) (xy 270.3489 -125.749245) (xy 270.312394 -125.796821) (xy 270.269989 -125.839226)
			(xy 270.222413 -125.875732) (xy 270.170479 -125.905716) (xy 270.115075 -125.928665) (xy 270.05715 -125.944186)
			(xy 269.997694 -125.952014) (xy 269.937726 -125.952014) (xy 269.87827 -125.944186) (xy 269.820345 -125.928665)
			(xy 269.764941 -125.905716) (xy 269.713007 -125.875732) (xy 269.665431 -125.839226) (xy 269.623026 -125.796821)
			(xy 269.58652 -125.749245) (xy 269.556536 -125.697311) (xy 269.533587 -125.641907) (xy 269.518066 -125.583982)
			(xy 269.510238 -125.524526) (xy 269.509748 -125.494542) (xy 168.800647 -125.494542) (xy 168.80029 -125.516398)
			(xy 168.792462 -125.575854) (xy 168.776941 -125.633779) (xy 168.753992 -125.689183) (xy 168.724008 -125.741117)
			(xy 168.687502 -125.788693) (xy 168.645097 -125.831098) (xy 168.597521 -125.867604) (xy 168.545587 -125.897588)
			(xy 168.490183 -125.920537) (xy 168.432258 -125.936058) (xy 168.372802 -125.943886) (xy 168.312834 -125.943886)
			(xy 168.253378 -125.936058) (xy 168.195453 -125.920537) (xy 168.140049 -125.897588) (xy 168.088115 -125.867604)
			(xy 168.040539 -125.831098) (xy 167.998134 -125.788693) (xy 167.961628 -125.741117) (xy 167.931644 -125.689183)
			(xy 167.908695 -125.633779) (xy 167.893174 -125.575854) (xy 167.885346 -125.516398) (xy 167.884856 -125.486414)
			(xy 154.325828 -125.486414) (xy 154.325828 -125.494542) (xy 154.325338 -125.524526) (xy 154.31751 -125.583982)
			(xy 154.301989 -125.641907) (xy 154.27904 -125.697311) (xy 154.249056 -125.749245) (xy 154.21255 -125.796821)
			(xy 154.170145 -125.839226) (xy 154.122569 -125.875732) (xy 154.070635 -125.905716) (xy 154.015231 -125.928665)
			(xy 153.957306 -125.944186) (xy 153.89785 -125.952014) (xy 153.837882 -125.952014) (xy 153.778426 -125.944186)
			(xy 153.720501 -125.928665) (xy 153.665097 -125.905716) (xy 153.613163 -125.875732) (xy 153.565587 -125.839226)
			(xy 153.523182 -125.796821) (xy 153.486676 -125.749245) (xy 153.456692 -125.697311) (xy 153.433743 -125.641907)
			(xy 153.418222 -125.583982) (xy 153.410394 -125.524526) (xy 153.409904 -125.494542) (xy 52.700295 -125.494542)
			(xy 52.699938 -125.516382) (xy 52.692115 -125.575804) (xy 52.676602 -125.633697) (xy 52.653666 -125.68907)
			(xy 52.623699 -125.740976) (xy 52.587212 -125.788526) (xy 52.544832 -125.830906) (xy 52.497282 -125.867393)
			(xy 52.445376 -125.89736) (xy 52.390003 -125.920296) (xy 52.33211 -125.935809) (xy 52.272688 -125.943632)
			(xy 52.212752 -125.943632) (xy 52.15333 -125.935809) (xy 52.095437 -125.920296) (xy 52.040064 -125.89736)
			(xy 51.988158 -125.867393) (xy 51.940608 -125.830906) (xy 51.898228 -125.788526) (xy 51.861741 -125.740976)
			(xy 51.831774 -125.68907) (xy 51.808838 -125.633697) (xy 51.793325 -125.575804) (xy 51.785502 -125.516382)
			(xy 51.785012 -125.486414) (xy 38.225476 -125.486414) (xy 38.225476 -125.494542) (xy 38.224986 -125.52451)
			(xy 38.217163 -125.583932) (xy 38.20165 -125.641825) (xy 38.178714 -125.697198) (xy 38.148747 -125.749104)
			(xy 38.11226 -125.796654) (xy 38.06988 -125.839034) (xy 38.02233 -125.875521) (xy 37.970424 -125.905488)
			(xy 37.915051 -125.928424) (xy 37.857158 -125.943937) (xy 37.797736 -125.95176) (xy 37.7378 -125.95176)
			(xy 37.678378 -125.943937) (xy 37.620485 -125.928424) (xy 37.565112 -125.905488) (xy 37.513206 -125.875521)
			(xy 37.465656 -125.839034) (xy 37.423276 -125.796654) (xy 37.386789 -125.749104) (xy 37.356822 -125.697198)
			(xy 37.333886 -125.641825) (xy 37.318373 -125.583932) (xy 37.31055 -125.52451) (xy 37.31006 -125.494542)
			(xy 5.324094 -125.494542) (xy 5.324094 -131.297934) (xy 34.667952 -131.297934) (xy 34.667952 -130.434334)
			(xy 34.668442 -130.404366) (xy 34.676265 -130.344944) (xy 34.691778 -130.287051) (xy 34.714714 -130.231678)
			(xy 34.744681 -130.179772) (xy 34.781168 -130.132222) (xy 34.823548 -130.089842) (xy 34.871098 -130.053355)
			(xy 34.923004 -130.023388) (xy 34.978377 -130.000452) (xy 35.03627 -129.984939) (xy 35.095692 -129.977116)
			(xy 35.155628 -129.977116) (xy 35.21505 -129.984939) (xy 35.272943 -130.000452) (xy 35.328316 -130.023388)
			(xy 35.380222 -130.053355) (xy 35.427772 -130.089842) (xy 35.470152 -130.132222) (xy 35.506639 -130.179772)
			(xy 35.536606 -130.231678) (xy 35.559542 -130.287051) (xy 35.575055 -130.344944) (xy 35.582878 -130.404366)
			(xy 35.583368 -130.434334) (xy 35.583368 -131.29641) (xy 53.639212 -131.29641) (xy 53.639212 -130.43281)
			(xy 53.639702 -130.402842) (xy 53.647525 -130.34342) (xy 53.663038 -130.285527) (xy 53.685974 -130.230154)
			(xy 53.715941 -130.178248) (xy 53.752428 -130.130698) (xy 53.794808 -130.088318) (xy 53.842358 -130.051831)
			(xy 53.894264 -130.021864) (xy 53.949637 -129.998928) (xy 54.00753 -129.983415) (xy 54.066952 -129.975592)
			(xy 54.126888 -129.975592) (xy 54.18631 -129.983415) (xy 54.244203 -129.998928) (xy 54.299576 -130.021864)
			(xy 54.351482 -130.051831) (xy 54.399032 -130.088318) (xy 54.441412 -130.130698) (xy 54.477899 -130.178248)
			(xy 54.507866 -130.230154) (xy 54.530802 -130.285527) (xy 54.546315 -130.34342) (xy 54.554138 -130.402842)
			(xy 54.554628 -130.43281) (xy 54.554628 -130.777234) (xy 66.599308 -130.777234) (xy 66.599308 -129.913634)
			(xy 66.599798 -129.88365) (xy 66.607626 -129.824194) (xy 66.623147 -129.766269) (xy 66.646096 -129.710865)
			(xy 66.67608 -129.658931) (xy 66.712586 -129.611355) (xy 66.754991 -129.56895) (xy 66.802567 -129.532444)
			(xy 66.854501 -129.50246) (xy 66.909905 -129.479511) (xy 66.96783 -129.46399) (xy 67.027286 -129.456162)
			(xy 67.087254 -129.456162) (xy 67.14671 -129.46399) (xy 67.204635 -129.479511) (xy 67.260039 -129.50246)
			(xy 67.311973 -129.532444) (xy 67.359549 -129.56895) (xy 67.401954 -129.611355) (xy 67.43846 -129.658931)
			(xy 67.468444 -129.710865) (xy 67.491393 -129.766269) (xy 67.506914 -129.824194) (xy 67.514742 -129.88365)
			(xy 67.515232 -129.913634) (xy 67.515232 -130.769106) (xy 81.07426 -130.769106) (xy 81.07426 -129.905506)
			(xy 81.07475 -129.875522) (xy 81.082578 -129.816066) (xy 81.098099 -129.758141) (xy 81.121048 -129.702737)
			(xy 81.151032 -129.650803) (xy 81.187538 -129.603227) (xy 81.229943 -129.560822) (xy 81.277519 -129.524316)
			(xy 81.329453 -129.494332) (xy 81.384857 -129.471383) (xy 81.442782 -129.455862) (xy 81.502238 -129.448034)
			(xy 81.562206 -129.448034) (xy 81.621662 -129.455862) (xy 81.679587 -129.471383) (xy 81.734991 -129.494332)
			(xy 81.786925 -129.524316) (xy 81.834501 -129.560822) (xy 81.876906 -129.603227) (xy 81.913412 -129.650803)
			(xy 81.943396 -129.702737) (xy 81.966345 -129.758141) (xy 81.981866 -129.816066) (xy 81.989694 -129.875522)
			(xy 81.990184 -129.905506) (xy 81.990184 -130.769106) (xy 81.989694 -130.79909) (xy 81.981866 -130.858546)
			(xy 81.966345 -130.916471) (xy 81.943396 -130.971875) (xy 81.913412 -131.023809) (xy 81.876906 -131.071385)
			(xy 81.834501 -131.11379) (xy 81.786925 -131.150296) (xy 81.734991 -131.18028) (xy 81.679587 -131.203229)
			(xy 81.621662 -131.21875) (xy 81.562206 -131.226578) (xy 81.502238 -131.226578) (xy 81.442782 -131.21875)
			(xy 81.384857 -131.203229) (xy 81.329453 -131.18028) (xy 81.277519 -131.150296) (xy 81.229943 -131.11379)
			(xy 81.187538 -131.071385) (xy 81.151032 -131.023809) (xy 81.121048 -130.971875) (xy 81.098099 -130.916471)
			(xy 81.082578 -130.858546) (xy 81.07475 -130.79909) (xy 81.07426 -130.769106) (xy 67.515232 -130.769106)
			(xy 67.515232 -130.777234) (xy 67.514742 -130.807218) (xy 67.506914 -130.866674) (xy 67.491393 -130.924599)
			(xy 67.468444 -130.980003) (xy 67.43846 -131.031937) (xy 67.401954 -131.079513) (xy 67.359549 -131.121918)
			(xy 67.311973 -131.158424) (xy 67.260039 -131.188408) (xy 67.204635 -131.211357) (xy 67.14671 -131.226878)
			(xy 67.087254 -131.234706) (xy 67.027286 -131.234706) (xy 66.96783 -131.226878) (xy 66.909905 -131.211357)
			(xy 66.854501 -131.188408) (xy 66.802567 -131.158424) (xy 66.754991 -131.121918) (xy 66.712586 -131.079513)
			(xy 66.67608 -131.031937) (xy 66.646096 -130.980003) (xy 66.623147 -130.924599) (xy 66.607626 -130.866674)
			(xy 66.599798 -130.807218) (xy 66.599308 -130.777234) (xy 54.554628 -130.777234) (xy 54.554628 -131.29641)
			(xy 54.554138 -131.326378) (xy 54.546315 -131.3858) (xy 54.530802 -131.443693) (xy 54.507866 -131.499066)
			(xy 54.477899 -131.550972) (xy 54.441412 -131.598522) (xy 54.399032 -131.640902) (xy 54.351482 -131.677389)
			(xy 54.299576 -131.707356) (xy 54.244203 -131.730292) (xy 54.18631 -131.745805) (xy 54.126888 -131.753628)
			(xy 54.066952 -131.753628) (xy 54.00753 -131.745805) (xy 53.949637 -131.730292) (xy 53.894264 -131.707356)
			(xy 53.842358 -131.677389) (xy 53.794808 -131.640902) (xy 53.752428 -131.598522) (xy 53.715941 -131.550972)
			(xy 53.685974 -131.499066) (xy 53.663038 -131.443693) (xy 53.647525 -131.3858) (xy 53.639702 -131.326378)
			(xy 53.639212 -131.29641) (xy 35.583368 -131.29641) (xy 35.583368 -131.297934) (xy 35.582878 -131.327902)
			(xy 35.575055 -131.387324) (xy 35.559542 -131.445217) (xy 35.536606 -131.50059) (xy 35.506639 -131.552496)
			(xy 35.470152 -131.600046) (xy 35.427772 -131.642426) (xy 35.380222 -131.678913) (xy 35.328316 -131.70888)
			(xy 35.272943 -131.731816) (xy 35.21505 -131.747329) (xy 35.155628 -131.755152) (xy 35.095692 -131.755152)
			(xy 35.03627 -131.747329) (xy 34.978377 -131.731816) (xy 34.923004 -131.70888) (xy 34.871098 -131.678913)
			(xy 34.823548 -131.642426) (xy 34.781168 -131.600046) (xy 34.744681 -131.552496) (xy 34.714714 -131.50059)
			(xy 34.691778 -131.445217) (xy 34.676265 -131.387324) (xy 34.668442 -131.327902) (xy 34.667952 -131.297934)
			(xy 5.324094 -131.297934) (xy 5.324094 -133.104382) (xy 37.31006 -133.104382) (xy 37.31006 -132.240782)
			(xy 37.31055 -132.210814) (xy 37.318373 -132.151392) (xy 37.333886 -132.093499) (xy 37.356822 -132.038126)
			(xy 37.386789 -131.98622) (xy 37.423276 -131.93867) (xy 37.465656 -131.89629) (xy 37.513206 -131.859803)
			(xy 37.565112 -131.829836) (xy 37.620485 -131.8069) (xy 37.678378 -131.791387) (xy 37.7378 -131.783564)
			(xy 37.797736 -131.783564) (xy 37.857158 -131.791387) (xy 37.915051 -131.8069) (xy 37.970424 -131.829836)
			(xy 38.02233 -131.859803) (xy 38.06988 -131.89629) (xy 38.11226 -131.93867) (xy 38.148747 -131.98622)
			(xy 38.178714 -132.038126) (xy 38.20165 -132.093499) (xy 38.217163 -132.151392) (xy 38.224986 -132.210814)
			(xy 38.225476 -132.240782) (xy 38.225476 -133.096508) (xy 51.785012 -133.096508) (xy 51.785012 -132.232908)
			(xy 51.785502 -132.20294) (xy 51.793325 -132.143518) (xy 51.808838 -132.085625) (xy 51.831774 -132.030252)
			(xy 51.861741 -131.978346) (xy 51.898228 -131.930796) (xy 51.940608 -131.888416) (xy 51.988158 -131.851929)
			(xy 52.040064 -131.821962) (xy 52.095437 -131.799026) (xy 52.15333 -131.783513) (xy 52.212752 -131.77569)
			(xy 52.272688 -131.77569) (xy 52.33211 -131.783513) (xy 52.390003 -131.799026) (xy 52.445376 -131.821962)
			(xy 52.497282 -131.851929) (xy 52.544832 -131.888416) (xy 52.587212 -131.930796) (xy 52.623699 -131.978346)
			(xy 52.653666 -132.030252) (xy 52.676602 -132.085625) (xy 52.692115 -132.143518) (xy 52.699938 -132.20294)
			(xy 52.700428 -132.232908) (xy 52.700428 -132.577332) (xy 64.745108 -132.577332) (xy 64.745108 -131.713732)
			(xy 64.745598 -131.683748) (xy 64.753426 -131.624292) (xy 64.768947 -131.566367) (xy 64.791896 -131.510963)
			(xy 64.82188 -131.459029) (xy 64.858386 -131.411453) (xy 64.900791 -131.369048) (xy 64.948367 -131.332542)
			(xy 65.000301 -131.302558) (xy 65.055705 -131.279609) (xy 65.11363 -131.264088) (xy 65.173086 -131.25626)
			(xy 65.233054 -131.25626) (xy 65.29251 -131.264088) (xy 65.350435 -131.279609) (xy 65.405839 -131.302558)
			(xy 65.457773 -131.332542) (xy 65.505349 -131.369048) (xy 65.547754 -131.411453) (xy 65.58426 -131.459029)
			(xy 65.614244 -131.510963) (xy 65.637193 -131.566367) (xy 65.652714 -131.624292) (xy 65.660542 -131.683748)
			(xy 65.661032 -131.713732) (xy 65.661032 -132.575808) (xy 83.716368 -132.575808) (xy 83.716368 -131.712208)
			(xy 83.716858 -131.682224) (xy 83.724686 -131.622768) (xy 83.740207 -131.564843) (xy 83.763156 -131.509439)
			(xy 83.79314 -131.457505) (xy 83.829646 -131.409929) (xy 83.872051 -131.367524) (xy 83.919627 -131.331018)
			(xy 83.971561 -131.301034) (xy 84.026965 -131.278085) (xy 84.08489 -131.262564) (xy 84.144346 -131.254736)
			(xy 84.204314 -131.254736) (xy 84.26377 -131.262564) (xy 84.321695 -131.278085) (xy 84.369615 -131.297934)
			(xy 150.767796 -131.297934) (xy 150.767796 -130.434334) (xy 150.768286 -130.40435) (xy 150.776114 -130.344894)
			(xy 150.791635 -130.286969) (xy 150.814584 -130.231565) (xy 150.844568 -130.179631) (xy 150.881074 -130.132055)
			(xy 150.923479 -130.08965) (xy 150.971055 -130.053144) (xy 151.022989 -130.02316) (xy 151.078393 -130.000211)
			(xy 151.136318 -129.98469) (xy 151.195774 -129.976862) (xy 151.255742 -129.976862) (xy 151.315198 -129.98469)
			(xy 151.373123 -130.000211) (xy 151.428527 -130.02316) (xy 151.480461 -130.053144) (xy 151.528037 -130.08965)
			(xy 151.570442 -130.132055) (xy 151.606948 -130.179631) (xy 151.636932 -130.231565) (xy 151.659881 -130.286969)
			(xy 151.675402 -130.344894) (xy 151.68323 -130.40435) (xy 151.68372 -130.434334) (xy 151.68372 -131.29641)
			(xy 169.739056 -131.29641) (xy 169.739056 -130.43281) (xy 169.739546 -130.402826) (xy 169.747374 -130.34337)
			(xy 169.762895 -130.285445) (xy 169.785844 -130.230041) (xy 169.815828 -130.178107) (xy 169.852334 -130.130531)
			(xy 169.894739 -130.088126) (xy 169.942315 -130.05162) (xy 169.994249 -130.021636) (xy 170.049653 -129.998687)
			(xy 170.107578 -129.983166) (xy 170.167034 -129.975338) (xy 170.227002 -129.975338) (xy 170.286458 -129.983166)
			(xy 170.344383 -129.998687) (xy 170.399787 -130.021636) (xy 170.451721 -130.05162) (xy 170.499297 -130.088126)
			(xy 170.541702 -130.130531) (xy 170.578208 -130.178107) (xy 170.608192 -130.230041) (xy 170.631141 -130.285445)
			(xy 170.646662 -130.34337) (xy 170.65449 -130.402826) (xy 170.65498 -130.43281) (xy 170.65498 -130.777234)
			(xy 182.69966 -130.777234) (xy 182.69966 -129.913634) (xy 182.70015 -129.883666) (xy 182.707973 -129.824244)
			(xy 182.723486 -129.766351) (xy 182.746422 -129.710978) (xy 182.776389 -129.659072) (xy 182.812876 -129.611522)
			(xy 182.855256 -129.569142) (xy 182.902806 -129.532655) (xy 182.954712 -129.502688) (xy 183.010085 -129.479752)
			(xy 183.067978 -129.464239) (xy 183.1274 -129.456416) (xy 183.187336 -129.456416) (xy 183.246758 -129.464239)
			(xy 183.304651 -129.479752) (xy 183.360024 -129.502688) (xy 183.41193 -129.532655) (xy 183.45948 -129.569142)
			(xy 183.50186 -129.611522) (xy 183.538347 -129.659072) (xy 183.568314 -129.710978) (xy 183.59125 -129.766351)
			(xy 183.606763 -129.824244) (xy 183.614586 -129.883666) (xy 183.615076 -129.913634) (xy 183.615076 -130.769106)
			(xy 197.174612 -130.769106) (xy 197.174612 -129.905506) (xy 197.175102 -129.875538) (xy 197.182925 -129.816116)
			(xy 197.198438 -129.758223) (xy 197.221374 -129.70285) (xy 197.251341 -129.650944) (xy 197.287828 -129.603394)
			(xy 197.330208 -129.561014) (xy 197.377758 -129.524527) (xy 197.429664 -129.49456) (xy 197.485037 -129.471624)
			(xy 197.54293 -129.456111) (xy 197.602352 -129.448288) (xy 197.662288 -129.448288) (xy 197.72171 -129.456111)
			(xy 197.779603 -129.471624) (xy 197.834976 -129.49456) (xy 197.886882 -129.524527) (xy 197.934432 -129.561014)
			(xy 197.976812 -129.603394) (xy 198.013299 -129.650944) (xy 198.043266 -129.70285) (xy 198.066202 -129.758223)
			(xy 198.081715 -129.816116) (xy 198.089538 -129.875538) (xy 198.090028 -129.905506) (xy 198.090028 -130.769106)
			(xy 198.089538 -130.799074) (xy 198.081715 -130.858496) (xy 198.066202 -130.916389) (xy 198.043266 -130.971762)
			(xy 198.013299 -131.023668) (xy 197.976812 -131.071218) (xy 197.934432 -131.113598) (xy 197.886882 -131.150085)
			(xy 197.834976 -131.180052) (xy 197.779603 -131.202988) (xy 197.72171 -131.218501) (xy 197.662288 -131.226324)
			(xy 197.602352 -131.226324) (xy 197.54293 -131.218501) (xy 197.485037 -131.202988) (xy 197.429664 -131.180052)
			(xy 197.377758 -131.150085) (xy 197.330208 -131.113598) (xy 197.287828 -131.071218) (xy 197.251341 -131.023668)
			(xy 197.221374 -130.971762) (xy 197.198438 -130.916389) (xy 197.182925 -130.858496) (xy 197.175102 -130.799074)
			(xy 197.174612 -130.769106) (xy 183.615076 -130.769106) (xy 183.615076 -130.777234) (xy 183.614586 -130.807202)
			(xy 183.606763 -130.866624) (xy 183.59125 -130.924517) (xy 183.568314 -130.97989) (xy 183.538347 -131.031796)
			(xy 183.50186 -131.079346) (xy 183.45948 -131.121726) (xy 183.41193 -131.158213) (xy 183.360024 -131.18818)
			(xy 183.304651 -131.211116) (xy 183.246758 -131.226629) (xy 183.187336 -131.234452) (xy 183.1274 -131.234452)
			(xy 183.067978 -131.226629) (xy 183.010085 -131.211116) (xy 182.954712 -131.18818) (xy 182.902806 -131.158213)
			(xy 182.855256 -131.121726) (xy 182.812876 -131.079346) (xy 182.776389 -131.031796) (xy 182.746422 -130.97989)
			(xy 182.723486 -130.924517) (xy 182.707973 -130.866624) (xy 182.70015 -130.807202) (xy 182.69966 -130.777234)
			(xy 170.65498 -130.777234) (xy 170.65498 -131.29641) (xy 170.65449 -131.326394) (xy 170.646662 -131.38585)
			(xy 170.631141 -131.443775) (xy 170.608192 -131.499179) (xy 170.578208 -131.551113) (xy 170.541702 -131.598689)
			(xy 170.499297 -131.641094) (xy 170.451721 -131.6776) (xy 170.399787 -131.707584) (xy 170.344383 -131.730533)
			(xy 170.286458 -131.746054) (xy 170.227002 -131.753882) (xy 170.167034 -131.753882) (xy 170.107578 -131.746054)
			(xy 170.049653 -131.730533) (xy 169.994249 -131.707584) (xy 169.942315 -131.6776) (xy 169.894739 -131.641094)
			(xy 169.852334 -131.598689) (xy 169.815828 -131.551113) (xy 169.785844 -131.499179) (xy 169.762895 -131.443775)
			(xy 169.747374 -131.38585) (xy 169.739546 -131.326394) (xy 169.739056 -131.29641) (xy 151.68372 -131.29641)
			(xy 151.68372 -131.297934) (xy 151.68323 -131.327918) (xy 151.675402 -131.387374) (xy 151.659881 -131.445299)
			(xy 151.636932 -131.500703) (xy 151.606948 -131.552637) (xy 151.570442 -131.600213) (xy 151.528037 -131.642618)
			(xy 151.480461 -131.679124) (xy 151.428527 -131.709108) (xy 151.373123 -131.732057) (xy 151.315198 -131.747578)
			(xy 151.255742 -131.755406) (xy 151.195774 -131.755406) (xy 151.136318 -131.747578) (xy 151.078393 -131.732057)
			(xy 151.022989 -131.709108) (xy 150.971055 -131.679124) (xy 150.923479 -131.642618) (xy 150.881074 -131.600213)
			(xy 150.844568 -131.552637) (xy 150.814584 -131.500703) (xy 150.791635 -131.445299) (xy 150.776114 -131.387374)
			(xy 150.768286 -131.327918) (xy 150.767796 -131.297934) (xy 84.369615 -131.297934) (xy 84.377099 -131.301034)
			(xy 84.429033 -131.331018) (xy 84.476609 -131.367524) (xy 84.519014 -131.409929) (xy 84.55552 -131.457505)
			(xy 84.585504 -131.509439) (xy 84.608453 -131.564843) (xy 84.623974 -131.622768) (xy 84.631802 -131.682224)
			(xy 84.632292 -131.712208) (xy 84.632292 -132.575808) (xy 84.631802 -132.605792) (xy 84.623974 -132.665248)
			(xy 84.608453 -132.723173) (xy 84.585504 -132.778577) (xy 84.55552 -132.830511) (xy 84.519014 -132.878087)
			(xy 84.476609 -132.920492) (xy 84.429033 -132.956998) (xy 84.377099 -132.986982) (xy 84.321695 -133.009931)
			(xy 84.26377 -133.025452) (xy 84.204314 -133.03328) (xy 84.144346 -133.03328) (xy 84.08489 -133.025452)
			(xy 84.026965 -133.009931) (xy 83.971561 -132.986982) (xy 83.919627 -132.956998) (xy 83.872051 -132.920492)
			(xy 83.829646 -132.878087) (xy 83.79314 -132.830511) (xy 83.763156 -132.778577) (xy 83.740207 -132.723173)
			(xy 83.724686 -132.665248) (xy 83.716858 -132.605792) (xy 83.716368 -132.575808) (xy 65.661032 -132.575808)
			(xy 65.661032 -132.577332) (xy 65.660542 -132.607316) (xy 65.652714 -132.666772) (xy 65.637193 -132.724697)
			(xy 65.614244 -132.780101) (xy 65.58426 -132.832035) (xy 65.547754 -132.879611) (xy 65.505349 -132.922016)
			(xy 65.457773 -132.958522) (xy 65.405839 -132.988506) (xy 65.350435 -133.011455) (xy 65.29251 -133.026976)
			(xy 65.233054 -133.034804) (xy 65.173086 -133.034804) (xy 65.11363 -133.026976) (xy 65.055705 -133.011455)
			(xy 65.000301 -132.988506) (xy 64.948367 -132.958522) (xy 64.900791 -132.922016) (xy 64.858386 -132.879611)
			(xy 64.82188 -132.832035) (xy 64.791896 -132.780101) (xy 64.768947 -132.724697) (xy 64.753426 -132.666772)
			(xy 64.745598 -132.607316) (xy 64.745108 -132.577332) (xy 52.700428 -132.577332) (xy 52.700428 -133.096508)
			(xy 52.699938 -133.126476) (xy 52.692115 -133.185898) (xy 52.676602 -133.243791) (xy 52.653666 -133.299164)
			(xy 52.623699 -133.35107) (xy 52.587212 -133.39862) (xy 52.544832 -133.441) (xy 52.497282 -133.477487)
			(xy 52.445376 -133.507454) (xy 52.390003 -133.53039) (xy 52.33211 -133.545903) (xy 52.272688 -133.553726)
			(xy 52.212752 -133.553726) (xy 52.15333 -133.545903) (xy 52.095437 -133.53039) (xy 52.040064 -133.507454)
			(xy 51.988158 -133.477487) (xy 51.940608 -133.441) (xy 51.898228 -133.39862) (xy 51.861741 -133.35107)
			(xy 51.831774 -133.299164) (xy 51.808838 -133.243791) (xy 51.793325 -133.185898) (xy 51.785502 -133.126476)
			(xy 51.785012 -133.096508) (xy 38.225476 -133.096508) (xy 38.225476 -133.104382) (xy 38.224986 -133.13435)
			(xy 38.217163 -133.193772) (xy 38.20165 -133.251665) (xy 38.178714 -133.307038) (xy 38.148747 -133.358944)
			(xy 38.11226 -133.406494) (xy 38.06988 -133.448874) (xy 38.02233 -133.485361) (xy 37.970424 -133.515328)
			(xy 37.915051 -133.538264) (xy 37.857158 -133.553777) (xy 37.797736 -133.5616) (xy 37.7378 -133.5616)
			(xy 37.678378 -133.553777) (xy 37.620485 -133.538264) (xy 37.565112 -133.515328) (xy 37.513206 -133.485361)
			(xy 37.465656 -133.448874) (xy 37.423276 -133.406494) (xy 37.386789 -133.358944) (xy 37.356822 -133.307038)
			(xy 37.333886 -133.251665) (xy 37.318373 -133.193772) (xy 37.31055 -133.13435) (xy 37.31006 -133.104382)
			(xy 5.324094 -133.104382) (xy 5.324094 -134.897876) (xy 34.667952 -134.897876) (xy 34.667952 -134.034276)
			(xy 34.668442 -134.004308) (xy 34.676265 -133.944886) (xy 34.691778 -133.886993) (xy 34.714714 -133.83162)
			(xy 34.744681 -133.779714) (xy 34.781168 -133.732164) (xy 34.823548 -133.689784) (xy 34.871098 -133.653297)
			(xy 34.923004 -133.62333) (xy 34.978377 -133.600394) (xy 35.03627 -133.584881) (xy 35.095692 -133.577058)
			(xy 35.155628 -133.577058) (xy 35.21505 -133.584881) (xy 35.272943 -133.600394) (xy 35.328316 -133.62333)
			(xy 35.380222 -133.653297) (xy 35.427772 -133.689784) (xy 35.470152 -133.732164) (xy 35.506639 -133.779714)
			(xy 35.536606 -133.83162) (xy 35.559542 -133.886993) (xy 35.575055 -133.944886) (xy 35.582878 -134.004308)
			(xy 35.583368 -134.034276) (xy 35.583368 -134.896352) (xy 53.639212 -134.896352) (xy 53.639212 -134.032752)
			(xy 53.639702 -134.002784) (xy 53.647525 -133.943362) (xy 53.663038 -133.885469) (xy 53.685974 -133.830096)
			(xy 53.715941 -133.77819) (xy 53.752428 -133.73064) (xy 53.794808 -133.68826) (xy 53.842358 -133.651773)
			(xy 53.894264 -133.621806) (xy 53.949637 -133.59887) (xy 54.00753 -133.583357) (xy 54.066952 -133.575534)
			(xy 54.126888 -133.575534) (xy 54.18631 -133.583357) (xy 54.244203 -133.59887) (xy 54.299576 -133.621806)
			(xy 54.351482 -133.651773) (xy 54.399032 -133.68826) (xy 54.441412 -133.73064) (xy 54.477899 -133.77819)
			(xy 54.507866 -133.830096) (xy 54.530802 -133.885469) (xy 54.546315 -133.943362) (xy 54.554138 -134.002784)
			(xy 54.554628 -134.032752) (xy 54.554628 -134.377176) (xy 66.599308 -134.377176) (xy 66.599308 -133.513576)
			(xy 66.599798 -133.483592) (xy 66.607626 -133.424136) (xy 66.623147 -133.366211) (xy 66.646096 -133.310807)
			(xy 66.67608 -133.258873) (xy 66.712586 -133.211297) (xy 66.754991 -133.168892) (xy 66.802567 -133.132386)
			(xy 66.854501 -133.102402) (xy 66.909905 -133.079453) (xy 66.96783 -133.063932) (xy 67.027286 -133.056104)
			(xy 67.087254 -133.056104) (xy 67.14671 -133.063932) (xy 67.204635 -133.079453) (xy 67.260039 -133.102402)
			(xy 67.311973 -133.132386) (xy 67.359549 -133.168892) (xy 67.401954 -133.211297) (xy 67.43846 -133.258873)
			(xy 67.468444 -133.310807) (xy 67.491393 -133.366211) (xy 67.506914 -133.424136) (xy 67.514742 -133.483592)
			(xy 67.515232 -133.513576) (xy 67.515232 -134.369302) (xy 81.07426 -134.369302) (xy 81.07426 -133.505702)
			(xy 81.07475 -133.475718) (xy 81.082578 -133.416262) (xy 81.098099 -133.358337) (xy 81.121048 -133.302933)
			(xy 81.151032 -133.250999) (xy 81.187538 -133.203423) (xy 81.229943 -133.161018) (xy 81.277519 -133.124512)
			(xy 81.329453 -133.094528) (xy 81.384857 -133.071579) (xy 81.442782 -133.056058) (xy 81.502238 -133.04823)
			(xy 81.562206 -133.04823) (xy 81.621662 -133.056058) (xy 81.679587 -133.071579) (xy 81.734991 -133.094528)
			(xy 81.752059 -133.104382) (xy 153.409904 -133.104382) (xy 153.409904 -132.240782) (xy 153.410394 -132.210798)
			(xy 153.418222 -132.151342) (xy 153.433743 -132.093417) (xy 153.456692 -132.038013) (xy 153.486676 -131.986079)
			(xy 153.523182 -131.938503) (xy 153.565587 -131.896098) (xy 153.613163 -131.859592) (xy 153.665097 -131.829608)
			(xy 153.720501 -131.806659) (xy 153.778426 -131.791138) (xy 153.837882 -131.78331) (xy 153.89785 -131.78331)
			(xy 153.957306 -131.791138) (xy 154.015231 -131.806659) (xy 154.070635 -131.829608) (xy 154.122569 -131.859592)
			(xy 154.170145 -131.896098) (xy 154.21255 -131.938503) (xy 154.249056 -131.986079) (xy 154.27904 -132.038013)
			(xy 154.301989 -132.093417) (xy 154.31751 -132.151342) (xy 154.325338 -132.210798) (xy 154.325828 -132.240782)
			(xy 154.325828 -133.096508) (xy 167.884856 -133.096508) (xy 167.884856 -132.232908) (xy 167.885346 -132.202924)
			(xy 167.893174 -132.143468) (xy 167.908695 -132.085543) (xy 167.931644 -132.030139) (xy 167.961628 -131.978205)
			(xy 167.998134 -131.930629) (xy 168.040539 -131.888224) (xy 168.088115 -131.851718) (xy 168.140049 -131.821734)
			(xy 168.195453 -131.798785) (xy 168.253378 -131.783264) (xy 168.312834 -131.775436) (xy 168.372802 -131.775436)
			(xy 168.432258 -131.783264) (xy 168.490183 -131.798785) (xy 168.545587 -131.821734) (xy 168.597521 -131.851718)
			(xy 168.645097 -131.888224) (xy 168.687502 -131.930629) (xy 168.724008 -131.978205) (xy 168.753992 -132.030139)
			(xy 168.776941 -132.085543) (xy 168.792462 -132.143468) (xy 168.80029 -132.202924) (xy 168.80078 -132.232908)
			(xy 168.80078 -132.577332) (xy 180.84546 -132.577332) (xy 180.84546 -131.713732) (xy 180.84595 -131.683764)
			(xy 180.853773 -131.624342) (xy 180.869286 -131.566449) (xy 180.892222 -131.511076) (xy 180.922189 -131.45917)
			(xy 180.958676 -131.41162) (xy 181.001056 -131.36924) (xy 181.048606 -131.332753) (xy 181.100512 -131.302786)
			(xy 181.155885 -131.27985) (xy 181.213778 -131.264337) (xy 181.2732 -131.256514) (xy 181.333136 -131.256514)
			(xy 181.392558 -131.264337) (xy 181.450451 -131.27985) (xy 181.505824 -131.302786) (xy 181.55773 -131.332753)
			(xy 181.60528 -131.36924) (xy 181.64766 -131.41162) (xy 181.684147 -131.45917) (xy 181.714114 -131.511076)
			(xy 181.73705 -131.566449) (xy 181.752563 -131.624342) (xy 181.760386 -131.683764) (xy 181.760876 -131.713732)
			(xy 181.760876 -132.575808) (xy 199.81672 -132.575808) (xy 199.81672 -131.712208) (xy 199.81721 -131.68224)
			(xy 199.825033 -131.622818) (xy 199.840546 -131.564925) (xy 199.863482 -131.509552) (xy 199.893449 -131.457646)
			(xy 199.929936 -131.410096) (xy 199.972316 -131.367716) (xy 200.019866 -131.331229) (xy 200.071772 -131.301262)
			(xy 200.127145 -131.278326) (xy 200.185038 -131.262813) (xy 200.24446 -131.25499) (xy 200.304396 -131.25499)
			(xy 200.363818 -131.262813) (xy 200.421711 -131.278326) (xy 200.469049 -131.297934) (xy 266.86764 -131.297934)
			(xy 266.86764 -130.434334) (xy 266.86813 -130.40435) (xy 266.875958 -130.344894) (xy 266.891479 -130.286969)
			(xy 266.914428 -130.231565) (xy 266.944412 -130.179631) (xy 266.980918 -130.132055) (xy 267.023323 -130.08965)
			(xy 267.070899 -130.053144) (xy 267.122833 -130.02316) (xy 267.178237 -130.000211) (xy 267.236162 -129.98469)
			(xy 267.295618 -129.976862) (xy 267.355586 -129.976862) (xy 267.415042 -129.98469) (xy 267.472967 -130.000211)
			(xy 267.528371 -130.02316) (xy 267.580305 -130.053144) (xy 267.627881 -130.08965) (xy 267.670286 -130.132055)
			(xy 267.706792 -130.179631) (xy 267.736776 -130.231565) (xy 267.759725 -130.286969) (xy 267.775246 -130.344894)
			(xy 267.783074 -130.40435) (xy 267.783564 -130.434334) (xy 267.783564 -131.29641) (xy 285.8389 -131.29641)
			(xy 285.8389 -130.43281) (xy 285.83939 -130.402826) (xy 285.847218 -130.34337) (xy 285.862739 -130.285445)
			(xy 285.885688 -130.230041) (xy 285.915672 -130.178107) (xy 285.952178 -130.130531) (xy 285.994583 -130.088126)
			(xy 286.042159 -130.05162) (xy 286.094093 -130.021636) (xy 286.149497 -129.998687) (xy 286.207422 -129.983166)
			(xy 286.266878 -129.975338) (xy 286.326846 -129.975338) (xy 286.386302 -129.983166) (xy 286.444227 -129.998687)
			(xy 286.499631 -130.021636) (xy 286.551565 -130.05162) (xy 286.599141 -130.088126) (xy 286.641546 -130.130531)
			(xy 286.678052 -130.178107) (xy 286.708036 -130.230041) (xy 286.730985 -130.285445) (xy 286.746506 -130.34337)
			(xy 286.754334 -130.402826) (xy 286.754824 -130.43281) (xy 286.754824 -130.777234) (xy 298.799504 -130.777234)
			(xy 298.799504 -129.913634) (xy 298.799994 -129.883666) (xy 298.807817 -129.824244) (xy 298.82333 -129.766351)
			(xy 298.846266 -129.710978) (xy 298.876233 -129.659072) (xy 298.91272 -129.611522) (xy 298.9551 -129.569142)
			(xy 299.00265 -129.532655) (xy 299.054556 -129.502688) (xy 299.109929 -129.479752) (xy 299.167822 -129.464239)
			(xy 299.227244 -129.456416) (xy 299.28718 -129.456416) (xy 299.346602 -129.464239) (xy 299.404495 -129.479752)
			(xy 299.459868 -129.502688) (xy 299.511774 -129.532655) (xy 299.559324 -129.569142) (xy 299.601704 -129.611522)
			(xy 299.638191 -129.659072) (xy 299.668158 -129.710978) (xy 299.691094 -129.766351) (xy 299.706607 -129.824244)
			(xy 299.71443 -129.883666) (xy 299.71492 -129.913634) (xy 299.71492 -130.769106) (xy 313.274456 -130.769106)
			(xy 313.274456 -129.905506) (xy 313.274946 -129.875538) (xy 313.282769 -129.816116) (xy 313.298282 -129.758223)
			(xy 313.321218 -129.70285) (xy 313.351185 -129.650944) (xy 313.387672 -129.603394) (xy 313.430052 -129.561014)
			(xy 313.477602 -129.524527) (xy 313.529508 -129.49456) (xy 313.584881 -129.471624) (xy 313.642774 -129.456111)
			(xy 313.702196 -129.448288) (xy 313.762132 -129.448288) (xy 313.821554 -129.456111) (xy 313.879447 -129.471624)
			(xy 313.93482 -129.49456) (xy 313.986726 -129.524527) (xy 314.034276 -129.561014) (xy 314.076656 -129.603394)
			(xy 314.113143 -129.650944) (xy 314.14311 -129.70285) (xy 314.166046 -129.758223) (xy 314.181559 -129.816116)
			(xy 314.189382 -129.875538) (xy 314.189872 -129.905506) (xy 314.189872 -130.769106) (xy 314.189382 -130.799074)
			(xy 314.181559 -130.858496) (xy 314.166046 -130.916389) (xy 314.14311 -130.971762) (xy 314.113143 -131.023668)
			(xy 314.076656 -131.071218) (xy 314.034276 -131.113598) (xy 313.986726 -131.150085) (xy 313.93482 -131.180052)
			(xy 313.879447 -131.202988) (xy 313.821554 -131.218501) (xy 313.762132 -131.226324) (xy 313.702196 -131.226324)
			(xy 313.642774 -131.218501) (xy 313.584881 -131.202988) (xy 313.529508 -131.180052) (xy 313.477602 -131.150085)
			(xy 313.430052 -131.113598) (xy 313.387672 -131.071218) (xy 313.351185 -131.023668) (xy 313.321218 -130.971762)
			(xy 313.298282 -130.916389) (xy 313.282769 -130.858496) (xy 313.274946 -130.799074) (xy 313.274456 -130.769106)
			(xy 299.71492 -130.769106) (xy 299.71492 -130.777234) (xy 299.71443 -130.807202) (xy 299.706607 -130.866624)
			(xy 299.691094 -130.924517) (xy 299.668158 -130.97989) (xy 299.638191 -131.031796) (xy 299.601704 -131.079346)
			(xy 299.559324 -131.121726) (xy 299.511774 -131.158213) (xy 299.459868 -131.18818) (xy 299.404495 -131.211116)
			(xy 299.346602 -131.226629) (xy 299.28718 -131.234452) (xy 299.227244 -131.234452) (xy 299.167822 -131.226629)
			(xy 299.109929 -131.211116) (xy 299.054556 -131.18818) (xy 299.00265 -131.158213) (xy 298.9551 -131.121726)
			(xy 298.91272 -131.079346) (xy 298.876233 -131.031796) (xy 298.846266 -130.97989) (xy 298.82333 -130.924517)
			(xy 298.807817 -130.866624) (xy 298.799994 -130.807202) (xy 298.799504 -130.777234) (xy 286.754824 -130.777234)
			(xy 286.754824 -131.29641) (xy 286.754334 -131.326394) (xy 286.746506 -131.38585) (xy 286.730985 -131.443775)
			(xy 286.708036 -131.499179) (xy 286.678052 -131.551113) (xy 286.641546 -131.598689) (xy 286.599141 -131.641094)
			(xy 286.551565 -131.6776) (xy 286.499631 -131.707584) (xy 286.444227 -131.730533) (xy 286.386302 -131.746054)
			(xy 286.326846 -131.753882) (xy 286.266878 -131.753882) (xy 286.207422 -131.746054) (xy 286.149497 -131.730533)
			(xy 286.094093 -131.707584) (xy 286.042159 -131.6776) (xy 285.994583 -131.641094) (xy 285.952178 -131.598689)
			(xy 285.915672 -131.551113) (xy 285.885688 -131.499179) (xy 285.862739 -131.443775) (xy 285.847218 -131.38585)
			(xy 285.83939 -131.326394) (xy 285.8389 -131.29641) (xy 267.783564 -131.29641) (xy 267.783564 -131.297934)
			(xy 267.783074 -131.327918) (xy 267.775246 -131.387374) (xy 267.759725 -131.445299) (xy 267.736776 -131.500703)
			(xy 267.706792 -131.552637) (xy 267.670286 -131.600213) (xy 267.627881 -131.642618) (xy 267.580305 -131.679124)
			(xy 267.528371 -131.709108) (xy 267.472967 -131.732057) (xy 267.415042 -131.747578) (xy 267.355586 -131.755406)
			(xy 267.295618 -131.755406) (xy 267.236162 -131.747578) (xy 267.178237 -131.732057) (xy 267.122833 -131.709108)
			(xy 267.070899 -131.679124) (xy 267.023323 -131.642618) (xy 266.980918 -131.600213) (xy 266.944412 -131.552637)
			(xy 266.914428 -131.500703) (xy 266.891479 -131.445299) (xy 266.875958 -131.387374) (xy 266.86813 -131.327918)
			(xy 266.86764 -131.297934) (xy 200.469049 -131.297934) (xy 200.477084 -131.301262) (xy 200.52899 -131.331229)
			(xy 200.57654 -131.367716) (xy 200.61892 -131.410096) (xy 200.655407 -131.457646) (xy 200.685374 -131.509552)
			(xy 200.70831 -131.564925) (xy 200.723823 -131.622818) (xy 200.731646 -131.68224) (xy 200.732136 -131.712208)
			(xy 200.732136 -132.575808) (xy 200.731646 -132.605776) (xy 200.723823 -132.665198) (xy 200.70831 -132.723091)
			(xy 200.685374 -132.778464) (xy 200.655407 -132.83037) (xy 200.61892 -132.87792) (xy 200.57654 -132.9203)
			(xy 200.52899 -132.956787) (xy 200.477084 -132.986754) (xy 200.421711 -133.00969) (xy 200.363818 -133.025203)
			(xy 200.304396 -133.033026) (xy 200.24446 -133.033026) (xy 200.185038 -133.025203) (xy 200.127145 -133.00969)
			(xy 200.071772 -132.986754) (xy 200.019866 -132.956787) (xy 199.972316 -132.9203) (xy 199.929936 -132.87792)
			(xy 199.893449 -132.83037) (xy 199.863482 -132.778464) (xy 199.840546 -132.723091) (xy 199.825033 -132.665198)
			(xy 199.81721 -132.605776) (xy 199.81672 -132.575808) (xy 181.760876 -132.575808) (xy 181.760876 -132.577332)
			(xy 181.760386 -132.6073) (xy 181.752563 -132.666722) (xy 181.73705 -132.724615) (xy 181.714114 -132.779988)
			(xy 181.684147 -132.831894) (xy 181.64766 -132.879444) (xy 181.60528 -132.921824) (xy 181.55773 -132.958311)
			(xy 181.505824 -132.988278) (xy 181.450451 -133.011214) (xy 181.392558 -133.026727) (xy 181.333136 -133.03455)
			(xy 181.2732 -133.03455) (xy 181.213778 -133.026727) (xy 181.155885 -133.011214) (xy 181.100512 -132.988278)
			(xy 181.048606 -132.958311) (xy 181.001056 -132.921824) (xy 180.958676 -132.879444) (xy 180.922189 -132.831894)
			(xy 180.892222 -132.779988) (xy 180.869286 -132.724615) (xy 180.853773 -132.666722) (xy 180.84595 -132.6073)
			(xy 180.84546 -132.577332) (xy 168.80078 -132.577332) (xy 168.80078 -133.096508) (xy 168.80029 -133.126492)
			(xy 168.792462 -133.185948) (xy 168.776941 -133.243873) (xy 168.753992 -133.299277) (xy 168.724008 -133.351211)
			(xy 168.687502 -133.398787) (xy 168.645097 -133.441192) (xy 168.597521 -133.477698) (xy 168.545587 -133.507682)
			(xy 168.490183 -133.530631) (xy 168.432258 -133.546152) (xy 168.372802 -133.55398) (xy 168.312834 -133.55398)
			(xy 168.253378 -133.546152) (xy 168.195453 -133.530631) (xy 168.140049 -133.507682) (xy 168.088115 -133.477698)
			(xy 168.040539 -133.441192) (xy 167.998134 -133.398787) (xy 167.961628 -133.351211) (xy 167.931644 -133.299277)
			(xy 167.908695 -133.243873) (xy 167.893174 -133.185948) (xy 167.885346 -133.126492) (xy 167.884856 -133.096508)
			(xy 154.325828 -133.096508) (xy 154.325828 -133.104382) (xy 154.325338 -133.134366) (xy 154.31751 -133.193822)
			(xy 154.301989 -133.251747) (xy 154.27904 -133.307151) (xy 154.249056 -133.359085) (xy 154.21255 -133.406661)
			(xy 154.170145 -133.449066) (xy 154.122569 -133.485572) (xy 154.070635 -133.515556) (xy 154.015231 -133.538505)
			(xy 153.957306 -133.554026) (xy 153.89785 -133.561854) (xy 153.837882 -133.561854) (xy 153.778426 -133.554026)
			(xy 153.720501 -133.538505) (xy 153.665097 -133.515556) (xy 153.613163 -133.485572) (xy 153.565587 -133.449066)
			(xy 153.523182 -133.406661) (xy 153.486676 -133.359085) (xy 153.456692 -133.307151) (xy 153.433743 -133.251747)
			(xy 153.418222 -133.193822) (xy 153.410394 -133.134366) (xy 153.409904 -133.104382) (xy 81.752059 -133.104382)
			(xy 81.786925 -133.124512) (xy 81.834501 -133.161018) (xy 81.876906 -133.203423) (xy 81.913412 -133.250999)
			(xy 81.943396 -133.302933) (xy 81.966345 -133.358337) (xy 81.981866 -133.416262) (xy 81.989694 -133.475718)
			(xy 81.990184 -133.505702) (xy 81.990184 -134.369302) (xy 81.989694 -134.399286) (xy 81.981866 -134.458742)
			(xy 81.966345 -134.516667) (xy 81.943396 -134.572071) (xy 81.913412 -134.624005) (xy 81.876906 -134.671581)
			(xy 81.834501 -134.713986) (xy 81.786925 -134.750492) (xy 81.734991 -134.780476) (xy 81.679587 -134.803425)
			(xy 81.621662 -134.818946) (xy 81.562206 -134.826774) (xy 81.502238 -134.826774) (xy 81.442782 -134.818946)
			(xy 81.384857 -134.803425) (xy 81.329453 -134.780476) (xy 81.277519 -134.750492) (xy 81.229943 -134.713986)
			(xy 81.187538 -134.671581) (xy 81.151032 -134.624005) (xy 81.121048 -134.572071) (xy 81.098099 -134.516667)
			(xy 81.082578 -134.458742) (xy 81.07475 -134.399286) (xy 81.07426 -134.369302) (xy 67.515232 -134.369302)
			(xy 67.515232 -134.377176) (xy 67.514742 -134.40716) (xy 67.506914 -134.466616) (xy 67.491393 -134.524541)
			(xy 67.468444 -134.579945) (xy 67.43846 -134.631879) (xy 67.401954 -134.679455) (xy 67.359549 -134.72186)
			(xy 67.311973 -134.758366) (xy 67.260039 -134.78835) (xy 67.204635 -134.811299) (xy 67.14671 -134.82682)
			(xy 67.087254 -134.834648) (xy 67.027286 -134.834648) (xy 66.96783 -134.82682) (xy 66.909905 -134.811299)
			(xy 66.854501 -134.78835) (xy 66.802567 -134.758366) (xy 66.754991 -134.72186) (xy 66.712586 -134.679455)
			(xy 66.67608 -134.631879) (xy 66.646096 -134.579945) (xy 66.623147 -134.524541) (xy 66.607626 -134.466616)
			(xy 66.599798 -134.40716) (xy 66.599308 -134.377176) (xy 54.554628 -134.377176) (xy 54.554628 -134.896352)
			(xy 54.554138 -134.92632) (xy 54.546315 -134.985742) (xy 54.530802 -135.043635) (xy 54.507866 -135.099008)
			(xy 54.477899 -135.150914) (xy 54.441412 -135.198464) (xy 54.399032 -135.240844) (xy 54.351482 -135.277331)
			(xy 54.299576 -135.307298) (xy 54.244203 -135.330234) (xy 54.18631 -135.345747) (xy 54.126888 -135.35357)
			(xy 54.066952 -135.35357) (xy 54.00753 -135.345747) (xy 53.949637 -135.330234) (xy 53.894264 -135.307298)
			(xy 53.842358 -135.277331) (xy 53.794808 -135.240844) (xy 53.752428 -135.198464) (xy 53.715941 -135.150914)
			(xy 53.685974 -135.099008) (xy 53.663038 -135.043635) (xy 53.647525 -134.985742) (xy 53.639702 -134.92632)
			(xy 53.639212 -134.896352) (xy 35.583368 -134.896352) (xy 35.583368 -134.897876) (xy 35.582878 -134.927844)
			(xy 35.575055 -134.987266) (xy 35.559542 -135.045159) (xy 35.536606 -135.100532) (xy 35.506639 -135.152438)
			(xy 35.470152 -135.199988) (xy 35.427772 -135.242368) (xy 35.380222 -135.278855) (xy 35.328316 -135.308822)
			(xy 35.272943 -135.331758) (xy 35.21505 -135.347271) (xy 35.155628 -135.355094) (xy 35.095692 -135.355094)
			(xy 35.03627 -135.347271) (xy 34.978377 -135.331758) (xy 34.923004 -135.308822) (xy 34.871098 -135.278855)
			(xy 34.823548 -135.242368) (xy 34.781168 -135.199988) (xy 34.744681 -135.152438) (xy 34.714714 -135.100532)
			(xy 34.691778 -135.045159) (xy 34.676265 -134.987266) (xy 34.668442 -134.927844) (xy 34.667952 -134.897876)
			(xy 5.324094 -134.897876) (xy 5.324094 -136.704324) (xy 37.31006 -136.704324) (xy 37.31006 -135.840724)
			(xy 37.31055 -135.810756) (xy 37.318373 -135.751334) (xy 37.333886 -135.693441) (xy 37.356822 -135.638068)
			(xy 37.386789 -135.586162) (xy 37.423276 -135.538612) (xy 37.465656 -135.496232) (xy 37.513206 -135.459745)
			(xy 37.565112 -135.429778) (xy 37.620485 -135.406842) (xy 37.678378 -135.391329) (xy 37.7378 -135.383506)
			(xy 37.797736 -135.383506) (xy 37.857158 -135.391329) (xy 37.915051 -135.406842) (xy 37.970424 -135.429778)
			(xy 38.02233 -135.459745) (xy 38.06988 -135.496232) (xy 38.11226 -135.538612) (xy 38.148747 -135.586162)
			(xy 38.178714 -135.638068) (xy 38.20165 -135.693441) (xy 38.217163 -135.751334) (xy 38.224986 -135.810756)
			(xy 38.225476 -135.840724) (xy 38.225476 -136.69645) (xy 51.785012 -136.69645) (xy 51.785012 -135.83285)
			(xy 51.785502 -135.802882) (xy 51.793325 -135.74346) (xy 51.808838 -135.685567) (xy 51.831774 -135.630194)
			(xy 51.861741 -135.578288) (xy 51.898228 -135.530738) (xy 51.940608 -135.488358) (xy 51.988158 -135.451871)
			(xy 52.040064 -135.421904) (xy 52.095437 -135.398968) (xy 52.15333 -135.383455) (xy 52.212752 -135.375632)
			(xy 52.272688 -135.375632) (xy 52.33211 -135.383455) (xy 52.390003 -135.398968) (xy 52.445376 -135.421904)
			(xy 52.497282 -135.451871) (xy 52.544832 -135.488358) (xy 52.587212 -135.530738) (xy 52.623699 -135.578288)
			(xy 52.653666 -135.630194) (xy 52.676602 -135.685567) (xy 52.692115 -135.74346) (xy 52.699938 -135.802882)
			(xy 52.700428 -135.83285) (xy 52.700428 -136.177274) (xy 64.745108 -136.177274) (xy 64.745108 -135.313674)
			(xy 64.745598 -135.28369) (xy 64.753426 -135.224234) (xy 64.768947 -135.166309) (xy 64.791896 -135.110905)
			(xy 64.82188 -135.058971) (xy 64.858386 -135.011395) (xy 64.900791 -134.96899) (xy 64.948367 -134.932484)
			(xy 65.000301 -134.9025) (xy 65.055705 -134.879551) (xy 65.11363 -134.86403) (xy 65.173086 -134.856202)
			(xy 65.233054 -134.856202) (xy 65.29251 -134.86403) (xy 65.350435 -134.879551) (xy 65.405839 -134.9025)
			(xy 65.457773 -134.932484) (xy 65.505349 -134.96899) (xy 65.547754 -135.011395) (xy 65.58426 -135.058971)
			(xy 65.614244 -135.110905) (xy 65.637193 -135.166309) (xy 65.652714 -135.224234) (xy 65.660542 -135.28369)
			(xy 65.661032 -135.313674) (xy 65.661032 -136.17575) (xy 83.716368 -136.17575) (xy 83.716368 -135.31215)
			(xy 83.716858 -135.282166) (xy 83.724686 -135.22271) (xy 83.740207 -135.164785) (xy 83.763156 -135.109381)
			(xy 83.79314 -135.057447) (xy 83.829646 -135.009871) (xy 83.872051 -134.967466) (xy 83.919627 -134.93096)
			(xy 83.971561 -134.900976) (xy 84.026965 -134.878027) (xy 84.08489 -134.862506) (xy 84.144346 -134.854678)
			(xy 84.204314 -134.854678) (xy 84.26377 -134.862506) (xy 84.321695 -134.878027) (xy 84.369615 -134.897876)
			(xy 150.767796 -134.897876) (xy 150.767796 -134.034276) (xy 150.768286 -134.004292) (xy 150.776114 -133.944836)
			(xy 150.791635 -133.886911) (xy 150.814584 -133.831507) (xy 150.844568 -133.779573) (xy 150.881074 -133.731997)
			(xy 150.923479 -133.689592) (xy 150.971055 -133.653086) (xy 151.022989 -133.623102) (xy 151.078393 -133.600153)
			(xy 151.136318 -133.584632) (xy 151.195774 -133.576804) (xy 151.255742 -133.576804) (xy 151.315198 -133.584632)
			(xy 151.373123 -133.600153) (xy 151.428527 -133.623102) (xy 151.480461 -133.653086) (xy 151.528037 -133.689592)
			(xy 151.570442 -133.731997) (xy 151.606948 -133.779573) (xy 151.636932 -133.831507) (xy 151.659881 -133.886911)
			(xy 151.675402 -133.944836) (xy 151.68323 -134.004292) (xy 151.68372 -134.034276) (xy 151.68372 -134.896352)
			(xy 169.739056 -134.896352) (xy 169.739056 -134.032752) (xy 169.739546 -134.002768) (xy 169.747374 -133.943312)
			(xy 169.762895 -133.885387) (xy 169.785844 -133.829983) (xy 169.815828 -133.778049) (xy 169.852334 -133.730473)
			(xy 169.894739 -133.688068) (xy 169.942315 -133.651562) (xy 169.994249 -133.621578) (xy 170.049653 -133.598629)
			(xy 170.107578 -133.583108) (xy 170.167034 -133.57528) (xy 170.227002 -133.57528) (xy 170.286458 -133.583108)
			(xy 170.344383 -133.598629) (xy 170.399787 -133.621578) (xy 170.451721 -133.651562) (xy 170.499297 -133.688068)
			(xy 170.541702 -133.730473) (xy 170.578208 -133.778049) (xy 170.608192 -133.829983) (xy 170.631141 -133.885387)
			(xy 170.646662 -133.943312) (xy 170.65449 -134.002768) (xy 170.65498 -134.032752) (xy 170.65498 -134.377176)
			(xy 182.69966 -134.377176) (xy 182.69966 -133.513576) (xy 182.70015 -133.483608) (xy 182.707973 -133.424186)
			(xy 182.723486 -133.366293) (xy 182.746422 -133.31092) (xy 182.776389 -133.259014) (xy 182.812876 -133.211464)
			(xy 182.855256 -133.169084) (xy 182.902806 -133.132597) (xy 182.954712 -133.10263) (xy 183.010085 -133.079694)
			(xy 183.067978 -133.064181) (xy 183.1274 -133.056358) (xy 183.187336 -133.056358) (xy 183.246758 -133.064181)
			(xy 183.304651 -133.079694) (xy 183.360024 -133.10263) (xy 183.41193 -133.132597) (xy 183.45948 -133.169084)
			(xy 183.50186 -133.211464) (xy 183.538347 -133.259014) (xy 183.568314 -133.31092) (xy 183.59125 -133.366293)
			(xy 183.606763 -133.424186) (xy 183.614586 -133.483608) (xy 183.615076 -133.513576) (xy 183.615076 -134.369302)
			(xy 197.174612 -134.369302) (xy 197.174612 -133.505702) (xy 197.175102 -133.475734) (xy 197.182925 -133.416312)
			(xy 197.198438 -133.358419) (xy 197.221374 -133.303046) (xy 197.251341 -133.25114) (xy 197.287828 -133.20359)
			(xy 197.330208 -133.16121) (xy 197.377758 -133.124723) (xy 197.429664 -133.094756) (xy 197.485037 -133.07182)
			(xy 197.54293 -133.056307) (xy 197.602352 -133.048484) (xy 197.662288 -133.048484) (xy 197.72171 -133.056307)
			(xy 197.779603 -133.07182) (xy 197.834976 -133.094756) (xy 197.851649 -133.104382) (xy 269.509748 -133.104382)
			(xy 269.509748 -132.240782) (xy 269.510238 -132.210798) (xy 269.518066 -132.151342) (xy 269.533587 -132.093417)
			(xy 269.556536 -132.038013) (xy 269.58652 -131.986079) (xy 269.623026 -131.938503) (xy 269.665431 -131.896098)
			(xy 269.713007 -131.859592) (xy 269.764941 -131.829608) (xy 269.820345 -131.806659) (xy 269.87827 -131.791138)
			(xy 269.937726 -131.78331) (xy 269.997694 -131.78331) (xy 270.05715 -131.791138) (xy 270.115075 -131.806659)
			(xy 270.170479 -131.829608) (xy 270.222413 -131.859592) (xy 270.269989 -131.896098) (xy 270.312394 -131.938503)
			(xy 270.3489 -131.986079) (xy 270.378884 -132.038013) (xy 270.401833 -132.093417) (xy 270.417354 -132.151342)
			(xy 270.425182 -132.210798) (xy 270.425672 -132.240782) (xy 270.425672 -133.096508) (xy 283.9847 -133.096508)
			(xy 283.9847 -132.232908) (xy 283.98519 -132.202924) (xy 283.993018 -132.143468) (xy 284.008539 -132.085543)
			(xy 284.031488 -132.030139) (xy 284.061472 -131.978205) (xy 284.097978 -131.930629) (xy 284.140383 -131.888224)
			(xy 284.187959 -131.851718) (xy 284.239893 -131.821734) (xy 284.295297 -131.798785) (xy 284.353222 -131.783264)
			(xy 284.412678 -131.775436) (xy 284.472646 -131.775436) (xy 284.532102 -131.783264) (xy 284.590027 -131.798785)
			(xy 284.645431 -131.821734) (xy 284.697365 -131.851718) (xy 284.744941 -131.888224) (xy 284.787346 -131.930629)
			(xy 284.823852 -131.978205) (xy 284.853836 -132.030139) (xy 284.876785 -132.085543) (xy 284.892306 -132.143468)
			(xy 284.900134 -132.202924) (xy 284.900624 -132.232908) (xy 284.900624 -132.577332) (xy 296.945304 -132.577332)
			(xy 296.945304 -131.713732) (xy 296.945794 -131.683764) (xy 296.953617 -131.624342) (xy 296.96913 -131.566449)
			(xy 296.992066 -131.511076) (xy 297.022033 -131.45917) (xy 297.05852 -131.41162) (xy 297.1009 -131.36924)
			(xy 297.14845 -131.332753) (xy 297.200356 -131.302786) (xy 297.255729 -131.27985) (xy 297.313622 -131.264337)
			(xy 297.373044 -131.256514) (xy 297.43298 -131.256514) (xy 297.492402 -131.264337) (xy 297.550295 -131.27985)
			(xy 297.605668 -131.302786) (xy 297.657574 -131.332753) (xy 297.705124 -131.36924) (xy 297.747504 -131.41162)
			(xy 297.783991 -131.45917) (xy 297.813958 -131.511076) (xy 297.836894 -131.566449) (xy 297.852407 -131.624342)
			(xy 297.86023 -131.683764) (xy 297.86072 -131.713732) (xy 297.86072 -132.575808) (xy 315.916564 -132.575808)
			(xy 315.916564 -131.712208) (xy 315.917054 -131.68224) (xy 315.924877 -131.622818) (xy 315.94039 -131.564925)
			(xy 315.963326 -131.509552) (xy 315.993293 -131.457646) (xy 316.02978 -131.410096) (xy 316.07216 -131.367716)
			(xy 316.11971 -131.331229) (xy 316.171616 -131.301262) (xy 316.226989 -131.278326) (xy 316.284882 -131.262813)
			(xy 316.344304 -131.25499) (xy 316.40424 -131.25499) (xy 316.463662 -131.262813) (xy 316.521555 -131.278326)
			(xy 316.568893 -131.297934) (xy 382.967992 -131.297934) (xy 382.967992 -130.434334) (xy 382.968482 -130.404366)
			(xy 382.976305 -130.344944) (xy 382.991818 -130.287051) (xy 383.014754 -130.231678) (xy 383.044721 -130.179772)
			(xy 383.081208 -130.132222) (xy 383.123588 -130.089842) (xy 383.171138 -130.053355) (xy 383.223044 -130.023388)
			(xy 383.278417 -130.000452) (xy 383.33631 -129.984939) (xy 383.395732 -129.977116) (xy 383.455668 -129.977116)
			(xy 383.51509 -129.984939) (xy 383.572983 -130.000452) (xy 383.628356 -130.023388) (xy 383.680262 -130.053355)
			(xy 383.727812 -130.089842) (xy 383.770192 -130.132222) (xy 383.806679 -130.179772) (xy 383.836646 -130.231678)
			(xy 383.859582 -130.287051) (xy 383.875095 -130.344944) (xy 383.882918 -130.404366) (xy 383.883408 -130.434334)
			(xy 383.883408 -131.29641) (xy 401.939252 -131.29641) (xy 401.939252 -130.43281) (xy 401.939742 -130.402842)
			(xy 401.947565 -130.34342) (xy 401.963078 -130.285527) (xy 401.986014 -130.230154) (xy 402.015981 -130.178248)
			(xy 402.052468 -130.130698) (xy 402.094848 -130.088318) (xy 402.142398 -130.051831) (xy 402.194304 -130.021864)
			(xy 402.249677 -129.998928) (xy 402.30757 -129.983415) (xy 402.366992 -129.975592) (xy 402.426928 -129.975592)
			(xy 402.48635 -129.983415) (xy 402.544243 -129.998928) (xy 402.599616 -130.021864) (xy 402.651522 -130.051831)
			(xy 402.699072 -130.088318) (xy 402.741452 -130.130698) (xy 402.777939 -130.178248) (xy 402.807906 -130.230154)
			(xy 402.830842 -130.285527) (xy 402.846355 -130.34342) (xy 402.854178 -130.402842) (xy 402.854668 -130.43281)
			(xy 402.854668 -130.777234) (xy 414.899348 -130.777234) (xy 414.899348 -129.913634) (xy 414.899838 -129.88365)
			(xy 414.907666 -129.824194) (xy 414.923187 -129.766269) (xy 414.946136 -129.710865) (xy 414.97612 -129.658931)
			(xy 415.012626 -129.611355) (xy 415.055031 -129.56895) (xy 415.102607 -129.532444) (xy 415.154541 -129.50246)
			(xy 415.209945 -129.479511) (xy 415.26787 -129.46399) (xy 415.327326 -129.456162) (xy 415.387294 -129.456162)
			(xy 415.44675 -129.46399) (xy 415.504675 -129.479511) (xy 415.560079 -129.50246) (xy 415.612013 -129.532444)
			(xy 415.659589 -129.56895) (xy 415.701994 -129.611355) (xy 415.7385 -129.658931) (xy 415.768484 -129.710865)
			(xy 415.791433 -129.766269) (xy 415.806954 -129.824194) (xy 415.814782 -129.88365) (xy 415.815272 -129.913634)
			(xy 415.815272 -130.769106) (xy 429.3743 -130.769106) (xy 429.3743 -129.905506) (xy 429.37479 -129.875522)
			(xy 429.382618 -129.816066) (xy 429.398139 -129.758141) (xy 429.421088 -129.702737) (xy 429.451072 -129.650803)
			(xy 429.487578 -129.603227) (xy 429.529983 -129.560822) (xy 429.577559 -129.524316) (xy 429.629493 -129.494332)
			(xy 429.684897 -129.471383) (xy 429.742822 -129.455862) (xy 429.802278 -129.448034) (xy 429.862246 -129.448034)
			(xy 429.921702 -129.455862) (xy 429.979627 -129.471383) (xy 430.035031 -129.494332) (xy 430.086965 -129.524316)
			(xy 430.134541 -129.560822) (xy 430.176946 -129.603227) (xy 430.213452 -129.650803) (xy 430.243436 -129.702737)
			(xy 430.266385 -129.758141) (xy 430.281906 -129.816066) (xy 430.289734 -129.875522) (xy 430.290224 -129.905506)
			(xy 430.290224 -130.769106) (xy 430.289734 -130.79909) (xy 430.281906 -130.858546) (xy 430.266385 -130.916471)
			(xy 430.243436 -130.971875) (xy 430.213452 -131.023809) (xy 430.176946 -131.071385) (xy 430.134541 -131.11379)
			(xy 430.086965 -131.150296) (xy 430.035031 -131.18028) (xy 429.979627 -131.203229) (xy 429.921702 -131.21875)
			(xy 429.862246 -131.226578) (xy 429.802278 -131.226578) (xy 429.742822 -131.21875) (xy 429.684897 -131.203229)
			(xy 429.629493 -131.18028) (xy 429.577559 -131.150296) (xy 429.529983 -131.11379) (xy 429.487578 -131.071385)
			(xy 429.451072 -131.023809) (xy 429.421088 -130.971875) (xy 429.398139 -130.916471) (xy 429.382618 -130.858546)
			(xy 429.37479 -130.79909) (xy 429.3743 -130.769106) (xy 415.815272 -130.769106) (xy 415.815272 -130.777234)
			(xy 415.814782 -130.807218) (xy 415.806954 -130.866674) (xy 415.791433 -130.924599) (xy 415.768484 -130.980003)
			(xy 415.7385 -131.031937) (xy 415.701994 -131.079513) (xy 415.659589 -131.121918) (xy 415.612013 -131.158424)
			(xy 415.560079 -131.188408) (xy 415.504675 -131.211357) (xy 415.44675 -131.226878) (xy 415.387294 -131.234706)
			(xy 415.327326 -131.234706) (xy 415.26787 -131.226878) (xy 415.209945 -131.211357) (xy 415.154541 -131.188408)
			(xy 415.102607 -131.158424) (xy 415.055031 -131.121918) (xy 415.012626 -131.079513) (xy 414.97612 -131.031937)
			(xy 414.946136 -130.980003) (xy 414.923187 -130.924599) (xy 414.907666 -130.866674) (xy 414.899838 -130.807218)
			(xy 414.899348 -130.777234) (xy 402.854668 -130.777234) (xy 402.854668 -131.29641) (xy 402.854178 -131.326378)
			(xy 402.846355 -131.3858) (xy 402.830842 -131.443693) (xy 402.807906 -131.499066) (xy 402.777939 -131.550972)
			(xy 402.741452 -131.598522) (xy 402.699072 -131.640902) (xy 402.651522 -131.677389) (xy 402.599616 -131.707356)
			(xy 402.544243 -131.730292) (xy 402.48635 -131.745805) (xy 402.426928 -131.753628) (xy 402.366992 -131.753628)
			(xy 402.30757 -131.745805) (xy 402.249677 -131.730292) (xy 402.194304 -131.707356) (xy 402.142398 -131.677389)
			(xy 402.094848 -131.640902) (xy 402.052468 -131.598522) (xy 402.015981 -131.550972) (xy 401.986014 -131.499066)
			(xy 401.963078 -131.443693) (xy 401.947565 -131.3858) (xy 401.939742 -131.326378) (xy 401.939252 -131.29641)
			(xy 383.883408 -131.29641) (xy 383.883408 -131.297934) (xy 383.882918 -131.327902) (xy 383.875095 -131.387324)
			(xy 383.859582 -131.445217) (xy 383.836646 -131.50059) (xy 383.806679 -131.552496) (xy 383.770192 -131.600046)
			(xy 383.727812 -131.642426) (xy 383.680262 -131.678913) (xy 383.628356 -131.70888) (xy 383.572983 -131.731816)
			(xy 383.51509 -131.747329) (xy 383.455668 -131.755152) (xy 383.395732 -131.755152) (xy 383.33631 -131.747329)
			(xy 383.278417 -131.731816) (xy 383.223044 -131.70888) (xy 383.171138 -131.678913) (xy 383.123588 -131.642426)
			(xy 383.081208 -131.600046) (xy 383.044721 -131.552496) (xy 383.014754 -131.50059) (xy 382.991818 -131.445217)
			(xy 382.976305 -131.387324) (xy 382.968482 -131.327902) (xy 382.967992 -131.297934) (xy 316.568893 -131.297934)
			(xy 316.576928 -131.301262) (xy 316.628834 -131.331229) (xy 316.676384 -131.367716) (xy 316.718764 -131.410096)
			(xy 316.755251 -131.457646) (xy 316.785218 -131.509552) (xy 316.808154 -131.564925) (xy 316.823667 -131.622818)
			(xy 316.83149 -131.68224) (xy 316.83198 -131.712208) (xy 316.83198 -132.575808) (xy 316.83149 -132.605776)
			(xy 316.823667 -132.665198) (xy 316.808154 -132.723091) (xy 316.785218 -132.778464) (xy 316.755251 -132.83037)
			(xy 316.718764 -132.87792) (xy 316.676384 -132.9203) (xy 316.628834 -132.956787) (xy 316.576928 -132.986754)
			(xy 316.521555 -133.00969) (xy 316.463662 -133.025203) (xy 316.40424 -133.033026) (xy 316.344304 -133.033026)
			(xy 316.284882 -133.025203) (xy 316.226989 -133.00969) (xy 316.171616 -132.986754) (xy 316.11971 -132.956787)
			(xy 316.07216 -132.9203) (xy 316.02978 -132.87792) (xy 315.993293 -132.83037) (xy 315.963326 -132.778464)
			(xy 315.94039 -132.723091) (xy 315.924877 -132.665198) (xy 315.917054 -132.605776) (xy 315.916564 -132.575808)
			(xy 297.86072 -132.575808) (xy 297.86072 -132.577332) (xy 297.86023 -132.6073) (xy 297.852407 -132.666722)
			(xy 297.836894 -132.724615) (xy 297.813958 -132.779988) (xy 297.783991 -132.831894) (xy 297.747504 -132.879444)
			(xy 297.705124 -132.921824) (xy 297.657574 -132.958311) (xy 297.605668 -132.988278) (xy 297.550295 -133.011214)
			(xy 297.492402 -133.026727) (xy 297.43298 -133.03455) (xy 297.373044 -133.03455) (xy 297.313622 -133.026727)
			(xy 297.255729 -133.011214) (xy 297.200356 -132.988278) (xy 297.14845 -132.958311) (xy 297.1009 -132.921824)
			(xy 297.05852 -132.879444) (xy 297.022033 -132.831894) (xy 296.992066 -132.779988) (xy 296.96913 -132.724615)
			(xy 296.953617 -132.666722) (xy 296.945794 -132.6073) (xy 296.945304 -132.577332) (xy 284.900624 -132.577332)
			(xy 284.900624 -133.096508) (xy 284.900134 -133.126492) (xy 284.892306 -133.185948) (xy 284.876785 -133.243873)
			(xy 284.853836 -133.299277) (xy 284.823852 -133.351211) (xy 284.787346 -133.398787) (xy 284.744941 -133.441192)
			(xy 284.697365 -133.477698) (xy 284.645431 -133.507682) (xy 284.590027 -133.530631) (xy 284.532102 -133.546152)
			(xy 284.472646 -133.55398) (xy 284.412678 -133.55398) (xy 284.353222 -133.546152) (xy 284.295297 -133.530631)
			(xy 284.239893 -133.507682) (xy 284.187959 -133.477698) (xy 284.140383 -133.441192) (xy 284.097978 -133.398787)
			(xy 284.061472 -133.351211) (xy 284.031488 -133.299277) (xy 284.008539 -133.243873) (xy 283.993018 -133.185948)
			(xy 283.98519 -133.126492) (xy 283.9847 -133.096508) (xy 270.425672 -133.096508) (xy 270.425672 -133.104382)
			(xy 270.425182 -133.134366) (xy 270.417354 -133.193822) (xy 270.401833 -133.251747) (xy 270.378884 -133.307151)
			(xy 270.3489 -133.359085) (xy 270.312394 -133.406661) (xy 270.269989 -133.449066) (xy 270.222413 -133.485572)
			(xy 270.170479 -133.515556) (xy 270.115075 -133.538505) (xy 270.05715 -133.554026) (xy 269.997694 -133.561854)
			(xy 269.937726 -133.561854) (xy 269.87827 -133.554026) (xy 269.820345 -133.538505) (xy 269.764941 -133.515556)
			(xy 269.713007 -133.485572) (xy 269.665431 -133.449066) (xy 269.623026 -133.406661) (xy 269.58652 -133.359085)
			(xy 269.556536 -133.307151) (xy 269.533587 -133.251747) (xy 269.518066 -133.193822) (xy 269.510238 -133.134366)
			(xy 269.509748 -133.104382) (xy 197.851649 -133.104382) (xy 197.886882 -133.124723) (xy 197.934432 -133.16121)
			(xy 197.976812 -133.20359) (xy 198.013299 -133.25114) (xy 198.043266 -133.303046) (xy 198.066202 -133.358419)
			(xy 198.081715 -133.416312) (xy 198.089538 -133.475734) (xy 198.090028 -133.505702) (xy 198.090028 -134.369302)
			(xy 198.089538 -134.39927) (xy 198.081715 -134.458692) (xy 198.066202 -134.516585) (xy 198.043266 -134.571958)
			(xy 198.013299 -134.623864) (xy 197.976812 -134.671414) (xy 197.934432 -134.713794) (xy 197.886882 -134.750281)
			(xy 197.834976 -134.780248) (xy 197.779603 -134.803184) (xy 197.72171 -134.818697) (xy 197.662288 -134.82652)
			(xy 197.602352 -134.82652) (xy 197.54293 -134.818697) (xy 197.485037 -134.803184) (xy 197.429664 -134.780248)
			(xy 197.377758 -134.750281) (xy 197.330208 -134.713794) (xy 197.287828 -134.671414) (xy 197.251341 -134.623864)
			(xy 197.221374 -134.571958) (xy 197.198438 -134.516585) (xy 197.182925 -134.458692) (xy 197.175102 -134.39927)
			(xy 197.174612 -134.369302) (xy 183.615076 -134.369302) (xy 183.615076 -134.377176) (xy 183.614586 -134.407144)
			(xy 183.606763 -134.466566) (xy 183.59125 -134.524459) (xy 183.568314 -134.579832) (xy 183.538347 -134.631738)
			(xy 183.50186 -134.679288) (xy 183.45948 -134.721668) (xy 183.41193 -134.758155) (xy 183.360024 -134.788122)
			(xy 183.304651 -134.811058) (xy 183.246758 -134.826571) (xy 183.187336 -134.834394) (xy 183.1274 -134.834394)
			(xy 183.067978 -134.826571) (xy 183.010085 -134.811058) (xy 182.954712 -134.788122) (xy 182.902806 -134.758155)
			(xy 182.855256 -134.721668) (xy 182.812876 -134.679288) (xy 182.776389 -134.631738) (xy 182.746422 -134.579832)
			(xy 182.723486 -134.524459) (xy 182.707973 -134.466566) (xy 182.70015 -134.407144) (xy 182.69966 -134.377176)
			(xy 170.65498 -134.377176) (xy 170.65498 -134.896352) (xy 170.65449 -134.926336) (xy 170.646662 -134.985792)
			(xy 170.631141 -135.043717) (xy 170.608192 -135.099121) (xy 170.578208 -135.151055) (xy 170.541702 -135.198631)
			(xy 170.499297 -135.241036) (xy 170.451721 -135.277542) (xy 170.399787 -135.307526) (xy 170.344383 -135.330475)
			(xy 170.286458 -135.345996) (xy 170.227002 -135.353824) (xy 170.167034 -135.353824) (xy 170.107578 -135.345996)
			(xy 170.049653 -135.330475) (xy 169.994249 -135.307526) (xy 169.942315 -135.277542) (xy 169.894739 -135.241036)
			(xy 169.852334 -135.198631) (xy 169.815828 -135.151055) (xy 169.785844 -135.099121) (xy 169.762895 -135.043717)
			(xy 169.747374 -134.985792) (xy 169.739546 -134.926336) (xy 169.739056 -134.896352) (xy 151.68372 -134.896352)
			(xy 151.68372 -134.897876) (xy 151.68323 -134.92786) (xy 151.675402 -134.987316) (xy 151.659881 -135.045241)
			(xy 151.636932 -135.100645) (xy 151.606948 -135.152579) (xy 151.570442 -135.200155) (xy 151.528037 -135.24256)
			(xy 151.480461 -135.279066) (xy 151.428527 -135.30905) (xy 151.373123 -135.331999) (xy 151.315198 -135.34752)
			(xy 151.255742 -135.355348) (xy 151.195774 -135.355348) (xy 151.136318 -135.34752) (xy 151.078393 -135.331999)
			(xy 151.022989 -135.30905) (xy 150.971055 -135.279066) (xy 150.923479 -135.24256) (xy 150.881074 -135.200155)
			(xy 150.844568 -135.152579) (xy 150.814584 -135.100645) (xy 150.791635 -135.045241) (xy 150.776114 -134.987316)
			(xy 150.768286 -134.92786) (xy 150.767796 -134.897876) (xy 84.369615 -134.897876) (xy 84.377099 -134.900976)
			(xy 84.429033 -134.93096) (xy 84.476609 -134.967466) (xy 84.519014 -135.009871) (xy 84.55552 -135.057447)
			(xy 84.585504 -135.109381) (xy 84.608453 -135.164785) (xy 84.623974 -135.22271) (xy 84.631802 -135.282166)
			(xy 84.632292 -135.31215) (xy 84.632292 -136.17575) (xy 84.631802 -136.205734) (xy 84.623974 -136.26519)
			(xy 84.608453 -136.323115) (xy 84.585504 -136.378519) (xy 84.55552 -136.430453) (xy 84.519014 -136.478029)
			(xy 84.476609 -136.520434) (xy 84.429033 -136.55694) (xy 84.377099 -136.586924) (xy 84.321695 -136.609873)
			(xy 84.26377 -136.625394) (xy 84.204314 -136.633222) (xy 84.144346 -136.633222) (xy 84.08489 -136.625394)
			(xy 84.026965 -136.609873) (xy 83.971561 -136.586924) (xy 83.919627 -136.55694) (xy 83.872051 -136.520434)
			(xy 83.829646 -136.478029) (xy 83.79314 -136.430453) (xy 83.763156 -136.378519) (xy 83.740207 -136.323115)
			(xy 83.724686 -136.26519) (xy 83.716858 -136.205734) (xy 83.716368 -136.17575) (xy 65.661032 -136.17575)
			(xy 65.661032 -136.177274) (xy 65.660542 -136.207258) (xy 65.652714 -136.266714) (xy 65.637193 -136.324639)
			(xy 65.614244 -136.380043) (xy 65.58426 -136.431977) (xy 65.547754 -136.479553) (xy 65.505349 -136.521958)
			(xy 65.457773 -136.558464) (xy 65.405839 -136.588448) (xy 65.350435 -136.611397) (xy 65.29251 -136.626918)
			(xy 65.233054 -136.634746) (xy 65.173086 -136.634746) (xy 65.11363 -136.626918) (xy 65.055705 -136.611397)
			(xy 65.000301 -136.588448) (xy 64.948367 -136.558464) (xy 64.900791 -136.521958) (xy 64.858386 -136.479553)
			(xy 64.82188 -136.431977) (xy 64.791896 -136.380043) (xy 64.768947 -136.324639) (xy 64.753426 -136.266714)
			(xy 64.745598 -136.207258) (xy 64.745108 -136.177274) (xy 52.700428 -136.177274) (xy 52.700428 -136.69645)
			(xy 52.700299 -136.704324) (xy 153.409904 -136.704324) (xy 153.409904 -135.840724) (xy 153.410394 -135.81074)
			(xy 153.418222 -135.751284) (xy 153.433743 -135.693359) (xy 153.456692 -135.637955) (xy 153.486676 -135.586021)
			(xy 153.523182 -135.538445) (xy 153.565587 -135.49604) (xy 153.613163 -135.459534) (xy 153.665097 -135.42955)
			(xy 153.720501 -135.406601) (xy 153.778426 -135.39108) (xy 153.837882 -135.383252) (xy 153.89785 -135.383252)
			(xy 153.957306 -135.39108) (xy 154.015231 -135.406601) (xy 154.070635 -135.42955) (xy 154.122569 -135.459534)
			(xy 154.170145 -135.49604) (xy 154.21255 -135.538445) (xy 154.249056 -135.586021) (xy 154.27904 -135.637955)
			(xy 154.301989 -135.693359) (xy 154.31751 -135.751284) (xy 154.325338 -135.81074) (xy 154.325828 -135.840724)
			(xy 154.325828 -136.69645) (xy 167.884856 -136.69645) (xy 167.884856 -135.83285) (xy 167.885346 -135.802866)
			(xy 167.893174 -135.74341) (xy 167.908695 -135.685485) (xy 167.931644 -135.630081) (xy 167.961628 -135.578147)
			(xy 167.998134 -135.530571) (xy 168.040539 -135.488166) (xy 168.088115 -135.45166) (xy 168.140049 -135.421676)
			(xy 168.195453 -135.398727) (xy 168.253378 -135.383206) (xy 168.312834 -135.375378) (xy 168.372802 -135.375378)
			(xy 168.432258 -135.383206) (xy 168.490183 -135.398727) (xy 168.545587 -135.421676) (xy 168.597521 -135.45166)
			(xy 168.645097 -135.488166) (xy 168.687502 -135.530571) (xy 168.724008 -135.578147) (xy 168.753992 -135.630081)
			(xy 168.776941 -135.685485) (xy 168.792462 -135.74341) (xy 168.80029 -135.802866) (xy 168.80078 -135.83285)
			(xy 168.80078 -136.177274) (xy 180.84546 -136.177274) (xy 180.84546 -135.313674) (xy 180.84595 -135.283706)
			(xy 180.853773 -135.224284) (xy 180.869286 -135.166391) (xy 180.892222 -135.111018) (xy 180.922189 -135.059112)
			(xy 180.958676 -135.011562) (xy 181.001056 -134.969182) (xy 181.048606 -134.932695) (xy 181.100512 -134.902728)
			(xy 181.155885 -134.879792) (xy 181.213778 -134.864279) (xy 181.2732 -134.856456) (xy 181.333136 -134.856456)
			(xy 181.392558 -134.864279) (xy 181.450451 -134.879792) (xy 181.505824 -134.902728) (xy 181.55773 -134.932695)
			(xy 181.60528 -134.969182) (xy 181.64766 -135.011562) (xy 181.684147 -135.059112) (xy 181.714114 -135.111018)
			(xy 181.73705 -135.166391) (xy 181.752563 -135.224284) (xy 181.760386 -135.283706) (xy 181.760876 -135.313674)
			(xy 181.760876 -136.17575) (xy 199.81672 -136.17575) (xy 199.81672 -135.31215) (xy 199.81721 -135.282182)
			(xy 199.825033 -135.22276) (xy 199.840546 -135.164867) (xy 199.863482 -135.109494) (xy 199.893449 -135.057588)
			(xy 199.929936 -135.010038) (xy 199.972316 -134.967658) (xy 200.019866 -134.931171) (xy 200.071772 -134.901204)
			(xy 200.127145 -134.878268) (xy 200.185038 -134.862755) (xy 200.24446 -134.854932) (xy 200.304396 -134.854932)
			(xy 200.363818 -134.862755) (xy 200.421711 -134.878268) (xy 200.469049 -134.897876) (xy 266.86764 -134.897876)
			(xy 266.86764 -134.034276) (xy 266.86813 -134.004292) (xy 266.875958 -133.944836) (xy 266.891479 -133.886911)
			(xy 266.914428 -133.831507) (xy 266.944412 -133.779573) (xy 266.980918 -133.731997) (xy 267.023323 -133.689592)
			(xy 267.070899 -133.653086) (xy 267.122833 -133.623102) (xy 267.178237 -133.600153) (xy 267.236162 -133.584632)
			(xy 267.295618 -133.576804) (xy 267.355586 -133.576804) (xy 267.415042 -133.584632) (xy 267.472967 -133.600153)
			(xy 267.528371 -133.623102) (xy 267.580305 -133.653086) (xy 267.627881 -133.689592) (xy 267.670286 -133.731997)
			(xy 267.706792 -133.779573) (xy 267.736776 -133.831507) (xy 267.759725 -133.886911) (xy 267.775246 -133.944836)
			(xy 267.783074 -134.004292) (xy 267.783564 -134.034276) (xy 267.783564 -134.896352) (xy 285.8389 -134.896352)
			(xy 285.8389 -134.032752) (xy 285.83939 -134.002768) (xy 285.847218 -133.943312) (xy 285.862739 -133.885387)
			(xy 285.885688 -133.829983) (xy 285.915672 -133.778049) (xy 285.952178 -133.730473) (xy 285.994583 -133.688068)
			(xy 286.042159 -133.651562) (xy 286.094093 -133.621578) (xy 286.149497 -133.598629) (xy 286.207422 -133.583108)
			(xy 286.266878 -133.57528) (xy 286.326846 -133.57528) (xy 286.386302 -133.583108) (xy 286.444227 -133.598629)
			(xy 286.499631 -133.621578) (xy 286.551565 -133.651562) (xy 286.599141 -133.688068) (xy 286.641546 -133.730473)
			(xy 286.678052 -133.778049) (xy 286.708036 -133.829983) (xy 286.730985 -133.885387) (xy 286.746506 -133.943312)
			(xy 286.754334 -134.002768) (xy 286.754824 -134.032752) (xy 286.754824 -134.377176) (xy 298.799504 -134.377176)
			(xy 298.799504 -133.513576) (xy 298.799994 -133.483608) (xy 298.807817 -133.424186) (xy 298.82333 -133.366293)
			(xy 298.846266 -133.31092) (xy 298.876233 -133.259014) (xy 298.91272 -133.211464) (xy 298.9551 -133.169084)
			(xy 299.00265 -133.132597) (xy 299.054556 -133.10263) (xy 299.109929 -133.079694) (xy 299.167822 -133.064181)
			(xy 299.227244 -133.056358) (xy 299.28718 -133.056358) (xy 299.346602 -133.064181) (xy 299.404495 -133.079694)
			(xy 299.459868 -133.10263) (xy 299.511774 -133.132597) (xy 299.559324 -133.169084) (xy 299.601704 -133.211464)
			(xy 299.638191 -133.259014) (xy 299.668158 -133.31092) (xy 299.691094 -133.366293) (xy 299.706607 -133.424186)
			(xy 299.71443 -133.483608) (xy 299.71492 -133.513576) (xy 299.71492 -134.369302) (xy 313.274456 -134.369302)
			(xy 313.274456 -133.505702) (xy 313.274946 -133.475734) (xy 313.282769 -133.416312) (xy 313.298282 -133.358419)
			(xy 313.321218 -133.303046) (xy 313.351185 -133.25114) (xy 313.387672 -133.20359) (xy 313.430052 -133.16121)
			(xy 313.477602 -133.124723) (xy 313.529508 -133.094756) (xy 313.584881 -133.07182) (xy 313.642774 -133.056307)
			(xy 313.702196 -133.048484) (xy 313.762132 -133.048484) (xy 313.821554 -133.056307) (xy 313.879447 -133.07182)
			(xy 313.93482 -133.094756) (xy 313.951493 -133.104382) (xy 385.6101 -133.104382) (xy 385.6101 -132.240782)
			(xy 385.61059 -132.210814) (xy 385.618413 -132.151392) (xy 385.633926 -132.093499) (xy 385.656862 -132.038126)
			(xy 385.686829 -131.98622) (xy 385.723316 -131.93867) (xy 385.765696 -131.89629) (xy 385.813246 -131.859803)
			(xy 385.865152 -131.829836) (xy 385.920525 -131.8069) (xy 385.978418 -131.791387) (xy 386.03784 -131.783564)
			(xy 386.097776 -131.783564) (xy 386.157198 -131.791387) (xy 386.215091 -131.8069) (xy 386.270464 -131.829836)
			(xy 386.32237 -131.859803) (xy 386.36992 -131.89629) (xy 386.4123 -131.93867) (xy 386.448787 -131.98622)
			(xy 386.478754 -132.038126) (xy 386.50169 -132.093499) (xy 386.517203 -132.151392) (xy 386.525026 -132.210814)
			(xy 386.525516 -132.240782) (xy 386.525516 -133.096508) (xy 400.085052 -133.096508) (xy 400.085052 -132.232908)
			(xy 400.085542 -132.20294) (xy 400.093365 -132.143518) (xy 400.108878 -132.085625) (xy 400.131814 -132.030252)
			(xy 400.161781 -131.978346) (xy 400.198268 -131.930796) (xy 400.240648 -131.888416) (xy 400.288198 -131.851929)
			(xy 400.340104 -131.821962) (xy 400.395477 -131.799026) (xy 400.45337 -131.783513) (xy 400.512792 -131.77569)
			(xy 400.572728 -131.77569) (xy 400.63215 -131.783513) (xy 400.690043 -131.799026) (xy 400.745416 -131.821962)
			(xy 400.797322 -131.851929) (xy 400.844872 -131.888416) (xy 400.887252 -131.930796) (xy 400.923739 -131.978346)
			(xy 400.953706 -132.030252) (xy 400.976642 -132.085625) (xy 400.992155 -132.143518) (xy 400.999978 -132.20294)
			(xy 401.000468 -132.232908) (xy 401.000468 -132.577332) (xy 413.045148 -132.577332) (xy 413.045148 -131.713732)
			(xy 413.045638 -131.683748) (xy 413.053466 -131.624292) (xy 413.068987 -131.566367) (xy 413.091936 -131.510963)
			(xy 413.12192 -131.459029) (xy 413.158426 -131.411453) (xy 413.200831 -131.369048) (xy 413.248407 -131.332542)
			(xy 413.300341 -131.302558) (xy 413.355745 -131.279609) (xy 413.41367 -131.264088) (xy 413.473126 -131.25626)
			(xy 413.533094 -131.25626) (xy 413.59255 -131.264088) (xy 413.650475 -131.279609) (xy 413.705879 -131.302558)
			(xy 413.757813 -131.332542) (xy 413.805389 -131.369048) (xy 413.847794 -131.411453) (xy 413.8843 -131.459029)
			(xy 413.914284 -131.510963) (xy 413.937233 -131.566367) (xy 413.952754 -131.624292) (xy 413.960582 -131.683748)
			(xy 413.961072 -131.713732) (xy 413.961072 -132.575808) (xy 432.016408 -132.575808) (xy 432.016408 -131.712208)
			(xy 432.016898 -131.682224) (xy 432.024726 -131.622768) (xy 432.040247 -131.564843) (xy 432.063196 -131.509439)
			(xy 432.09318 -131.457505) (xy 432.129686 -131.409929) (xy 432.172091 -131.367524) (xy 432.219667 -131.331018)
			(xy 432.271601 -131.301034) (xy 432.327005 -131.278085) (xy 432.38493 -131.262564) (xy 432.444386 -131.254736)
			(xy 432.504354 -131.254736) (xy 432.56381 -131.262564) (xy 432.621735 -131.278085) (xy 432.677139 -131.301034)
			(xy 432.729073 -131.331018) (xy 432.776649 -131.367524) (xy 432.819054 -131.409929) (xy 432.85556 -131.457505)
			(xy 432.885544 -131.509439) (xy 432.908493 -131.564843) (xy 432.924014 -131.622768) (xy 432.931842 -131.682224)
			(xy 432.932332 -131.712208) (xy 432.932332 -132.575808) (xy 432.931842 -132.605792) (xy 432.924014 -132.665248)
			(xy 432.908493 -132.723173) (xy 432.885544 -132.778577) (xy 432.85556 -132.830511) (xy 432.819054 -132.878087)
			(xy 432.776649 -132.920492) (xy 432.729073 -132.956998) (xy 432.677139 -132.986982) (xy 432.621735 -133.009931)
			(xy 432.56381 -133.025452) (xy 432.504354 -133.03328) (xy 432.444386 -133.03328) (xy 432.38493 -133.025452)
			(xy 432.327005 -133.009931) (xy 432.271601 -132.986982) (xy 432.219667 -132.956998) (xy 432.172091 -132.920492)
			(xy 432.129686 -132.878087) (xy 432.09318 -132.830511) (xy 432.063196 -132.778577) (xy 432.040247 -132.723173)
			(xy 432.024726 -132.665248) (xy 432.016898 -132.605792) (xy 432.016408 -132.575808) (xy 413.961072 -132.575808)
			(xy 413.961072 -132.577332) (xy 413.960582 -132.607316) (xy 413.952754 -132.666772) (xy 413.937233 -132.724697)
			(xy 413.914284 -132.780101) (xy 413.8843 -132.832035) (xy 413.847794 -132.879611) (xy 413.805389 -132.922016)
			(xy 413.757813 -132.958522) (xy 413.705879 -132.988506) (xy 413.650475 -133.011455) (xy 413.59255 -133.026976)
			(xy 413.533094 -133.034804) (xy 413.473126 -133.034804) (xy 413.41367 -133.026976) (xy 413.355745 -133.011455)
			(xy 413.300341 -132.988506) (xy 413.248407 -132.958522) (xy 413.200831 -132.922016) (xy 413.158426 -132.879611)
			(xy 413.12192 -132.832035) (xy 413.091936 -132.780101) (xy 413.068987 -132.724697) (xy 413.053466 -132.666772)
			(xy 413.045638 -132.607316) (xy 413.045148 -132.577332) (xy 401.000468 -132.577332) (xy 401.000468 -133.096508)
			(xy 400.999978 -133.126476) (xy 400.992155 -133.185898) (xy 400.976642 -133.243791) (xy 400.953706 -133.299164)
			(xy 400.923739 -133.35107) (xy 400.887252 -133.39862) (xy 400.844872 -133.441) (xy 400.797322 -133.477487)
			(xy 400.745416 -133.507454) (xy 400.690043 -133.53039) (xy 400.63215 -133.545903) (xy 400.572728 -133.553726)
			(xy 400.512792 -133.553726) (xy 400.45337 -133.545903) (xy 400.395477 -133.53039) (xy 400.340104 -133.507454)
			(xy 400.288198 -133.477487) (xy 400.240648 -133.441) (xy 400.198268 -133.39862) (xy 400.161781 -133.35107)
			(xy 400.131814 -133.299164) (xy 400.108878 -133.243791) (xy 400.093365 -133.185898) (xy 400.085542 -133.126476)
			(xy 400.085052 -133.096508) (xy 386.525516 -133.096508) (xy 386.525516 -133.104382) (xy 386.525026 -133.13435)
			(xy 386.517203 -133.193772) (xy 386.50169 -133.251665) (xy 386.478754 -133.307038) (xy 386.448787 -133.358944)
			(xy 386.4123 -133.406494) (xy 386.36992 -133.448874) (xy 386.32237 -133.485361) (xy 386.270464 -133.515328)
			(xy 386.215091 -133.538264) (xy 386.157198 -133.553777) (xy 386.097776 -133.5616) (xy 386.03784 -133.5616)
			(xy 385.978418 -133.553777) (xy 385.920525 -133.538264) (xy 385.865152 -133.515328) (xy 385.813246 -133.485361)
			(xy 385.765696 -133.448874) (xy 385.723316 -133.406494) (xy 385.686829 -133.358944) (xy 385.656862 -133.307038)
			(xy 385.633926 -133.251665) (xy 385.618413 -133.193772) (xy 385.61059 -133.13435) (xy 385.6101 -133.104382)
			(xy 313.951493 -133.104382) (xy 313.986726 -133.124723) (xy 314.034276 -133.16121) (xy 314.076656 -133.20359)
			(xy 314.113143 -133.25114) (xy 314.14311 -133.303046) (xy 314.166046 -133.358419) (xy 314.181559 -133.416312)
			(xy 314.189382 -133.475734) (xy 314.189872 -133.505702) (xy 314.189872 -134.369302) (xy 314.189382 -134.39927)
			(xy 314.181559 -134.458692) (xy 314.166046 -134.516585) (xy 314.14311 -134.571958) (xy 314.113143 -134.623864)
			(xy 314.076656 -134.671414) (xy 314.034276 -134.713794) (xy 313.986726 -134.750281) (xy 313.93482 -134.780248)
			(xy 313.879447 -134.803184) (xy 313.821554 -134.818697) (xy 313.762132 -134.82652) (xy 313.702196 -134.82652)
			(xy 313.642774 -134.818697) (xy 313.584881 -134.803184) (xy 313.529508 -134.780248) (xy 313.477602 -134.750281)
			(xy 313.430052 -134.713794) (xy 313.387672 -134.671414) (xy 313.351185 -134.623864) (xy 313.321218 -134.571958)
			(xy 313.298282 -134.516585) (xy 313.282769 -134.458692) (xy 313.274946 -134.39927) (xy 313.274456 -134.369302)
			(xy 299.71492 -134.369302) (xy 299.71492 -134.377176) (xy 299.71443 -134.407144) (xy 299.706607 -134.466566)
			(xy 299.691094 -134.524459) (xy 299.668158 -134.579832) (xy 299.638191 -134.631738) (xy 299.601704 -134.679288)
			(xy 299.559324 -134.721668) (xy 299.511774 -134.758155) (xy 299.459868 -134.788122) (xy 299.404495 -134.811058)
			(xy 299.346602 -134.826571) (xy 299.28718 -134.834394) (xy 299.227244 -134.834394) (xy 299.167822 -134.826571)
			(xy 299.109929 -134.811058) (xy 299.054556 -134.788122) (xy 299.00265 -134.758155) (xy 298.9551 -134.721668)
			(xy 298.91272 -134.679288) (xy 298.876233 -134.631738) (xy 298.846266 -134.579832) (xy 298.82333 -134.524459)
			(xy 298.807817 -134.466566) (xy 298.799994 -134.407144) (xy 298.799504 -134.377176) (xy 286.754824 -134.377176)
			(xy 286.754824 -134.896352) (xy 286.754334 -134.926336) (xy 286.746506 -134.985792) (xy 286.730985 -135.043717)
			(xy 286.708036 -135.099121) (xy 286.678052 -135.151055) (xy 286.641546 -135.198631) (xy 286.599141 -135.241036)
			(xy 286.551565 -135.277542) (xy 286.499631 -135.307526) (xy 286.444227 -135.330475) (xy 286.386302 -135.345996)
			(xy 286.326846 -135.353824) (xy 286.266878 -135.353824) (xy 286.207422 -135.345996) (xy 286.149497 -135.330475)
			(xy 286.094093 -135.307526) (xy 286.042159 -135.277542) (xy 285.994583 -135.241036) (xy 285.952178 -135.198631)
			(xy 285.915672 -135.151055) (xy 285.885688 -135.099121) (xy 285.862739 -135.043717) (xy 285.847218 -134.985792)
			(xy 285.83939 -134.926336) (xy 285.8389 -134.896352) (xy 267.783564 -134.896352) (xy 267.783564 -134.897876)
			(xy 267.783074 -134.92786) (xy 267.775246 -134.987316) (xy 267.759725 -135.045241) (xy 267.736776 -135.100645)
			(xy 267.706792 -135.152579) (xy 267.670286 -135.200155) (xy 267.627881 -135.24256) (xy 267.580305 -135.279066)
			(xy 267.528371 -135.30905) (xy 267.472967 -135.331999) (xy 267.415042 -135.34752) (xy 267.355586 -135.355348)
			(xy 267.295618 -135.355348) (xy 267.236162 -135.34752) (xy 267.178237 -135.331999) (xy 267.122833 -135.30905)
			(xy 267.070899 -135.279066) (xy 267.023323 -135.24256) (xy 266.980918 -135.200155) (xy 266.944412 -135.152579)
			(xy 266.914428 -135.100645) (xy 266.891479 -135.045241) (xy 266.875958 -134.987316) (xy 266.86813 -134.92786)
			(xy 266.86764 -134.897876) (xy 200.469049 -134.897876) (xy 200.477084 -134.901204) (xy 200.52899 -134.931171)
			(xy 200.57654 -134.967658) (xy 200.61892 -135.010038) (xy 200.655407 -135.057588) (xy 200.685374 -135.109494)
			(xy 200.70831 -135.164867) (xy 200.723823 -135.22276) (xy 200.731646 -135.282182) (xy 200.732136 -135.31215)
			(xy 200.732136 -136.17575) (xy 200.731646 -136.205718) (xy 200.723823 -136.26514) (xy 200.70831 -136.323033)
			(xy 200.685374 -136.378406) (xy 200.655407 -136.430312) (xy 200.61892 -136.477862) (xy 200.57654 -136.520242)
			(xy 200.52899 -136.556729) (xy 200.477084 -136.586696) (xy 200.421711 -136.609632) (xy 200.363818 -136.625145)
			(xy 200.304396 -136.632968) (xy 200.24446 -136.632968) (xy 200.185038 -136.625145) (xy 200.127145 -136.609632)
			(xy 200.071772 -136.586696) (xy 200.019866 -136.556729) (xy 199.972316 -136.520242) (xy 199.929936 -136.477862)
			(xy 199.893449 -136.430312) (xy 199.863482 -136.378406) (xy 199.840546 -136.323033) (xy 199.825033 -136.26514)
			(xy 199.81721 -136.205718) (xy 199.81672 -136.17575) (xy 181.760876 -136.17575) (xy 181.760876 -136.177274)
			(xy 181.760386 -136.207242) (xy 181.752563 -136.266664) (xy 181.73705 -136.324557) (xy 181.714114 -136.37993)
			(xy 181.684147 -136.431836) (xy 181.64766 -136.479386) (xy 181.60528 -136.521766) (xy 181.55773 -136.558253)
			(xy 181.505824 -136.58822) (xy 181.450451 -136.611156) (xy 181.392558 -136.626669) (xy 181.333136 -136.634492)
			(xy 181.2732 -136.634492) (xy 181.213778 -136.626669) (xy 181.155885 -136.611156) (xy 181.100512 -136.58822)
			(xy 181.048606 -136.558253) (xy 181.001056 -136.521766) (xy 180.958676 -136.479386) (xy 180.922189 -136.431836)
			(xy 180.892222 -136.37993) (xy 180.869286 -136.324557) (xy 180.853773 -136.266664) (xy 180.84595 -136.207242)
			(xy 180.84546 -136.177274) (xy 168.80078 -136.177274) (xy 168.80078 -136.69645) (xy 168.800651 -136.704324)
			(xy 269.509748 -136.704324) (xy 269.509748 -135.840724) (xy 269.510238 -135.81074) (xy 269.518066 -135.751284)
			(xy 269.533587 -135.693359) (xy 269.556536 -135.637955) (xy 269.58652 -135.586021) (xy 269.623026 -135.538445)
			(xy 269.665431 -135.49604) (xy 269.713007 -135.459534) (xy 269.764941 -135.42955) (xy 269.820345 -135.406601)
			(xy 269.87827 -135.39108) (xy 269.937726 -135.383252) (xy 269.997694 -135.383252) (xy 270.05715 -135.39108)
			(xy 270.115075 -135.406601) (xy 270.170479 -135.42955) (xy 270.222413 -135.459534) (xy 270.269989 -135.49604)
			(xy 270.312394 -135.538445) (xy 270.3489 -135.586021) (xy 270.378884 -135.637955) (xy 270.401833 -135.693359)
			(xy 270.417354 -135.751284) (xy 270.425182 -135.81074) (xy 270.425672 -135.840724) (xy 270.425672 -136.69645)
			(xy 283.9847 -136.69645) (xy 283.9847 -135.83285) (xy 283.98519 -135.802866) (xy 283.993018 -135.74341)
			(xy 284.008539 -135.685485) (xy 284.031488 -135.630081) (xy 284.061472 -135.578147) (xy 284.097978 -135.530571)
			(xy 284.140383 -135.488166) (xy 284.187959 -135.45166) (xy 284.239893 -135.421676) (xy 284.295297 -135.398727)
			(xy 284.353222 -135.383206) (xy 284.412678 -135.375378) (xy 284.472646 -135.375378) (xy 284.532102 -135.383206)
			(xy 284.590027 -135.398727) (xy 284.645431 -135.421676) (xy 284.697365 -135.45166) (xy 284.744941 -135.488166)
			(xy 284.787346 -135.530571) (xy 284.823852 -135.578147) (xy 284.853836 -135.630081) (xy 284.876785 -135.685485)
			(xy 284.892306 -135.74341) (xy 284.900134 -135.802866) (xy 284.900624 -135.83285) (xy 284.900624 -136.177274)
			(xy 296.945304 -136.177274) (xy 296.945304 -135.313674) (xy 296.945794 -135.283706) (xy 296.953617 -135.224284)
			(xy 296.96913 -135.166391) (xy 296.992066 -135.111018) (xy 297.022033 -135.059112) (xy 297.05852 -135.011562)
			(xy 297.1009 -134.969182) (xy 297.14845 -134.932695) (xy 297.200356 -134.902728) (xy 297.255729 -134.879792)
			(xy 297.313622 -134.864279) (xy 297.373044 -134.856456) (xy 297.43298 -134.856456) (xy 297.492402 -134.864279)
			(xy 297.550295 -134.879792) (xy 297.605668 -134.902728) (xy 297.657574 -134.932695) (xy 297.705124 -134.969182)
			(xy 297.747504 -135.011562) (xy 297.783991 -135.059112) (xy 297.813958 -135.111018) (xy 297.836894 -135.166391)
			(xy 297.852407 -135.224284) (xy 297.86023 -135.283706) (xy 297.86072 -135.313674) (xy 297.86072 -136.17575)
			(xy 315.916564 -136.17575) (xy 315.916564 -135.31215) (xy 315.917054 -135.282182) (xy 315.924877 -135.22276)
			(xy 315.94039 -135.164867) (xy 315.963326 -135.109494) (xy 315.993293 -135.057588) (xy 316.02978 -135.010038)
			(xy 316.07216 -134.967658) (xy 316.11971 -134.931171) (xy 316.171616 -134.901204) (xy 316.226989 -134.878268)
			(xy 316.284882 -134.862755) (xy 316.344304 -134.854932) (xy 316.40424 -134.854932) (xy 316.463662 -134.862755)
			(xy 316.521555 -134.878268) (xy 316.568893 -134.897876) (xy 382.967992 -134.897876) (xy 382.967992 -134.034276)
			(xy 382.968482 -134.004308) (xy 382.976305 -133.944886) (xy 382.991818 -133.886993) (xy 383.014754 -133.83162)
			(xy 383.044721 -133.779714) (xy 383.081208 -133.732164) (xy 383.123588 -133.689784) (xy 383.171138 -133.653297)
			(xy 383.223044 -133.62333) (xy 383.278417 -133.600394) (xy 383.33631 -133.584881) (xy 383.395732 -133.577058)
			(xy 383.455668 -133.577058) (xy 383.51509 -133.584881) (xy 383.572983 -133.600394) (xy 383.628356 -133.62333)
			(xy 383.680262 -133.653297) (xy 383.727812 -133.689784) (xy 383.770192 -133.732164) (xy 383.806679 -133.779714)
			(xy 383.836646 -133.83162) (xy 383.859582 -133.886993) (xy 383.875095 -133.944886) (xy 383.882918 -134.004308)
			(xy 383.883408 -134.034276) (xy 383.883408 -134.896352) (xy 401.939252 -134.896352) (xy 401.939252 -134.032752)
			(xy 401.939742 -134.002784) (xy 401.947565 -133.943362) (xy 401.963078 -133.885469) (xy 401.986014 -133.830096)
			(xy 402.015981 -133.77819) (xy 402.052468 -133.73064) (xy 402.094848 -133.68826) (xy 402.142398 -133.651773)
			(xy 402.194304 -133.621806) (xy 402.249677 -133.59887) (xy 402.30757 -133.583357) (xy 402.366992 -133.575534)
			(xy 402.426928 -133.575534) (xy 402.48635 -133.583357) (xy 402.544243 -133.59887) (xy 402.599616 -133.621806)
			(xy 402.651522 -133.651773) (xy 402.699072 -133.68826) (xy 402.741452 -133.73064) (xy 402.777939 -133.77819)
			(xy 402.807906 -133.830096) (xy 402.830842 -133.885469) (xy 402.846355 -133.943362) (xy 402.854178 -134.002784)
			(xy 402.854668 -134.032752) (xy 402.854668 -134.377176) (xy 414.899348 -134.377176) (xy 414.899348 -133.513576)
			(xy 414.899838 -133.483592) (xy 414.907666 -133.424136) (xy 414.923187 -133.366211) (xy 414.946136 -133.310807)
			(xy 414.97612 -133.258873) (xy 415.012626 -133.211297) (xy 415.055031 -133.168892) (xy 415.102607 -133.132386)
			(xy 415.154541 -133.102402) (xy 415.209945 -133.079453) (xy 415.26787 -133.063932) (xy 415.327326 -133.056104)
			(xy 415.387294 -133.056104) (xy 415.44675 -133.063932) (xy 415.504675 -133.079453) (xy 415.560079 -133.102402)
			(xy 415.612013 -133.132386) (xy 415.659589 -133.168892) (xy 415.701994 -133.211297) (xy 415.7385 -133.258873)
			(xy 415.768484 -133.310807) (xy 415.791433 -133.366211) (xy 415.806954 -133.424136) (xy 415.814782 -133.483592)
			(xy 415.815272 -133.513576) (xy 415.815272 -134.369302) (xy 429.3743 -134.369302) (xy 429.3743 -133.505702)
			(xy 429.37479 -133.475718) (xy 429.382618 -133.416262) (xy 429.398139 -133.358337) (xy 429.421088 -133.302933)
			(xy 429.451072 -133.250999) (xy 429.487578 -133.203423) (xy 429.529983 -133.161018) (xy 429.577559 -133.124512)
			(xy 429.629493 -133.094528) (xy 429.684897 -133.071579) (xy 429.742822 -133.056058) (xy 429.802278 -133.04823)
			(xy 429.862246 -133.04823) (xy 429.921702 -133.056058) (xy 429.979627 -133.071579) (xy 430.035031 -133.094528)
			(xy 430.086965 -133.124512) (xy 430.134541 -133.161018) (xy 430.176946 -133.203423) (xy 430.213452 -133.250999)
			(xy 430.243436 -133.302933) (xy 430.266385 -133.358337) (xy 430.281906 -133.416262) (xy 430.289734 -133.475718)
			(xy 430.290224 -133.505702) (xy 430.290224 -134.369302) (xy 430.289734 -134.399286) (xy 430.281906 -134.458742)
			(xy 430.266385 -134.516667) (xy 430.243436 -134.572071) (xy 430.213452 -134.624005) (xy 430.176946 -134.671581)
			(xy 430.134541 -134.713986) (xy 430.086965 -134.750492) (xy 430.035031 -134.780476) (xy 429.979627 -134.803425)
			(xy 429.921702 -134.818946) (xy 429.862246 -134.826774) (xy 429.802278 -134.826774) (xy 429.742822 -134.818946)
			(xy 429.684897 -134.803425) (xy 429.629493 -134.780476) (xy 429.577559 -134.750492) (xy 429.529983 -134.713986)
			(xy 429.487578 -134.671581) (xy 429.451072 -134.624005) (xy 429.421088 -134.572071) (xy 429.398139 -134.516667)
			(xy 429.382618 -134.458742) (xy 429.37479 -134.399286) (xy 429.3743 -134.369302) (xy 415.815272 -134.369302)
			(xy 415.815272 -134.377176) (xy 415.814782 -134.40716) (xy 415.806954 -134.466616) (xy 415.791433 -134.524541)
			(xy 415.768484 -134.579945) (xy 415.7385 -134.631879) (xy 415.701994 -134.679455) (xy 415.659589 -134.72186)
			(xy 415.612013 -134.758366) (xy 415.560079 -134.78835) (xy 415.504675 -134.811299) (xy 415.44675 -134.82682)
			(xy 415.387294 -134.834648) (xy 415.327326 -134.834648) (xy 415.26787 -134.82682) (xy 415.209945 -134.811299)
			(xy 415.154541 -134.78835) (xy 415.102607 -134.758366) (xy 415.055031 -134.72186) (xy 415.012626 -134.679455)
			(xy 414.97612 -134.631879) (xy 414.946136 -134.579945) (xy 414.923187 -134.524541) (xy 414.907666 -134.466616)
			(xy 414.899838 -134.40716) (xy 414.899348 -134.377176) (xy 402.854668 -134.377176) (xy 402.854668 -134.896352)
			(xy 402.854178 -134.92632) (xy 402.846355 -134.985742) (xy 402.830842 -135.043635) (xy 402.807906 -135.099008)
			(xy 402.777939 -135.150914) (xy 402.741452 -135.198464) (xy 402.699072 -135.240844) (xy 402.651522 -135.277331)
			(xy 402.599616 -135.307298) (xy 402.544243 -135.330234) (xy 402.48635 -135.345747) (xy 402.426928 -135.35357)
			(xy 402.366992 -135.35357) (xy 402.30757 -135.345747) (xy 402.249677 -135.330234) (xy 402.194304 -135.307298)
			(xy 402.142398 -135.277331) (xy 402.094848 -135.240844) (xy 402.052468 -135.198464) (xy 402.015981 -135.150914)
			(xy 401.986014 -135.099008) (xy 401.963078 -135.043635) (xy 401.947565 -134.985742) (xy 401.939742 -134.92632)
			(xy 401.939252 -134.896352) (xy 383.883408 -134.896352) (xy 383.883408 -134.897876) (xy 383.882918 -134.927844)
			(xy 383.875095 -134.987266) (xy 383.859582 -135.045159) (xy 383.836646 -135.100532) (xy 383.806679 -135.152438)
			(xy 383.770192 -135.199988) (xy 383.727812 -135.242368) (xy 383.680262 -135.278855) (xy 383.628356 -135.308822)
			(xy 383.572983 -135.331758) (xy 383.51509 -135.347271) (xy 383.455668 -135.355094) (xy 383.395732 -135.355094)
			(xy 383.33631 -135.347271) (xy 383.278417 -135.331758) (xy 383.223044 -135.308822) (xy 383.171138 -135.278855)
			(xy 383.123588 -135.242368) (xy 383.081208 -135.199988) (xy 383.044721 -135.152438) (xy 383.014754 -135.100532)
			(xy 382.991818 -135.045159) (xy 382.976305 -134.987266) (xy 382.968482 -134.927844) (xy 382.967992 -134.897876)
			(xy 316.568893 -134.897876) (xy 316.576928 -134.901204) (xy 316.628834 -134.931171) (xy 316.676384 -134.967658)
			(xy 316.718764 -135.010038) (xy 316.755251 -135.057588) (xy 316.785218 -135.109494) (xy 316.808154 -135.164867)
			(xy 316.823667 -135.22276) (xy 316.83149 -135.282182) (xy 316.83198 -135.31215) (xy 316.83198 -136.17575)
			(xy 316.83149 -136.205718) (xy 316.823667 -136.26514) (xy 316.808154 -136.323033) (xy 316.785218 -136.378406)
			(xy 316.755251 -136.430312) (xy 316.718764 -136.477862) (xy 316.676384 -136.520242) (xy 316.628834 -136.556729)
			(xy 316.576928 -136.586696) (xy 316.521555 -136.609632) (xy 316.463662 -136.625145) (xy 316.40424 -136.632968)
			(xy 316.344304 -136.632968) (xy 316.284882 -136.625145) (xy 316.226989 -136.609632) (xy 316.171616 -136.586696)
			(xy 316.11971 -136.556729) (xy 316.07216 -136.520242) (xy 316.02978 -136.477862) (xy 315.993293 -136.430312)
			(xy 315.963326 -136.378406) (xy 315.94039 -136.323033) (xy 315.924877 -136.26514) (xy 315.917054 -136.205718)
			(xy 315.916564 -136.17575) (xy 297.86072 -136.17575) (xy 297.86072 -136.177274) (xy 297.86023 -136.207242)
			(xy 297.852407 -136.266664) (xy 297.836894 -136.324557) (xy 297.813958 -136.37993) (xy 297.783991 -136.431836)
			(xy 297.747504 -136.479386) (xy 297.705124 -136.521766) (xy 297.657574 -136.558253) (xy 297.605668 -136.58822)
			(xy 297.550295 -136.611156) (xy 297.492402 -136.626669) (xy 297.43298 -136.634492) (xy 297.373044 -136.634492)
			(xy 297.313622 -136.626669) (xy 297.255729 -136.611156) (xy 297.200356 -136.58822) (xy 297.14845 -136.558253)
			(xy 297.1009 -136.521766) (xy 297.05852 -136.479386) (xy 297.022033 -136.431836) (xy 296.992066 -136.37993)
			(xy 296.96913 -136.324557) (xy 296.953617 -136.266664) (xy 296.945794 -136.207242) (xy 296.945304 -136.177274)
			(xy 284.900624 -136.177274) (xy 284.900624 -136.69645) (xy 284.900495 -136.704324) (xy 385.6101 -136.704324)
			(xy 385.6101 -135.840724) (xy 385.61059 -135.810756) (xy 385.618413 -135.751334) (xy 385.633926 -135.693441)
			(xy 385.656862 -135.638068) (xy 385.686829 -135.586162) (xy 385.723316 -135.538612) (xy 385.765696 -135.496232)
			(xy 385.813246 -135.459745) (xy 385.865152 -135.429778) (xy 385.920525 -135.406842) (xy 385.978418 -135.391329)
			(xy 386.03784 -135.383506) (xy 386.097776 -135.383506) (xy 386.157198 -135.391329) (xy 386.215091 -135.406842)
			(xy 386.270464 -135.429778) (xy 386.32237 -135.459745) (xy 386.36992 -135.496232) (xy 386.4123 -135.538612)
			(xy 386.448787 -135.586162) (xy 386.478754 -135.638068) (xy 386.50169 -135.693441) (xy 386.517203 -135.751334)
			(xy 386.525026 -135.810756) (xy 386.525516 -135.840724) (xy 386.525516 -136.69645) (xy 400.085052 -136.69645)
			(xy 400.085052 -135.83285) (xy 400.085542 -135.802882) (xy 400.093365 -135.74346) (xy 400.108878 -135.685567)
			(xy 400.131814 -135.630194) (xy 400.161781 -135.578288) (xy 400.198268 -135.530738) (xy 400.240648 -135.488358)
			(xy 400.288198 -135.451871) (xy 400.340104 -135.421904) (xy 400.395477 -135.398968) (xy 400.45337 -135.383455)
			(xy 400.512792 -135.375632) (xy 400.572728 -135.375632) (xy 400.63215 -135.383455) (xy 400.690043 -135.398968)
			(xy 400.745416 -135.421904) (xy 400.797322 -135.451871) (xy 400.844872 -135.488358) (xy 400.887252 -135.530738)
			(xy 400.923739 -135.578288) (xy 400.953706 -135.630194) (xy 400.976642 -135.685567) (xy 400.992155 -135.74346)
			(xy 400.999978 -135.802882) (xy 401.000468 -135.83285) (xy 401.000468 -136.177274) (xy 413.045148 -136.177274)
			(xy 413.045148 -135.313674) (xy 413.045638 -135.28369) (xy 413.053466 -135.224234) (xy 413.068987 -135.166309)
			(xy 413.091936 -135.110905) (xy 413.12192 -135.058971) (xy 413.158426 -135.011395) (xy 413.200831 -134.96899)
			(xy 413.248407 -134.932484) (xy 413.300341 -134.9025) (xy 413.355745 -134.879551) (xy 413.41367 -134.86403)
			(xy 413.473126 -134.856202) (xy 413.533094 -134.856202) (xy 413.59255 -134.86403) (xy 413.650475 -134.879551)
			(xy 413.705879 -134.9025) (xy 413.757813 -134.932484) (xy 413.805389 -134.96899) (xy 413.847794 -135.011395)
			(xy 413.8843 -135.058971) (xy 413.914284 -135.110905) (xy 413.937233 -135.166309) (xy 413.952754 -135.224234)
			(xy 413.960582 -135.28369) (xy 413.961072 -135.313674) (xy 413.961072 -136.17575) (xy 432.016408 -136.17575)
			(xy 432.016408 -135.31215) (xy 432.016898 -135.282166) (xy 432.024726 -135.22271) (xy 432.040247 -135.164785)
			(xy 432.063196 -135.109381) (xy 432.09318 -135.057447) (xy 432.129686 -135.009871) (xy 432.172091 -134.967466)
			(xy 432.219667 -134.93096) (xy 432.271601 -134.900976) (xy 432.327005 -134.878027) (xy 432.38493 -134.862506)
			(xy 432.444386 -134.854678) (xy 432.504354 -134.854678) (xy 432.56381 -134.862506) (xy 432.621735 -134.878027)
			(xy 432.677139 -134.900976) (xy 432.729073 -134.93096) (xy 432.776649 -134.967466) (xy 432.819054 -135.009871)
			(xy 432.85556 -135.057447) (xy 432.885544 -135.109381) (xy 432.908493 -135.164785) (xy 432.924014 -135.22271)
			(xy 432.931842 -135.282166) (xy 432.932332 -135.31215) (xy 432.932332 -136.17575) (xy 432.931842 -136.205734)
			(xy 432.924014 -136.26519) (xy 432.908493 -136.323115) (xy 432.885544 -136.378519) (xy 432.85556 -136.430453)
			(xy 432.819054 -136.478029) (xy 432.776649 -136.520434) (xy 432.729073 -136.55694) (xy 432.677139 -136.586924)
			(xy 432.621735 -136.609873) (xy 432.56381 -136.625394) (xy 432.504354 -136.633222) (xy 432.444386 -136.633222)
			(xy 432.38493 -136.625394) (xy 432.327005 -136.609873) (xy 432.271601 -136.586924) (xy 432.219667 -136.55694)
			(xy 432.172091 -136.520434) (xy 432.129686 -136.478029) (xy 432.09318 -136.430453) (xy 432.063196 -136.378519)
			(xy 432.040247 -136.323115) (xy 432.024726 -136.26519) (xy 432.016898 -136.205734) (xy 432.016408 -136.17575)
			(xy 413.961072 -136.17575) (xy 413.961072 -136.177274) (xy 413.960582 -136.207258) (xy 413.952754 -136.266714)
			(xy 413.937233 -136.324639) (xy 413.914284 -136.380043) (xy 413.8843 -136.431977) (xy 413.847794 -136.479553)
			(xy 413.805389 -136.521958) (xy 413.757813 -136.558464) (xy 413.705879 -136.588448) (xy 413.650475 -136.611397)
			(xy 413.59255 -136.626918) (xy 413.533094 -136.634746) (xy 413.473126 -136.634746) (xy 413.41367 -136.626918)
			(xy 413.355745 -136.611397) (xy 413.300341 -136.588448) (xy 413.248407 -136.558464) (xy 413.200831 -136.521958)
			(xy 413.158426 -136.479553) (xy 413.12192 -136.431977) (xy 413.091936 -136.380043) (xy 413.068987 -136.324639)
			(xy 413.053466 -136.266714) (xy 413.045638 -136.207258) (xy 413.045148 -136.177274) (xy 401.000468 -136.177274)
			(xy 401.000468 -136.69645) (xy 400.999978 -136.726418) (xy 400.992155 -136.78584) (xy 400.976642 -136.843733)
			(xy 400.953706 -136.899106) (xy 400.923739 -136.951012) (xy 400.887252 -136.998562) (xy 400.844872 -137.040942)
			(xy 400.797322 -137.077429) (xy 400.745416 -137.107396) (xy 400.690043 -137.130332) (xy 400.63215 -137.145845)
			(xy 400.572728 -137.153668) (xy 400.512792 -137.153668) (xy 400.45337 -137.145845) (xy 400.395477 -137.130332)
			(xy 400.340104 -137.107396) (xy 400.288198 -137.077429) (xy 400.240648 -137.040942) (xy 400.198268 -136.998562)
			(xy 400.161781 -136.951012) (xy 400.131814 -136.899106) (xy 400.108878 -136.843733) (xy 400.093365 -136.78584)
			(xy 400.085542 -136.726418) (xy 400.085052 -136.69645) (xy 386.525516 -136.69645) (xy 386.525516 -136.704324)
			(xy 386.525026 -136.734292) (xy 386.517203 -136.793714) (xy 386.50169 -136.851607) (xy 386.478754 -136.90698)
			(xy 386.448787 -136.958886) (xy 386.4123 -137.006436) (xy 386.36992 -137.048816) (xy 386.32237 -137.085303)
			(xy 386.270464 -137.11527) (xy 386.215091 -137.138206) (xy 386.157198 -137.153719) (xy 386.097776 -137.161542)
			(xy 386.03784 -137.161542) (xy 385.978418 -137.153719) (xy 385.920525 -137.138206) (xy 385.865152 -137.11527)
			(xy 385.813246 -137.085303) (xy 385.765696 -137.048816) (xy 385.723316 -137.006436) (xy 385.686829 -136.958886)
			(xy 385.656862 -136.90698) (xy 385.633926 -136.851607) (xy 385.618413 -136.793714) (xy 385.61059 -136.734292)
			(xy 385.6101 -136.704324) (xy 284.900495 -136.704324) (xy 284.900134 -136.726434) (xy 284.892306 -136.78589)
			(xy 284.876785 -136.843815) (xy 284.853836 -136.899219) (xy 284.823852 -136.951153) (xy 284.787346 -136.998729)
			(xy 284.744941 -137.041134) (xy 284.697365 -137.07764) (xy 284.645431 -137.107624) (xy 284.590027 -137.130573)
			(xy 284.532102 -137.146094) (xy 284.472646 -137.153922) (xy 284.412678 -137.153922) (xy 284.353222 -137.146094)
			(xy 284.295297 -137.130573) (xy 284.239893 -137.107624) (xy 284.187959 -137.07764) (xy 284.140383 -137.041134)
			(xy 284.097978 -136.998729) (xy 284.061472 -136.951153) (xy 284.031488 -136.899219) (xy 284.008539 -136.843815)
			(xy 283.993018 -136.78589) (xy 283.98519 -136.726434) (xy 283.9847 -136.69645) (xy 270.425672 -136.69645)
			(xy 270.425672 -136.704324) (xy 270.425182 -136.734308) (xy 270.417354 -136.793764) (xy 270.401833 -136.851689)
			(xy 270.378884 -136.907093) (xy 270.3489 -136.959027) (xy 270.312394 -137.006603) (xy 270.269989 -137.049008)
			(xy 270.222413 -137.085514) (xy 270.170479 -137.115498) (xy 270.115075 -137.138447) (xy 270.05715 -137.153968)
			(xy 269.997694 -137.161796) (xy 269.937726 -137.161796) (xy 269.87827 -137.153968) (xy 269.820345 -137.138447)
			(xy 269.764941 -137.115498) (xy 269.713007 -137.085514) (xy 269.665431 -137.049008) (xy 269.623026 -137.006603)
			(xy 269.58652 -136.959027) (xy 269.556536 -136.907093) (xy 269.533587 -136.851689) (xy 269.518066 -136.793764)
			(xy 269.510238 -136.734308) (xy 269.509748 -136.704324) (xy 168.800651 -136.704324) (xy 168.80029 -136.726434)
			(xy 168.792462 -136.78589) (xy 168.776941 -136.843815) (xy 168.753992 -136.899219) (xy 168.724008 -136.951153)
			(xy 168.687502 -136.998729) (xy 168.645097 -137.041134) (xy 168.597521 -137.07764) (xy 168.545587 -137.107624)
			(xy 168.490183 -137.130573) (xy 168.432258 -137.146094) (xy 168.372802 -137.153922) (xy 168.312834 -137.153922)
			(xy 168.253378 -137.146094) (xy 168.195453 -137.130573) (xy 168.140049 -137.107624) (xy 168.088115 -137.07764)
			(xy 168.040539 -137.041134) (xy 167.998134 -136.998729) (xy 167.961628 -136.951153) (xy 167.931644 -136.899219)
			(xy 167.908695 -136.843815) (xy 167.893174 -136.78589) (xy 167.885346 -136.726434) (xy 167.884856 -136.69645)
			(xy 154.325828 -136.69645) (xy 154.325828 -136.704324) (xy 154.325338 -136.734308) (xy 154.31751 -136.793764)
			(xy 154.301989 -136.851689) (xy 154.27904 -136.907093) (xy 154.249056 -136.959027) (xy 154.21255 -137.006603)
			(xy 154.170145 -137.049008) (xy 154.122569 -137.085514) (xy 154.070635 -137.115498) (xy 154.015231 -137.138447)
			(xy 153.957306 -137.153968) (xy 153.89785 -137.161796) (xy 153.837882 -137.161796) (xy 153.778426 -137.153968)
			(xy 153.720501 -137.138447) (xy 153.665097 -137.115498) (xy 153.613163 -137.085514) (xy 153.565587 -137.049008)
			(xy 153.523182 -137.006603) (xy 153.486676 -136.959027) (xy 153.456692 -136.907093) (xy 153.433743 -136.851689)
			(xy 153.418222 -136.793764) (xy 153.410394 -136.734308) (xy 153.409904 -136.704324) (xy 52.700299 -136.704324)
			(xy 52.699938 -136.726418) (xy 52.692115 -136.78584) (xy 52.676602 -136.843733) (xy 52.653666 -136.899106)
			(xy 52.623699 -136.951012) (xy 52.587212 -136.998562) (xy 52.544832 -137.040942) (xy 52.497282 -137.077429)
			(xy 52.445376 -137.107396) (xy 52.390003 -137.130332) (xy 52.33211 -137.145845) (xy 52.272688 -137.153668)
			(xy 52.212752 -137.153668) (xy 52.15333 -137.145845) (xy 52.095437 -137.130332) (xy 52.040064 -137.107396)
			(xy 51.988158 -137.077429) (xy 51.940608 -137.040942) (xy 51.898228 -136.998562) (xy 51.861741 -136.951012)
			(xy 51.831774 -136.899106) (xy 51.808838 -136.843733) (xy 51.793325 -136.78584) (xy 51.785502 -136.726418)
			(xy 51.785012 -136.69645) (xy 38.225476 -136.69645) (xy 38.225476 -136.704324) (xy 38.224986 -136.734292)
			(xy 38.217163 -136.793714) (xy 38.20165 -136.851607) (xy 38.178714 -136.90698) (xy 38.148747 -136.958886)
			(xy 38.11226 -137.006436) (xy 38.06988 -137.048816) (xy 38.02233 -137.085303) (xy 37.970424 -137.11527)
			(xy 37.915051 -137.138206) (xy 37.857158 -137.153719) (xy 37.797736 -137.161542) (xy 37.7378 -137.161542)
			(xy 37.678378 -137.153719) (xy 37.620485 -137.138206) (xy 37.565112 -137.11527) (xy 37.513206 -137.085303)
			(xy 37.465656 -137.048816) (xy 37.423276 -137.006436) (xy 37.386789 -136.958886) (xy 37.356822 -136.90698)
			(xy 37.333886 -136.851607) (xy 37.318373 -136.793714) (xy 37.31055 -136.734292) (xy 37.31006 -136.704324)
			(xy 5.324094 -136.704324) (xy 5.324094 -138.496548) (xy 43.97248 -138.496548) (xy 43.97248 -137.632948)
			(xy 43.97297 -137.602964) (xy 43.980798 -137.543508) (xy 43.996319 -137.485583) (xy 44.019268 -137.430179)
			(xy 44.049252 -137.378245) (xy 44.085758 -137.330669) (xy 44.128163 -137.288264) (xy 44.175739 -137.251758)
			(xy 44.227673 -137.221774) (xy 44.283077 -137.198825) (xy 44.341002 -137.183304) (xy 44.400458 -137.175476)
			(xy 44.460426 -137.175476) (xy 44.519882 -137.183304) (xy 44.577807 -137.198825) (xy 44.633211 -137.221774)
			(xy 44.685145 -137.251758) (xy 44.732721 -137.288264) (xy 44.775126 -137.330669) (xy 44.811632 -137.378245)
			(xy 44.841616 -137.430179) (xy 44.864565 -137.485583) (xy 44.880086 -137.543508) (xy 44.887914 -137.602964)
			(xy 44.888404 -137.632948) (xy 44.888404 -138.496548) (xy 160.072324 -138.496548) (xy 160.072324 -137.632948)
			(xy 160.072814 -137.602964) (xy 160.080642 -137.543508) (xy 160.096163 -137.485583) (xy 160.119112 -137.430179)
			(xy 160.149096 -137.378245) (xy 160.185602 -137.330669) (xy 160.228007 -137.288264) (xy 160.275583 -137.251758)
			(xy 160.327517 -137.221774) (xy 160.382921 -137.198825) (xy 160.440846 -137.183304) (xy 160.500302 -137.175476)
			(xy 160.56027 -137.175476) (xy 160.619726 -137.183304) (xy 160.677651 -137.198825) (xy 160.733055 -137.221774)
			(xy 160.784989 -137.251758) (xy 160.832565 -137.288264) (xy 160.87497 -137.330669) (xy 160.911476 -137.378245)
			(xy 160.94146 -137.430179) (xy 160.964409 -137.485583) (xy 160.97993 -137.543508) (xy 160.987758 -137.602964)
			(xy 160.988248 -137.632948) (xy 160.988248 -138.496548) (xy 276.172676 -138.496548) (xy 276.172676 -137.632948)
			(xy 276.173166 -137.60298) (xy 276.180989 -137.543558) (xy 276.196502 -137.485665) (xy 276.219438 -137.430292)
			(xy 276.249405 -137.378386) (xy 276.285892 -137.330836) (xy 276.328272 -137.288456) (xy 276.375822 -137.251969)
			(xy 276.427728 -137.222002) (xy 276.483101 -137.199066) (xy 276.540994 -137.183553) (xy 276.600416 -137.17573)
			(xy 276.660352 -137.17573) (xy 276.719774 -137.183553) (xy 276.777667 -137.199066) (xy 276.83304 -137.222002)
			(xy 276.884946 -137.251969) (xy 276.932496 -137.288456) (xy 276.974876 -137.330836) (xy 277.011363 -137.378386)
			(xy 277.04133 -137.430292) (xy 277.064266 -137.485665) (xy 277.079779 -137.543558) (xy 277.087602 -137.60298)
			(xy 277.088092 -137.632948) (xy 277.088092 -138.496548) (xy 277.088084 -138.497056) (xy 392.27252 -138.497056)
			(xy 392.27252 -137.633456) (xy 392.27301 -137.603472) (xy 392.280838 -137.544016) (xy 392.296359 -137.486091)
			(xy 392.319308 -137.430687) (xy 392.349292 -137.378753) (xy 392.385798 -137.331177) (xy 392.428203 -137.288772)
			(xy 392.475779 -137.252266) (xy 392.527713 -137.222282) (xy 392.583117 -137.199333) (xy 392.641042 -137.183812)
			(xy 392.700498 -137.175984) (xy 392.760466 -137.175984) (xy 392.819922 -137.183812) (xy 392.877847 -137.199333)
			(xy 392.933251 -137.222282) (xy 392.985185 -137.252266) (xy 393.032761 -137.288772) (xy 393.075166 -137.331177)
			(xy 393.111672 -137.378753) (xy 393.141656 -137.430687) (xy 393.164605 -137.486091) (xy 393.180126 -137.544016)
			(xy 393.187954 -137.603472) (xy 393.188444 -137.633456) (xy 393.188444 -138.497056) (xy 393.187954 -138.52704)
			(xy 393.180126 -138.586496) (xy 393.164605 -138.644421) (xy 393.141656 -138.699825) (xy 393.111672 -138.751759)
			(xy 393.075166 -138.799335) (xy 393.032761 -138.84174) (xy 392.985185 -138.878246) (xy 392.933251 -138.90823)
			(xy 392.877847 -138.931179) (xy 392.819922 -138.9467) (xy 392.760466 -138.954528) (xy 392.700498 -138.954528)
			(xy 392.641042 -138.9467) (xy 392.583117 -138.931179) (xy 392.527713 -138.90823) (xy 392.475779 -138.878246)
			(xy 392.428203 -138.84174) (xy 392.385798 -138.799335) (xy 392.349292 -138.751759) (xy 392.319308 -138.699825)
			(xy 392.296359 -138.644421) (xy 392.280838 -138.586496) (xy 392.27301 -138.52704) (xy 392.27252 -138.497056)
			(xy 277.088084 -138.497056) (xy 277.087602 -138.526516) (xy 277.079779 -138.585938) (xy 277.064266 -138.643831)
			(xy 277.04133 -138.699204) (xy 277.011363 -138.75111) (xy 276.974876 -138.79866) (xy 276.932496 -138.84104)
			(xy 276.884946 -138.877527) (xy 276.83304 -138.907494) (xy 276.777667 -138.93043) (xy 276.719774 -138.945943)
			(xy 276.660352 -138.953766) (xy 276.600416 -138.953766) (xy 276.540994 -138.945943) (xy 276.483101 -138.93043)
			(xy 276.427728 -138.907494) (xy 276.375822 -138.877527) (xy 276.328272 -138.84104) (xy 276.285892 -138.79866)
			(xy 276.249405 -138.75111) (xy 276.219438 -138.699204) (xy 276.196502 -138.643831) (xy 276.180989 -138.585938)
			(xy 276.173166 -138.526516) (xy 276.172676 -138.496548) (xy 160.988248 -138.496548) (xy 160.987758 -138.526532)
			(xy 160.97993 -138.585988) (xy 160.964409 -138.643913) (xy 160.94146 -138.699317) (xy 160.911476 -138.751251)
			(xy 160.87497 -138.798827) (xy 160.832565 -138.841232) (xy 160.784989 -138.877738) (xy 160.733055 -138.907722)
			(xy 160.677651 -138.930671) (xy 160.619726 -138.946192) (xy 160.56027 -138.95402) (xy 160.500302 -138.95402)
			(xy 160.440846 -138.946192) (xy 160.382921 -138.930671) (xy 160.327517 -138.907722) (xy 160.275583 -138.877738)
			(xy 160.228007 -138.841232) (xy 160.185602 -138.798827) (xy 160.149096 -138.751251) (xy 160.119112 -138.699317)
			(xy 160.096163 -138.643913) (xy 160.080642 -138.585988) (xy 160.072814 -138.526532) (xy 160.072324 -138.496548)
			(xy 44.888404 -138.496548) (xy 44.887914 -138.526532) (xy 44.880086 -138.585988) (xy 44.864565 -138.643913)
			(xy 44.841616 -138.699317) (xy 44.811632 -138.751251) (xy 44.775126 -138.798827) (xy 44.732721 -138.841232)
			(xy 44.685145 -138.877738) (xy 44.633211 -138.907722) (xy 44.577807 -138.930671) (xy 44.519882 -138.946192)
			(xy 44.460426 -138.95402) (xy 44.400458 -138.95402) (xy 44.341002 -138.946192) (xy 44.283077 -138.930671)
			(xy 44.227673 -138.907722) (xy 44.175739 -138.877738) (xy 44.128163 -138.841232) (xy 44.085758 -138.798827)
			(xy 44.049252 -138.751251) (xy 44.019268 -138.699317) (xy 43.996319 -138.643913) (xy 43.980798 -138.585988)
			(xy 43.97297 -138.526532) (xy 43.97248 -138.496548) (xy 5.324094 -138.496548) (xy 5.324094 -143.48714)
			(xy 66.599308 -143.48714) (xy 66.599308 -142.62354) (xy 66.599798 -142.593556) (xy 66.607626 -142.5341)
			(xy 66.623147 -142.476175) (xy 66.646096 -142.420771) (xy 66.67608 -142.368837) (xy 66.712586 -142.321261)
			(xy 66.754991 -142.278856) (xy 66.802567 -142.24235) (xy 66.854501 -142.212366) (xy 66.909905 -142.189417)
			(xy 66.96783 -142.173896) (xy 67.027286 -142.166068) (xy 67.087254 -142.166068) (xy 67.14671 -142.173896)
			(xy 67.204635 -142.189417) (xy 67.260039 -142.212366) (xy 67.311973 -142.24235) (xy 67.359549 -142.278856)
			(xy 67.401954 -142.321261) (xy 67.43846 -142.368837) (xy 67.468444 -142.420771) (xy 67.491393 -142.476175)
			(xy 67.506914 -142.5341) (xy 67.514742 -142.593556) (xy 67.515232 -142.62354) (xy 67.515232 -143.479266)
			(xy 81.07426 -143.479266) (xy 81.07426 -142.615666) (xy 81.07475 -142.585682) (xy 81.082578 -142.526226)
			(xy 81.098099 -142.468301) (xy 81.121048 -142.412897) (xy 81.151032 -142.360963) (xy 81.187538 -142.313387)
			(xy 81.229943 -142.270982) (xy 81.277519 -142.234476) (xy 81.329453 -142.204492) (xy 81.384857 -142.181543)
			(xy 81.442782 -142.166022) (xy 81.502238 -142.158194) (xy 81.562206 -142.158194) (xy 81.621662 -142.166022)
			(xy 81.679587 -142.181543) (xy 81.734991 -142.204492) (xy 81.786925 -142.234476) (xy 81.834501 -142.270982)
			(xy 81.876906 -142.313387) (xy 81.913412 -142.360963) (xy 81.943396 -142.412897) (xy 81.966345 -142.468301)
			(xy 81.981866 -142.526226) (xy 81.989694 -142.585682) (xy 81.990184 -142.615666) (xy 81.990184 -143.479266)
			(xy 81.990055 -143.48714) (xy 182.69966 -143.48714) (xy 182.69966 -142.62354) (xy 182.70015 -142.593572)
			(xy 182.707973 -142.53415) (xy 182.723486 -142.476257) (xy 182.746422 -142.420884) (xy 182.776389 -142.368978)
			(xy 182.812876 -142.321428) (xy 182.855256 -142.279048) (xy 182.902806 -142.242561) (xy 182.954712 -142.212594)
			(xy 183.010085 -142.189658) (xy 183.067978 -142.174145) (xy 183.1274 -142.166322) (xy 183.187336 -142.166322)
			(xy 183.246758 -142.174145) (xy 183.304651 -142.189658) (xy 183.360024 -142.212594) (xy 183.41193 -142.242561)
			(xy 183.45948 -142.279048) (xy 183.50186 -142.321428) (xy 183.538347 -142.368978) (xy 183.568314 -142.420884)
			(xy 183.59125 -142.476257) (xy 183.606763 -142.53415) (xy 183.614586 -142.593572) (xy 183.615076 -142.62354)
			(xy 183.615076 -143.479266) (xy 197.174612 -143.479266) (xy 197.174612 -142.615666) (xy 197.175102 -142.585698)
			(xy 197.182925 -142.526276) (xy 197.198438 -142.468383) (xy 197.221374 -142.41301) (xy 197.251341 -142.361104)
			(xy 197.287828 -142.313554) (xy 197.330208 -142.271174) (xy 197.377758 -142.234687) (xy 197.429664 -142.20472)
			(xy 197.485037 -142.181784) (xy 197.54293 -142.166271) (xy 197.602352 -142.158448) (xy 197.662288 -142.158448)
			(xy 197.72171 -142.166271) (xy 197.779603 -142.181784) (xy 197.834976 -142.20472) (xy 197.886882 -142.234687)
			(xy 197.934432 -142.271174) (xy 197.976812 -142.313554) (xy 198.013299 -142.361104) (xy 198.043266 -142.41301)
			(xy 198.066202 -142.468383) (xy 198.081715 -142.526276) (xy 198.089538 -142.585698) (xy 198.090028 -142.615666)
			(xy 198.090028 -143.479266) (xy 198.089899 -143.48714) (xy 298.799504 -143.48714) (xy 298.799504 -142.62354)
			(xy 298.799994 -142.593572) (xy 298.807817 -142.53415) (xy 298.82333 -142.476257) (xy 298.846266 -142.420884)
			(xy 298.876233 -142.368978) (xy 298.91272 -142.321428) (xy 298.9551 -142.279048) (xy 299.00265 -142.242561)
			(xy 299.054556 -142.212594) (xy 299.109929 -142.189658) (xy 299.167822 -142.174145) (xy 299.227244 -142.166322)
			(xy 299.28718 -142.166322) (xy 299.346602 -142.174145) (xy 299.404495 -142.189658) (xy 299.459868 -142.212594)
			(xy 299.511774 -142.242561) (xy 299.559324 -142.279048) (xy 299.601704 -142.321428) (xy 299.638191 -142.368978)
			(xy 299.668158 -142.420884) (xy 299.691094 -142.476257) (xy 299.706607 -142.53415) (xy 299.71443 -142.593572)
			(xy 299.71492 -142.62354) (xy 299.71492 -143.479266) (xy 313.274456 -143.479266) (xy 313.274456 -142.615666)
			(xy 313.274946 -142.585698) (xy 313.282769 -142.526276) (xy 313.298282 -142.468383) (xy 313.321218 -142.41301)
			(xy 313.351185 -142.361104) (xy 313.387672 -142.313554) (xy 313.430052 -142.271174) (xy 313.477602 -142.234687)
			(xy 313.529508 -142.20472) (xy 313.584881 -142.181784) (xy 313.642774 -142.166271) (xy 313.702196 -142.158448)
			(xy 313.762132 -142.158448) (xy 313.821554 -142.166271) (xy 313.879447 -142.181784) (xy 313.93482 -142.20472)
			(xy 313.986726 -142.234687) (xy 314.034276 -142.271174) (xy 314.076656 -142.313554) (xy 314.113143 -142.361104)
			(xy 314.14311 -142.41301) (xy 314.166046 -142.468383) (xy 314.181559 -142.526276) (xy 314.189382 -142.585698)
			(xy 314.189872 -142.615666) (xy 314.189872 -143.479266) (xy 314.189743 -143.48714) (xy 414.899348 -143.48714)
			(xy 414.899348 -142.62354) (xy 414.899838 -142.593556) (xy 414.907666 -142.5341) (xy 414.923187 -142.476175)
			(xy 414.946136 -142.420771) (xy 414.97612 -142.368837) (xy 415.012626 -142.321261) (xy 415.055031 -142.278856)
			(xy 415.102607 -142.24235) (xy 415.154541 -142.212366) (xy 415.209945 -142.189417) (xy 415.26787 -142.173896)
			(xy 415.327326 -142.166068) (xy 415.387294 -142.166068) (xy 415.44675 -142.173896) (xy 415.504675 -142.189417)
			(xy 415.560079 -142.212366) (xy 415.612013 -142.24235) (xy 415.659589 -142.278856) (xy 415.701994 -142.321261)
			(xy 415.7385 -142.368837) (xy 415.768484 -142.420771) (xy 415.791433 -142.476175) (xy 415.806954 -142.5341)
			(xy 415.814782 -142.593556) (xy 415.815272 -142.62354) (xy 415.815272 -143.479266) (xy 429.3743 -143.479266)
			(xy 429.3743 -142.615666) (xy 429.37479 -142.585682) (xy 429.382618 -142.526226) (xy 429.398139 -142.468301)
			(xy 429.421088 -142.412897) (xy 429.451072 -142.360963) (xy 429.487578 -142.313387) (xy 429.529983 -142.270982)
			(xy 429.577559 -142.234476) (xy 429.629493 -142.204492) (xy 429.684897 -142.181543) (xy 429.742822 -142.166022)
			(xy 429.802278 -142.158194) (xy 429.862246 -142.158194) (xy 429.921702 -142.166022) (xy 429.979627 -142.181543)
			(xy 430.035031 -142.204492) (xy 430.086965 -142.234476) (xy 430.134541 -142.270982) (xy 430.176946 -142.313387)
			(xy 430.213452 -142.360963) (xy 430.243436 -142.412897) (xy 430.266385 -142.468301) (xy 430.281906 -142.526226)
			(xy 430.289734 -142.585682) (xy 430.290224 -142.615666) (xy 430.290224 -143.479266) (xy 430.289734 -143.50925)
			(xy 430.281906 -143.568706) (xy 430.266385 -143.626631) (xy 430.243436 -143.682035) (xy 430.213452 -143.733969)
			(xy 430.176946 -143.781545) (xy 430.134541 -143.82395) (xy 430.086965 -143.860456) (xy 430.035031 -143.89044)
			(xy 429.979627 -143.913389) (xy 429.921702 -143.92891) (xy 429.862246 -143.936738) (xy 429.802278 -143.936738)
			(xy 429.742822 -143.92891) (xy 429.684897 -143.913389) (xy 429.629493 -143.89044) (xy 429.577559 -143.860456)
			(xy 429.529983 -143.82395) (xy 429.487578 -143.781545) (xy 429.451072 -143.733969) (xy 429.421088 -143.682035)
			(xy 429.398139 -143.626631) (xy 429.382618 -143.568706) (xy 429.37479 -143.50925) (xy 429.3743 -143.479266)
			(xy 415.815272 -143.479266) (xy 415.815272 -143.48714) (xy 415.814782 -143.517124) (xy 415.806954 -143.57658)
			(xy 415.791433 -143.634505) (xy 415.768484 -143.689909) (xy 415.7385 -143.741843) (xy 415.701994 -143.789419)
			(xy 415.659589 -143.831824) (xy 415.612013 -143.86833) (xy 415.560079 -143.898314) (xy 415.504675 -143.921263)
			(xy 415.44675 -143.936784) (xy 415.387294 -143.944612) (xy 415.327326 -143.944612) (xy 415.26787 -143.936784)
			(xy 415.209945 -143.921263) (xy 415.154541 -143.898314) (xy 415.102607 -143.86833) (xy 415.055031 -143.831824)
			(xy 415.012626 -143.789419) (xy 414.97612 -143.741843) (xy 414.946136 -143.689909) (xy 414.923187 -143.634505)
			(xy 414.907666 -143.57658) (xy 414.899838 -143.517124) (xy 414.899348 -143.48714) (xy 314.189743 -143.48714)
			(xy 314.189382 -143.509234) (xy 314.181559 -143.568656) (xy 314.166046 -143.626549) (xy 314.14311 -143.681922)
			(xy 314.113143 -143.733828) (xy 314.076656 -143.781378) (xy 314.034276 -143.823758) (xy 313.986726 -143.860245)
			(xy 313.93482 -143.890212) (xy 313.879447 -143.913148) (xy 313.821554 -143.928661) (xy 313.762132 -143.936484)
			(xy 313.702196 -143.936484) (xy 313.642774 -143.928661) (xy 313.584881 -143.913148) (xy 313.529508 -143.890212)
			(xy 313.477602 -143.860245) (xy 313.430052 -143.823758) (xy 313.387672 -143.781378) (xy 313.351185 -143.733828)
			(xy 313.321218 -143.681922) (xy 313.298282 -143.626549) (xy 313.282769 -143.568656) (xy 313.274946 -143.509234)
			(xy 313.274456 -143.479266) (xy 299.71492 -143.479266) (xy 299.71492 -143.48714) (xy 299.71443 -143.517108)
			(xy 299.706607 -143.57653) (xy 299.691094 -143.634423) (xy 299.668158 -143.689796) (xy 299.638191 -143.741702)
			(xy 299.601704 -143.789252) (xy 299.559324 -143.831632) (xy 299.511774 -143.868119) (xy 299.459868 -143.898086)
			(xy 299.404495 -143.921022) (xy 299.346602 -143.936535) (xy 299.28718 -143.944358) (xy 299.227244 -143.944358)
			(xy 299.167822 -143.936535) (xy 299.109929 -143.921022) (xy 299.054556 -143.898086) (xy 299.00265 -143.868119)
			(xy 298.9551 -143.831632) (xy 298.91272 -143.789252) (xy 298.876233 -143.741702) (xy 298.846266 -143.689796)
			(xy 298.82333 -143.634423) (xy 298.807817 -143.57653) (xy 298.799994 -143.517108) (xy 298.799504 -143.48714)
			(xy 198.089899 -143.48714) (xy 198.089538 -143.509234) (xy 198.081715 -143.568656) (xy 198.066202 -143.626549)
			(xy 198.043266 -143.681922) (xy 198.013299 -143.733828) (xy 197.976812 -143.781378) (xy 197.934432 -143.823758)
			(xy 197.886882 -143.860245) (xy 197.834976 -143.890212) (xy 197.779603 -143.913148) (xy 197.72171 -143.928661)
			(xy 197.662288 -143.936484) (xy 197.602352 -143.936484) (xy 197.54293 -143.928661) (xy 197.485037 -143.913148)
			(xy 197.429664 -143.890212) (xy 197.377758 -143.860245) (xy 197.330208 -143.823758) (xy 197.287828 -143.781378)
			(xy 197.251341 -143.733828) (xy 197.221374 -143.681922) (xy 197.198438 -143.626549) (xy 197.182925 -143.568656)
			(xy 197.175102 -143.509234) (xy 197.174612 -143.479266) (xy 183.615076 -143.479266) (xy 183.615076 -143.48714)
			(xy 183.614586 -143.517108) (xy 183.606763 -143.57653) (xy 183.59125 -143.634423) (xy 183.568314 -143.689796)
			(xy 183.538347 -143.741702) (xy 183.50186 -143.789252) (xy 183.45948 -143.831632) (xy 183.41193 -143.868119)
			(xy 183.360024 -143.898086) (xy 183.304651 -143.921022) (xy 183.246758 -143.936535) (xy 183.187336 -143.944358)
			(xy 183.1274 -143.944358) (xy 183.067978 -143.936535) (xy 183.010085 -143.921022) (xy 182.954712 -143.898086)
			(xy 182.902806 -143.868119) (xy 182.855256 -143.831632) (xy 182.812876 -143.789252) (xy 182.776389 -143.741702)
			(xy 182.746422 -143.689796) (xy 182.723486 -143.634423) (xy 182.707973 -143.57653) (xy 182.70015 -143.517108)
			(xy 182.69966 -143.48714) (xy 81.990055 -143.48714) (xy 81.989694 -143.50925) (xy 81.981866 -143.568706)
			(xy 81.966345 -143.626631) (xy 81.943396 -143.682035) (xy 81.913412 -143.733969) (xy 81.876906 -143.781545)
			(xy 81.834501 -143.82395) (xy 81.786925 -143.860456) (xy 81.734991 -143.89044) (xy 81.679587 -143.913389)
			(xy 81.621662 -143.92891) (xy 81.562206 -143.936738) (xy 81.502238 -143.936738) (xy 81.442782 -143.92891)
			(xy 81.384857 -143.913389) (xy 81.329453 -143.89044) (xy 81.277519 -143.860456) (xy 81.229943 -143.82395)
			(xy 81.187538 -143.781545) (xy 81.151032 -143.733969) (xy 81.121048 -143.682035) (xy 81.098099 -143.626631)
			(xy 81.082578 -143.568706) (xy 81.07475 -143.50925) (xy 81.07426 -143.479266) (xy 67.515232 -143.479266)
			(xy 67.515232 -143.48714) (xy 67.514742 -143.517124) (xy 67.506914 -143.57658) (xy 67.491393 -143.634505)
			(xy 67.468444 -143.689909) (xy 67.43846 -143.741843) (xy 67.401954 -143.789419) (xy 67.359549 -143.831824)
			(xy 67.311973 -143.86833) (xy 67.260039 -143.898314) (xy 67.204635 -143.921263) (xy 67.14671 -143.936784)
			(xy 67.087254 -143.944612) (xy 67.027286 -143.944612) (xy 66.96783 -143.936784) (xy 66.909905 -143.921263)
			(xy 66.854501 -143.898314) (xy 66.802567 -143.86833) (xy 66.754991 -143.831824) (xy 66.712586 -143.789419)
			(xy 66.67608 -143.741843) (xy 66.646096 -143.689909) (xy 66.623147 -143.634505) (xy 66.607626 -143.57658)
			(xy 66.599798 -143.517124) (xy 66.599308 -143.48714) (xy 5.324094 -143.48714) (xy 5.324094 -145.287238)
			(xy 64.745108 -145.287238) (xy 64.745108 -144.423638) (xy 64.745598 -144.393654) (xy 64.753426 -144.334198)
			(xy 64.768947 -144.276273) (xy 64.791896 -144.220869) (xy 64.82188 -144.168935) (xy 64.858386 -144.121359)
			(xy 64.900791 -144.078954) (xy 64.948367 -144.042448) (xy 65.000301 -144.012464) (xy 65.055705 -143.989515)
			(xy 65.11363 -143.973994) (xy 65.173086 -143.966166) (xy 65.233054 -143.966166) (xy 65.29251 -143.973994)
			(xy 65.350435 -143.989515) (xy 65.405839 -144.012464) (xy 65.457773 -144.042448) (xy 65.505349 -144.078954)
			(xy 65.547754 -144.121359) (xy 65.58426 -144.168935) (xy 65.614244 -144.220869) (xy 65.637193 -144.276273)
			(xy 65.652714 -144.334198) (xy 65.660542 -144.393654) (xy 65.661032 -144.423638) (xy 65.661032 -145.285714)
			(xy 83.716368 -145.285714) (xy 83.716368 -144.422114) (xy 83.716858 -144.39213) (xy 83.724686 -144.332674)
			(xy 83.740207 -144.274749) (xy 83.763156 -144.219345) (xy 83.79314 -144.167411) (xy 83.829646 -144.119835)
			(xy 83.872051 -144.07743) (xy 83.919627 -144.040924) (xy 83.971561 -144.01094) (xy 84.026965 -143.987991)
			(xy 84.08489 -143.97247) (xy 84.144346 -143.964642) (xy 84.204314 -143.964642) (xy 84.26377 -143.97247)
			(xy 84.321695 -143.987991) (xy 84.377099 -144.01094) (xy 84.429033 -144.040924) (xy 84.476609 -144.07743)
			(xy 84.519014 -144.119835) (xy 84.55552 -144.167411) (xy 84.585504 -144.219345) (xy 84.608453 -144.274749)
			(xy 84.623974 -144.332674) (xy 84.631802 -144.39213) (xy 84.632292 -144.422114) (xy 84.632292 -145.285714)
			(xy 84.632267 -145.287238) (xy 180.84546 -145.287238) (xy 180.84546 -144.423638) (xy 180.84595 -144.39367)
			(xy 180.853773 -144.334248) (xy 180.869286 -144.276355) (xy 180.892222 -144.220982) (xy 180.922189 -144.169076)
			(xy 180.958676 -144.121526) (xy 181.001056 -144.079146) (xy 181.048606 -144.042659) (xy 181.100512 -144.012692)
			(xy 181.155885 -143.989756) (xy 181.213778 -143.974243) (xy 181.2732 -143.96642) (xy 181.333136 -143.96642)
			(xy 181.392558 -143.974243) (xy 181.450451 -143.989756) (xy 181.505824 -144.012692) (xy 181.55773 -144.042659)
			(xy 181.60528 -144.079146) (xy 181.64766 -144.121526) (xy 181.684147 -144.169076) (xy 181.714114 -144.220982)
			(xy 181.73705 -144.276355) (xy 181.752563 -144.334248) (xy 181.760386 -144.39367) (xy 181.760876 -144.423638)
			(xy 181.760876 -145.285714) (xy 199.81672 -145.285714) (xy 199.81672 -144.422114) (xy 199.81721 -144.392146)
			(xy 199.825033 -144.332724) (xy 199.840546 -144.274831) (xy 199.863482 -144.219458) (xy 199.893449 -144.167552)
			(xy 199.929936 -144.120002) (xy 199.972316 -144.077622) (xy 200.019866 -144.041135) (xy 200.071772 -144.011168)
			(xy 200.127145 -143.988232) (xy 200.185038 -143.972719) (xy 200.24446 -143.964896) (xy 200.304396 -143.964896)
			(xy 200.363818 -143.972719) (xy 200.421711 -143.988232) (xy 200.477084 -144.011168) (xy 200.52899 -144.041135)
			(xy 200.57654 -144.077622) (xy 200.61892 -144.120002) (xy 200.655407 -144.167552) (xy 200.685374 -144.219458)
			(xy 200.70831 -144.274831) (xy 200.723823 -144.332724) (xy 200.731646 -144.392146) (xy 200.732136 -144.422114)
			(xy 200.732136 -145.285714) (xy 200.732111 -145.287238) (xy 296.945304 -145.287238) (xy 296.945304 -144.423638)
			(xy 296.945794 -144.39367) (xy 296.953617 -144.334248) (xy 296.96913 -144.276355) (xy 296.992066 -144.220982)
			(xy 297.022033 -144.169076) (xy 297.05852 -144.121526) (xy 297.1009 -144.079146) (xy 297.14845 -144.042659)
			(xy 297.200356 -144.012692) (xy 297.255729 -143.989756) (xy 297.313622 -143.974243) (xy 297.373044 -143.96642)
			(xy 297.43298 -143.96642) (xy 297.492402 -143.974243) (xy 297.550295 -143.989756) (xy 297.605668 -144.012692)
			(xy 297.657574 -144.042659) (xy 297.705124 -144.079146) (xy 297.747504 -144.121526) (xy 297.783991 -144.169076)
			(xy 297.813958 -144.220982) (xy 297.836894 -144.276355) (xy 297.852407 -144.334248) (xy 297.86023 -144.39367)
			(xy 297.86072 -144.423638) (xy 297.86072 -145.285714) (xy 315.916564 -145.285714) (xy 315.916564 -144.422114)
			(xy 315.917054 -144.392146) (xy 315.924877 -144.332724) (xy 315.94039 -144.274831) (xy 315.963326 -144.219458)
			(xy 315.993293 -144.167552) (xy 316.02978 -144.120002) (xy 316.07216 -144.077622) (xy 316.11971 -144.041135)
			(xy 316.171616 -144.011168) (xy 316.226989 -143.988232) (xy 316.284882 -143.972719) (xy 316.344304 -143.964896)
			(xy 316.40424 -143.964896) (xy 316.463662 -143.972719) (xy 316.521555 -143.988232) (xy 316.576928 -144.011168)
			(xy 316.628834 -144.041135) (xy 316.676384 -144.077622) (xy 316.718764 -144.120002) (xy 316.755251 -144.167552)
			(xy 316.785218 -144.219458) (xy 316.808154 -144.274831) (xy 316.823667 -144.332724) (xy 316.83149 -144.392146)
			(xy 316.83198 -144.422114) (xy 316.83198 -145.285714) (xy 316.831955 -145.287238) (xy 413.045148 -145.287238)
			(xy 413.045148 -144.423638) (xy 413.045638 -144.393654) (xy 413.053466 -144.334198) (xy 413.068987 -144.276273)
			(xy 413.091936 -144.220869) (xy 413.12192 -144.168935) (xy 413.158426 -144.121359) (xy 413.200831 -144.078954)
			(xy 413.248407 -144.042448) (xy 413.300341 -144.012464) (xy 413.355745 -143.989515) (xy 413.41367 -143.973994)
			(xy 413.473126 -143.966166) (xy 413.533094 -143.966166) (xy 413.59255 -143.973994) (xy 413.650475 -143.989515)
			(xy 413.705879 -144.012464) (xy 413.757813 -144.042448) (xy 413.805389 -144.078954) (xy 413.847794 -144.121359)
			(xy 413.8843 -144.168935) (xy 413.914284 -144.220869) (xy 413.937233 -144.276273) (xy 413.952754 -144.334198)
			(xy 413.960582 -144.393654) (xy 413.961072 -144.423638) (xy 413.961072 -145.285714) (xy 432.016408 -145.285714)
			(xy 432.016408 -144.422114) (xy 432.016898 -144.39213) (xy 432.024726 -144.332674) (xy 432.040247 -144.274749)
			(xy 432.063196 -144.219345) (xy 432.09318 -144.167411) (xy 432.129686 -144.119835) (xy 432.172091 -144.07743)
			(xy 432.219667 -144.040924) (xy 432.271601 -144.01094) (xy 432.327005 -143.987991) (xy 432.38493 -143.97247)
			(xy 432.444386 -143.964642) (xy 432.504354 -143.964642) (xy 432.56381 -143.97247) (xy 432.621735 -143.987991)
			(xy 432.677139 -144.01094) (xy 432.729073 -144.040924) (xy 432.776649 -144.07743) (xy 432.819054 -144.119835)
			(xy 432.85556 -144.167411) (xy 432.885544 -144.219345) (xy 432.908493 -144.274749) (xy 432.924014 -144.332674)
			(xy 432.931842 -144.39213) (xy 432.932332 -144.422114) (xy 432.932332 -145.285714) (xy 432.931842 -145.315698)
			(xy 432.924014 -145.375154) (xy 432.908493 -145.433079) (xy 432.885544 -145.488483) (xy 432.85556 -145.540417)
			(xy 432.819054 -145.587993) (xy 432.776649 -145.630398) (xy 432.729073 -145.666904) (xy 432.677139 -145.696888)
			(xy 432.621735 -145.719837) (xy 432.56381 -145.735358) (xy 432.504354 -145.743186) (xy 432.444386 -145.743186)
			(xy 432.38493 -145.735358) (xy 432.327005 -145.719837) (xy 432.271601 -145.696888) (xy 432.219667 -145.666904)
			(xy 432.172091 -145.630398) (xy 432.129686 -145.587993) (xy 432.09318 -145.540417) (xy 432.063196 -145.488483)
			(xy 432.040247 -145.433079) (xy 432.024726 -145.375154) (xy 432.016898 -145.315698) (xy 432.016408 -145.285714)
			(xy 413.961072 -145.285714) (xy 413.961072 -145.287238) (xy 413.960582 -145.317222) (xy 413.952754 -145.376678)
			(xy 413.937233 -145.434603) (xy 413.914284 -145.490007) (xy 413.8843 -145.541941) (xy 413.847794 -145.589517)
			(xy 413.805389 -145.631922) (xy 413.757813 -145.668428) (xy 413.705879 -145.698412) (xy 413.650475 -145.721361)
			(xy 413.59255 -145.736882) (xy 413.533094 -145.74471) (xy 413.473126 -145.74471) (xy 413.41367 -145.736882)
			(xy 413.355745 -145.721361) (xy 413.300341 -145.698412) (xy 413.248407 -145.668428) (xy 413.200831 -145.631922)
			(xy 413.158426 -145.589517) (xy 413.12192 -145.541941) (xy 413.091936 -145.490007) (xy 413.068987 -145.434603)
			(xy 413.053466 -145.376678) (xy 413.045638 -145.317222) (xy 413.045148 -145.287238) (xy 316.831955 -145.287238)
			(xy 316.83149 -145.315682) (xy 316.823667 -145.375104) (xy 316.808154 -145.432997) (xy 316.785218 -145.48837)
			(xy 316.755251 -145.540276) (xy 316.718764 -145.587826) (xy 316.676384 -145.630206) (xy 316.628834 -145.666693)
			(xy 316.576928 -145.69666) (xy 316.521555 -145.719596) (xy 316.463662 -145.735109) (xy 316.40424 -145.742932)
			(xy 316.344304 -145.742932) (xy 316.284882 -145.735109) (xy 316.226989 -145.719596) (xy 316.171616 -145.69666)
			(xy 316.11971 -145.666693) (xy 316.07216 -145.630206) (xy 316.02978 -145.587826) (xy 315.993293 -145.540276)
			(xy 315.963326 -145.48837) (xy 315.94039 -145.432997) (xy 315.924877 -145.375104) (xy 315.917054 -145.315682)
			(xy 315.916564 -145.285714) (xy 297.86072 -145.285714) (xy 297.86072 -145.287238) (xy 297.86023 -145.317206)
			(xy 297.852407 -145.376628) (xy 297.836894 -145.434521) (xy 297.813958 -145.489894) (xy 297.783991 -145.5418)
			(xy 297.747504 -145.58935) (xy 297.705124 -145.63173) (xy 297.657574 -145.668217) (xy 297.605668 -145.698184)
			(xy 297.550295 -145.72112) (xy 297.492402 -145.736633) (xy 297.43298 -145.744456) (xy 297.373044 -145.744456)
			(xy 297.313622 -145.736633) (xy 297.255729 -145.72112) (xy 297.200356 -145.698184) (xy 297.14845 -145.668217)
			(xy 297.1009 -145.63173) (xy 297.05852 -145.58935) (xy 297.022033 -145.5418) (xy 296.992066 -145.489894)
			(xy 296.96913 -145.434521) (xy 296.953617 -145.376628) (xy 296.945794 -145.317206) (xy 296.945304 -145.287238)
			(xy 200.732111 -145.287238) (xy 200.731646 -145.315682) (xy 200.723823 -145.375104) (xy 200.70831 -145.432997)
			(xy 200.685374 -145.48837) (xy 200.655407 -145.540276) (xy 200.61892 -145.587826) (xy 200.57654 -145.630206)
			(xy 200.52899 -145.666693) (xy 200.477084 -145.69666) (xy 200.421711 -145.719596) (xy 200.363818 -145.735109)
			(xy 200.304396 -145.742932) (xy 200.24446 -145.742932) (xy 200.185038 -145.735109) (xy 200.127145 -145.719596)
			(xy 200.071772 -145.69666) (xy 200.019866 -145.666693) (xy 199.972316 -145.630206) (xy 199.929936 -145.587826)
			(xy 199.893449 -145.540276) (xy 199.863482 -145.48837) (xy 199.840546 -145.432997) (xy 199.825033 -145.375104)
			(xy 199.81721 -145.315682) (xy 199.81672 -145.285714) (xy 181.760876 -145.285714) (xy 181.760876 -145.287238)
			(xy 181.760386 -145.317206) (xy 181.752563 -145.376628) (xy 181.73705 -145.434521) (xy 181.714114 -145.489894)
			(xy 181.684147 -145.5418) (xy 181.64766 -145.58935) (xy 181.60528 -145.63173) (xy 181.55773 -145.668217)
			(xy 181.505824 -145.698184) (xy 181.450451 -145.72112) (xy 181.392558 -145.736633) (xy 181.333136 -145.744456)
			(xy 181.2732 -145.744456) (xy 181.213778 -145.736633) (xy 181.155885 -145.72112) (xy 181.100512 -145.698184)
			(xy 181.048606 -145.668217) (xy 181.001056 -145.63173) (xy 180.958676 -145.58935) (xy 180.922189 -145.5418)
			(xy 180.892222 -145.489894) (xy 180.869286 -145.434521) (xy 180.853773 -145.376628) (xy 180.84595 -145.317206)
			(xy 180.84546 -145.287238) (xy 84.632267 -145.287238) (xy 84.631802 -145.315698) (xy 84.623974 -145.375154)
			(xy 84.608453 -145.433079) (xy 84.585504 -145.488483) (xy 84.55552 -145.540417) (xy 84.519014 -145.587993)
			(xy 84.476609 -145.630398) (xy 84.429033 -145.666904) (xy 84.377099 -145.696888) (xy 84.321695 -145.719837)
			(xy 84.26377 -145.735358) (xy 84.204314 -145.743186) (xy 84.144346 -145.743186) (xy 84.08489 -145.735358)
			(xy 84.026965 -145.719837) (xy 83.971561 -145.696888) (xy 83.919627 -145.666904) (xy 83.872051 -145.630398)
			(xy 83.829646 -145.587993) (xy 83.79314 -145.540417) (xy 83.763156 -145.488483) (xy 83.740207 -145.433079)
			(xy 83.724686 -145.375154) (xy 83.716858 -145.315698) (xy 83.716368 -145.285714) (xy 65.661032 -145.285714)
			(xy 65.661032 -145.287238) (xy 65.660542 -145.317222) (xy 65.652714 -145.376678) (xy 65.637193 -145.434603)
			(xy 65.614244 -145.490007) (xy 65.58426 -145.541941) (xy 65.547754 -145.589517) (xy 65.505349 -145.631922)
			(xy 65.457773 -145.668428) (xy 65.405839 -145.698412) (xy 65.350435 -145.721361) (xy 65.29251 -145.736882)
			(xy 65.233054 -145.74471) (xy 65.173086 -145.74471) (xy 65.11363 -145.736882) (xy 65.055705 -145.721361)
			(xy 65.000301 -145.698412) (xy 64.948367 -145.668428) (xy 64.900791 -145.631922) (xy 64.858386 -145.589517)
			(xy 64.82188 -145.541941) (xy 64.791896 -145.490007) (xy 64.768947 -145.434603) (xy 64.753426 -145.376678)
			(xy 64.745598 -145.317222) (xy 64.745108 -145.287238) (xy 5.324094 -145.287238) (xy 5.324094 -147.087336)
			(xy 66.599308 -147.087336) (xy 66.599308 -146.223736) (xy 66.599798 -146.193752) (xy 66.607626 -146.134296)
			(xy 66.623147 -146.076371) (xy 66.646096 -146.020967) (xy 66.67608 -145.969033) (xy 66.712586 -145.921457)
			(xy 66.754991 -145.879052) (xy 66.802567 -145.842546) (xy 66.854501 -145.812562) (xy 66.909905 -145.789613)
			(xy 66.96783 -145.774092) (xy 67.027286 -145.766264) (xy 67.087254 -145.766264) (xy 67.14671 -145.774092)
			(xy 67.204635 -145.789613) (xy 67.260039 -145.812562) (xy 67.311973 -145.842546) (xy 67.359549 -145.879052)
			(xy 67.401954 -145.921457) (xy 67.43846 -145.969033) (xy 67.468444 -146.020967) (xy 67.491393 -146.076371)
			(xy 67.506914 -146.134296) (xy 67.514742 -146.193752) (xy 67.515232 -146.223736) (xy 67.515232 -147.079208)
			(xy 81.07426 -147.079208) (xy 81.07426 -146.215608) (xy 81.07475 -146.185624) (xy 81.082578 -146.126168)
			(xy 81.098099 -146.068243) (xy 81.121048 -146.012839) (xy 81.151032 -145.960905) (xy 81.187538 -145.913329)
			(xy 81.229943 -145.870924) (xy 81.277519 -145.834418) (xy 81.329453 -145.804434) (xy 81.384857 -145.781485)
			(xy 81.442782 -145.765964) (xy 81.502238 -145.758136) (xy 81.562206 -145.758136) (xy 81.621662 -145.765964)
			(xy 81.679587 -145.781485) (xy 81.734991 -145.804434) (xy 81.786925 -145.834418) (xy 81.834501 -145.870924)
			(xy 81.876906 -145.913329) (xy 81.913412 -145.960905) (xy 81.943396 -146.012839) (xy 81.966345 -146.068243)
			(xy 81.981866 -146.126168) (xy 81.989694 -146.185624) (xy 81.990184 -146.215608) (xy 81.990184 -147.079208)
			(xy 81.990051 -147.087336) (xy 182.69966 -147.087336) (xy 182.69966 -146.223736) (xy 182.70015 -146.193768)
			(xy 182.707973 -146.134346) (xy 182.723486 -146.076453) (xy 182.746422 -146.02108) (xy 182.776389 -145.969174)
			(xy 182.812876 -145.921624) (xy 182.855256 -145.879244) (xy 182.902806 -145.842757) (xy 182.954712 -145.81279)
			(xy 183.010085 -145.789854) (xy 183.067978 -145.774341) (xy 183.1274 -145.766518) (xy 183.187336 -145.766518)
			(xy 183.246758 -145.774341) (xy 183.304651 -145.789854) (xy 183.360024 -145.81279) (xy 183.41193 -145.842757)
			(xy 183.45948 -145.879244) (xy 183.50186 -145.921624) (xy 183.538347 -145.969174) (xy 183.568314 -146.02108)
			(xy 183.59125 -146.076453) (xy 183.606763 -146.134346) (xy 183.614586 -146.193768) (xy 183.615076 -146.223736)
			(xy 183.615076 -147.079208) (xy 197.174612 -147.079208) (xy 197.174612 -146.215608) (xy 197.175102 -146.18564)
			(xy 197.182925 -146.126218) (xy 197.198438 -146.068325) (xy 197.221374 -146.012952) (xy 197.251341 -145.961046)
			(xy 197.287828 -145.913496) (xy 197.330208 -145.871116) (xy 197.377758 -145.834629) (xy 197.429664 -145.804662)
			(xy 197.485037 -145.781726) (xy 197.54293 -145.766213) (xy 197.602352 -145.75839) (xy 197.662288 -145.75839)
			(xy 197.72171 -145.766213) (xy 197.779603 -145.781726) (xy 197.834976 -145.804662) (xy 197.886882 -145.834629)
			(xy 197.934432 -145.871116) (xy 197.976812 -145.913496) (xy 198.013299 -145.961046) (xy 198.043266 -146.012952)
			(xy 198.066202 -146.068325) (xy 198.081715 -146.126218) (xy 198.089538 -146.18564) (xy 198.090028 -146.215608)
			(xy 198.090028 -147.079208) (xy 198.089895 -147.087336) (xy 298.799504 -147.087336) (xy 298.799504 -146.223736)
			(xy 298.799994 -146.193768) (xy 298.807817 -146.134346) (xy 298.82333 -146.076453) (xy 298.846266 -146.02108)
			(xy 298.876233 -145.969174) (xy 298.91272 -145.921624) (xy 298.9551 -145.879244) (xy 299.00265 -145.842757)
			(xy 299.054556 -145.81279) (xy 299.109929 -145.789854) (xy 299.167822 -145.774341) (xy 299.227244 -145.766518)
			(xy 299.28718 -145.766518) (xy 299.346602 -145.774341) (xy 299.404495 -145.789854) (xy 299.459868 -145.81279)
			(xy 299.511774 -145.842757) (xy 299.559324 -145.879244) (xy 299.601704 -145.921624) (xy 299.638191 -145.969174)
			(xy 299.668158 -146.02108) (xy 299.691094 -146.076453) (xy 299.706607 -146.134346) (xy 299.71443 -146.193768)
			(xy 299.71492 -146.223736) (xy 299.71492 -147.079208) (xy 313.274456 -147.079208) (xy 313.274456 -146.215608)
			(xy 313.274946 -146.18564) (xy 313.282769 -146.126218) (xy 313.298282 -146.068325) (xy 313.321218 -146.012952)
			(xy 313.351185 -145.961046) (xy 313.387672 -145.913496) (xy 313.430052 -145.871116) (xy 313.477602 -145.834629)
			(xy 313.529508 -145.804662) (xy 313.584881 -145.781726) (xy 313.642774 -145.766213) (xy 313.702196 -145.75839)
			(xy 313.762132 -145.75839) (xy 313.821554 -145.766213) (xy 313.879447 -145.781726) (xy 313.93482 -145.804662)
			(xy 313.986726 -145.834629) (xy 314.034276 -145.871116) (xy 314.076656 -145.913496) (xy 314.113143 -145.961046)
			(xy 314.14311 -146.012952) (xy 314.166046 -146.068325) (xy 314.181559 -146.126218) (xy 314.189382 -146.18564)
			(xy 314.189872 -146.215608) (xy 314.189872 -147.079208) (xy 314.189739 -147.087336) (xy 414.899348 -147.087336)
			(xy 414.899348 -146.223736) (xy 414.899838 -146.193752) (xy 414.907666 -146.134296) (xy 414.923187 -146.076371)
			(xy 414.946136 -146.020967) (xy 414.97612 -145.969033) (xy 415.012626 -145.921457) (xy 415.055031 -145.879052)
			(xy 415.102607 -145.842546) (xy 415.154541 -145.812562) (xy 415.209945 -145.789613) (xy 415.26787 -145.774092)
			(xy 415.327326 -145.766264) (xy 415.387294 -145.766264) (xy 415.44675 -145.774092) (xy 415.504675 -145.789613)
			(xy 415.560079 -145.812562) (xy 415.612013 -145.842546) (xy 415.659589 -145.879052) (xy 415.701994 -145.921457)
			(xy 415.7385 -145.969033) (xy 415.768484 -146.020967) (xy 415.791433 -146.076371) (xy 415.806954 -146.134296)
			(xy 415.814782 -146.193752) (xy 415.815272 -146.223736) (xy 415.815272 -147.079208) (xy 429.3743 -147.079208)
			(xy 429.3743 -146.215608) (xy 429.37479 -146.185624) (xy 429.382618 -146.126168) (xy 429.398139 -146.068243)
			(xy 429.421088 -146.012839) (xy 429.451072 -145.960905) (xy 429.487578 -145.913329) (xy 429.529983 -145.870924)
			(xy 429.577559 -145.834418) (xy 429.629493 -145.804434) (xy 429.684897 -145.781485) (xy 429.742822 -145.765964)
			(xy 429.802278 -145.758136) (xy 429.862246 -145.758136) (xy 429.921702 -145.765964) (xy 429.979627 -145.781485)
			(xy 430.035031 -145.804434) (xy 430.086965 -145.834418) (xy 430.134541 -145.870924) (xy 430.176946 -145.913329)
			(xy 430.213452 -145.960905) (xy 430.243436 -146.012839) (xy 430.266385 -146.068243) (xy 430.281906 -146.126168)
			(xy 430.289734 -146.185624) (xy 430.290224 -146.215608) (xy 430.290224 -147.079208) (xy 430.289734 -147.109192)
			(xy 430.281906 -147.168648) (xy 430.266385 -147.226573) (xy 430.243436 -147.281977) (xy 430.213452 -147.333911)
			(xy 430.176946 -147.381487) (xy 430.134541 -147.423892) (xy 430.086965 -147.460398) (xy 430.035031 -147.490382)
			(xy 429.979627 -147.513331) (xy 429.921702 -147.528852) (xy 429.862246 -147.53668) (xy 429.802278 -147.53668)
			(xy 429.742822 -147.528852) (xy 429.684897 -147.513331) (xy 429.629493 -147.490382) (xy 429.577559 -147.460398)
			(xy 429.529983 -147.423892) (xy 429.487578 -147.381487) (xy 429.451072 -147.333911) (xy 429.421088 -147.281977)
			(xy 429.398139 -147.226573) (xy 429.382618 -147.168648) (xy 429.37479 -147.109192) (xy 429.3743 -147.079208)
			(xy 415.815272 -147.079208) (xy 415.815272 -147.087336) (xy 415.814782 -147.11732) (xy 415.806954 -147.176776)
			(xy 415.791433 -147.234701) (xy 415.768484 -147.290105) (xy 415.7385 -147.342039) (xy 415.701994 -147.389615)
			(xy 415.659589 -147.43202) (xy 415.612013 -147.468526) (xy 415.560079 -147.49851) (xy 415.504675 -147.521459)
			(xy 415.44675 -147.53698) (xy 415.387294 -147.544808) (xy 415.327326 -147.544808) (xy 415.26787 -147.53698)
			(xy 415.209945 -147.521459) (xy 415.154541 -147.49851) (xy 415.102607 -147.468526) (xy 415.055031 -147.43202)
			(xy 415.012626 -147.389615) (xy 414.97612 -147.342039) (xy 414.946136 -147.290105) (xy 414.923187 -147.234701)
			(xy 414.907666 -147.176776) (xy 414.899838 -147.11732) (xy 414.899348 -147.087336) (xy 314.189739 -147.087336)
			(xy 314.189382 -147.109176) (xy 314.181559 -147.168598) (xy 314.166046 -147.226491) (xy 314.14311 -147.281864)
			(xy 314.113143 -147.33377) (xy 314.076656 -147.38132) (xy 314.034276 -147.4237) (xy 313.986726 -147.460187)
			(xy 313.93482 -147.490154) (xy 313.879447 -147.51309) (xy 313.821554 -147.528603) (xy 313.762132 -147.536426)
			(xy 313.702196 -147.536426) (xy 313.642774 -147.528603) (xy 313.584881 -147.51309) (xy 313.529508 -147.490154)
			(xy 313.477602 -147.460187) (xy 313.430052 -147.4237) (xy 313.387672 -147.38132) (xy 313.351185 -147.33377)
			(xy 313.321218 -147.281864) (xy 313.298282 -147.226491) (xy 313.282769 -147.168598) (xy 313.274946 -147.109176)
			(xy 313.274456 -147.079208) (xy 299.71492 -147.079208) (xy 299.71492 -147.087336) (xy 299.71443 -147.117304)
			(xy 299.706607 -147.176726) (xy 299.691094 -147.234619) (xy 299.668158 -147.289992) (xy 299.638191 -147.341898)
			(xy 299.601704 -147.389448) (xy 299.559324 -147.431828) (xy 299.511774 -147.468315) (xy 299.459868 -147.498282)
			(xy 299.404495 -147.521218) (xy 299.346602 -147.536731) (xy 299.28718 -147.544554) (xy 299.227244 -147.544554)
			(xy 299.167822 -147.536731) (xy 299.109929 -147.521218) (xy 299.054556 -147.498282) (xy 299.00265 -147.468315)
			(xy 298.9551 -147.431828) (xy 298.91272 -147.389448) (xy 298.876233 -147.341898) (xy 298.846266 -147.289992)
			(xy 298.82333 -147.234619) (xy 298.807817 -147.176726) (xy 298.799994 -147.117304) (xy 298.799504 -147.087336)
			(xy 198.089895 -147.087336) (xy 198.089538 -147.109176) (xy 198.081715 -147.168598) (xy 198.066202 -147.226491)
			(xy 198.043266 -147.281864) (xy 198.013299 -147.33377) (xy 197.976812 -147.38132) (xy 197.934432 -147.4237)
			(xy 197.886882 -147.460187) (xy 197.834976 -147.490154) (xy 197.779603 -147.51309) (xy 197.72171 -147.528603)
			(xy 197.662288 -147.536426) (xy 197.602352 -147.536426) (xy 197.54293 -147.528603) (xy 197.485037 -147.51309)
			(xy 197.429664 -147.490154) (xy 197.377758 -147.460187) (xy 197.330208 -147.4237) (xy 197.287828 -147.38132)
			(xy 197.251341 -147.33377) (xy 197.221374 -147.281864) (xy 197.198438 -147.226491) (xy 197.182925 -147.168598)
			(xy 197.175102 -147.109176) (xy 197.174612 -147.079208) (xy 183.615076 -147.079208) (xy 183.615076 -147.087336)
			(xy 183.614586 -147.117304) (xy 183.606763 -147.176726) (xy 183.59125 -147.234619) (xy 183.568314 -147.289992)
			(xy 183.538347 -147.341898) (xy 183.50186 -147.389448) (xy 183.45948 -147.431828) (xy 183.41193 -147.468315)
			(xy 183.360024 -147.498282) (xy 183.304651 -147.521218) (xy 183.246758 -147.536731) (xy 183.187336 -147.544554)
			(xy 183.1274 -147.544554) (xy 183.067978 -147.536731) (xy 183.010085 -147.521218) (xy 182.954712 -147.498282)
			(xy 182.902806 -147.468315) (xy 182.855256 -147.431828) (xy 182.812876 -147.389448) (xy 182.776389 -147.341898)
			(xy 182.746422 -147.289992) (xy 182.723486 -147.234619) (xy 182.707973 -147.176726) (xy 182.70015 -147.117304)
			(xy 182.69966 -147.087336) (xy 81.990051 -147.087336) (xy 81.989694 -147.109192) (xy 81.981866 -147.168648)
			(xy 81.966345 -147.226573) (xy 81.943396 -147.281977) (xy 81.913412 -147.333911) (xy 81.876906 -147.381487)
			(xy 81.834501 -147.423892) (xy 81.786925 -147.460398) (xy 81.734991 -147.490382) (xy 81.679587 -147.513331)
			(xy 81.621662 -147.528852) (xy 81.562206 -147.53668) (xy 81.502238 -147.53668) (xy 81.442782 -147.528852)
			(xy 81.384857 -147.513331) (xy 81.329453 -147.490382) (xy 81.277519 -147.460398) (xy 81.229943 -147.423892)
			(xy 81.187538 -147.381487) (xy 81.151032 -147.333911) (xy 81.121048 -147.281977) (xy 81.098099 -147.226573)
			(xy 81.082578 -147.168648) (xy 81.07475 -147.109192) (xy 81.07426 -147.079208) (xy 67.515232 -147.079208)
			(xy 67.515232 -147.087336) (xy 67.514742 -147.11732) (xy 67.506914 -147.176776) (xy 67.491393 -147.234701)
			(xy 67.468444 -147.290105) (xy 67.43846 -147.342039) (xy 67.401954 -147.389615) (xy 67.359549 -147.43202)
			(xy 67.311973 -147.468526) (xy 67.260039 -147.49851) (xy 67.204635 -147.521459) (xy 67.14671 -147.53698)
			(xy 67.087254 -147.544808) (xy 67.027286 -147.544808) (xy 66.96783 -147.53698) (xy 66.909905 -147.521459)
			(xy 66.854501 -147.49851) (xy 66.802567 -147.468526) (xy 66.754991 -147.43202) (xy 66.712586 -147.389615)
			(xy 66.67608 -147.342039) (xy 66.646096 -147.290105) (xy 66.623147 -147.234701) (xy 66.607626 -147.176776)
			(xy 66.599798 -147.11732) (xy 66.599308 -147.087336) (xy 5.324094 -147.087336) (xy 5.324094 -148.887434)
			(xy 64.745108 -148.887434) (xy 64.745108 -148.023834) (xy 64.745598 -147.99385) (xy 64.753426 -147.934394)
			(xy 64.768947 -147.876469) (xy 64.791896 -147.821065) (xy 64.82188 -147.769131) (xy 64.858386 -147.721555)
			(xy 64.900791 -147.67915) (xy 64.948367 -147.642644) (xy 65.000301 -147.61266) (xy 65.055705 -147.589711)
			(xy 65.11363 -147.57419) (xy 65.173086 -147.566362) (xy 65.233054 -147.566362) (xy 65.29251 -147.57419)
			(xy 65.350435 -147.589711) (xy 65.405839 -147.61266) (xy 65.457773 -147.642644) (xy 65.505349 -147.67915)
			(xy 65.547754 -147.721555) (xy 65.58426 -147.769131) (xy 65.614244 -147.821065) (xy 65.637193 -147.876469)
			(xy 65.652714 -147.934394) (xy 65.660542 -147.99385) (xy 65.661032 -148.023834) (xy 65.661032 -148.88591)
			(xy 83.716368 -148.88591) (xy 83.716368 -148.02231) (xy 83.716858 -147.992326) (xy 83.724686 -147.93287)
			(xy 83.740207 -147.874945) (xy 83.763156 -147.819541) (xy 83.79314 -147.767607) (xy 83.829646 -147.720031)
			(xy 83.872051 -147.677626) (xy 83.919627 -147.64112) (xy 83.971561 -147.611136) (xy 84.026965 -147.588187)
			(xy 84.08489 -147.572666) (xy 84.144346 -147.564838) (xy 84.204314 -147.564838) (xy 84.26377 -147.572666)
			(xy 84.321695 -147.588187) (xy 84.377099 -147.611136) (xy 84.429033 -147.64112) (xy 84.476609 -147.677626)
			(xy 84.519014 -147.720031) (xy 84.55552 -147.767607) (xy 84.585504 -147.819541) (xy 84.608453 -147.874945)
			(xy 84.623974 -147.93287) (xy 84.631802 -147.992326) (xy 84.632292 -148.02231) (xy 84.632292 -148.88591)
			(xy 84.632267 -148.887434) (xy 180.84546 -148.887434) (xy 180.84546 -148.023834) (xy 180.84595 -147.993866)
			(xy 180.853773 -147.934444) (xy 180.869286 -147.876551) (xy 180.892222 -147.821178) (xy 180.922189 -147.769272)
			(xy 180.958676 -147.721722) (xy 181.001056 -147.679342) (xy 181.048606 -147.642855) (xy 181.100512 -147.612888)
			(xy 181.155885 -147.589952) (xy 181.213778 -147.574439) (xy 181.2732 -147.566616) (xy 181.333136 -147.566616)
			(xy 181.392558 -147.574439) (xy 181.450451 -147.589952) (xy 181.505824 -147.612888) (xy 181.55773 -147.642855)
			(xy 181.60528 -147.679342) (xy 181.64766 -147.721722) (xy 181.684147 -147.769272) (xy 181.714114 -147.821178)
			(xy 181.73705 -147.876551) (xy 181.752563 -147.934444) (xy 181.760386 -147.993866) (xy 181.760876 -148.023834)
			(xy 181.760876 -148.88591) (xy 199.81672 -148.88591) (xy 199.81672 -148.02231) (xy 199.81721 -147.992342)
			(xy 199.825033 -147.93292) (xy 199.840546 -147.875027) (xy 199.863482 -147.819654) (xy 199.893449 -147.767748)
			(xy 199.929936 -147.720198) (xy 199.972316 -147.677818) (xy 200.019866 -147.641331) (xy 200.071772 -147.611364)
			(xy 200.127145 -147.588428) (xy 200.185038 -147.572915) (xy 200.24446 -147.565092) (xy 200.304396 -147.565092)
			(xy 200.363818 -147.572915) (xy 200.421711 -147.588428) (xy 200.477084 -147.611364) (xy 200.52899 -147.641331)
			(xy 200.57654 -147.677818) (xy 200.61892 -147.720198) (xy 200.655407 -147.767748) (xy 200.685374 -147.819654)
			(xy 200.70831 -147.875027) (xy 200.723823 -147.93292) (xy 200.731646 -147.992342) (xy 200.732136 -148.02231)
			(xy 200.732136 -148.88591) (xy 200.731646 -148.915878) (xy 200.723823 -148.9753) (xy 200.70831 -149.033193)
			(xy 200.685374 -149.088566) (xy 200.655407 -149.140472) (xy 200.61892 -149.188022) (xy 200.57654 -149.230402)
			(xy 200.52899 -149.266889) (xy 200.477084 -149.296856) (xy 200.421711 -149.319792) (xy 200.363818 -149.335305)
			(xy 200.304396 -149.343128) (xy 200.24446 -149.343128) (xy 200.185038 -149.335305) (xy 200.127145 -149.319792)
			(xy 200.071772 -149.296856) (xy 200.019866 -149.266889) (xy 199.972316 -149.230402) (xy 199.929936 -149.188022)
			(xy 199.893449 -149.140472) (xy 199.863482 -149.088566) (xy 199.840546 -149.033193) (xy 199.825033 -148.9753)
			(xy 199.81721 -148.915878) (xy 199.81672 -148.88591) (xy 181.760876 -148.88591) (xy 181.760876 -148.887434)
			(xy 181.760386 -148.917402) (xy 181.752563 -148.976824) (xy 181.73705 -149.034717) (xy 181.714114 -149.09009)
			(xy 181.684147 -149.141996) (xy 181.64766 -149.189546) (xy 181.60528 -149.231926) (xy 181.55773 -149.268413)
			(xy 181.505824 -149.29838) (xy 181.450451 -149.321316) (xy 181.392558 -149.336829) (xy 181.333136 -149.344652)
			(xy 181.2732 -149.344652) (xy 181.213778 -149.336829) (xy 181.155885 -149.321316) (xy 181.100512 -149.29838)
			(xy 181.048606 -149.268413) (xy 181.001056 -149.231926) (xy 180.958676 -149.189546) (xy 180.922189 -149.141996)
			(xy 180.892222 -149.09009) (xy 180.869286 -149.034717) (xy 180.853773 -148.976824) (xy 180.84595 -148.917402)
			(xy 180.84546 -148.887434) (xy 84.632267 -148.887434) (xy 84.631802 -148.915894) (xy 84.623974 -148.97535)
			(xy 84.608453 -149.033275) (xy 84.585504 -149.088679) (xy 84.55552 -149.140613) (xy 84.519014 -149.188189)
			(xy 84.476609 -149.230594) (xy 84.429033 -149.2671) (xy 84.377099 -149.297084) (xy 84.321695 -149.320033)
			(xy 84.26377 -149.335554) (xy 84.204314 -149.343382) (xy 84.144346 -149.343382) (xy 84.08489 -149.335554)
			(xy 84.026965 -149.320033) (xy 83.971561 -149.297084) (xy 83.919627 -149.2671) (xy 83.872051 -149.230594)
			(xy 83.829646 -149.188189) (xy 83.79314 -149.140613) (xy 83.763156 -149.088679) (xy 83.740207 -149.033275)
			(xy 83.724686 -148.97535) (xy 83.716858 -148.915894) (xy 83.716368 -148.88591) (xy 65.661032 -148.88591)
			(xy 65.661032 -148.887434) (xy 65.660542 -148.917418) (xy 65.652714 -148.976874) (xy 65.637193 -149.034799)
			(xy 65.614244 -149.090203) (xy 65.58426 -149.142137) (xy 65.547754 -149.189713) (xy 65.505349 -149.232118)
			(xy 65.457773 -149.268624) (xy 65.405839 -149.298608) (xy 65.350435 -149.321557) (xy 65.29251 -149.337078)
			(xy 65.233054 -149.344906) (xy 65.173086 -149.344906) (xy 65.11363 -149.337078) (xy 65.055705 -149.321557)
			(xy 65.000301 -149.298608) (xy 64.948367 -149.268624) (xy 64.900791 -149.232118) (xy 64.858386 -149.189713)
			(xy 64.82188 -149.142137) (xy 64.791896 -149.090203) (xy 64.768947 -149.034799) (xy 64.753426 -148.976874)
			(xy 64.745598 -148.917418) (xy 64.745108 -148.887434) (xy 5.324094 -148.887434) (xy 5.324094 -150.687278)
			(xy 66.599308 -150.687278) (xy 66.599308 -149.823678) (xy 66.599798 -149.793694) (xy 66.607626 -149.734238)
			(xy 66.623147 -149.676313) (xy 66.646096 -149.620909) (xy 66.67608 -149.568975) (xy 66.712586 -149.521399)
			(xy 66.754991 -149.478994) (xy 66.802567 -149.442488) (xy 66.854501 -149.412504) (xy 66.909905 -149.389555)
			(xy 66.96783 -149.374034) (xy 67.027286 -149.366206) (xy 67.087254 -149.366206) (xy 67.14671 -149.374034)
			(xy 67.204635 -149.389555) (xy 67.260039 -149.412504) (xy 67.311973 -149.442488) (xy 67.359549 -149.478994)
			(xy 67.401954 -149.521399) (xy 67.43846 -149.568975) (xy 67.468444 -149.620909) (xy 67.491393 -149.676313)
			(xy 67.506914 -149.734238) (xy 67.514742 -149.793694) (xy 67.515232 -149.823678) (xy 67.515232 -150.67915)
			(xy 81.07426 -150.67915) (xy 81.07426 -149.81555) (xy 81.07475 -149.785566) (xy 81.082578 -149.72611)
			(xy 81.098099 -149.668185) (xy 81.121048 -149.612781) (xy 81.151032 -149.560847) (xy 81.187538 -149.513271)
			(xy 81.229943 -149.470866) (xy 81.277519 -149.43436) (xy 81.329453 -149.404376) (xy 81.384857 -149.381427)
			(xy 81.442782 -149.365906) (xy 81.502238 -149.358078) (xy 81.562206 -149.358078) (xy 81.621662 -149.365906)
			(xy 81.679587 -149.381427) (xy 81.734991 -149.404376) (xy 81.786925 -149.43436) (xy 81.834501 -149.470866)
			(xy 81.876906 -149.513271) (xy 81.913412 -149.560847) (xy 81.943396 -149.612781) (xy 81.966345 -149.668185)
			(xy 81.981866 -149.72611) (xy 81.989694 -149.785566) (xy 81.990184 -149.81555) (xy 81.990184 -150.67915)
			(xy 81.990051 -150.687278) (xy 182.69966 -150.687278) (xy 182.69966 -149.823678) (xy 182.70015 -149.79371)
			(xy 182.707973 -149.734288) (xy 182.723486 -149.676395) (xy 182.746422 -149.621022) (xy 182.776389 -149.569116)
			(xy 182.812876 -149.521566) (xy 182.855256 -149.479186) (xy 182.902806 -149.442699) (xy 182.954712 -149.412732)
			(xy 183.010085 -149.389796) (xy 183.067978 -149.374283) (xy 183.1274 -149.36646) (xy 183.187336 -149.36646)
			(xy 183.246758 -149.374283) (xy 183.304651 -149.389796) (xy 183.360024 -149.412732) (xy 183.41193 -149.442699)
			(xy 183.45948 -149.479186) (xy 183.50186 -149.521566) (xy 183.538347 -149.569116) (xy 183.568314 -149.621022)
			(xy 183.59125 -149.676395) (xy 183.606763 -149.734288) (xy 183.614586 -149.79371) (xy 183.615076 -149.823678)
			(xy 183.615076 -150.67915) (xy 197.174612 -150.67915) (xy 197.174612 -149.81555) (xy 197.175102 -149.785582)
			(xy 197.182925 -149.72616) (xy 197.198438 -149.668267) (xy 197.221374 -149.612894) (xy 197.251341 -149.560988)
			(xy 197.287828 -149.513438) (xy 197.330208 -149.471058) (xy 197.377758 -149.434571) (xy 197.429664 -149.404604)
			(xy 197.485037 -149.381668) (xy 197.54293 -149.366155) (xy 197.602352 -149.358332) (xy 197.662288 -149.358332)
			(xy 197.72171 -149.366155) (xy 197.779603 -149.381668) (xy 197.834976 -149.404604) (xy 197.886882 -149.434571)
			(xy 197.934432 -149.471058) (xy 197.976812 -149.513438) (xy 198.013299 -149.560988) (xy 198.043266 -149.612894)
			(xy 198.066202 -149.668267) (xy 198.072386 -149.691344) (xy 236.708188 -149.691344) (xy 236.708188 -148.827744)
			(xy 236.708678 -148.79776) (xy 236.716506 -148.738304) (xy 236.732027 -148.680379) (xy 236.754976 -148.624975)
			(xy 236.78496 -148.573041) (xy 236.821466 -148.525465) (xy 236.863871 -148.48306) (xy 236.911447 -148.446554)
			(xy 236.963381 -148.41657) (xy 237.018785 -148.393621) (xy 237.07671 -148.3781) (xy 237.136166 -148.370272)
			(xy 237.196134 -148.370272) (xy 237.25559 -148.3781) (xy 237.313515 -148.393621) (xy 237.368919 -148.41657)
			(xy 237.420853 -148.446554) (xy 237.468429 -148.48306) (xy 237.510834 -148.525465) (xy 237.54734 -148.573041)
			(xy 237.577324 -148.624975) (xy 237.600273 -148.680379) (xy 237.615794 -148.738304) (xy 237.623622 -148.79776)
			(xy 237.624112 -148.827744) (xy 237.624112 -148.887434) (xy 296.945304 -148.887434) (xy 296.945304 -148.023834)
			(xy 296.945794 -147.993866) (xy 296.953617 -147.934444) (xy 296.96913 -147.876551) (xy 296.992066 -147.821178)
			(xy 297.022033 -147.769272) (xy 297.05852 -147.721722) (xy 297.1009 -147.679342) (xy 297.14845 -147.642855)
			(xy 297.200356 -147.612888) (xy 297.255729 -147.589952) (xy 297.313622 -147.574439) (xy 297.373044 -147.566616)
			(xy 297.43298 -147.566616) (xy 297.492402 -147.574439) (xy 297.550295 -147.589952) (xy 297.605668 -147.612888)
			(xy 297.657574 -147.642855) (xy 297.705124 -147.679342) (xy 297.747504 -147.721722) (xy 297.783991 -147.769272)
			(xy 297.813958 -147.821178) (xy 297.836894 -147.876551) (xy 297.852407 -147.934444) (xy 297.86023 -147.993866)
			(xy 297.86072 -148.023834) (xy 297.86072 -148.88591) (xy 315.916564 -148.88591) (xy 315.916564 -148.02231)
			(xy 315.917054 -147.992342) (xy 315.924877 -147.93292) (xy 315.94039 -147.875027) (xy 315.963326 -147.819654)
			(xy 315.993293 -147.767748) (xy 316.02978 -147.720198) (xy 316.07216 -147.677818) (xy 316.11971 -147.641331)
			(xy 316.171616 -147.611364) (xy 316.226989 -147.588428) (xy 316.284882 -147.572915) (xy 316.344304 -147.565092)
			(xy 316.40424 -147.565092) (xy 316.463662 -147.572915) (xy 316.521555 -147.588428) (xy 316.576928 -147.611364)
			(xy 316.628834 -147.641331) (xy 316.676384 -147.677818) (xy 316.718764 -147.720198) (xy 316.755251 -147.767748)
			(xy 316.785218 -147.819654) (xy 316.808154 -147.875027) (xy 316.823667 -147.93292) (xy 316.83149 -147.992342)
			(xy 316.83198 -148.02231) (xy 316.83198 -148.88591) (xy 316.831955 -148.887434) (xy 413.045148 -148.887434)
			(xy 413.045148 -148.023834) (xy 413.045638 -147.99385) (xy 413.053466 -147.934394) (xy 413.068987 -147.876469)
			(xy 413.091936 -147.821065) (xy 413.12192 -147.769131) (xy 413.158426 -147.721555) (xy 413.200831 -147.67915)
			(xy 413.248407 -147.642644) (xy 413.300341 -147.61266) (xy 413.355745 -147.589711) (xy 413.41367 -147.57419)
			(xy 413.473126 -147.566362) (xy 413.533094 -147.566362) (xy 413.59255 -147.57419) (xy 413.650475 -147.589711)
			(xy 413.705879 -147.61266) (xy 413.757813 -147.642644) (xy 413.805389 -147.67915) (xy 413.847794 -147.721555)
			(xy 413.8843 -147.769131) (xy 413.914284 -147.821065) (xy 413.937233 -147.876469) (xy 413.952754 -147.934394)
			(xy 413.960582 -147.99385) (xy 413.961072 -148.023834) (xy 413.961072 -148.88591) (xy 432.016408 -148.88591)
			(xy 432.016408 -148.02231) (xy 432.016898 -147.992326) (xy 432.024726 -147.93287) (xy 432.040247 -147.874945)
			(xy 432.063196 -147.819541) (xy 432.09318 -147.767607) (xy 432.129686 -147.720031) (xy 432.172091 -147.677626)
			(xy 432.219667 -147.64112) (xy 432.271601 -147.611136) (xy 432.327005 -147.588187) (xy 432.38493 -147.572666)
			(xy 432.444386 -147.564838) (xy 432.504354 -147.564838) (xy 432.56381 -147.572666) (xy 432.621735 -147.588187)
			(xy 432.677139 -147.611136) (xy 432.729073 -147.64112) (xy 432.776649 -147.677626) (xy 432.819054 -147.720031)
			(xy 432.85556 -147.767607) (xy 432.885544 -147.819541) (xy 432.908493 -147.874945) (xy 432.924014 -147.93287)
			(xy 432.931842 -147.992326) (xy 432.932332 -148.02231) (xy 432.932332 -148.88591) (xy 432.931842 -148.915894)
			(xy 432.924014 -148.97535) (xy 432.908493 -149.033275) (xy 432.885544 -149.088679) (xy 432.85556 -149.140613)
			(xy 432.819054 -149.188189) (xy 432.776649 -149.230594) (xy 432.729073 -149.2671) (xy 432.677139 -149.297084)
			(xy 432.621735 -149.320033) (xy 432.56381 -149.335554) (xy 432.504354 -149.343382) (xy 432.444386 -149.343382)
			(xy 432.38493 -149.335554) (xy 432.327005 -149.320033) (xy 432.271601 -149.297084) (xy 432.219667 -149.2671)
			(xy 432.172091 -149.230594) (xy 432.129686 -149.188189) (xy 432.09318 -149.140613) (xy 432.063196 -149.088679)
			(xy 432.040247 -149.033275) (xy 432.024726 -148.97535) (xy 432.016898 -148.915894) (xy 432.016408 -148.88591)
			(xy 413.961072 -148.88591) (xy 413.961072 -148.887434) (xy 413.960582 -148.917418) (xy 413.952754 -148.976874)
			(xy 413.937233 -149.034799) (xy 413.914284 -149.090203) (xy 413.8843 -149.142137) (xy 413.847794 -149.189713)
			(xy 413.805389 -149.232118) (xy 413.757813 -149.268624) (xy 413.705879 -149.298608) (xy 413.650475 -149.321557)
			(xy 413.59255 -149.337078) (xy 413.533094 -149.344906) (xy 413.473126 -149.344906) (xy 413.41367 -149.337078)
			(xy 413.355745 -149.321557) (xy 413.300341 -149.298608) (xy 413.248407 -149.268624) (xy 413.200831 -149.232118)
			(xy 413.158426 -149.189713) (xy 413.12192 -149.142137) (xy 413.091936 -149.090203) (xy 413.068987 -149.034799)
			(xy 413.053466 -148.976874) (xy 413.045638 -148.917418) (xy 413.045148 -148.887434) (xy 316.831955 -148.887434)
			(xy 316.83149 -148.915878) (xy 316.823667 -148.9753) (xy 316.808154 -149.033193) (xy 316.785218 -149.088566)
			(xy 316.755251 -149.140472) (xy 316.718764 -149.188022) (xy 316.676384 -149.230402) (xy 316.628834 -149.266889)
			(xy 316.576928 -149.296856) (xy 316.521555 -149.319792) (xy 316.463662 -149.335305) (xy 316.40424 -149.343128)
			(xy 316.344304 -149.343128) (xy 316.284882 -149.335305) (xy 316.226989 -149.319792) (xy 316.171616 -149.296856)
			(xy 316.11971 -149.266889) (xy 316.07216 -149.230402) (xy 316.02978 -149.188022) (xy 315.993293 -149.140472)
			(xy 315.963326 -149.088566) (xy 315.94039 -149.033193) (xy 315.924877 -148.9753) (xy 315.917054 -148.915878)
			(xy 315.916564 -148.88591) (xy 297.86072 -148.88591) (xy 297.86072 -148.887434) (xy 297.86023 -148.917402)
			(xy 297.852407 -148.976824) (xy 297.836894 -149.034717) (xy 297.813958 -149.09009) (xy 297.783991 -149.141996)
			(xy 297.747504 -149.189546) (xy 297.705124 -149.231926) (xy 297.657574 -149.268413) (xy 297.605668 -149.29838)
			(xy 297.550295 -149.321316) (xy 297.492402 -149.336829) (xy 297.43298 -149.344652) (xy 297.373044 -149.344652)
			(xy 297.313622 -149.336829) (xy 297.255729 -149.321316) (xy 297.200356 -149.29838) (xy 297.14845 -149.268413)
			(xy 297.1009 -149.231926) (xy 297.05852 -149.189546) (xy 297.022033 -149.141996) (xy 296.992066 -149.09009)
			(xy 296.96913 -149.034717) (xy 296.953617 -148.976824) (xy 296.945794 -148.917402) (xy 296.945304 -148.887434)
			(xy 237.624112 -148.887434) (xy 237.624112 -149.691344) (xy 237.623622 -149.721328) (xy 237.615794 -149.780784)
			(xy 237.600273 -149.838709) (xy 237.577324 -149.894113) (xy 237.54734 -149.946047) (xy 237.510834 -149.993623)
			(xy 237.468429 -150.036028) (xy 237.420853 -150.072534) (xy 237.368919 -150.102518) (xy 237.313515 -150.125467)
			(xy 237.25559 -150.140988) (xy 237.196134 -150.148816) (xy 237.136166 -150.148816) (xy 237.07671 -150.140988)
			(xy 237.018785 -150.125467) (xy 236.963381 -150.102518) (xy 236.911447 -150.072534) (xy 236.863871 -150.036028)
			(xy 236.821466 -149.993623) (xy 236.78496 -149.946047) (xy 236.754976 -149.894113) (xy 236.732027 -149.838709)
			(xy 236.716506 -149.780784) (xy 236.708678 -149.721328) (xy 236.708188 -149.691344) (xy 198.072386 -149.691344)
			(xy 198.081715 -149.72616) (xy 198.089538 -149.785582) (xy 198.090028 -149.81555) (xy 198.090028 -150.67915)
			(xy 198.089538 -150.709118) (xy 198.081715 -150.76854) (xy 198.066202 -150.826433) (xy 198.043266 -150.881806)
			(xy 198.013299 -150.933712) (xy 197.976812 -150.981262) (xy 197.934432 -151.023642) (xy 197.886882 -151.060129)
			(xy 197.834976 -151.090096) (xy 197.779603 -151.113032) (xy 197.72171 -151.128545) (xy 197.662288 -151.136368)
			(xy 197.602352 -151.136368) (xy 197.54293 -151.128545) (xy 197.485037 -151.113032) (xy 197.429664 -151.090096)
			(xy 197.377758 -151.060129) (xy 197.330208 -151.023642) (xy 197.287828 -150.981262) (xy 197.251341 -150.933712)
			(xy 197.221374 -150.881806) (xy 197.198438 -150.826433) (xy 197.182925 -150.76854) (xy 197.175102 -150.709118)
			(xy 197.174612 -150.67915) (xy 183.615076 -150.67915) (xy 183.615076 -150.687278) (xy 183.614586 -150.717246)
			(xy 183.606763 -150.776668) (xy 183.59125 -150.834561) (xy 183.568314 -150.889934) (xy 183.538347 -150.94184)
			(xy 183.50186 -150.98939) (xy 183.45948 -151.03177) (xy 183.41193 -151.068257) (xy 183.360024 -151.098224)
			(xy 183.304651 -151.12116) (xy 183.246758 -151.136673) (xy 183.187336 -151.144496) (xy 183.1274 -151.144496)
			(xy 183.067978 -151.136673) (xy 183.010085 -151.12116) (xy 182.954712 -151.098224) (xy 182.902806 -151.068257)
			(xy 182.855256 -151.03177) (xy 182.812876 -150.98939) (xy 182.776389 -150.94184) (xy 182.746422 -150.889934)
			(xy 182.723486 -150.834561) (xy 182.707973 -150.776668) (xy 182.70015 -150.717246) (xy 182.69966 -150.687278)
			(xy 81.990051 -150.687278) (xy 81.989694 -150.709134) (xy 81.981866 -150.76859) (xy 81.966345 -150.826515)
			(xy 81.943396 -150.881919) (xy 81.913412 -150.933853) (xy 81.876906 -150.981429) (xy 81.834501 -151.023834)
			(xy 81.786925 -151.06034) (xy 81.734991 -151.090324) (xy 81.679587 -151.113273) (xy 81.621662 -151.128794)
			(xy 81.562206 -151.136622) (xy 81.502238 -151.136622) (xy 81.442782 -151.128794) (xy 81.384857 -151.113273)
			(xy 81.329453 -151.090324) (xy 81.277519 -151.06034) (xy 81.229943 -151.023834) (xy 81.187538 -150.981429)
			(xy 81.151032 -150.933853) (xy 81.121048 -150.881919) (xy 81.098099 -150.826515) (xy 81.082578 -150.76859)
			(xy 81.07475 -150.709134) (xy 81.07426 -150.67915) (xy 67.515232 -150.67915) (xy 67.515232 -150.687278)
			(xy 67.514742 -150.717262) (xy 67.506914 -150.776718) (xy 67.491393 -150.834643) (xy 67.468444 -150.890047)
			(xy 67.43846 -150.941981) (xy 67.401954 -150.989557) (xy 67.359549 -151.031962) (xy 67.311973 -151.068468)
			(xy 67.260039 -151.098452) (xy 67.204635 -151.121401) (xy 67.14671 -151.136922) (xy 67.087254 -151.14475)
			(xy 67.027286 -151.14475) (xy 66.96783 -151.136922) (xy 66.909905 -151.121401) (xy 66.854501 -151.098452)
			(xy 66.802567 -151.068468) (xy 66.754991 -151.031962) (xy 66.712586 -150.989557) (xy 66.67608 -150.941981)
			(xy 66.646096 -150.890047) (xy 66.623147 -150.834643) (xy 66.607626 -150.776718) (xy 66.599798 -150.717262)
			(xy 66.599308 -150.687278) (xy 5.324094 -150.687278) (xy 5.324094 -152.487376) (xy 64.745108 -152.487376)
			(xy 64.745108 -151.623776) (xy 64.745598 -151.593792) (xy 64.753426 -151.534336) (xy 64.768947 -151.476411)
			(xy 64.791896 -151.421007) (xy 64.82188 -151.369073) (xy 64.858386 -151.321497) (xy 64.900791 -151.279092)
			(xy 64.948367 -151.242586) (xy 65.000301 -151.212602) (xy 65.055705 -151.189653) (xy 65.11363 -151.174132)
			(xy 65.173086 -151.166304) (xy 65.233054 -151.166304) (xy 65.29251 -151.174132) (xy 65.350435 -151.189653)
			(xy 65.405839 -151.212602) (xy 65.457773 -151.242586) (xy 65.505349 -151.279092) (xy 65.547754 -151.321497)
			(xy 65.58426 -151.369073) (xy 65.614244 -151.421007) (xy 65.637193 -151.476411) (xy 65.652714 -151.534336)
			(xy 65.660542 -151.593792) (xy 65.661032 -151.623776) (xy 65.661032 -152.485852) (xy 83.716368 -152.485852)
			(xy 83.716368 -151.622252) (xy 83.716858 -151.592268) (xy 83.724686 -151.532812) (xy 83.740207 -151.474887)
			(xy 83.763156 -151.419483) (xy 83.79314 -151.367549) (xy 83.829646 -151.319973) (xy 83.872051 -151.277568)
			(xy 83.919627 -151.241062) (xy 83.971561 -151.211078) (xy 84.026965 -151.188129) (xy 84.08489 -151.172608)
			(xy 84.144346 -151.16478) (xy 84.204314 -151.16478) (xy 84.26377 -151.172608) (xy 84.321695 -151.188129)
			(xy 84.377099 -151.211078) (xy 84.429033 -151.241062) (xy 84.476609 -151.277568) (xy 84.519014 -151.319973)
			(xy 84.55552 -151.367549) (xy 84.585504 -151.419483) (xy 84.608453 -151.474887) (xy 84.623974 -151.532812)
			(xy 84.631802 -151.592268) (xy 84.632292 -151.622252) (xy 84.632292 -152.485852) (xy 84.632267 -152.487376)
			(xy 180.84546 -152.487376) (xy 180.84546 -151.623776) (xy 180.84595 -151.593808) (xy 180.853773 -151.534386)
			(xy 180.869286 -151.476493) (xy 180.892222 -151.42112) (xy 180.922189 -151.369214) (xy 180.958676 -151.321664)
			(xy 181.001056 -151.279284) (xy 181.048606 -151.242797) (xy 181.100512 -151.21283) (xy 181.155885 -151.189894)
			(xy 181.213778 -151.174381) (xy 181.2732 -151.166558) (xy 181.333136 -151.166558) (xy 181.392558 -151.174381)
			(xy 181.450451 -151.189894) (xy 181.505824 -151.21283) (xy 181.55773 -151.242797) (xy 181.60528 -151.279284)
			(xy 181.64766 -151.321664) (xy 181.684147 -151.369214) (xy 181.714114 -151.42112) (xy 181.73705 -151.476493)
			(xy 181.752563 -151.534386) (xy 181.760386 -151.593808) (xy 181.760876 -151.623776) (xy 181.760876 -152.485852)
			(xy 199.81672 -152.485852) (xy 199.81672 -151.622252) (xy 199.81721 -151.592284) (xy 199.825033 -151.532862)
			(xy 199.840546 -151.474969) (xy 199.863482 -151.419596) (xy 199.893449 -151.36769) (xy 199.929936 -151.32014)
			(xy 199.972316 -151.27776) (xy 200.019866 -151.241273) (xy 200.071772 -151.211306) (xy 200.127145 -151.18837)
			(xy 200.185038 -151.172857) (xy 200.24446 -151.165034) (xy 200.304396 -151.165034) (xy 200.363818 -151.172857)
			(xy 200.421711 -151.18837) (xy 200.477084 -151.211306) (xy 200.52899 -151.241273) (xy 200.57654 -151.27776)
			(xy 200.61892 -151.32014) (xy 200.655407 -151.36769) (xy 200.685374 -151.419596) (xy 200.70831 -151.474969)
			(xy 200.723823 -151.532862) (xy 200.731646 -151.592284) (xy 200.732136 -151.622252) (xy 200.732136 -151.914098)
			(xy 236.712252 -151.914098) (xy 236.712252 -151.050498) (xy 236.712742 -151.020514) (xy 236.72057 -150.961058)
			(xy 236.736091 -150.903133) (xy 236.75904 -150.847729) (xy 236.789024 -150.795795) (xy 236.82553 -150.748219)
			(xy 236.867935 -150.705814) (xy 236.915511 -150.669308) (xy 236.967445 -150.639324) (xy 237.022849 -150.616375)
			(xy 237.080774 -150.600854) (xy 237.14023 -150.593026) (xy 237.200198 -150.593026) (xy 237.259654 -150.600854)
			(xy 237.317579 -150.616375) (xy 237.372983 -150.639324) (xy 237.424917 -150.669308) (xy 237.448336 -150.687278)
			(xy 298.799504 -150.687278) (xy 298.799504 -149.823678) (xy 298.799994 -149.79371) (xy 298.807817 -149.734288)
			(xy 298.82333 -149.676395) (xy 298.846266 -149.621022) (xy 298.876233 -149.569116) (xy 298.91272 -149.521566)
			(xy 298.9551 -149.479186) (xy 299.00265 -149.442699) (xy 299.054556 -149.412732) (xy 299.109929 -149.389796)
			(xy 299.167822 -149.374283) (xy 299.227244 -149.36646) (xy 299.28718 -149.36646) (xy 299.346602 -149.374283)
			(xy 299.404495 -149.389796) (xy 299.459868 -149.412732) (xy 299.511774 -149.442699) (xy 299.559324 -149.479186)
			(xy 299.601704 -149.521566) (xy 299.638191 -149.569116) (xy 299.668158 -149.621022) (xy 299.691094 -149.676395)
			(xy 299.706607 -149.734288) (xy 299.71443 -149.79371) (xy 299.71492 -149.823678) (xy 299.71492 -150.67915)
			(xy 313.274456 -150.67915) (xy 313.274456 -149.81555) (xy 313.274946 -149.785582) (xy 313.282769 -149.72616)
			(xy 313.298282 -149.668267) (xy 313.321218 -149.612894) (xy 313.351185 -149.560988) (xy 313.387672 -149.513438)
			(xy 313.430052 -149.471058) (xy 313.477602 -149.434571) (xy 313.529508 -149.404604) (xy 313.584881 -149.381668)
			(xy 313.642774 -149.366155) (xy 313.702196 -149.358332) (xy 313.762132 -149.358332) (xy 313.821554 -149.366155)
			(xy 313.879447 -149.381668) (xy 313.93482 -149.404604) (xy 313.986726 -149.434571) (xy 314.034276 -149.471058)
			(xy 314.076656 -149.513438) (xy 314.113143 -149.560988) (xy 314.14311 -149.612894) (xy 314.166046 -149.668267)
			(xy 314.181559 -149.72616) (xy 314.189382 -149.785582) (xy 314.189872 -149.81555) (xy 314.189872 -150.67915)
			(xy 314.189739 -150.687278) (xy 414.899348 -150.687278) (xy 414.899348 -149.823678) (xy 414.899838 -149.793694)
			(xy 414.907666 -149.734238) (xy 414.923187 -149.676313) (xy 414.946136 -149.620909) (xy 414.97612 -149.568975)
			(xy 415.012626 -149.521399) (xy 415.055031 -149.478994) (xy 415.102607 -149.442488) (xy 415.154541 -149.412504)
			(xy 415.209945 -149.389555) (xy 415.26787 -149.374034) (xy 415.327326 -149.366206) (xy 415.387294 -149.366206)
			(xy 415.44675 -149.374034) (xy 415.504675 -149.389555) (xy 415.560079 -149.412504) (xy 415.612013 -149.442488)
			(xy 415.659589 -149.478994) (xy 415.701994 -149.521399) (xy 415.7385 -149.568975) (xy 415.768484 -149.620909)
			(xy 415.791433 -149.676313) (xy 415.806954 -149.734238) (xy 415.814782 -149.793694) (xy 415.815272 -149.823678)
			(xy 415.815272 -150.67915) (xy 429.3743 -150.67915) (xy 429.3743 -149.81555) (xy 429.37479 -149.785566)
			(xy 429.382618 -149.72611) (xy 429.398139 -149.668185) (xy 429.421088 -149.612781) (xy 429.451072 -149.560847)
			(xy 429.487578 -149.513271) (xy 429.529983 -149.470866) (xy 429.577559 -149.43436) (xy 429.629493 -149.404376)
			(xy 429.684897 -149.381427) (xy 429.742822 -149.365906) (xy 429.802278 -149.358078) (xy 429.862246 -149.358078)
			(xy 429.921702 -149.365906) (xy 429.979627 -149.381427) (xy 430.035031 -149.404376) (xy 430.086965 -149.43436)
			(xy 430.134541 -149.470866) (xy 430.176946 -149.513271) (xy 430.213452 -149.560847) (xy 430.243436 -149.612781)
			(xy 430.266385 -149.668185) (xy 430.281906 -149.72611) (xy 430.289734 -149.785566) (xy 430.290224 -149.81555)
			(xy 430.290224 -150.67915) (xy 430.289734 -150.709134) (xy 430.281906 -150.76859) (xy 430.266385 -150.826515)
			(xy 430.243436 -150.881919) (xy 430.213452 -150.933853) (xy 430.176946 -150.981429) (xy 430.134541 -151.023834)
			(xy 430.086965 -151.06034) (xy 430.035031 -151.090324) (xy 429.979627 -151.113273) (xy 429.921702 -151.128794)
			(xy 429.862246 -151.136622) (xy 429.802278 -151.136622) (xy 429.742822 -151.128794) (xy 429.684897 -151.113273)
			(xy 429.629493 -151.090324) (xy 429.577559 -151.06034) (xy 429.529983 -151.023834) (xy 429.487578 -150.981429)
			(xy 429.451072 -150.933853) (xy 429.421088 -150.881919) (xy 429.398139 -150.826515) (xy 429.382618 -150.76859)
			(xy 429.37479 -150.709134) (xy 429.3743 -150.67915) (xy 415.815272 -150.67915) (xy 415.815272 -150.687278)
			(xy 415.814782 -150.717262) (xy 415.806954 -150.776718) (xy 415.791433 -150.834643) (xy 415.768484 -150.890047)
			(xy 415.7385 -150.941981) (xy 415.701994 -150.989557) (xy 415.659589 -151.031962) (xy 415.612013 -151.068468)
			(xy 415.560079 -151.098452) (xy 415.504675 -151.121401) (xy 415.44675 -151.136922) (xy 415.387294 -151.14475)
			(xy 415.327326 -151.14475) (xy 415.26787 -151.136922) (xy 415.209945 -151.121401) (xy 415.154541 -151.098452)
			(xy 415.102607 -151.068468) (xy 415.055031 -151.031962) (xy 415.012626 -150.989557) (xy 414.97612 -150.941981)
			(xy 414.946136 -150.890047) (xy 414.923187 -150.834643) (xy 414.907666 -150.776718) (xy 414.899838 -150.717262)
			(xy 414.899348 -150.687278) (xy 314.189739 -150.687278) (xy 314.189382 -150.709118) (xy 314.181559 -150.76854)
			(xy 314.166046 -150.826433) (xy 314.14311 -150.881806) (xy 314.113143 -150.933712) (xy 314.076656 -150.981262)
			(xy 314.034276 -151.023642) (xy 313.986726 -151.060129) (xy 313.93482 -151.090096) (xy 313.879447 -151.113032)
			(xy 313.821554 -151.128545) (xy 313.762132 -151.136368) (xy 313.702196 -151.136368) (xy 313.642774 -151.128545)
			(xy 313.584881 -151.113032) (xy 313.529508 -151.090096) (xy 313.477602 -151.060129) (xy 313.430052 -151.023642)
			(xy 313.387672 -150.981262) (xy 313.351185 -150.933712) (xy 313.321218 -150.881806) (xy 313.298282 -150.826433)
			(xy 313.282769 -150.76854) (xy 313.274946 -150.709118) (xy 313.274456 -150.67915) (xy 299.71492 -150.67915)
			(xy 299.71492 -150.687278) (xy 299.71443 -150.717246) (xy 299.706607 -150.776668) (xy 299.691094 -150.834561)
			(xy 299.668158 -150.889934) (xy 299.638191 -150.94184) (xy 299.601704 -150.98939) (xy 299.559324 -151.03177)
			(xy 299.511774 -151.068257) (xy 299.459868 -151.098224) (xy 299.404495 -151.12116) (xy 299.346602 -151.136673)
			(xy 299.28718 -151.144496) (xy 299.227244 -151.144496) (xy 299.167822 -151.136673) (xy 299.109929 -151.12116)
			(xy 299.054556 -151.098224) (xy 299.00265 -151.068257) (xy 298.9551 -151.03177) (xy 298.91272 -150.98939)
			(xy 298.876233 -150.94184) (xy 298.846266 -150.889934) (xy 298.82333 -150.834561) (xy 298.807817 -150.776668)
			(xy 298.799994 -150.717246) (xy 298.799504 -150.687278) (xy 237.448336 -150.687278) (xy 237.472493 -150.705814)
			(xy 237.514898 -150.748219) (xy 237.551404 -150.795795) (xy 237.581388 -150.847729) (xy 237.604337 -150.903133)
			(xy 237.619858 -150.961058) (xy 237.627686 -151.020514) (xy 237.628176 -151.050498) (xy 237.628176 -151.914098)
			(xy 237.627686 -151.944082) (xy 237.619858 -152.003538) (xy 237.604337 -152.061463) (xy 237.581388 -152.116867)
			(xy 237.551404 -152.168801) (xy 237.514898 -152.216377) (xy 237.472493 -152.258782) (xy 237.424917 -152.295288)
			(xy 237.372983 -152.325272) (xy 237.317579 -152.348221) (xy 237.259654 -152.363742) (xy 237.200198 -152.37157)
			(xy 237.14023 -152.37157) (xy 237.080774 -152.363742) (xy 237.022849 -152.348221) (xy 236.967445 -152.325272)
			(xy 236.915511 -152.295288) (xy 236.867935 -152.258782) (xy 236.82553 -152.216377) (xy 236.789024 -152.168801)
			(xy 236.75904 -152.116867) (xy 236.736091 -152.061463) (xy 236.72057 -152.003538) (xy 236.712742 -151.944082)
			(xy 236.712252 -151.914098) (xy 200.732136 -151.914098) (xy 200.732136 -152.485852) (xy 200.732111 -152.487376)
			(xy 296.945304 -152.487376) (xy 296.945304 -151.623776) (xy 296.945794 -151.593808) (xy 296.953617 -151.534386)
			(xy 296.96913 -151.476493) (xy 296.992066 -151.42112) (xy 297.022033 -151.369214) (xy 297.05852 -151.321664)
			(xy 297.1009 -151.279284) (xy 297.14845 -151.242797) (xy 297.200356 -151.21283) (xy 297.255729 -151.189894)
			(xy 297.313622 -151.174381) (xy 297.373044 -151.166558) (xy 297.43298 -151.166558) (xy 297.492402 -151.174381)
			(xy 297.550295 -151.189894) (xy 297.605668 -151.21283) (xy 297.657574 -151.242797) (xy 297.705124 -151.279284)
			(xy 297.747504 -151.321664) (xy 297.783991 -151.369214) (xy 297.813958 -151.42112) (xy 297.836894 -151.476493)
			(xy 297.852407 -151.534386) (xy 297.86023 -151.593808) (xy 297.86072 -151.623776) (xy 297.86072 -152.485852)
			(xy 315.916564 -152.485852) (xy 315.916564 -151.622252) (xy 315.917054 -151.592284) (xy 315.924877 -151.532862)
			(xy 315.94039 -151.474969) (xy 315.963326 -151.419596) (xy 315.993293 -151.36769) (xy 316.02978 -151.32014)
			(xy 316.07216 -151.27776) (xy 316.11971 -151.241273) (xy 316.171616 -151.211306) (xy 316.226989 -151.18837)
			(xy 316.284882 -151.172857) (xy 316.344304 -151.165034) (xy 316.40424 -151.165034) (xy 316.463662 -151.172857)
			(xy 316.521555 -151.18837) (xy 316.576928 -151.211306) (xy 316.628834 -151.241273) (xy 316.676384 -151.27776)
			(xy 316.718764 -151.32014) (xy 316.755251 -151.36769) (xy 316.785218 -151.419596) (xy 316.808154 -151.474969)
			(xy 316.823667 -151.532862) (xy 316.83149 -151.592284) (xy 316.83198 -151.622252) (xy 316.83198 -152.485852)
			(xy 316.831955 -152.487376) (xy 413.045148 -152.487376) (xy 413.045148 -151.623776) (xy 413.045638 -151.593792)
			(xy 413.053466 -151.534336) (xy 413.068987 -151.476411) (xy 413.091936 -151.421007) (xy 413.12192 -151.369073)
			(xy 413.158426 -151.321497) (xy 413.200831 -151.279092) (xy 413.248407 -151.242586) (xy 413.300341 -151.212602)
			(xy 413.355745 -151.189653) (xy 413.41367 -151.174132) (xy 413.473126 -151.166304) (xy 413.533094 -151.166304)
			(xy 413.59255 -151.174132) (xy 413.650475 -151.189653) (xy 413.705879 -151.212602) (xy 413.757813 -151.242586)
			(xy 413.805389 -151.279092) (xy 413.847794 -151.321497) (xy 413.8843 -151.369073) (xy 413.914284 -151.421007)
			(xy 413.937233 -151.476411) (xy 413.952754 -151.534336) (xy 413.960582 -151.593792) (xy 413.961072 -151.623776)
			(xy 413.961072 -152.485852) (xy 432.016408 -152.485852) (xy 432.016408 -151.622252) (xy 432.016898 -151.592268)
			(xy 432.024726 -151.532812) (xy 432.040247 -151.474887) (xy 432.063196 -151.419483) (xy 432.09318 -151.367549)
			(xy 432.129686 -151.319973) (xy 432.172091 -151.277568) (xy 432.219667 -151.241062) (xy 432.271601 -151.211078)
			(xy 432.327005 -151.188129) (xy 432.38493 -151.172608) (xy 432.444386 -151.16478) (xy 432.504354 -151.16478)
			(xy 432.56381 -151.172608) (xy 432.621735 -151.188129) (xy 432.677139 -151.211078) (xy 432.729073 -151.241062)
			(xy 432.776649 -151.277568) (xy 432.819054 -151.319973) (xy 432.85556 -151.367549) (xy 432.885544 -151.419483)
			(xy 432.908493 -151.474887) (xy 432.924014 -151.532812) (xy 432.931842 -151.592268) (xy 432.932332 -151.622252)
			(xy 432.932332 -152.485852) (xy 432.931842 -152.515836) (xy 432.924014 -152.575292) (xy 432.908493 -152.633217)
			(xy 432.885544 -152.688621) (xy 432.85556 -152.740555) (xy 432.819054 -152.788131) (xy 432.776649 -152.830536)
			(xy 432.729073 -152.867042) (xy 432.677139 -152.897026) (xy 432.621735 -152.919975) (xy 432.56381 -152.935496)
			(xy 432.504354 -152.943324) (xy 432.444386 -152.943324) (xy 432.38493 -152.935496) (xy 432.327005 -152.919975)
			(xy 432.271601 -152.897026) (xy 432.219667 -152.867042) (xy 432.172091 -152.830536) (xy 432.129686 -152.788131)
			(xy 432.09318 -152.740555) (xy 432.063196 -152.688621) (xy 432.040247 -152.633217) (xy 432.024726 -152.575292)
			(xy 432.016898 -152.515836) (xy 432.016408 -152.485852) (xy 413.961072 -152.485852) (xy 413.961072 -152.487376)
			(xy 413.960582 -152.51736) (xy 413.952754 -152.576816) (xy 413.937233 -152.634741) (xy 413.914284 -152.690145)
			(xy 413.8843 -152.742079) (xy 413.847794 -152.789655) (xy 413.805389 -152.83206) (xy 413.757813 -152.868566)
			(xy 413.705879 -152.89855) (xy 413.650475 -152.921499) (xy 413.59255 -152.93702) (xy 413.533094 -152.944848)
			(xy 413.473126 -152.944848) (xy 413.41367 -152.93702) (xy 413.355745 -152.921499) (xy 413.300341 -152.89855)
			(xy 413.248407 -152.868566) (xy 413.200831 -152.83206) (xy 413.158426 -152.789655) (xy 413.12192 -152.742079)
			(xy 413.091936 -152.690145) (xy 413.068987 -152.634741) (xy 413.053466 -152.576816) (xy 413.045638 -152.51736)
			(xy 413.045148 -152.487376) (xy 316.831955 -152.487376) (xy 316.83149 -152.51582) (xy 316.823667 -152.575242)
			(xy 316.808154 -152.633135) (xy 316.785218 -152.688508) (xy 316.755251 -152.740414) (xy 316.718764 -152.787964)
			(xy 316.676384 -152.830344) (xy 316.628834 -152.866831) (xy 316.576928 -152.896798) (xy 316.521555 -152.919734)
			(xy 316.463662 -152.935247) (xy 316.40424 -152.94307) (xy 316.344304 -152.94307) (xy 316.284882 -152.935247)
			(xy 316.226989 -152.919734) (xy 316.171616 -152.896798) (xy 316.11971 -152.866831) (xy 316.07216 -152.830344)
			(xy 316.02978 -152.787964) (xy 315.993293 -152.740414) (xy 315.963326 -152.688508) (xy 315.94039 -152.633135)
			(xy 315.924877 -152.575242) (xy 315.917054 -152.51582) (xy 315.916564 -152.485852) (xy 297.86072 -152.485852)
			(xy 297.86072 -152.487376) (xy 297.86023 -152.517344) (xy 297.852407 -152.576766) (xy 297.836894 -152.634659)
			(xy 297.813958 -152.690032) (xy 297.783991 -152.741938) (xy 297.747504 -152.789488) (xy 297.705124 -152.831868)
			(xy 297.657574 -152.868355) (xy 297.605668 -152.898322) (xy 297.550295 -152.921258) (xy 297.492402 -152.936771)
			(xy 297.43298 -152.944594) (xy 297.373044 -152.944594) (xy 297.313622 -152.936771) (xy 297.255729 -152.921258)
			(xy 297.200356 -152.898322) (xy 297.14845 -152.868355) (xy 297.1009 -152.831868) (xy 297.05852 -152.789488)
			(xy 297.022033 -152.741938) (xy 296.992066 -152.690032) (xy 296.96913 -152.634659) (xy 296.953617 -152.576766)
			(xy 296.945794 -152.517344) (xy 296.945304 -152.487376) (xy 200.732111 -152.487376) (xy 200.731646 -152.51582)
			(xy 200.723823 -152.575242) (xy 200.70831 -152.633135) (xy 200.685374 -152.688508) (xy 200.655407 -152.740414)
			(xy 200.61892 -152.787964) (xy 200.57654 -152.830344) (xy 200.52899 -152.866831) (xy 200.477084 -152.896798)
			(xy 200.421711 -152.919734) (xy 200.363818 -152.935247) (xy 200.304396 -152.94307) (xy 200.24446 -152.94307)
			(xy 200.185038 -152.935247) (xy 200.127145 -152.919734) (xy 200.071772 -152.896798) (xy 200.019866 -152.866831)
			(xy 199.972316 -152.830344) (xy 199.929936 -152.787964) (xy 199.893449 -152.740414) (xy 199.863482 -152.688508)
			(xy 199.840546 -152.633135) (xy 199.825033 -152.575242) (xy 199.81721 -152.51582) (xy 199.81672 -152.485852)
			(xy 181.760876 -152.485852) (xy 181.760876 -152.487376) (xy 181.760386 -152.517344) (xy 181.752563 -152.576766)
			(xy 181.73705 -152.634659) (xy 181.714114 -152.690032) (xy 181.684147 -152.741938) (xy 181.64766 -152.789488)
			(xy 181.60528 -152.831868) (xy 181.55773 -152.868355) (xy 181.505824 -152.898322) (xy 181.450451 -152.921258)
			(xy 181.392558 -152.936771) (xy 181.333136 -152.944594) (xy 181.2732 -152.944594) (xy 181.213778 -152.936771)
			(xy 181.155885 -152.921258) (xy 181.100512 -152.898322) (xy 181.048606 -152.868355) (xy 181.001056 -152.831868)
			(xy 180.958676 -152.789488) (xy 180.922189 -152.741938) (xy 180.892222 -152.690032) (xy 180.869286 -152.634659)
			(xy 180.853773 -152.576766) (xy 180.84595 -152.517344) (xy 180.84546 -152.487376) (xy 84.632267 -152.487376)
			(xy 84.631802 -152.515836) (xy 84.623974 -152.575292) (xy 84.608453 -152.633217) (xy 84.585504 -152.688621)
			(xy 84.55552 -152.740555) (xy 84.519014 -152.788131) (xy 84.476609 -152.830536) (xy 84.429033 -152.867042)
			(xy 84.377099 -152.897026) (xy 84.321695 -152.919975) (xy 84.26377 -152.935496) (xy 84.204314 -152.943324)
			(xy 84.144346 -152.943324) (xy 84.08489 -152.935496) (xy 84.026965 -152.919975) (xy 83.971561 -152.897026)
			(xy 83.919627 -152.867042) (xy 83.872051 -152.830536) (xy 83.829646 -152.788131) (xy 83.79314 -152.740555)
			(xy 83.763156 -152.688621) (xy 83.740207 -152.633217) (xy 83.724686 -152.575292) (xy 83.716858 -152.515836)
			(xy 83.716368 -152.485852) (xy 65.661032 -152.485852) (xy 65.661032 -152.487376) (xy 65.660542 -152.51736)
			(xy 65.652714 -152.576816) (xy 65.637193 -152.634741) (xy 65.614244 -152.690145) (xy 65.58426 -152.742079)
			(xy 65.547754 -152.789655) (xy 65.505349 -152.83206) (xy 65.457773 -152.868566) (xy 65.405839 -152.89855)
			(xy 65.350435 -152.921499) (xy 65.29251 -152.93702) (xy 65.233054 -152.944848) (xy 65.173086 -152.944848)
			(xy 65.11363 -152.93702) (xy 65.055705 -152.921499) (xy 65.000301 -152.89855) (xy 64.948367 -152.868566)
			(xy 64.900791 -152.83206) (xy 64.858386 -152.789655) (xy 64.82188 -152.742079) (xy 64.791896 -152.690145)
			(xy 64.768947 -152.634741) (xy 64.753426 -152.576816) (xy 64.745598 -152.51736) (xy 64.745108 -152.487376)
			(xy 5.324094 -152.487376) (xy 5.324094 -154.28722) (xy 66.599308 -154.28722) (xy 66.599308 -153.42362)
			(xy 66.599798 -153.393636) (xy 66.607626 -153.33418) (xy 66.623147 -153.276255) (xy 66.646096 -153.220851)
			(xy 66.67608 -153.168917) (xy 66.712586 -153.121341) (xy 66.754991 -153.078936) (xy 66.802567 -153.04243)
			(xy 66.854501 -153.012446) (xy 66.909905 -152.989497) (xy 66.96783 -152.973976) (xy 67.027286 -152.966148)
			(xy 67.087254 -152.966148) (xy 67.14671 -152.973976) (xy 67.204635 -152.989497) (xy 67.260039 -153.012446)
			(xy 67.311973 -153.04243) (xy 67.359549 -153.078936) (xy 67.401954 -153.121341) (xy 67.43846 -153.168917)
			(xy 67.468444 -153.220851) (xy 67.491393 -153.276255) (xy 67.506914 -153.33418) (xy 67.514742 -153.393636)
			(xy 67.515232 -153.42362) (xy 67.515232 -154.279346) (xy 81.07426 -154.279346) (xy 81.07426 -153.415746)
			(xy 81.07475 -153.385762) (xy 81.082578 -153.326306) (xy 81.098099 -153.268381) (xy 81.121048 -153.212977)
			(xy 81.151032 -153.161043) (xy 81.187538 -153.113467) (xy 81.229943 -153.071062) (xy 81.277519 -153.034556)
			(xy 81.329453 -153.004572) (xy 81.384857 -152.981623) (xy 81.442782 -152.966102) (xy 81.502238 -152.958274)
			(xy 81.562206 -152.958274) (xy 81.621662 -152.966102) (xy 81.679587 -152.981623) (xy 81.734991 -153.004572)
			(xy 81.786925 -153.034556) (xy 81.834501 -153.071062) (xy 81.876906 -153.113467) (xy 81.913412 -153.161043)
			(xy 81.943396 -153.212977) (xy 81.966345 -153.268381) (xy 81.981866 -153.326306) (xy 81.989694 -153.385762)
			(xy 81.990184 -153.415746) (xy 81.990184 -154.279346) (xy 81.990055 -154.28722) (xy 182.69966 -154.28722)
			(xy 182.69966 -153.42362) (xy 182.70015 -153.393652) (xy 182.707973 -153.33423) (xy 182.723486 -153.276337)
			(xy 182.746422 -153.220964) (xy 182.776389 -153.169058) (xy 182.812876 -153.121508) (xy 182.855256 -153.079128)
			(xy 182.902806 -153.042641) (xy 182.954712 -153.012674) (xy 183.010085 -152.989738) (xy 183.067978 -152.974225)
			(xy 183.1274 -152.966402) (xy 183.187336 -152.966402) (xy 183.246758 -152.974225) (xy 183.304651 -152.989738)
			(xy 183.360024 -153.012674) (xy 183.41193 -153.042641) (xy 183.45948 -153.079128) (xy 183.50186 -153.121508)
			(xy 183.538347 -153.169058) (xy 183.568314 -153.220964) (xy 183.59125 -153.276337) (xy 183.606763 -153.33423)
			(xy 183.614586 -153.393652) (xy 183.615076 -153.42362) (xy 183.615076 -154.279346) (xy 197.174612 -154.279346)
			(xy 197.174612 -153.415746) (xy 197.175102 -153.385778) (xy 197.182925 -153.326356) (xy 197.198438 -153.268463)
			(xy 197.221374 -153.21309) (xy 197.251341 -153.161184) (xy 197.287828 -153.113634) (xy 197.330208 -153.071254)
			(xy 197.377758 -153.034767) (xy 197.429664 -153.0048) (xy 197.485037 -152.981864) (xy 197.54293 -152.966351)
			(xy 197.602352 -152.958528) (xy 197.662288 -152.958528) (xy 197.72171 -152.966351) (xy 197.779603 -152.981864)
			(xy 197.834976 -153.0048) (xy 197.886882 -153.034767) (xy 197.934432 -153.071254) (xy 197.976812 -153.113634)
			(xy 198.013299 -153.161184) (xy 198.043266 -153.21309) (xy 198.066202 -153.268463) (xy 198.081715 -153.326356)
			(xy 198.089538 -153.385778) (xy 198.090028 -153.415746) (xy 198.090028 -154.279346) (xy 198.089899 -154.28722)
			(xy 298.799504 -154.28722) (xy 298.799504 -153.42362) (xy 298.799994 -153.393652) (xy 298.807817 -153.33423)
			(xy 298.82333 -153.276337) (xy 298.846266 -153.220964) (xy 298.876233 -153.169058) (xy 298.91272 -153.121508)
			(xy 298.9551 -153.079128) (xy 299.00265 -153.042641) (xy 299.054556 -153.012674) (xy 299.109929 -152.989738)
			(xy 299.167822 -152.974225) (xy 299.227244 -152.966402) (xy 299.28718 -152.966402) (xy 299.346602 -152.974225)
			(xy 299.404495 -152.989738) (xy 299.459868 -153.012674) (xy 299.511774 -153.042641) (xy 299.559324 -153.079128)
			(xy 299.601704 -153.121508) (xy 299.638191 -153.169058) (xy 299.668158 -153.220964) (xy 299.691094 -153.276337)
			(xy 299.706607 -153.33423) (xy 299.71443 -153.393652) (xy 299.71492 -153.42362) (xy 299.71492 -154.279346)
			(xy 313.274456 -154.279346) (xy 313.274456 -153.415746) (xy 313.274946 -153.385778) (xy 313.282769 -153.326356)
			(xy 313.298282 -153.268463) (xy 313.321218 -153.21309) (xy 313.351185 -153.161184) (xy 313.387672 -153.113634)
			(xy 313.430052 -153.071254) (xy 313.477602 -153.034767) (xy 313.529508 -153.0048) (xy 313.584881 -152.981864)
			(xy 313.642774 -152.966351) (xy 313.702196 -152.958528) (xy 313.762132 -152.958528) (xy 313.821554 -152.966351)
			(xy 313.879447 -152.981864) (xy 313.93482 -153.0048) (xy 313.986726 -153.034767) (xy 314.034276 -153.071254)
			(xy 314.076656 -153.113634) (xy 314.113143 -153.161184) (xy 314.14311 -153.21309) (xy 314.166046 -153.268463)
			(xy 314.181559 -153.326356) (xy 314.189382 -153.385778) (xy 314.189872 -153.415746) (xy 314.189872 -154.279346)
			(xy 314.189743 -154.28722) (xy 414.899348 -154.28722) (xy 414.899348 -153.42362) (xy 414.899838 -153.393636)
			(xy 414.907666 -153.33418) (xy 414.923187 -153.276255) (xy 414.946136 -153.220851) (xy 414.97612 -153.168917)
			(xy 415.012626 -153.121341) (xy 415.055031 -153.078936) (xy 415.102607 -153.04243) (xy 415.154541 -153.012446)
			(xy 415.209945 -152.989497) (xy 415.26787 -152.973976) (xy 415.327326 -152.966148) (xy 415.387294 -152.966148)
			(xy 415.44675 -152.973976) (xy 415.504675 -152.989497) (xy 415.560079 -153.012446) (xy 415.612013 -153.04243)
			(xy 415.659589 -153.078936) (xy 415.701994 -153.121341) (xy 415.7385 -153.168917) (xy 415.768484 -153.220851)
			(xy 415.791433 -153.276255) (xy 415.806954 -153.33418) (xy 415.814782 -153.393636) (xy 415.815272 -153.42362)
			(xy 415.815272 -154.279346) (xy 429.3743 -154.279346) (xy 429.3743 -153.415746) (xy 429.37479 -153.385762)
			(xy 429.382618 -153.326306) (xy 429.398139 -153.268381) (xy 429.421088 -153.212977) (xy 429.451072 -153.161043)
			(xy 429.487578 -153.113467) (xy 429.529983 -153.071062) (xy 429.577559 -153.034556) (xy 429.629493 -153.004572)
			(xy 429.684897 -152.981623) (xy 429.742822 -152.966102) (xy 429.802278 -152.958274) (xy 429.862246 -152.958274)
			(xy 429.921702 -152.966102) (xy 429.979627 -152.981623) (xy 430.035031 -153.004572) (xy 430.086965 -153.034556)
			(xy 430.134541 -153.071062) (xy 430.176946 -153.113467) (xy 430.213452 -153.161043) (xy 430.243436 -153.212977)
			(xy 430.266385 -153.268381) (xy 430.281906 -153.326306) (xy 430.289734 -153.385762) (xy 430.290224 -153.415746)
			(xy 430.290224 -154.279346) (xy 430.289734 -154.30933) (xy 430.281906 -154.368786) (xy 430.266385 -154.426711)
			(xy 430.243436 -154.482115) (xy 430.213452 -154.534049) (xy 430.176946 -154.581625) (xy 430.134541 -154.62403)
			(xy 430.086965 -154.660536) (xy 430.035031 -154.69052) (xy 429.979627 -154.713469) (xy 429.921702 -154.72899)
			(xy 429.862246 -154.736818) (xy 429.802278 -154.736818) (xy 429.742822 -154.72899) (xy 429.684897 -154.713469)
			(xy 429.629493 -154.69052) (xy 429.577559 -154.660536) (xy 429.529983 -154.62403) (xy 429.487578 -154.581625)
			(xy 429.451072 -154.534049) (xy 429.421088 -154.482115) (xy 429.398139 -154.426711) (xy 429.382618 -154.368786)
			(xy 429.37479 -154.30933) (xy 429.3743 -154.279346) (xy 415.815272 -154.279346) (xy 415.815272 -154.28722)
			(xy 415.814782 -154.317204) (xy 415.806954 -154.37666) (xy 415.791433 -154.434585) (xy 415.768484 -154.489989)
			(xy 415.7385 -154.541923) (xy 415.701994 -154.589499) (xy 415.659589 -154.631904) (xy 415.612013 -154.66841)
			(xy 415.560079 -154.698394) (xy 415.504675 -154.721343) (xy 415.44675 -154.736864) (xy 415.387294 -154.744692)
			(xy 415.327326 -154.744692) (xy 415.26787 -154.736864) (xy 415.209945 -154.721343) (xy 415.154541 -154.698394)
			(xy 415.102607 -154.66841) (xy 415.055031 -154.631904) (xy 415.012626 -154.589499) (xy 414.97612 -154.541923)
			(xy 414.946136 -154.489989) (xy 414.923187 -154.434585) (xy 414.907666 -154.37666) (xy 414.899838 -154.317204)
			(xy 414.899348 -154.28722) (xy 314.189743 -154.28722) (xy 314.189382 -154.309314) (xy 314.181559 -154.368736)
			(xy 314.166046 -154.426629) (xy 314.14311 -154.482002) (xy 314.113143 -154.533908) (xy 314.076656 -154.581458)
			(xy 314.034276 -154.623838) (xy 313.986726 -154.660325) (xy 313.93482 -154.690292) (xy 313.879447 -154.713228)
			(xy 313.821554 -154.728741) (xy 313.762132 -154.736564) (xy 313.702196 -154.736564) (xy 313.642774 -154.728741)
			(xy 313.584881 -154.713228) (xy 313.529508 -154.690292) (xy 313.477602 -154.660325) (xy 313.430052 -154.623838)
			(xy 313.387672 -154.581458) (xy 313.351185 -154.533908) (xy 313.321218 -154.482002) (xy 313.298282 -154.426629)
			(xy 313.282769 -154.368736) (xy 313.274946 -154.309314) (xy 313.274456 -154.279346) (xy 299.71492 -154.279346)
			(xy 299.71492 -154.28722) (xy 299.71443 -154.317188) (xy 299.706607 -154.37661) (xy 299.691094 -154.434503)
			(xy 299.668158 -154.489876) (xy 299.638191 -154.541782) (xy 299.601704 -154.589332) (xy 299.559324 -154.631712)
			(xy 299.511774 -154.668199) (xy 299.459868 -154.698166) (xy 299.404495 -154.721102) (xy 299.346602 -154.736615)
			(xy 299.28718 -154.744438) (xy 299.227244 -154.744438) (xy 299.167822 -154.736615) (xy 299.109929 -154.721102)
			(xy 299.054556 -154.698166) (xy 299.00265 -154.668199) (xy 298.9551 -154.631712) (xy 298.91272 -154.589332)
			(xy 298.876233 -154.541782) (xy 298.846266 -154.489876) (xy 298.82333 -154.434503) (xy 298.807817 -154.37661)
			(xy 298.799994 -154.317188) (xy 298.799504 -154.28722) (xy 198.089899 -154.28722) (xy 198.089538 -154.309314)
			(xy 198.081715 -154.368736) (xy 198.066202 -154.426629) (xy 198.043266 -154.482002) (xy 198.013299 -154.533908)
			(xy 197.976812 -154.581458) (xy 197.934432 -154.623838) (xy 197.886882 -154.660325) (xy 197.834976 -154.690292)
			(xy 197.779603 -154.713228) (xy 197.72171 -154.728741) (xy 197.662288 -154.736564) (xy 197.602352 -154.736564)
			(xy 197.54293 -154.728741) (xy 197.485037 -154.713228) (xy 197.429664 -154.690292) (xy 197.377758 -154.660325)
			(xy 197.330208 -154.623838) (xy 197.287828 -154.581458) (xy 197.251341 -154.533908) (xy 197.221374 -154.482002)
			(xy 197.198438 -154.426629) (xy 197.182925 -154.368736) (xy 197.175102 -154.309314) (xy 197.174612 -154.279346)
			(xy 183.615076 -154.279346) (xy 183.615076 -154.28722) (xy 183.614586 -154.317188) (xy 183.606763 -154.37661)
			(xy 183.59125 -154.434503) (xy 183.568314 -154.489876) (xy 183.538347 -154.541782) (xy 183.50186 -154.589332)
			(xy 183.45948 -154.631712) (xy 183.41193 -154.668199) (xy 183.360024 -154.698166) (xy 183.304651 -154.721102)
			(xy 183.246758 -154.736615) (xy 183.187336 -154.744438) (xy 183.1274 -154.744438) (xy 183.067978 -154.736615)
			(xy 183.010085 -154.721102) (xy 182.954712 -154.698166) (xy 182.902806 -154.668199) (xy 182.855256 -154.631712)
			(xy 182.812876 -154.589332) (xy 182.776389 -154.541782) (xy 182.746422 -154.489876) (xy 182.723486 -154.434503)
			(xy 182.707973 -154.37661) (xy 182.70015 -154.317188) (xy 182.69966 -154.28722) (xy 81.990055 -154.28722)
			(xy 81.989694 -154.30933) (xy 81.981866 -154.368786) (xy 81.966345 -154.426711) (xy 81.943396 -154.482115)
			(xy 81.913412 -154.534049) (xy 81.876906 -154.581625) (xy 81.834501 -154.62403) (xy 81.786925 -154.660536)
			(xy 81.734991 -154.69052) (xy 81.679587 -154.713469) (xy 81.621662 -154.72899) (xy 81.562206 -154.736818)
			(xy 81.502238 -154.736818) (xy 81.442782 -154.72899) (xy 81.384857 -154.713469) (xy 81.329453 -154.69052)
			(xy 81.277519 -154.660536) (xy 81.229943 -154.62403) (xy 81.187538 -154.581625) (xy 81.151032 -154.534049)
			(xy 81.121048 -154.482115) (xy 81.098099 -154.426711) (xy 81.082578 -154.368786) (xy 81.07475 -154.30933)
			(xy 81.07426 -154.279346) (xy 67.515232 -154.279346) (xy 67.515232 -154.28722) (xy 67.514742 -154.317204)
			(xy 67.506914 -154.37666) (xy 67.491393 -154.434585) (xy 67.468444 -154.489989) (xy 67.43846 -154.541923)
			(xy 67.401954 -154.589499) (xy 67.359549 -154.631904) (xy 67.311973 -154.66841) (xy 67.260039 -154.698394)
			(xy 67.204635 -154.721343) (xy 67.14671 -154.736864) (xy 67.087254 -154.744692) (xy 67.027286 -154.744692)
			(xy 66.96783 -154.736864) (xy 66.909905 -154.721343) (xy 66.854501 -154.698394) (xy 66.802567 -154.66841)
			(xy 66.754991 -154.631904) (xy 66.712586 -154.589499) (xy 66.67608 -154.541923) (xy 66.646096 -154.489989)
			(xy 66.623147 -154.434585) (xy 66.607626 -154.37666) (xy 66.599798 -154.317204) (xy 66.599308 -154.28722)
			(xy 5.324094 -154.28722) (xy 5.324094 -156.087318) (xy 64.745108 -156.087318) (xy 64.745108 -155.223718)
			(xy 64.745598 -155.193734) (xy 64.753426 -155.134278) (xy 64.768947 -155.076353) (xy 64.791896 -155.020949)
			(xy 64.82188 -154.969015) (xy 64.858386 -154.921439) (xy 64.900791 -154.879034) (xy 64.948367 -154.842528)
			(xy 65.000301 -154.812544) (xy 65.055705 -154.789595) (xy 65.11363 -154.774074) (xy 65.173086 -154.766246)
			(xy 65.233054 -154.766246) (xy 65.29251 -154.774074) (xy 65.350435 -154.789595) (xy 65.405839 -154.812544)
			(xy 65.457773 -154.842528) (xy 65.505349 -154.879034) (xy 65.547754 -154.921439) (xy 65.58426 -154.969015)
			(xy 65.614244 -155.020949) (xy 65.637193 -155.076353) (xy 65.652714 -155.134278) (xy 65.660542 -155.193734)
			(xy 65.661032 -155.223718) (xy 65.661032 -156.085794) (xy 83.716368 -156.085794) (xy 83.716368 -155.222194)
			(xy 83.716858 -155.19221) (xy 83.724686 -155.132754) (xy 83.740207 -155.074829) (xy 83.763156 -155.019425)
			(xy 83.79314 -154.967491) (xy 83.829646 -154.919915) (xy 83.872051 -154.87751) (xy 83.919627 -154.841004)
			(xy 83.971561 -154.81102) (xy 84.026965 -154.788071) (xy 84.08489 -154.77255) (xy 84.144346 -154.764722)
			(xy 84.204314 -154.764722) (xy 84.26377 -154.77255) (xy 84.321695 -154.788071) (xy 84.377099 -154.81102)
			(xy 84.429033 -154.841004) (xy 84.476609 -154.87751) (xy 84.519014 -154.919915) (xy 84.55552 -154.967491)
			(xy 84.585504 -155.019425) (xy 84.608453 -155.074829) (xy 84.623974 -155.132754) (xy 84.631802 -155.19221)
			(xy 84.632292 -155.222194) (xy 84.632292 -156.085794) (xy 84.632267 -156.087318) (xy 180.84546 -156.087318)
			(xy 180.84546 -155.223718) (xy 180.84595 -155.19375) (xy 180.853773 -155.134328) (xy 180.869286 -155.076435)
			(xy 180.892222 -155.021062) (xy 180.922189 -154.969156) (xy 180.958676 -154.921606) (xy 181.001056 -154.879226)
			(xy 181.048606 -154.842739) (xy 181.100512 -154.812772) (xy 181.155885 -154.789836) (xy 181.213778 -154.774323)
			(xy 181.2732 -154.7665) (xy 181.333136 -154.7665) (xy 181.392558 -154.774323) (xy 181.450451 -154.789836)
			(xy 181.505824 -154.812772) (xy 181.55773 -154.842739) (xy 181.60528 -154.879226) (xy 181.64766 -154.921606)
			(xy 181.684147 -154.969156) (xy 181.714114 -155.021062) (xy 181.73705 -155.076435) (xy 181.752563 -155.134328)
			(xy 181.760386 -155.19375) (xy 181.760876 -155.223718) (xy 181.760876 -156.085794) (xy 199.81672 -156.085794)
			(xy 199.81672 -155.222194) (xy 199.81721 -155.192226) (xy 199.825033 -155.132804) (xy 199.840546 -155.074911)
			(xy 199.863482 -155.019538) (xy 199.893449 -154.967632) (xy 199.929936 -154.920082) (xy 199.972316 -154.877702)
			(xy 200.019866 -154.841215) (xy 200.071772 -154.811248) (xy 200.127145 -154.788312) (xy 200.185038 -154.772799)
			(xy 200.24446 -154.764976) (xy 200.304396 -154.764976) (xy 200.363818 -154.772799) (xy 200.421711 -154.788312)
			(xy 200.477084 -154.811248) (xy 200.52899 -154.841215) (xy 200.57654 -154.877702) (xy 200.61892 -154.920082)
			(xy 200.655407 -154.967632) (xy 200.685374 -155.019538) (xy 200.70831 -155.074911) (xy 200.723823 -155.132804)
			(xy 200.731646 -155.192226) (xy 200.732136 -155.222194) (xy 200.732136 -156.085794) (xy 200.732111 -156.087318)
			(xy 296.945304 -156.087318) (xy 296.945304 -155.223718) (xy 296.945794 -155.19375) (xy 296.953617 -155.134328)
			(xy 296.96913 -155.076435) (xy 296.992066 -155.021062) (xy 297.022033 -154.969156) (xy 297.05852 -154.921606)
			(xy 297.1009 -154.879226) (xy 297.14845 -154.842739) (xy 297.200356 -154.812772) (xy 297.255729 -154.789836)
			(xy 297.313622 -154.774323) (xy 297.373044 -154.7665) (xy 297.43298 -154.7665) (xy 297.492402 -154.774323)
			(xy 297.550295 -154.789836) (xy 297.605668 -154.812772) (xy 297.657574 -154.842739) (xy 297.705124 -154.879226)
			(xy 297.747504 -154.921606) (xy 297.783991 -154.969156) (xy 297.813958 -155.021062) (xy 297.836894 -155.076435)
			(xy 297.852407 -155.134328) (xy 297.86023 -155.19375) (xy 297.86072 -155.223718) (xy 297.86072 -156.085794)
			(xy 315.916564 -156.085794) (xy 315.916564 -155.222194) (xy 315.917054 -155.192226) (xy 315.924877 -155.132804)
			(xy 315.94039 -155.074911) (xy 315.963326 -155.019538) (xy 315.993293 -154.967632) (xy 316.02978 -154.920082)
			(xy 316.07216 -154.877702) (xy 316.11971 -154.841215) (xy 316.171616 -154.811248) (xy 316.226989 -154.788312)
			(xy 316.284882 -154.772799) (xy 316.344304 -154.764976) (xy 316.40424 -154.764976) (xy 316.463662 -154.772799)
			(xy 316.521555 -154.788312) (xy 316.576928 -154.811248) (xy 316.628834 -154.841215) (xy 316.676384 -154.877702)
			(xy 316.718764 -154.920082) (xy 316.755251 -154.967632) (xy 316.785218 -155.019538) (xy 316.808154 -155.074911)
			(xy 316.823667 -155.132804) (xy 316.83149 -155.192226) (xy 316.83198 -155.222194) (xy 316.83198 -156.085794)
			(xy 316.831955 -156.087318) (xy 413.045148 -156.087318) (xy 413.045148 -155.223718) (xy 413.045638 -155.193734)
			(xy 413.053466 -155.134278) (xy 413.068987 -155.076353) (xy 413.091936 -155.020949) (xy 413.12192 -154.969015)
			(xy 413.158426 -154.921439) (xy 413.200831 -154.879034) (xy 413.248407 -154.842528) (xy 413.300341 -154.812544)
			(xy 413.355745 -154.789595) (xy 413.41367 -154.774074) (xy 413.473126 -154.766246) (xy 413.533094 -154.766246)
			(xy 413.59255 -154.774074) (xy 413.650475 -154.789595) (xy 413.705879 -154.812544) (xy 413.757813 -154.842528)
			(xy 413.805389 -154.879034) (xy 413.847794 -154.921439) (xy 413.8843 -154.969015) (xy 413.914284 -155.020949)
			(xy 413.937233 -155.076353) (xy 413.952754 -155.134278) (xy 413.960582 -155.193734) (xy 413.961072 -155.223718)
			(xy 413.961072 -156.085794) (xy 432.016408 -156.085794) (xy 432.016408 -155.222194) (xy 432.016898 -155.19221)
			(xy 432.024726 -155.132754) (xy 432.040247 -155.074829) (xy 432.063196 -155.019425) (xy 432.09318 -154.967491)
			(xy 432.129686 -154.919915) (xy 432.172091 -154.87751) (xy 432.219667 -154.841004) (xy 432.271601 -154.81102)
			(xy 432.327005 -154.788071) (xy 432.38493 -154.77255) (xy 432.444386 -154.764722) (xy 432.504354 -154.764722)
			(xy 432.56381 -154.77255) (xy 432.621735 -154.788071) (xy 432.677139 -154.81102) (xy 432.729073 -154.841004)
			(xy 432.776649 -154.87751) (xy 432.819054 -154.919915) (xy 432.85556 -154.967491) (xy 432.885544 -155.019425)
			(xy 432.908493 -155.074829) (xy 432.924014 -155.132754) (xy 432.931842 -155.19221) (xy 432.932332 -155.222194)
			(xy 432.932332 -156.085794) (xy 432.931842 -156.115778) (xy 432.924014 -156.175234) (xy 432.908493 -156.233159)
			(xy 432.885544 -156.288563) (xy 432.85556 -156.340497) (xy 432.819054 -156.388073) (xy 432.776649 -156.430478)
			(xy 432.729073 -156.466984) (xy 432.677139 -156.496968) (xy 432.621735 -156.519917) (xy 432.56381 -156.535438)
			(xy 432.504354 -156.543266) (xy 432.444386 -156.543266) (xy 432.38493 -156.535438) (xy 432.327005 -156.519917)
			(xy 432.271601 -156.496968) (xy 432.219667 -156.466984) (xy 432.172091 -156.430478) (xy 432.129686 -156.388073)
			(xy 432.09318 -156.340497) (xy 432.063196 -156.288563) (xy 432.040247 -156.233159) (xy 432.024726 -156.175234)
			(xy 432.016898 -156.115778) (xy 432.016408 -156.085794) (xy 413.961072 -156.085794) (xy 413.961072 -156.087318)
			(xy 413.960582 -156.117302) (xy 413.952754 -156.176758) (xy 413.937233 -156.234683) (xy 413.914284 -156.290087)
			(xy 413.8843 -156.342021) (xy 413.847794 -156.389597) (xy 413.805389 -156.432002) (xy 413.757813 -156.468508)
			(xy 413.705879 -156.498492) (xy 413.650475 -156.521441) (xy 413.59255 -156.536962) (xy 413.533094 -156.54479)
			(xy 413.473126 -156.54479) (xy 413.41367 -156.536962) (xy 413.355745 -156.521441) (xy 413.300341 -156.498492)
			(xy 413.248407 -156.468508) (xy 413.200831 -156.432002) (xy 413.158426 -156.389597) (xy 413.12192 -156.342021)
			(xy 413.091936 -156.290087) (xy 413.068987 -156.234683) (xy 413.053466 -156.176758) (xy 413.045638 -156.117302)
			(xy 413.045148 -156.087318) (xy 316.831955 -156.087318) (xy 316.83149 -156.115762) (xy 316.823667 -156.175184)
			(xy 316.808154 -156.233077) (xy 316.785218 -156.28845) (xy 316.755251 -156.340356) (xy 316.718764 -156.387906)
			(xy 316.676384 -156.430286) (xy 316.628834 -156.466773) (xy 316.576928 -156.49674) (xy 316.521555 -156.519676)
			(xy 316.463662 -156.535189) (xy 316.40424 -156.543012) (xy 316.344304 -156.543012) (xy 316.284882 -156.535189)
			(xy 316.226989 -156.519676) (xy 316.171616 -156.49674) (xy 316.11971 -156.466773) (xy 316.07216 -156.430286)
			(xy 316.02978 -156.387906) (xy 315.993293 -156.340356) (xy 315.963326 -156.28845) (xy 315.94039 -156.233077)
			(xy 315.924877 -156.175184) (xy 315.917054 -156.115762) (xy 315.916564 -156.085794) (xy 297.86072 -156.085794)
			(xy 297.86072 -156.087318) (xy 297.86023 -156.117286) (xy 297.852407 -156.176708) (xy 297.836894 -156.234601)
			(xy 297.813958 -156.289974) (xy 297.783991 -156.34188) (xy 297.747504 -156.38943) (xy 297.705124 -156.43181)
			(xy 297.657574 -156.468297) (xy 297.605668 -156.498264) (xy 297.550295 -156.5212) (xy 297.492402 -156.536713)
			(xy 297.43298 -156.544536) (xy 297.373044 -156.544536) (xy 297.313622 -156.536713) (xy 297.255729 -156.5212)
			(xy 297.200356 -156.498264) (xy 297.14845 -156.468297) (xy 297.1009 -156.43181) (xy 297.05852 -156.38943)
			(xy 297.022033 -156.34188) (xy 296.992066 -156.289974) (xy 296.96913 -156.234601) (xy 296.953617 -156.176708)
			(xy 296.945794 -156.117286) (xy 296.945304 -156.087318) (xy 200.732111 -156.087318) (xy 200.731646 -156.115762)
			(xy 200.723823 -156.175184) (xy 200.70831 -156.233077) (xy 200.685374 -156.28845) (xy 200.655407 -156.340356)
			(xy 200.61892 -156.387906) (xy 200.57654 -156.430286) (xy 200.52899 -156.466773) (xy 200.477084 -156.49674)
			(xy 200.421711 -156.519676) (xy 200.363818 -156.535189) (xy 200.304396 -156.543012) (xy 200.24446 -156.543012)
			(xy 200.185038 -156.535189) (xy 200.127145 -156.519676) (xy 200.071772 -156.49674) (xy 200.019866 -156.466773)
			(xy 199.972316 -156.430286) (xy 199.929936 -156.387906) (xy 199.893449 -156.340356) (xy 199.863482 -156.28845)
			(xy 199.840546 -156.233077) (xy 199.825033 -156.175184) (xy 199.81721 -156.115762) (xy 199.81672 -156.085794)
			(xy 181.760876 -156.085794) (xy 181.760876 -156.087318) (xy 181.760386 -156.117286) (xy 181.752563 -156.176708)
			(xy 181.73705 -156.234601) (xy 181.714114 -156.289974) (xy 181.684147 -156.34188) (xy 181.64766 -156.38943)
			(xy 181.60528 -156.43181) (xy 181.55773 -156.468297) (xy 181.505824 -156.498264) (xy 181.450451 -156.5212)
			(xy 181.392558 -156.536713) (xy 181.333136 -156.544536) (xy 181.2732 -156.544536) (xy 181.213778 -156.536713)
			(xy 181.155885 -156.5212) (xy 181.100512 -156.498264) (xy 181.048606 -156.468297) (xy 181.001056 -156.43181)
			(xy 180.958676 -156.38943) (xy 180.922189 -156.34188) (xy 180.892222 -156.289974) (xy 180.869286 -156.234601)
			(xy 180.853773 -156.176708) (xy 180.84595 -156.117286) (xy 180.84546 -156.087318) (xy 84.632267 -156.087318)
			(xy 84.631802 -156.115778) (xy 84.623974 -156.175234) (xy 84.608453 -156.233159) (xy 84.585504 -156.288563)
			(xy 84.55552 -156.340497) (xy 84.519014 -156.388073) (xy 84.476609 -156.430478) (xy 84.429033 -156.466984)
			(xy 84.377099 -156.496968) (xy 84.321695 -156.519917) (xy 84.26377 -156.535438) (xy 84.204314 -156.543266)
			(xy 84.144346 -156.543266) (xy 84.08489 -156.535438) (xy 84.026965 -156.519917) (xy 83.971561 -156.496968)
			(xy 83.919627 -156.466984) (xy 83.872051 -156.430478) (xy 83.829646 -156.388073) (xy 83.79314 -156.340497)
			(xy 83.763156 -156.288563) (xy 83.740207 -156.233159) (xy 83.724686 -156.175234) (xy 83.716858 -156.115778)
			(xy 83.716368 -156.085794) (xy 65.661032 -156.085794) (xy 65.661032 -156.087318) (xy 65.660542 -156.117302)
			(xy 65.652714 -156.176758) (xy 65.637193 -156.234683) (xy 65.614244 -156.290087) (xy 65.58426 -156.342021)
			(xy 65.547754 -156.389597) (xy 65.505349 -156.432002) (xy 65.457773 -156.468508) (xy 65.405839 -156.498492)
			(xy 65.350435 -156.521441) (xy 65.29251 -156.536962) (xy 65.233054 -156.54479) (xy 65.173086 -156.54479)
			(xy 65.11363 -156.536962) (xy 65.055705 -156.521441) (xy 65.000301 -156.498492) (xy 64.948367 -156.468508)
			(xy 64.900791 -156.432002) (xy 64.858386 -156.389597) (xy 64.82188 -156.342021) (xy 64.791896 -156.290087)
			(xy 64.768947 -156.234683) (xy 64.753426 -156.176758) (xy 64.745598 -156.117302) (xy 64.745108 -156.087318)
			(xy 5.324094 -156.087318) (xy 5.324094 -157.900066) (xy 228.314505 -157.900066) (xy 228.314505 -157.840134)
			(xy 228.322328 -157.780714) (xy 228.33784 -157.722823) (xy 228.360775 -157.667453) (xy 228.390741 -157.61555)
			(xy 228.427226 -157.568002) (xy 228.469605 -157.525624) (xy 228.517153 -157.489139) (xy 228.569056 -157.459173)
			(xy 228.624427 -157.436238) (xy 228.682318 -157.420727) (xy 228.741738 -157.412905) (xy 228.771704 -157.412436)
			(xy 229.635304 -157.412436) (xy 229.665274 -157.412838) (xy 229.724702 -157.420663) (xy 229.7826 -157.436177)
			(xy 229.837978 -157.459116) (xy 229.889888 -157.489086) (xy 229.937442 -157.525576) (xy 229.979827 -157.567961)
			(xy 230.016316 -157.615515) (xy 230.046286 -157.667425) (xy 230.069224 -157.722803) (xy 230.084738 -157.780702)
			(xy 230.092562 -157.84013) (xy 230.092562 -157.90007) (xy 230.089876 -157.920473) (xy 230.557725 -157.920473)
			(xy 230.557725 -157.860527) (xy 230.56555 -157.801095) (xy 230.581066 -157.743192) (xy 230.604007 -157.68781)
			(xy 230.633981 -157.635897) (xy 230.670475 -157.58834) (xy 230.712864 -157.545953) (xy 230.760423 -157.509463)
			(xy 230.812339 -157.479493) (xy 230.867722 -157.456555) (xy 230.925626 -157.441044) (xy 230.985059 -157.433223)
			(xy 231.015032 -157.432756) (xy 231.878632 -157.432756) (xy 231.908596 -157.43332) (xy 231.968011 -157.441146)
			(xy 232.025896 -157.45666) (xy 232.081261 -157.479596) (xy 232.133158 -157.509563) (xy 232.180701 -157.546046)
			(xy 232.223075 -157.588423) (xy 232.259555 -157.635968) (xy 232.289518 -157.687868) (xy 232.31245 -157.743235)
			(xy 232.32796 -157.801121) (xy 232.335782 -157.860536) (xy 232.335782 -157.920464) (xy 232.32796 -157.979879)
			(xy 232.31245 -158.037765) (xy 232.289518 -158.093132) (xy 232.259555 -158.145032) (xy 232.223075 -158.192577)
			(xy 232.180701 -158.234954) (xy 232.133158 -158.271437) (xy 232.081261 -158.301404) (xy 232.025896 -158.32434)
			(xy 231.968011 -158.339854) (xy 231.908596 -158.34768) (xy 231.878632 -158.348172) (xy 231.015032 -158.348172)
			(xy 230.985059 -158.347777) (xy 230.925626 -158.339956) (xy 230.867722 -158.324445) (xy 230.812339 -158.301507)
			(xy 230.760423 -158.271537) (xy 230.712864 -158.235047) (xy 230.670475 -158.19266) (xy 230.633981 -158.145103)
			(xy 230.604007 -158.09319) (xy 230.581066 -158.037808) (xy 230.56555 -157.979905) (xy 230.557725 -157.920473)
			(xy 230.089876 -157.920473) (xy 230.084738 -157.959498) (xy 230.069224 -158.017397) (xy 230.046286 -158.072775)
			(xy 230.016316 -158.124685) (xy 229.979827 -158.172239) (xy 229.937442 -158.214624) (xy 229.889888 -158.251114)
			(xy 229.837978 -158.281084) (xy 229.7826 -158.304023) (xy 229.724702 -158.319537) (xy 229.665274 -158.327362)
			(xy 229.635304 -158.327852) (xy 228.771704 -158.327852) (xy 228.741738 -158.327295) (xy 228.682318 -158.319473)
			(xy 228.624427 -158.303962) (xy 228.569056 -158.281027) (xy 228.517153 -158.251061) (xy 228.469605 -158.214576)
			(xy 228.427226 -158.172198) (xy 228.390741 -158.12465) (xy 228.360775 -158.072747) (xy 228.33784 -158.017377)
			(xy 228.322328 -157.959486) (xy 228.314505 -157.900066) (xy 5.324094 -157.900066) (xy 5.324094 -160.1851)
			(xy 45.524434 -160.1851) (xy 45.528387 -160.093285) (xy 45.540219 -160.002149) (xy 45.559842 -159.912368)
			(xy 45.58711 -159.824606) (xy 45.621821 -159.739514) (xy 45.663719 -159.65772) (xy 45.712494 -159.579831)
			(xy 45.767783 -159.506422) (xy 45.829178 -159.438039) (xy 45.896225 -159.375187) (xy 45.968427 -159.31833)
			(xy 46.045248 -159.267892) (xy 46.126122 -159.224243) (xy 46.210448 -159.187709) (xy 46.297603 -159.158559)
			(xy 46.386941 -159.137009) (xy 46.477801 -159.123219) (xy 46.56951 -159.117291) (xy 46.661389 -159.119268)
			(xy 46.752758 -159.129136) (xy 46.84294 -159.146823) (xy 46.931268 -159.172196) (xy 47.017088 -159.205069)
			(xy 47.099765 -159.245197) (xy 47.178685 -159.292284) (xy 47.253266 -159.345982) (xy 47.322955 -159.405891)
			(xy 47.387235 -159.47157) (xy 47.445632 -159.542532) (xy 47.497712 -159.61825) (xy 47.54309 -159.698166)
			(xy 47.58143 -159.781687) (xy 47.612448 -159.868194) (xy 47.635916 -159.957048) (xy 47.651657 -160.04759)
			(xy 47.659558 -160.13915) (xy 47.660052 -160.1851) (xy 69.889129 -160.1851) (xy 69.893084 -160.093263)
			(xy 69.904919 -160.002106) (xy 69.924546 -159.912303) (xy 69.95182 -159.824521) (xy 69.98654 -159.739407)
			(xy 70.028448 -159.657594) (xy 70.077234 -159.579686) (xy 70.132537 -159.506261) (xy 70.193947 -159.437861)
			(xy 70.261009 -159.374994) (xy 70.333228 -159.318124) (xy 70.410068 -159.267673) (xy 70.490961 -159.224014)
			(xy 70.575307 -159.187471) (xy 70.662483 -159.158314) (xy 70.751842 -159.13676) (xy 70.842723 -159.122966)
			(xy 70.934454 -159.117036) (xy 71.026355 -159.119014) (xy 71.117746 -159.128885) (xy 71.20795 -159.146575)
			(xy 71.296299 -159.171955) (xy 71.382139 -159.204835) (xy 71.464835 -159.244973) (xy 71.543775 -159.292072)
			(xy 71.618373 -159.345782) (xy 71.688079 -159.405706) (xy 71.752374 -159.4714) (xy 71.810785 -159.542378)
			(xy 71.862877 -159.618115) (xy 71.908266 -159.69805) (xy 71.946616 -159.78159) (xy 71.977641 -159.868118)
			(xy 72.001114 -159.956993) (xy 72.01686 -160.047557) (xy 72.024762 -160.139139) (xy 72.025256 -160.1851)
			(xy 161.624532 -160.1851) (xy 161.628485 -160.093285) (xy 161.640317 -160.002149) (xy 161.65994 -159.912368)
			(xy 161.687208 -159.824606) (xy 161.721919 -159.739514) (xy 161.763817 -159.65772) (xy 161.812592 -159.579831)
			(xy 161.867881 -159.506422) (xy 161.929276 -159.438039) (xy 161.996323 -159.375187) (xy 162.068525 -159.31833)
			(xy 162.145346 -159.267892) (xy 162.22622 -159.224243) (xy 162.310546 -159.187709) (xy 162.397701 -159.158559)
			(xy 162.487039 -159.137009) (xy 162.577899 -159.123219) (xy 162.669608 -159.117291) (xy 162.761487 -159.119268)
			(xy 162.852856 -159.129136) (xy 162.943038 -159.146823) (xy 163.031366 -159.172196) (xy 163.117186 -159.205069)
			(xy 163.199863 -159.245197) (xy 163.278783 -159.292284) (xy 163.353364 -159.345982) (xy 163.423053 -159.405891)
			(xy 163.487333 -159.47157) (xy 163.54573 -159.542532) (xy 163.59781 -159.61825) (xy 163.643188 -159.698166)
			(xy 163.681528 -159.781687) (xy 163.712546 -159.868194) (xy 163.736014 -159.957048) (xy 163.751755 -160.04759)
			(xy 163.759656 -160.13915) (xy 163.76015 -160.1851) (xy 185.989227 -160.1851) (xy 185.993182 -160.093263)
			(xy 186.005017 -160.002106) (xy 186.024644 -159.912303) (xy 186.051918 -159.824521) (xy 186.086638 -159.739407)
			(xy 186.128546 -159.657594) (xy 186.177332 -159.579686) (xy 186.232635 -159.506261) (xy 186.294045 -159.437861)
			(xy 186.361107 -159.374994) (xy 186.433326 -159.318124) (xy 186.510166 -159.267673) (xy 186.591059 -159.224014)
			(xy 186.675405 -159.187471) (xy 186.762581 -159.158314) (xy 186.85194 -159.13676) (xy 186.942821 -159.122966)
			(xy 187.034552 -159.117036) (xy 187.126453 -159.119014) (xy 187.217844 -159.128885) (xy 187.308048 -159.146575)
			(xy 187.396397 -159.171955) (xy 187.482237 -159.204835) (xy 187.564933 -159.244973) (xy 187.643873 -159.292072)
			(xy 187.718471 -159.345782) (xy 187.788177 -159.405706) (xy 187.852472 -159.4714) (xy 187.910883 -159.542378)
			(xy 187.962975 -159.618115) (xy 188.008364 -159.69805) (xy 188.046714 -159.78159) (xy 188.077739 -159.868118)
			(xy 188.101212 -159.956993) (xy 188.116958 -160.047557) (xy 188.12486 -160.139139) (xy 188.125354 -160.1851)
			(xy 277.724376 -160.1851) (xy 277.728329 -160.093285) (xy 277.740161 -160.002149) (xy 277.759784 -159.912368)
			(xy 277.787052 -159.824606) (xy 277.821763 -159.739514) (xy 277.863661 -159.65772) (xy 277.912436 -159.579831)
			(xy 277.967725 -159.506422) (xy 278.02912 -159.438039) (xy 278.096167 -159.375187) (xy 278.168369 -159.31833)
			(xy 278.24519 -159.267892) (xy 278.326064 -159.224243) (xy 278.41039 -159.187709) (xy 278.497545 -159.158559)
			(xy 278.586883 -159.137009) (xy 278.677743 -159.123219) (xy 278.769452 -159.117291) (xy 278.861331 -159.119268)
			(xy 278.9527 -159.129136) (xy 279.042882 -159.146823) (xy 279.13121 -159.172196) (xy 279.21703 -159.205069)
			(xy 279.299707 -159.245197) (xy 279.378627 -159.292284) (xy 279.453208 -159.345982) (xy 279.522897 -159.405891)
			(xy 279.587177 -159.47157) (xy 279.645574 -159.542532) (xy 279.697654 -159.61825) (xy 279.743032 -159.698166)
			(xy 279.781372 -159.781687) (xy 279.81239 -159.868194) (xy 279.835858 -159.957048) (xy 279.851599 -160.04759)
			(xy 279.8595 -160.13915) (xy 279.859994 -160.1851) (xy 302.089071 -160.1851) (xy 302.093026 -160.093263)
			(xy 302.104861 -160.002106) (xy 302.124488 -159.912303) (xy 302.151762 -159.824521) (xy 302.186482 -159.739407)
			(xy 302.22839 -159.657594) (xy 302.277176 -159.579686) (xy 302.332479 -159.506261) (xy 302.393889 -159.437861)
			(xy 302.460951 -159.374994) (xy 302.53317 -159.318124) (xy 302.61001 -159.267673) (xy 302.690903 -159.224014)
			(xy 302.775249 -159.187471) (xy 302.862425 -159.158314) (xy 302.951784 -159.13676) (xy 303.042665 -159.122966)
			(xy 303.134396 -159.117036) (xy 303.226297 -159.119014) (xy 303.317688 -159.128885) (xy 303.407892 -159.146575)
			(xy 303.496241 -159.171955) (xy 303.582081 -159.204835) (xy 303.664777 -159.244973) (xy 303.743717 -159.292072)
			(xy 303.818315 -159.345782) (xy 303.888021 -159.405706) (xy 303.952316 -159.4714) (xy 304.010727 -159.542378)
			(xy 304.062819 -159.618115) (xy 304.108208 -159.69805) (xy 304.146558 -159.78159) (xy 304.177583 -159.868118)
			(xy 304.201056 -159.956993) (xy 304.216802 -160.047557) (xy 304.224704 -160.139139) (xy 304.225198 -160.1851)
			(xy 393.824474 -160.1851) (xy 393.828427 -160.093285) (xy 393.840259 -160.002149) (xy 393.859882 -159.912368)
			(xy 393.88715 -159.824606) (xy 393.921861 -159.739514) (xy 393.963759 -159.65772) (xy 394.012534 -159.579831)
			(xy 394.067823 -159.506422) (xy 394.129218 -159.438039) (xy 394.196265 -159.375187) (xy 394.268467 -159.31833)
			(xy 394.345288 -159.267892) (xy 394.426162 -159.224243) (xy 394.510488 -159.187709) (xy 394.597643 -159.158559)
			(xy 394.686981 -159.137009) (xy 394.777841 -159.123219) (xy 394.86955 -159.117291) (xy 394.961429 -159.119268)
			(xy 395.052798 -159.129136) (xy 395.14298 -159.146823) (xy 395.231308 -159.172196) (xy 395.317128 -159.205069)
			(xy 395.399805 -159.245197) (xy 395.478725 -159.292284) (xy 395.553306 -159.345982) (xy 395.622995 -159.405891)
			(xy 395.687275 -159.47157) (xy 395.745672 -159.542532) (xy 395.797752 -159.61825) (xy 395.84313 -159.698166)
			(xy 395.88147 -159.781687) (xy 395.912488 -159.868194) (xy 395.935956 -159.957048) (xy 395.951697 -160.04759)
			(xy 395.959598 -160.13915) (xy 395.960092 -160.1851) (xy 418.189169 -160.1851) (xy 418.193124 -160.093263)
			(xy 418.204959 -160.002106) (xy 418.224586 -159.912303) (xy 418.25186 -159.824521) (xy 418.28658 -159.739407)
			(xy 418.328488 -159.657594) (xy 418.377274 -159.579686) (xy 418.432577 -159.506261) (xy 418.493987 -159.437861)
			(xy 418.561049 -159.374994) (xy 418.633268 -159.318124) (xy 418.710108 -159.267673) (xy 418.791001 -159.224014)
			(xy 418.875347 -159.187471) (xy 418.962523 -159.158314) (xy 419.051882 -159.13676) (xy 419.142763 -159.122966)
			(xy 419.234494 -159.117036) (xy 419.326395 -159.119014) (xy 419.417786 -159.128885) (xy 419.50799 -159.146575)
			(xy 419.596339 -159.171955) (xy 419.682179 -159.204835) (xy 419.764875 -159.244973) (xy 419.843815 -159.292072)
			(xy 419.918413 -159.345782) (xy 419.988119 -159.405706) (xy 420.052414 -159.4714) (xy 420.110825 -159.542378)
			(xy 420.162917 -159.618115) (xy 420.208306 -159.69805) (xy 420.246656 -159.78159) (xy 420.277681 -159.868118)
			(xy 420.301154 -159.956993) (xy 420.3169 -160.047557) (xy 420.324802 -160.139139) (xy 420.325296 -160.1851)
			(xy 420.324802 -160.231061) (xy 420.3169 -160.322643) (xy 420.301154 -160.413207) (xy 420.277681 -160.502082)
			(xy 420.246656 -160.58861) (xy 420.208306 -160.67215) (xy 420.162917 -160.752085) (xy 420.110825 -160.827822)
			(xy 420.052414 -160.8988) (xy 419.988119 -160.964494) (xy 419.918413 -161.024418) (xy 419.843815 -161.078128)
			(xy 419.764875 -161.125227) (xy 419.682179 -161.165365) (xy 419.596339 -161.198245) (xy 419.50799 -161.223625)
			(xy 419.417786 -161.241315) (xy 419.326395 -161.251186) (xy 419.234494 -161.253164) (xy 419.142763 -161.247234)
			(xy 419.051882 -161.23344) (xy 418.962523 -161.211886) (xy 418.875347 -161.182729) (xy 418.791001 -161.146186)
			(xy 418.710108 -161.102527) (xy 418.633268 -161.052076) (xy 418.561049 -160.995206) (xy 418.493987 -160.932339)
			(xy 418.432577 -160.863939) (xy 418.377274 -160.790514) (xy 418.328488 -160.712606) (xy 418.28658 -160.630793)
			(xy 418.25186 -160.545679) (xy 418.224586 -160.457897) (xy 418.204959 -160.368094) (xy 418.193124 -160.276937)
			(xy 418.189169 -160.1851) (xy 395.960092 -160.1851) (xy 395.959598 -160.23105) (xy 395.951697 -160.32261)
			(xy 395.935956 -160.413152) (xy 395.912488 -160.502006) (xy 395.88147 -160.588513) (xy 395.84313 -160.672034)
			(xy 395.797752 -160.75195) (xy 395.745672 -160.827668) (xy 395.687275 -160.89863) (xy 395.622995 -160.964309)
			(xy 395.553306 -161.024218) (xy 395.478725 -161.077916) (xy 395.399805 -161.125003) (xy 395.317128 -161.165131)
			(xy 395.231308 -161.198004) (xy 395.14298 -161.223377) (xy 395.052798 -161.241064) (xy 394.961429 -161.250932)
			(xy 394.86955 -161.252909) (xy 394.777841 -161.246981) (xy 394.686981 -161.233191) (xy 394.597643 -161.211641)
			(xy 394.510488 -161.182491) (xy 394.426162 -161.145957) (xy 394.345288 -161.102308) (xy 394.268467 -161.05187)
			(xy 394.196265 -160.995013) (xy 394.129218 -160.932161) (xy 394.067823 -160.863778) (xy 394.012534 -160.790369)
			(xy 393.963759 -160.71248) (xy 393.921861 -160.630686) (xy 393.88715 -160.545594) (xy 393.859882 -160.457832)
			(xy 393.840259 -160.368051) (xy 393.828427 -160.276915) (xy 393.824474 -160.1851) (xy 304.225198 -160.1851)
			(xy 304.224704 -160.231061) (xy 304.216802 -160.322643) (xy 304.201056 -160.413207) (xy 304.177583 -160.502082)
			(xy 304.146558 -160.58861) (xy 304.108208 -160.67215) (xy 304.062819 -160.752085) (xy 304.010727 -160.827822)
			(xy 303.952316 -160.8988) (xy 303.888021 -160.964494) (xy 303.818315 -161.024418) (xy 303.743717 -161.078128)
			(xy 303.664777 -161.125227) (xy 303.582081 -161.165365) (xy 303.496241 -161.198245) (xy 303.407892 -161.223625)
			(xy 303.317688 -161.241315) (xy 303.226297 -161.251186) (xy 303.134396 -161.253164) (xy 303.042665 -161.247234)
			(xy 302.951784 -161.23344) (xy 302.862425 -161.211886) (xy 302.775249 -161.182729) (xy 302.690903 -161.146186)
			(xy 302.61001 -161.102527) (xy 302.53317 -161.052076) (xy 302.460951 -160.995206) (xy 302.393889 -160.932339)
			(xy 302.332479 -160.863939) (xy 302.277176 -160.790514) (xy 302.22839 -160.712606) (xy 302.186482 -160.630793)
			(xy 302.151762 -160.545679) (xy 302.124488 -160.457897) (xy 302.104861 -160.368094) (xy 302.093026 -160.276937)
			(xy 302.089071 -160.1851) (xy 279.859994 -160.1851) (xy 279.8595 -160.23105) (xy 279.851599 -160.32261)
			(xy 279.835858 -160.413152) (xy 279.81239 -160.502006) (xy 279.781372 -160.588513) (xy 279.743032 -160.672034)
			(xy 279.697654 -160.75195) (xy 279.645574 -160.827668) (xy 279.587177 -160.89863) (xy 279.522897 -160.964309)
			(xy 279.453208 -161.024218) (xy 279.378627 -161.077916) (xy 279.299707 -161.125003) (xy 279.21703 -161.165131)
			(xy 279.13121 -161.198004) (xy 279.042882 -161.223377) (xy 278.9527 -161.241064) (xy 278.861331 -161.250932)
			(xy 278.769452 -161.252909) (xy 278.677743 -161.246981) (xy 278.586883 -161.233191) (xy 278.497545 -161.211641)
			(xy 278.41039 -161.182491) (xy 278.326064 -161.145957) (xy 278.24519 -161.102308) (xy 278.168369 -161.05187)
			(xy 278.096167 -160.995013) (xy 278.02912 -160.932161) (xy 277.967725 -160.863778) (xy 277.912436 -160.790369)
			(xy 277.863661 -160.71248) (xy 277.821763 -160.630686) (xy 277.787052 -160.545594) (xy 277.759784 -160.457832)
			(xy 277.740161 -160.368051) (xy 277.728329 -160.276915) (xy 277.724376 -160.1851) (xy 188.125354 -160.1851)
			(xy 188.12486 -160.231061) (xy 188.116958 -160.322643) (xy 188.101212 -160.413207) (xy 188.077739 -160.502082)
			(xy 188.046714 -160.58861) (xy 188.008364 -160.67215) (xy 187.962975 -160.752085) (xy 187.910883 -160.827822)
			(xy 187.852472 -160.8988) (xy 187.788177 -160.964494) (xy 187.718471 -161.024418) (xy 187.643873 -161.078128)
			(xy 187.564933 -161.125227) (xy 187.482237 -161.165365) (xy 187.396397 -161.198245) (xy 187.308048 -161.223625)
			(xy 187.217844 -161.241315) (xy 187.126453 -161.251186) (xy 187.034552 -161.253164) (xy 186.942821 -161.247234)
			(xy 186.85194 -161.23344) (xy 186.762581 -161.211886) (xy 186.675405 -161.182729) (xy 186.591059 -161.146186)
			(xy 186.510166 -161.102527) (xy 186.433326 -161.052076) (xy 186.361107 -160.995206) (xy 186.294045 -160.932339)
			(xy 186.232635 -160.863939) (xy 186.177332 -160.790514) (xy 186.128546 -160.712606) (xy 186.086638 -160.630793)
			(xy 186.051918 -160.545679) (xy 186.024644 -160.457897) (xy 186.005017 -160.368094) (xy 185.993182 -160.276937)
			(xy 185.989227 -160.1851) (xy 163.76015 -160.1851) (xy 163.759656 -160.23105) (xy 163.751755 -160.32261)
			(xy 163.736014 -160.413152) (xy 163.712546 -160.502006) (xy 163.681528 -160.588513) (xy 163.643188 -160.672034)
			(xy 163.59781 -160.75195) (xy 163.54573 -160.827668) (xy 163.487333 -160.89863) (xy 163.423053 -160.964309)
			(xy 163.353364 -161.024218) (xy 163.278783 -161.077916) (xy 163.199863 -161.125003) (xy 163.117186 -161.165131)
			(xy 163.031366 -161.198004) (xy 162.943038 -161.223377) (xy 162.852856 -161.241064) (xy 162.761487 -161.250932)
			(xy 162.669608 -161.252909) (xy 162.577899 -161.246981) (xy 162.487039 -161.233191) (xy 162.397701 -161.211641)
			(xy 162.310546 -161.182491) (xy 162.22622 -161.145957) (xy 162.145346 -161.102308) (xy 162.068525 -161.05187)
			(xy 161.996323 -160.995013) (xy 161.929276 -160.932161) (xy 161.867881 -160.863778) (xy 161.812592 -160.790369)
			(xy 161.763817 -160.71248) (xy 161.721919 -160.630686) (xy 161.687208 -160.545594) (xy 161.65994 -160.457832)
			(xy 161.640317 -160.368051) (xy 161.628485 -160.276915) (xy 161.624532 -160.1851) (xy 72.025256 -160.1851)
			(xy 72.024762 -160.231061) (xy 72.01686 -160.322643) (xy 72.001114 -160.413207) (xy 71.977641 -160.502082)
			(xy 71.946616 -160.58861) (xy 71.908266 -160.67215) (xy 71.862877 -160.752085) (xy 71.810785 -160.827822)
			(xy 71.752374 -160.8988) (xy 71.688079 -160.964494) (xy 71.618373 -161.024418) (xy 71.543775 -161.078128)
			(xy 71.464835 -161.125227) (xy 71.382139 -161.165365) (xy 71.296299 -161.198245) (xy 71.20795 -161.223625)
			(xy 71.117746 -161.241315) (xy 71.026355 -161.251186) (xy 70.934454 -161.253164) (xy 70.842723 -161.247234)
			(xy 70.751842 -161.23344) (xy 70.662483 -161.211886) (xy 70.575307 -161.182729) (xy 70.490961 -161.146186)
			(xy 70.410068 -161.102527) (xy 70.333228 -161.052076) (xy 70.261009 -160.995206) (xy 70.193947 -160.932339)
			(xy 70.132537 -160.863939) (xy 70.077234 -160.790514) (xy 70.028448 -160.712606) (xy 69.98654 -160.630793)
			(xy 69.95182 -160.545679) (xy 69.924546 -160.457897) (xy 69.904919 -160.368094) (xy 69.893084 -160.276937)
			(xy 69.889129 -160.1851) (xy 47.660052 -160.1851) (xy 47.659558 -160.23105) (xy 47.651657 -160.32261)
			(xy 47.635916 -160.413152) (xy 47.612448 -160.502006) (xy 47.58143 -160.588513) (xy 47.54309 -160.672034)
			(xy 47.497712 -160.75195) (xy 47.445632 -160.827668) (xy 47.387235 -160.89863) (xy 47.322955 -160.964309)
			(xy 47.253266 -161.024218) (xy 47.178685 -161.077916) (xy 47.099765 -161.125003) (xy 47.017088 -161.165131)
			(xy 46.931268 -161.198004) (xy 46.84294 -161.223377) (xy 46.752758 -161.241064) (xy 46.661389 -161.250932)
			(xy 46.56951 -161.252909) (xy 46.477801 -161.246981) (xy 46.386941 -161.233191) (xy 46.297603 -161.211641)
			(xy 46.210448 -161.182491) (xy 46.126122 -161.145957) (xy 46.045248 -161.102308) (xy 45.968427 -161.05187)
			(xy 45.896225 -160.995013) (xy 45.829178 -160.932161) (xy 45.767783 -160.863778) (xy 45.712494 -160.790369)
			(xy 45.663719 -160.71248) (xy 45.621821 -160.630686) (xy 45.58711 -160.545594) (xy 45.559842 -160.457832)
			(xy 45.540219 -160.368051) (xy 45.528387 -160.276915) (xy 45.524434 -160.1851) (xy 5.324094 -160.1851)
			(xy 5.324094 -168.065164) (xy 135.245906 -168.065164) (xy 135.245906 -168.005236) (xy 135.253728 -167.94582)
			(xy 135.269237 -167.887933) (xy 135.29217 -167.832566) (xy 135.322132 -167.780665) (xy 135.358612 -167.733119)
			(xy 135.400986 -167.690742) (xy 135.448529 -167.654257) (xy 135.500426 -167.624289) (xy 135.555791 -167.601351)
			(xy 135.613677 -167.585836) (xy 135.673092 -167.578009) (xy 135.703056 -167.577516) (xy 136.566656 -167.577516)
			(xy 136.596628 -167.577934) (xy 136.656061 -167.585754) (xy 136.713965 -167.601264) (xy 136.769348 -167.6242)
			(xy 136.821264 -167.654169) (xy 136.868823 -167.690658) (xy 136.911213 -167.733044) (xy 136.947707 -167.7806)
			(xy 136.977681 -167.832512) (xy 137.000622 -167.887894) (xy 137.016138 -167.945796) (xy 137.023963 -168.005228)
			(xy 137.023963 -168.065172) (xy 137.016138 -168.124604) (xy 137.000622 -168.182506) (xy 136.977681 -168.237888)
			(xy 136.947707 -168.2898) (xy 136.911213 -168.337356) (xy 136.868823 -168.379742) (xy 136.821264 -168.416231)
			(xy 136.769348 -168.4462) (xy 136.713965 -168.469136) (xy 136.656061 -168.484646) (xy 136.596628 -168.492466)
			(xy 136.566656 -168.492932) (xy 135.703056 -168.492932) (xy 135.673092 -168.492391) (xy 135.613677 -168.484564)
			(xy 135.555791 -168.469049) (xy 135.500426 -168.446111) (xy 135.448529 -168.416143) (xy 135.400986 -168.379658)
			(xy 135.358612 -168.337281) (xy 135.322132 -168.289735) (xy 135.29217 -168.237834) (xy 135.269237 -168.182467)
			(xy 135.253728 -168.12458) (xy 135.245906 -168.065164) (xy 5.324094 -168.065164) (xy 5.324094 -168.700164)
			(xy 133.213906 -168.700164) (xy 133.213906 -168.640236) (xy 133.221728 -168.58082) (xy 133.237237 -168.522933)
			(xy 133.26017 -168.467566) (xy 133.290132 -168.415665) (xy 133.326612 -168.368119) (xy 133.368986 -168.325742)
			(xy 133.416529 -168.289257) (xy 133.468426 -168.259289) (xy 133.523791 -168.236351) (xy 133.581677 -168.220836)
			(xy 133.641092 -168.213009) (xy 133.671056 -168.212516) (xy 134.534656 -168.212516) (xy 134.564628 -168.212934)
			(xy 134.624061 -168.220754) (xy 134.681965 -168.236264) (xy 134.737348 -168.2592) (xy 134.789264 -168.289169)
			(xy 134.836823 -168.325658) (xy 134.879213 -168.368044) (xy 134.915707 -168.4156) (xy 134.945681 -168.467512)
			(xy 134.968622 -168.522894) (xy 134.984138 -168.580796) (xy 134.991963 -168.640228) (xy 134.991963 -168.700172)
			(xy 134.984138 -168.759604) (xy 134.968622 -168.817506) (xy 134.945681 -168.872888) (xy 134.915707 -168.9248)
			(xy 134.879213 -168.972356) (xy 134.836823 -169.014742) (xy 134.789264 -169.051231) (xy 134.737348 -169.0812)
			(xy 134.681965 -169.104136) (xy 134.624061 -169.119646) (xy 134.564628 -169.127466) (xy 134.534656 -169.127932)
			(xy 133.671056 -169.127932) (xy 133.641092 -169.127391) (xy 133.581677 -169.119564) (xy 133.523791 -169.104049)
			(xy 133.468426 -169.081111) (xy 133.416529 -169.051143) (xy 133.368986 -169.014658) (xy 133.326612 -168.972281)
			(xy 133.290132 -168.924735) (xy 133.26017 -168.872834) (xy 133.237237 -168.817467) (xy 133.221728 -168.75958)
			(xy 133.213906 -168.700164) (xy 5.324094 -168.700164) (xy 5.324094 -169.61389) (xy 245.108869 -169.61389)
			(xy 245.108869 -169.55391) (xy 245.116699 -169.494444) (xy 245.132223 -169.436508) (xy 245.155178 -169.381095)
			(xy 245.185169 -169.329152) (xy 245.221684 -169.281569) (xy 245.264097 -169.239158) (xy 245.311684 -169.202648)
			(xy 245.363629 -169.172661) (xy 245.419045 -169.149711) (xy 245.476981 -169.134191) (xy 245.536448 -169.126367)
			(xy 245.566438 -169.1259) (xy 246.430038 -169.1259) (xy 246.460018 -169.126468) (xy 246.519465 -169.134299)
			(xy 246.577381 -169.149822) (xy 246.632776 -169.172772) (xy 246.684702 -169.202755) (xy 246.73227 -169.239259)
			(xy 246.774667 -169.281659) (xy 246.811166 -169.32923) (xy 246.841145 -169.381158) (xy 246.86409 -169.436555)
			(xy 246.879608 -169.494472) (xy 246.887434 -169.55392) (xy 246.887434 -169.61388) (xy 246.879608 -169.673328)
			(xy 246.86409 -169.731245) (xy 246.841145 -169.786642) (xy 246.811166 -169.83857) (xy 246.774667 -169.886141)
			(xy 246.73227 -169.928541) (xy 246.684702 -169.965045) (xy 246.632776 -169.995028) (xy 246.577381 -170.017978)
			(xy 246.519465 -170.033501) (xy 246.460018 -170.041332) (xy 246.430038 -170.041824) (xy 245.566438 -170.041824)
			(xy 245.536448 -170.041433) (xy 245.476981 -170.033609) (xy 245.419045 -170.018089) (xy 245.363629 -169.995139)
			(xy 245.311684 -169.965152) (xy 245.264097 -169.928642) (xy 245.221684 -169.886231) (xy 245.185169 -169.838648)
			(xy 245.155178 -169.786705) (xy 245.132223 -169.731292) (xy 245.116699 -169.673356) (xy 245.108869 -169.61389)
			(xy 5.324094 -169.61389) (xy 5.324094 -174.805086) (xy 141.546072 -174.805086) (xy 141.546072 -173.941486)
			(xy 141.546562 -173.911518) (xy 141.554385 -173.852096) (xy 141.569898 -173.794203) (xy 141.592834 -173.73883)
			(xy 141.622801 -173.686924) (xy 141.659288 -173.639374) (xy 141.701668 -173.596994) (xy 141.749218 -173.560507)
			(xy 141.801124 -173.53054) (xy 141.856497 -173.507604) (xy 141.91439 -173.492091) (xy 141.973812 -173.484268)
			(xy 142.033748 -173.484268) (xy 142.09317 -173.492091) (xy 142.106698 -173.495716) (xy 257.519424 -173.495716)
			(xy 257.519424 -172.632116) (xy 257.519914 -172.602132) (xy 257.527742 -172.542676) (xy 257.543263 -172.484751)
			(xy 257.566212 -172.429347) (xy 257.596196 -172.377413) (xy 257.632702 -172.329837) (xy 257.675107 -172.287432)
			(xy 257.722683 -172.250926) (xy 257.774617 -172.220942) (xy 257.830021 -172.197993) (xy 257.887946 -172.182472)
			(xy 257.947402 -172.174644) (xy 258.00737 -172.174644) (xy 258.066826 -172.182472) (xy 258.124751 -172.197993)
			(xy 258.180155 -172.220942) (xy 258.232089 -172.250926) (xy 258.279665 -172.287432) (xy 258.32207 -172.329837)
			(xy 258.358576 -172.377413) (xy 258.38856 -172.429347) (xy 258.411509 -172.484751) (xy 258.42703 -172.542676)
			(xy 258.434858 -172.602132) (xy 258.435348 -172.632116) (xy 258.435348 -173.495716) (xy 258.434858 -173.5257)
			(xy 258.42703 -173.585156) (xy 258.411509 -173.643081) (xy 258.38856 -173.698485) (xy 258.358576 -173.750419)
			(xy 258.32207 -173.797995) (xy 258.279665 -173.8404) (xy 258.232089 -173.876906) (xy 258.180155 -173.90689)
			(xy 258.124751 -173.929839) (xy 258.066826 -173.94536) (xy 258.00737 -173.953188) (xy 257.947402 -173.953188)
			(xy 257.887946 -173.94536) (xy 257.830021 -173.929839) (xy 257.774617 -173.90689) (xy 257.722683 -173.876906)
			(xy 257.675107 -173.8404) (xy 257.632702 -173.797995) (xy 257.596196 -173.750419) (xy 257.566212 -173.698485)
			(xy 257.543263 -173.643081) (xy 257.527742 -173.585156) (xy 257.519914 -173.5257) (xy 257.519424 -173.495716)
			(xy 142.106698 -173.495716) (xy 142.151063 -173.507604) (xy 142.206436 -173.53054) (xy 142.258342 -173.560507)
			(xy 142.305892 -173.596994) (xy 142.348272 -173.639374) (xy 142.384759 -173.686924) (xy 142.414726 -173.73883)
			(xy 142.437662 -173.794203) (xy 142.453175 -173.852096) (xy 142.460998 -173.911518) (xy 142.461488 -173.941486)
			(xy 142.461488 -174.805086) (xy 142.460998 -174.835054) (xy 142.453175 -174.894476) (xy 142.437662 -174.952369)
			(xy 142.414726 -175.007742) (xy 142.384759 -175.059648) (xy 142.348272 -175.107198) (xy 142.305892 -175.149578)
			(xy 142.258342 -175.186065) (xy 142.206436 -175.216032) (xy 142.151063 -175.238968) (xy 142.09317 -175.254481)
			(xy 142.033748 -175.262304) (xy 141.973812 -175.262304) (xy 141.91439 -175.254481) (xy 141.856497 -175.238968)
			(xy 141.801124 -175.216032) (xy 141.749218 -175.186065) (xy 141.701668 -175.149578) (xy 141.659288 -175.107198)
			(xy 141.622801 -175.059648) (xy 141.592834 -175.007742) (xy 141.569898 -174.952369) (xy 141.554385 -174.894476)
			(xy 141.546562 -174.835054) (xy 141.546072 -174.805086) (xy 5.324094 -174.805086) (xy 5.324094 -176.837086)
			(xy 142.181072 -176.837086) (xy 142.181072 -175.973486) (xy 142.181562 -175.943518) (xy 142.189385 -175.884096)
			(xy 142.204898 -175.826203) (xy 142.227834 -175.77083) (xy 142.257801 -175.718924) (xy 142.294288 -175.671374)
			(xy 142.336668 -175.628994) (xy 142.384218 -175.592507) (xy 142.436124 -175.56254) (xy 142.491497 -175.539604)
			(xy 142.54939 -175.524091) (xy 142.608812 -175.516268) (xy 142.668748 -175.516268) (xy 142.72817 -175.524091)
			(xy 142.786063 -175.539604) (xy 142.841436 -175.56254) (xy 142.893342 -175.592507) (xy 142.940892 -175.628994)
			(xy 142.983272 -175.671374) (xy 143.019759 -175.718924) (xy 143.049726 -175.77083) (xy 143.072662 -175.826203)
			(xy 143.088175 -175.884096) (xy 143.095998 -175.943518) (xy 143.096488 -175.973486) (xy 143.096488 -176.837086)
			(xy 143.095998 -176.867054) (xy 143.088175 -176.926476) (xy 143.072662 -176.984369) (xy 143.049726 -177.039742)
			(xy 143.019759 -177.091648) (xy 142.983272 -177.139198) (xy 142.940892 -177.181578) (xy 142.893342 -177.218065)
			(xy 142.841436 -177.248032) (xy 142.786063 -177.270968) (xy 142.72817 -177.286481) (xy 142.668748 -177.294304)
			(xy 142.608812 -177.294304) (xy 142.54939 -177.286481) (xy 142.491497 -177.270968) (xy 142.436124 -177.248032)
			(xy 142.384218 -177.218065) (xy 142.336668 -177.181578) (xy 142.294288 -177.139198) (xy 142.257801 -177.091648)
			(xy 142.227834 -177.039742) (xy 142.204898 -176.984369) (xy 142.189385 -176.926476) (xy 142.181562 -176.867054)
			(xy 142.181072 -176.837086) (xy 5.324094 -176.837086) (xy 5.324094 -178.995324) (xy 123.198636 -178.995324)
			(xy 123.198636 -178.131724) (xy 123.199126 -178.10174) (xy 123.206954 -178.042284) (xy 123.222475 -177.984359)
			(xy 123.245424 -177.928955) (xy 123.275408 -177.877021) (xy 123.311914 -177.829445) (xy 123.354319 -177.78704)
			(xy 123.401895 -177.750534) (xy 123.453829 -177.72055) (xy 123.509233 -177.697601) (xy 123.567158 -177.68208)
			(xy 123.626614 -177.674252) (xy 123.686582 -177.674252) (xy 123.746038 -177.68208) (xy 123.803963 -177.697601)
			(xy 123.859367 -177.72055) (xy 123.911301 -177.750534) (xy 123.958877 -177.78704) (xy 124.001282 -177.829445)
			(xy 124.037788 -177.877021) (xy 124.067772 -177.928955) (xy 124.090721 -177.984359) (xy 124.106242 -178.042284)
			(xy 124.11407 -178.10174) (xy 124.11456 -178.131724) (xy 124.11456 -178.869086) (xy 141.546072 -178.869086)
			(xy 141.546072 -178.005486) (xy 141.546562 -177.975518) (xy 141.554385 -177.916096) (xy 141.569898 -177.858203)
			(xy 141.592834 -177.80283) (xy 141.622801 -177.750924) (xy 141.659288 -177.703374) (xy 141.701668 -177.660994)
			(xy 141.749218 -177.624507) (xy 141.801124 -177.59454) (xy 141.856497 -177.571604) (xy 141.91439 -177.556091)
			(xy 141.973812 -177.548268) (xy 142.033748 -177.548268) (xy 142.09317 -177.556091) (xy 142.151063 -177.571604)
			(xy 142.206436 -177.59454) (xy 142.258342 -177.624507) (xy 142.305892 -177.660994) (xy 142.348272 -177.703374)
			(xy 142.384759 -177.750924) (xy 142.414726 -177.80283) (xy 142.437662 -177.858203) (xy 142.453175 -177.916096)
			(xy 142.460998 -177.975518) (xy 142.461488 -178.005486) (xy 142.461488 -178.869086) (xy 142.460998 -178.899054)
			(xy 142.453175 -178.958476) (xy 142.437662 -179.016369) (xy 142.414726 -179.071742) (xy 142.384759 -179.123648)
			(xy 142.348272 -179.171198) (xy 142.305892 -179.213578) (xy 142.258342 -179.250065) (xy 142.206436 -179.280032)
			(xy 142.151063 -179.302968) (xy 142.09317 -179.318481) (xy 142.033748 -179.326304) (xy 141.973812 -179.326304)
			(xy 141.91439 -179.318481) (xy 141.856497 -179.302968) (xy 141.801124 -179.280032) (xy 141.749218 -179.250065)
			(xy 141.701668 -179.213578) (xy 141.659288 -179.171198) (xy 141.622801 -179.123648) (xy 141.592834 -179.071742)
			(xy 141.569898 -179.016369) (xy 141.554385 -178.958476) (xy 141.546562 -178.899054) (xy 141.546072 -178.869086)
			(xy 124.11456 -178.869086) (xy 124.11456 -178.995324) (xy 124.11407 -179.025308) (xy 124.106242 -179.084764)
			(xy 124.090721 -179.142689) (xy 124.067772 -179.198093) (xy 124.037788 -179.250027) (xy 124.001282 -179.297603)
			(xy 123.958877 -179.340008) (xy 123.911301 -179.376514) (xy 123.859367 -179.406498) (xy 123.803963 -179.429447)
			(xy 123.746038 -179.444968) (xy 123.686582 -179.452796) (xy 123.626614 -179.452796) (xy 123.567158 -179.444968)
			(xy 123.509233 -179.429447) (xy 123.453829 -179.406498) (xy 123.401895 -179.376514) (xy 123.354319 -179.340008)
			(xy 123.311914 -179.297603) (xy 123.275408 -179.250027) (xy 123.245424 -179.198093) (xy 123.222475 -179.142689)
			(xy 123.206954 -179.084764) (xy 123.199126 -179.025308) (xy 123.198636 -178.995324) (xy 5.324094 -178.995324)
			(xy 5.324094 -180.901086) (xy 142.181072 -180.901086) (xy 142.181072 -180.037486) (xy 142.181562 -180.007518)
			(xy 142.189385 -179.948096) (xy 142.204898 -179.890203) (xy 142.227834 -179.83483) (xy 142.257801 -179.782924)
			(xy 142.294288 -179.735374) (xy 142.336668 -179.692994) (xy 142.384218 -179.656507) (xy 142.436124 -179.62654)
			(xy 142.491497 -179.603604) (xy 142.54939 -179.588091) (xy 142.608812 -179.580268) (xy 142.668748 -179.580268)
			(xy 142.72817 -179.588091) (xy 142.786063 -179.603604) (xy 142.841436 -179.62654) (xy 142.893342 -179.656507)
			(xy 142.940892 -179.692994) (xy 142.983272 -179.735374) (xy 143.019759 -179.782924) (xy 143.049726 -179.83483)
			(xy 143.072662 -179.890203) (xy 143.088175 -179.948096) (xy 143.095998 -180.007518) (xy 143.096488 -180.037486)
			(xy 143.096488 -180.901086) (xy 143.095998 -180.931054) (xy 143.088175 -180.990476) (xy 143.072662 -181.048369)
			(xy 143.049726 -181.103742) (xy 143.019759 -181.155648) (xy 142.983272 -181.203198) (xy 142.940892 -181.245578)
			(xy 142.893342 -181.282065) (xy 142.841436 -181.312032) (xy 142.786063 -181.334968) (xy 142.72817 -181.350481)
			(xy 142.668748 -181.358304) (xy 142.608812 -181.358304) (xy 142.54939 -181.350481) (xy 142.491497 -181.334968)
			(xy 142.436124 -181.312032) (xy 142.384218 -181.282065) (xy 142.336668 -181.245578) (xy 142.294288 -181.203198)
			(xy 142.257801 -181.155648) (xy 142.227834 -181.103742) (xy 142.204898 -181.048369) (xy 142.189385 -180.990476)
			(xy 142.181562 -180.931054) (xy 142.181072 -180.901086) (xy 5.324094 -180.901086) (xy 5.324094 -182.933086)
			(xy 141.546072 -182.933086) (xy 141.546072 -182.069486) (xy 141.546562 -182.039518) (xy 141.554385 -181.980096)
			(xy 141.569898 -181.922203) (xy 141.592834 -181.86683) (xy 141.622801 -181.814924) (xy 141.659288 -181.767374)
			(xy 141.701668 -181.724994) (xy 141.749218 -181.688507) (xy 141.801124 -181.65854) (xy 141.856497 -181.635604)
			(xy 141.91439 -181.620091) (xy 141.973812 -181.612268) (xy 142.033748 -181.612268) (xy 142.09317 -181.620091)
			(xy 142.151063 -181.635604) (xy 142.206436 -181.65854) (xy 142.258342 -181.688507) (xy 142.305892 -181.724994)
			(xy 142.348272 -181.767374) (xy 142.384759 -181.814924) (xy 142.414726 -181.86683) (xy 142.437662 -181.922203)
			(xy 142.453175 -181.980096) (xy 142.460998 -182.039518) (xy 142.461488 -182.069486) (xy 142.461488 -182.933086)
			(xy 142.460998 -182.963054) (xy 142.453175 -183.022476) (xy 142.437662 -183.080369) (xy 142.414726 -183.135742)
			(xy 142.384759 -183.187648) (xy 142.348272 -183.235198) (xy 142.305892 -183.277578) (xy 142.258342 -183.314065)
			(xy 142.206436 -183.344032) (xy 142.151063 -183.366968) (xy 142.09317 -183.382481) (xy 142.033748 -183.390304)
			(xy 141.973812 -183.390304) (xy 141.91439 -183.382481) (xy 141.856497 -183.366968) (xy 141.801124 -183.344032)
			(xy 141.749218 -183.314065) (xy 141.701668 -183.277578) (xy 141.659288 -183.235198) (xy 141.622801 -183.187648)
			(xy 141.592834 -183.135742) (xy 141.569898 -183.080369) (xy 141.554385 -183.022476) (xy 141.546562 -182.963054)
			(xy 141.546072 -182.933086) (xy 5.324094 -182.933086) (xy 5.324094 -187.124582) (xy 135.58115 -187.124582)
			(xy 135.58115 -187.064618) (xy 135.588977 -187.005166) (xy 135.604497 -186.947244) (xy 135.627444 -186.891844)
			(xy 135.657426 -186.839912) (xy 135.69393 -186.792339) (xy 135.736331 -186.749937) (xy 135.783904 -186.713432)
			(xy 135.835835 -186.683448) (xy 135.891235 -186.6605) (xy 135.949156 -186.644979) (xy 136.008608 -186.637151)
			(xy 136.03859 -186.63666) (xy 136.90219 -186.63666) (xy 136.932178 -186.637085) (xy 136.99164 -186.644912)
			(xy 137.049571 -186.660433) (xy 137.104981 -186.683384) (xy 137.156922 -186.713371) (xy 137.204504 -186.749881)
			(xy 137.246913 -186.792289) (xy 137.283424 -186.83987) (xy 137.313412 -186.89181) (xy 137.336363 -186.947219)
			(xy 137.351886 -187.005151) (xy 137.359715 -187.064612) (xy 137.359715 -187.124588) (xy 137.351886 -187.184049)
			(xy 137.336363 -187.241981) (xy 137.313412 -187.29739) (xy 137.283424 -187.34933) (xy 137.246913 -187.396911)
			(xy 137.204504 -187.439319) (xy 137.156922 -187.475829) (xy 137.104981 -187.505816) (xy 137.049571 -187.528767)
			(xy 136.99164 -187.544288) (xy 136.932178 -187.552115) (xy 136.90219 -187.552584) (xy 136.03859 -187.552584)
			(xy 136.008608 -187.552049) (xy 135.949156 -187.544221) (xy 135.891235 -187.5287) (xy 135.835835 -187.505752)
			(xy 135.783904 -187.475768) (xy 135.736331 -187.439263) (xy 135.69393 -187.396861) (xy 135.657426 -187.349288)
			(xy 135.627444 -187.297356) (xy 135.604497 -187.241956) (xy 135.588977 -187.184034) (xy 135.58115 -187.124582)
			(xy 5.324094 -187.124582) (xy 5.324094 -188.252885) (xy 128.656818 -188.252885) (xy 128.656818 -188.192915)
			(xy 128.664646 -188.133459) (xy 128.680167 -188.075533) (xy 128.703116 -188.020128) (xy 128.733101 -187.968193)
			(xy 128.769608 -187.920615) (xy 128.812012 -187.87821) (xy 128.859589 -187.841703) (xy 128.911524 -187.811718)
			(xy 128.966929 -187.788768) (xy 129.024855 -187.773246) (xy 129.084311 -187.765418) (xy 129.114296 -187.764928)
			(xy 129.977896 -187.764928) (xy 130.007881 -187.765417) (xy 130.067339 -187.773244) (xy 130.125266 -187.788765)
			(xy 130.180671 -187.811714) (xy 130.232607 -187.841699) (xy 130.280185 -187.878207) (xy 130.322591 -187.920612)
			(xy 130.359098 -187.96819) (xy 130.389084 -188.020125) (xy 130.412034 -188.075531) (xy 130.427555 -188.133458)
			(xy 130.435383 -188.192915) (xy 130.435383 -188.252885) (xy 130.434185 -188.261981) (xy 131.046262 -188.261981)
			(xy 131.046262 -188.202019) (xy 131.054088 -188.14257) (xy 131.069607 -188.084651) (xy 131.092553 -188.029253)
			(xy 131.122533 -187.977324) (xy 131.159034 -187.929752) (xy 131.201432 -187.887351) (xy 131.249002 -187.850847)
			(xy 131.30093 -187.820864) (xy 131.356326 -187.797915) (xy 131.414244 -187.782393) (xy 131.473693 -187.774564)
			(xy 131.503674 -187.774072) (xy 132.367274 -187.774072) (xy 132.397263 -187.774472) (xy 132.456728 -187.782297)
			(xy 132.514663 -187.797818) (xy 132.570077 -187.820768) (xy 132.62202 -187.850755) (xy 132.669605 -187.887266)
			(xy 132.712017 -187.929675) (xy 132.74853 -187.977258) (xy 132.77852 -188.0292) (xy 132.801474 -188.084612)
			(xy 132.816998 -188.142546) (xy 132.824827 -188.202011) (xy 132.824827 -188.261989) (xy 132.816998 -188.321454)
			(xy 132.801474 -188.379388) (xy 132.79518 -188.394582) (xy 133.54915 -188.394582) (xy 133.54915 -188.334618)
			(xy 133.556977 -188.275166) (xy 133.572497 -188.217244) (xy 133.595444 -188.161844) (xy 133.625426 -188.109912)
			(xy 133.66193 -188.062339) (xy 133.704331 -188.019937) (xy 133.751904 -187.983432) (xy 133.803835 -187.953448)
			(xy 133.859235 -187.9305) (xy 133.917156 -187.914979) (xy 133.976608 -187.907151) (xy 134.00659 -187.90666)
			(xy 134.87019 -187.90666) (xy 134.900178 -187.907085) (xy 134.95964 -187.914912) (xy 135.017571 -187.930433)
			(xy 135.072981 -187.953384) (xy 135.124922 -187.983371) (xy 135.172504 -188.019881) (xy 135.214913 -188.062289)
			(xy 135.251424 -188.10987) (xy 135.281412 -188.16181) (xy 135.304363 -188.217219) (xy 135.319886 -188.275151)
			(xy 135.327715 -188.334612) (xy 135.327715 -188.394588) (xy 135.319886 -188.454049) (xy 135.304363 -188.511981)
			(xy 135.281412 -188.56739) (xy 135.251424 -188.61933) (xy 135.214913 -188.666911) (xy 135.172504 -188.709319)
			(xy 135.124922 -188.745829) (xy 135.072981 -188.775816) (xy 135.017571 -188.798767) (xy 134.95964 -188.814288)
			(xy 134.900178 -188.822115) (xy 134.87019 -188.822584) (xy 134.00659 -188.822584) (xy 133.976608 -188.822049)
			(xy 133.917156 -188.814221) (xy 133.859235 -188.7987) (xy 133.803835 -188.775752) (xy 133.751904 -188.745768)
			(xy 133.704331 -188.709263) (xy 133.66193 -188.666861) (xy 133.625426 -188.619288) (xy 133.595444 -188.567356)
			(xy 133.572497 -188.511956) (xy 133.556977 -188.454034) (xy 133.54915 -188.394582) (xy 132.79518 -188.394582)
			(xy 132.77852 -188.4348) (xy 132.74853 -188.486742) (xy 132.712017 -188.534325) (xy 132.669605 -188.576734)
			(xy 132.62202 -188.613245) (xy 132.570077 -188.643232) (xy 132.514663 -188.666182) (xy 132.456728 -188.681703)
			(xy 132.397263 -188.689528) (xy 132.367274 -188.689996) (xy 131.503674 -188.689996) (xy 131.473693 -188.689436)
			(xy 131.414244 -188.681607) (xy 131.356326 -188.666085) (xy 131.30093 -188.643136) (xy 131.249002 -188.613153)
			(xy 131.201432 -188.576649) (xy 131.159034 -188.534248) (xy 131.122533 -188.486676) (xy 131.092553 -188.434747)
			(xy 131.069607 -188.379349) (xy 131.054088 -188.32143) (xy 131.046262 -188.261981) (xy 130.434185 -188.261981)
			(xy 130.427555 -188.312342) (xy 130.412034 -188.370269) (xy 130.389084 -188.425675) (xy 130.359098 -188.47761)
			(xy 130.322591 -188.525188) (xy 130.280185 -188.567593) (xy 130.232607 -188.604101) (xy 130.180671 -188.634086)
			(xy 130.125266 -188.657035) (xy 130.067339 -188.672556) (xy 130.007881 -188.680383) (xy 129.977896 -188.680852)
			(xy 129.114296 -188.680852) (xy 129.084311 -188.680382) (xy 129.024855 -188.672554) (xy 128.966929 -188.657032)
			(xy 128.911524 -188.634082) (xy 128.859589 -188.604097) (xy 128.812012 -188.56759) (xy 128.769608 -188.525185)
			(xy 128.733101 -188.477607) (xy 128.703116 -188.425672) (xy 128.680167 -188.370267) (xy 128.664646 -188.312341)
			(xy 128.656818 -188.252885) (xy 5.324094 -188.252885) (xy 5.324094 -194.360038) (xy 10.541008 -194.360038)
			(xy 10.545012 -194.15485) (xy 10.557019 -193.949974) (xy 10.57701 -193.745723) (xy 10.604955 -193.542408)
			(xy 10.640811 -193.340337) (xy 10.684525 -193.139819) (xy 10.736028 -192.94116) (xy 10.795243 -192.744661)
			(xy 10.862079 -192.550622) (xy 10.936435 -192.359339) (xy 11.018198 -192.171102) (xy 11.107243 -191.986199)
			(xy 11.203434 -191.804911) (xy 11.306625 -191.627514) (xy 11.416659 -191.454277) (xy 11.533368 -191.285466)
			(xy 11.656574 -191.121337) (xy 11.786091 -190.96214) (xy 11.92172 -190.808118) (xy 12.063255 -190.659504)
			(xy 12.21048 -190.516526) (xy 12.363172 -190.379401) (xy 12.521098 -190.248337) (xy 12.684017 -190.123535)
			(xy 12.851682 -190.005185) (xy 13.023836 -189.893466) (xy 13.200218 -189.788549) (xy 13.380559 -189.690594)
			(xy 13.564585 -189.59975) (xy 13.752015 -189.516154) (xy 13.942564 -189.439935) (xy 14.135941 -189.371209)
			(xy 14.331853 -189.31008) (xy 14.53 -189.256641) (xy 14.730082 -189.210974) (xy 14.931793 -189.173147)
			(xy 15.134826 -189.14322) (xy 15.338873 -189.121237) (xy 15.543622 -189.107232) (xy 15.748761 -189.101226)
			(xy 15.953978 -189.103228) (xy 16.158961 -189.113236) (xy 16.363398 -189.131233) (xy 16.566976 -189.157193)
			(xy 16.769387 -189.191076) (xy 16.970321 -189.232831) (xy 17.169474 -189.282394) (xy 17.366541 -189.339689)
			(xy 17.561223 -189.404629) (xy 17.753223 -189.477115) (xy 17.942248 -189.557038) (xy 18.128011 -189.644274)
			(xy 18.310229 -189.738692) (xy 18.488625 -189.840147) (xy 18.662926 -189.948486) (xy 18.832868 -190.063542)
			(xy 18.998191 -190.185142) (xy 19.158644 -190.313099) (xy 19.313983 -190.447218) (xy 19.46397 -190.587297)
			(xy 19.608378 -190.733121) (xy 19.746986 -190.884467) (xy 19.879584 -191.041107) (xy 20.00597 -191.202801)
			(xy 20.12595 -191.369303) (xy 20.239343 -191.540359) (xy 20.345976 -191.715709) (xy 20.445686 -191.895086)
			(xy 20.538322 -192.078216) (xy 20.623742 -192.264822) (xy 20.701816 -192.454618) (xy 20.772426 -192.647316)
			(xy 20.835463 -192.842622) (xy 20.890833 -193.040238) (xy 20.93845 -193.239865) (xy 20.978242 -193.441197)
			(xy 21.010149 -193.643929) (xy 21.034122 -193.847751) (xy 21.050124 -194.052354) (xy 21.058131 -194.257424)
			(xy 21.058632 -194.360038) (xy 112.440982 -194.360038) (xy 112.444986 -194.15485) (xy 112.456993 -193.949974)
			(xy 112.476984 -193.745723) (xy 112.504929 -193.542408) (xy 112.540785 -193.340337) (xy 112.584499 -193.139819)
			(xy 112.636002 -192.94116) (xy 112.695217 -192.744661) (xy 112.762053 -192.550622) (xy 112.836409 -192.359339)
			(xy 112.918172 -192.171102) (xy 113.007217 -191.986199) (xy 113.103408 -191.804911) (xy 113.206599 -191.627514)
			(xy 113.316633 -191.454277) (xy 113.433342 -191.285466) (xy 113.556548 -191.121337) (xy 113.686065 -190.96214)
			(xy 113.821694 -190.808118) (xy 113.963229 -190.659504) (xy 114.110454 -190.516526) (xy 114.263146 -190.379401)
			(xy 114.421072 -190.248337) (xy 114.583991 -190.123535) (xy 114.751656 -190.005185) (xy 114.92381 -189.893466)
			(xy 115.100192 -189.788549) (xy 115.280533 -189.690594) (xy 115.464559 -189.59975) (xy 115.651989 -189.516154)
			(xy 115.842538 -189.439935) (xy 116.035915 -189.371209) (xy 116.231827 -189.31008) (xy 116.429974 -189.256641)
			(xy 116.630056 -189.210974) (xy 116.831767 -189.173147) (xy 117.0348 -189.14322) (xy 117.238847 -189.121237)
			(xy 117.443596 -189.107232) (xy 117.648735 -189.101226) (xy 117.853952 -189.103228) (xy 118.058935 -189.113236)
			(xy 118.263372 -189.131233) (xy 118.46695 -189.157193) (xy 118.669361 -189.191076) (xy 118.870295 -189.232831)
			(xy 119.069448 -189.282394) (xy 119.266515 -189.339689) (xy 119.461197 -189.404629) (xy 119.653197 -189.477115)
			(xy 119.842222 -189.557038) (xy 120.027985 -189.644274) (xy 120.210203 -189.738692) (xy 120.388599 -189.840147)
			(xy 120.5629 -189.948486) (xy 120.732842 -190.063542) (xy 120.898165 -190.185142) (xy 121.058618 -190.313099)
			(xy 121.213957 -190.447218) (xy 121.363944 -190.587297) (xy 121.508352 -190.733121) (xy 121.64696 -190.884467)
			(xy 121.779558 -191.041107) (xy 121.905944 -191.202801) (xy 122.025924 -191.369303) (xy 122.139317 -191.540359)
			(xy 122.24595 -191.715709) (xy 122.34566 -191.895086) (xy 122.438296 -192.078216) (xy 122.523716 -192.264822)
			(xy 122.60179 -192.454618) (xy 122.6724 -192.647316) (xy 122.735437 -192.842622) (xy 122.790807 -193.040238)
			(xy 122.838424 -193.239865) (xy 122.878216 -193.441197) (xy 122.910123 -193.643929) (xy 122.934096 -193.847751)
			(xy 122.950098 -194.052354) (xy 122.958105 -194.257424) (xy 122.958605 -194.359784) (xy 228.54108 -194.359784)
			(xy 228.545084 -194.154596) (xy 228.557091 -193.94972) (xy 228.577082 -193.745469) (xy 228.605027 -193.542154)
			(xy 228.640883 -193.340083) (xy 228.684597 -193.139565) (xy 228.7361 -192.940906) (xy 228.795315 -192.744407)
			(xy 228.862151 -192.550368) (xy 228.936507 -192.359085) (xy 229.01827 -192.170848) (xy 229.107315 -191.985945)
			(xy 229.203506 -191.804657) (xy 229.306697 -191.62726) (xy 229.416731 -191.454023) (xy 229.53344 -191.285212)
			(xy 229.656646 -191.121083) (xy 229.786163 -190.961886) (xy 229.921792 -190.807864) (xy 230.063327 -190.65925)
			(xy 230.210552 -190.516272) (xy 230.363244 -190.379147) (xy 230.52117 -190.248083) (xy 230.684089 -190.123281)
			(xy 230.851754 -190.004931) (xy 231.023908 -189.893212) (xy 231.20029 -189.788295) (xy 231.380631 -189.69034)
			(xy 231.564657 -189.599496) (xy 231.752087 -189.5159) (xy 231.942636 -189.439681) (xy 232.136013 -189.370955)
			(xy 232.331925 -189.309826) (xy 232.530072 -189.256387) (xy 232.730154 -189.21072) (xy 232.931865 -189.172893)
			(xy 233.134898 -189.142966) (xy 233.338945 -189.120983) (xy 233.543694 -189.106978) (xy 233.748833 -189.100972)
			(xy 233.95405 -189.102974) (xy 234.159033 -189.112982) (xy 234.36347 -189.130979) (xy 234.567048 -189.156939)
			(xy 234.769459 -189.190822) (xy 234.970393 -189.232577) (xy 235.169546 -189.28214) (xy 235.366613 -189.339435)
			(xy 235.561295 -189.404375) (xy 235.753295 -189.476861) (xy 235.94232 -189.556784) (xy 236.128083 -189.64402)
			(xy 236.310301 -189.738438) (xy 236.488697 -189.839893) (xy 236.662998 -189.948232) (xy 236.83294 -190.063288)
			(xy 236.998263 -190.184888) (xy 237.158716 -190.312845) (xy 237.314055 -190.446964) (xy 237.464042 -190.587043)
			(xy 237.60845 -190.732867) (xy 237.747058 -190.884213) (xy 237.879656 -191.040853) (xy 238.006042 -191.202547)
			(xy 238.126022 -191.369049) (xy 238.239415 -191.540105) (xy 238.346048 -191.715455) (xy 238.445758 -191.894832)
			(xy 238.538394 -192.077962) (xy 238.623814 -192.264568) (xy 238.701888 -192.454364) (xy 238.772498 -192.647062)
			(xy 238.835535 -192.842368) (xy 238.890905 -193.039984) (xy 238.938522 -193.239611) (xy 238.978314 -193.440943)
			(xy 239.010221 -193.643675) (xy 239.034194 -193.847497) (xy 239.050196 -194.0521) (xy 239.058203 -194.25717)
			(xy 239.058704 -194.359784) (xy 239.058703 -194.360038) (xy 344.640924 -194.360038) (xy 344.644928 -194.15485)
			(xy 344.656935 -193.949974) (xy 344.676926 -193.745723) (xy 344.704871 -193.542408) (xy 344.740727 -193.340337)
			(xy 344.784441 -193.139819) (xy 344.835944 -192.94116) (xy 344.895159 -192.744661) (xy 344.961995 -192.550622)
			(xy 345.036351 -192.359339) (xy 345.118114 -192.171102) (xy 345.207159 -191.986199) (xy 345.30335 -191.804911)
			(xy 345.406541 -191.627514) (xy 345.516575 -191.454277) (xy 345.633284 -191.285466) (xy 345.75649 -191.121337)
			(xy 345.886007 -190.96214) (xy 346.021636 -190.808118) (xy 346.163171 -190.659504) (xy 346.310396 -190.516526)
			(xy 346.463088 -190.379401) (xy 346.621014 -190.248337) (xy 346.783933 -190.123535) (xy 346.951598 -190.005185)
			(xy 347.123752 -189.893466) (xy 347.300134 -189.788549) (xy 347.480475 -189.690594) (xy 347.664501 -189.59975)
			(xy 347.851931 -189.516154) (xy 348.04248 -189.439935) (xy 348.235857 -189.371209) (xy 348.431769 -189.31008)
			(xy 348.629916 -189.256641) (xy 348.829998 -189.210974) (xy 349.031709 -189.173147) (xy 349.234742 -189.14322)
			(xy 349.438789 -189.121237) (xy 349.643538 -189.107232) (xy 349.848677 -189.101226) (xy 350.053894 -189.103228)
			(xy 350.258877 -189.113236) (xy 350.463314 -189.131233) (xy 350.666892 -189.157193) (xy 350.869303 -189.191076)
			(xy 351.070237 -189.232831) (xy 351.26939 -189.282394) (xy 351.466457 -189.339689) (xy 351.661139 -189.404629)
			(xy 351.853139 -189.477115) (xy 352.042164 -189.557038) (xy 352.227927 -189.644274) (xy 352.410145 -189.738692)
			(xy 352.588541 -189.840147) (xy 352.762842 -189.948486) (xy 352.932784 -190.063542) (xy 353.098107 -190.185142)
			(xy 353.25856 -190.313099) (xy 353.413899 -190.447218) (xy 353.563886 -190.587297) (xy 353.708294 -190.733121)
			(xy 353.846902 -190.884467) (xy 353.9795 -191.041107) (xy 354.105886 -191.202801) (xy 354.225866 -191.369303)
			(xy 354.339259 -191.540359) (xy 354.445892 -191.715709) (xy 354.545602 -191.895086) (xy 354.638238 -192.078216)
			(xy 354.723658 -192.264822) (xy 354.801732 -192.454618) (xy 354.872342 -192.647316) (xy 354.935379 -192.842622)
			(xy 354.990749 -193.040238) (xy 355.038366 -193.239865) (xy 355.078158 -193.441197) (xy 355.110065 -193.643929)
			(xy 355.134038 -193.847751) (xy 355.15004 -194.052354) (xy 355.158047 -194.257424) (xy 355.158548 -194.360038)
			(xy 446.540898 -194.360038) (xy 446.544902 -194.15485) (xy 446.556909 -193.949974) (xy 446.5769 -193.745723)
			(xy 446.604845 -193.542408) (xy 446.640701 -193.340337) (xy 446.684415 -193.139819) (xy 446.735918 -192.94116)
			(xy 446.795133 -192.744661) (xy 446.861969 -192.550622) (xy 446.936325 -192.359339) (xy 447.018088 -192.171102)
			(xy 447.107133 -191.986199) (xy 447.203324 -191.804911) (xy 447.306515 -191.627514) (xy 447.416549 -191.454277)
			(xy 447.533258 -191.285466) (xy 447.656464 -191.121337) (xy 447.785981 -190.96214) (xy 447.92161 -190.808118)
			(xy 448.063145 -190.659504) (xy 448.21037 -190.516526) (xy 448.363062 -190.379401) (xy 448.520988 -190.248337)
			(xy 448.683907 -190.123535) (xy 448.851572 -190.005185) (xy 449.023726 -189.893466) (xy 449.200108 -189.788549)
			(xy 449.380449 -189.690594) (xy 449.564475 -189.59975) (xy 449.751905 -189.516154) (xy 449.942454 -189.439935)
			(xy 450.135831 -189.371209) (xy 450.331743 -189.31008) (xy 450.52989 -189.256641) (xy 450.729972 -189.210974)
			(xy 450.931683 -189.173147) (xy 451.134716 -189.14322) (xy 451.338763 -189.121237) (xy 451.543512 -189.107232)
			(xy 451.748651 -189.101226) (xy 451.953868 -189.103228) (xy 452.158851 -189.113236) (xy 452.363288 -189.131233)
			(xy 452.566866 -189.157193) (xy 452.769277 -189.191076) (xy 452.970211 -189.232831) (xy 453.169364 -189.282394)
			(xy 453.366431 -189.339689) (xy 453.561113 -189.404629) (xy 453.753113 -189.477115) (xy 453.942138 -189.557038)
			(xy 454.127901 -189.644274) (xy 454.310119 -189.738692) (xy 454.488515 -189.840147) (xy 454.662816 -189.948486)
			(xy 454.832758 -190.063542) (xy 454.998081 -190.185142) (xy 455.158534 -190.313099) (xy 455.313873 -190.447218)
			(xy 455.46386 -190.587297) (xy 455.608268 -190.733121) (xy 455.746876 -190.884467) (xy 455.879474 -191.041107)
			(xy 456.00586 -191.202801) (xy 456.12584 -191.369303) (xy 456.239233 -191.540359) (xy 456.345866 -191.715709)
			(xy 456.445576 -191.895086) (xy 456.538212 -192.078216) (xy 456.623632 -192.264822) (xy 456.701706 -192.454618)
			(xy 456.772316 -192.647316) (xy 456.835353 -192.842622) (xy 456.890723 -193.040238) (xy 456.93834 -193.239865)
			(xy 456.978132 -193.441197) (xy 457.010039 -193.643929) (xy 457.034012 -193.847751) (xy 457.050014 -194.052354)
			(xy 457.058021 -194.257424) (xy 457.058522 -194.360038) (xy 457.058021 -194.462652) (xy 457.050014 -194.667722)
			(xy 457.034012 -194.872325) (xy 457.010039 -195.076147) (xy 456.978132 -195.278879) (xy 456.93834 -195.480211)
			(xy 456.890723 -195.679838) (xy 456.835353 -195.877454) (xy 456.772316 -196.07276) (xy 456.701706 -196.265458)
			(xy 456.623632 -196.455254) (xy 456.538212 -196.64186) (xy 456.445576 -196.82499) (xy 456.345866 -197.004367)
			(xy 456.239233 -197.179717) (xy 456.12584 -197.350773) (xy 456.00586 -197.517275) (xy 455.879474 -197.678969)
			(xy 455.746876 -197.835609) (xy 455.608268 -197.986955) (xy 455.46386 -198.132779) (xy 455.313873 -198.272858)
			(xy 455.158534 -198.406977) (xy 454.998081 -198.534934) (xy 454.832758 -198.656534) (xy 454.662816 -198.77159)
			(xy 454.488515 -198.879929) (xy 454.310119 -198.981384) (xy 454.127901 -199.075802) (xy 453.942138 -199.163038)
			(xy 453.753113 -199.242961) (xy 453.561113 -199.315447) (xy 453.366431 -199.380387) (xy 453.169364 -199.437682)
			(xy 452.970211 -199.487245) (xy 452.769277 -199.529) (xy 452.566866 -199.562883) (xy 452.363288 -199.588843)
			(xy 452.158851 -199.60684) (xy 451.953868 -199.616848) (xy 451.748651 -199.61885) (xy 451.543512 -199.612844)
			(xy 451.338763 -199.598839) (xy 451.134716 -199.576856) (xy 450.931683 -199.546929) (xy 450.729972 -199.509102)
			(xy 450.52989 -199.463435) (xy 450.331743 -199.409996) (xy 450.135831 -199.348867) (xy 449.942454 -199.280141)
			(xy 449.751905 -199.203922) (xy 449.564475 -199.120326) (xy 449.380449 -199.029482) (xy 449.200108 -198.931527)
			(xy 449.023726 -198.82661) (xy 448.851572 -198.714891) (xy 448.683907 -198.596541) (xy 448.520988 -198.471739)
			(xy 448.363062 -198.340675) (xy 448.21037 -198.20355) (xy 448.063145 -198.060572) (xy 447.92161 -197.911958)
			(xy 447.785981 -197.757936) (xy 447.656464 -197.598739) (xy 447.533258 -197.43461) (xy 447.416549 -197.265799)
			(xy 447.306515 -197.092562) (xy 447.203324 -196.915165) (xy 447.107133 -196.733877) (xy 447.018088 -196.548974)
			(xy 446.936325 -196.360737) (xy 446.861969 -196.169454) (xy 446.795133 -195.975415) (xy 446.735918 -195.778916)
			(xy 446.684415 -195.580257) (xy 446.640701 -195.379739) (xy 446.604845 -195.177668) (xy 446.5769 -194.974353)
			(xy 446.556909 -194.770102) (xy 446.544902 -194.565226) (xy 446.540898 -194.360038) (xy 355.158548 -194.360038)
			(xy 355.158047 -194.462652) (xy 355.15004 -194.667722) (xy 355.134038 -194.872325) (xy 355.110065 -195.076147)
			(xy 355.078158 -195.278879) (xy 355.038366 -195.480211) (xy 354.990749 -195.679838) (xy 354.935379 -195.877454)
			(xy 354.872342 -196.07276) (xy 354.801732 -196.265458) (xy 354.723658 -196.455254) (xy 354.638238 -196.64186)
			(xy 354.545602 -196.82499) (xy 354.445892 -197.004367) (xy 354.339259 -197.179717) (xy 354.225866 -197.350773)
			(xy 354.105886 -197.517275) (xy 353.9795 -197.678969) (xy 353.846902 -197.835609) (xy 353.708294 -197.986955)
			(xy 353.563886 -198.132779) (xy 353.413899 -198.272858) (xy 353.25856 -198.406977) (xy 353.098107 -198.534934)
			(xy 352.932784 -198.656534) (xy 352.762842 -198.77159) (xy 352.588541 -198.879929) (xy 352.410145 -198.981384)
			(xy 352.227927 -199.075802) (xy 352.042164 -199.163038) (xy 351.853139 -199.242961) (xy 351.661139 -199.315447)
			(xy 351.466457 -199.380387) (xy 351.26939 -199.437682) (xy 351.070237 -199.487245) (xy 350.869303 -199.529)
			(xy 350.666892 -199.562883) (xy 350.463314 -199.588843) (xy 350.258877 -199.60684) (xy 350.053894 -199.616848)
			(xy 349.848677 -199.61885) (xy 349.643538 -199.612844) (xy 349.438789 -199.598839) (xy 349.234742 -199.576856)
			(xy 349.031709 -199.546929) (xy 348.829998 -199.509102) (xy 348.629916 -199.463435) (xy 348.431769 -199.409996)
			(xy 348.235857 -199.348867) (xy 348.04248 -199.280141) (xy 347.851931 -199.203922) (xy 347.664501 -199.120326)
			(xy 347.480475 -199.029482) (xy 347.300134 -198.931527) (xy 347.123752 -198.82661) (xy 346.951598 -198.714891)
			(xy 346.783933 -198.596541) (xy 346.621014 -198.471739) (xy 346.463088 -198.340675) (xy 346.310396 -198.20355)
			(xy 346.163171 -198.060572) (xy 346.021636 -197.911958) (xy 345.886007 -197.757936) (xy 345.75649 -197.598739)
			(xy 345.633284 -197.43461) (xy 345.516575 -197.265799) (xy 345.406541 -197.092562) (xy 345.30335 -196.915165)
			(xy 345.207159 -196.733877) (xy 345.118114 -196.548974) (xy 345.036351 -196.360737) (xy 344.961995 -196.169454)
			(xy 344.895159 -195.975415) (xy 344.835944 -195.778916) (xy 344.784441 -195.580257) (xy 344.740727 -195.379739)
			(xy 344.704871 -195.177668) (xy 344.676926 -194.974353) (xy 344.656935 -194.770102) (xy 344.644928 -194.565226)
			(xy 344.640924 -194.360038) (xy 239.058703 -194.360038) (xy 239.058203 -194.462398) (xy 239.050196 -194.667468)
			(xy 239.034194 -194.872071) (xy 239.010221 -195.075893) (xy 238.978314 -195.278625) (xy 238.938522 -195.479957)
			(xy 238.890905 -195.679584) (xy 238.835535 -195.8772) (xy 238.772498 -196.072506) (xy 238.701888 -196.265204)
			(xy 238.623814 -196.455) (xy 238.538394 -196.641606) (xy 238.445758 -196.824736) (xy 238.346048 -197.004113)
			(xy 238.239415 -197.179463) (xy 238.126022 -197.350519) (xy 238.006042 -197.517021) (xy 237.879656 -197.678715)
			(xy 237.747058 -197.835355) (xy 237.60845 -197.986701) (xy 237.464042 -198.132525) (xy 237.314055 -198.272604)
			(xy 237.158716 -198.406723) (xy 236.998263 -198.53468) (xy 236.83294 -198.65628) (xy 236.662998 -198.771336)
			(xy 236.488697 -198.879675) (xy 236.310301 -198.98113) (xy 236.128083 -199.075548) (xy 235.94232 -199.162784)
			(xy 235.753295 -199.242707) (xy 235.561295 -199.315193) (xy 235.366613 -199.380133) (xy 235.169546 -199.437428)
			(xy 234.970393 -199.486991) (xy 234.769459 -199.528746) (xy 234.567048 -199.562629) (xy 234.36347 -199.588589)
			(xy 234.159033 -199.606586) (xy 233.95405 -199.616594) (xy 233.748833 -199.618596) (xy 233.543694 -199.61259)
			(xy 233.338945 -199.598585) (xy 233.134898 -199.576602) (xy 232.931865 -199.546675) (xy 232.730154 -199.508848)
			(xy 232.530072 -199.463181) (xy 232.331925 -199.409742) (xy 232.136013 -199.348613) (xy 231.942636 -199.279887)
			(xy 231.752087 -199.203668) (xy 231.564657 -199.120072) (xy 231.380631 -199.029228) (xy 231.20029 -198.931273)
			(xy 231.023908 -198.826356) (xy 230.851754 -198.714637) (xy 230.684089 -198.596287) (xy 230.52117 -198.471485)
			(xy 230.363244 -198.340421) (xy 230.210552 -198.203296) (xy 230.063327 -198.060318) (xy 229.921792 -197.911704)
			(xy 229.786163 -197.757682) (xy 229.656646 -197.598485) (xy 229.53344 -197.434356) (xy 229.416731 -197.265545)
			(xy 229.306697 -197.092308) (xy 229.203506 -196.914911) (xy 229.107315 -196.733623) (xy 229.01827 -196.54872)
			(xy 228.936507 -196.360483) (xy 228.862151 -196.1692) (xy 228.795315 -195.975161) (xy 228.7361 -195.778662)
			(xy 228.684597 -195.580003) (xy 228.640883 -195.379485) (xy 228.605027 -195.177414) (xy 228.577082 -194.974099)
			(xy 228.557091 -194.769848) (xy 228.545084 -194.564972) (xy 228.54108 -194.359784) (xy 122.958605 -194.359784)
			(xy 122.958606 -194.360038) (xy 122.958105 -194.462652) (xy 122.950098 -194.667722) (xy 122.934096 -194.872325)
			(xy 122.910123 -195.076147) (xy 122.878216 -195.278879) (xy 122.838424 -195.480211) (xy 122.790807 -195.679838)
			(xy 122.777848 -195.726088) (xy 126.922185 -195.726088) (xy 126.922185 -195.666112) (xy 126.930014 -195.606648)
			(xy 126.945538 -195.548715) (xy 126.968491 -195.493304) (xy 126.99848 -195.441364) (xy 127.034993 -195.393782)
			(xy 127.077404 -195.351373) (xy 127.124989 -195.314864) (xy 127.176931 -195.284878) (xy 127.232344 -195.261928)
			(xy 127.290278 -195.246408) (xy 127.349742 -195.238583) (xy 127.37973 -195.238116) (xy 128.24333 -195.238116)
			(xy 128.273312 -195.238652) (xy 128.332761 -195.246482) (xy 128.39068 -195.262005) (xy 128.446078 -195.284955)
			(xy 128.498007 -195.314939) (xy 128.545577 -195.351444) (xy 128.587976 -195.393845) (xy 128.624478 -195.441418)
			(xy 128.654459 -195.493349) (xy 128.677405 -195.548748) (xy 128.692924 -195.606668) (xy 128.70075 -195.666118)
			(xy 128.70075 -195.726082) (xy 128.692924 -195.785532) (xy 128.677405 -195.843452) (xy 128.654459 -195.898851)
			(xy 128.624478 -195.950782) (xy 128.587976 -195.998355) (xy 128.545577 -196.040756) (xy 128.498007 -196.077261)
			(xy 128.446078 -196.107245) (xy 128.39068 -196.130195) (xy 128.332761 -196.145718) (xy 128.273312 -196.153548)
			(xy 128.24333 -196.15404) (xy 127.37973 -196.15404) (xy 127.349742 -196.153617) (xy 127.290278 -196.145792)
			(xy 127.232344 -196.130272) (xy 127.176931 -196.107322) (xy 127.124989 -196.077336) (xy 127.077404 -196.040827)
			(xy 127.034993 -195.998418) (xy 126.99848 -195.950836) (xy 126.968491 -195.898896) (xy 126.945538 -195.843485)
			(xy 126.930014 -195.785552) (xy 126.922185 -195.726088) (xy 122.777848 -195.726088) (xy 122.735437 -195.877454)
			(xy 122.6724 -196.07276) (xy 122.60179 -196.265458) (xy 122.523716 -196.455254) (xy 122.438296 -196.64186)
			(xy 122.34566 -196.82499) (xy 122.24595 -197.004367) (xy 122.139317 -197.179717) (xy 122.025924 -197.350773)
			(xy 121.905944 -197.517275) (xy 121.779558 -197.678969) (xy 121.64696 -197.835609) (xy 121.508352 -197.986955)
			(xy 121.363944 -198.132779) (xy 121.213957 -198.272858) (xy 121.058618 -198.406977) (xy 120.898165 -198.534934)
			(xy 120.886683 -198.543379) (xy 138.243826 -198.543379) (xy 138.245281 -198.488882) (xy 138.254477 -198.435147)
			(xy 138.271228 -198.383268) (xy 138.295193 -198.334301) (xy 138.325882 -198.289243) (xy 138.362672 -198.249012)
			(xy 138.404814 -198.214428) (xy 138.451449 -198.186193) (xy 138.501628 -198.164883) (xy 138.554329 -198.150932)
			(xy 138.608479 -198.144623) (xy 138.63574 -198.144892) (xy 139.488672 -198.144892) (xy 139.515926 -198.145353)
			(xy 139.56988 -198.153107) (xy 139.622181 -198.168461) (xy 139.671765 -198.191102) (xy 139.717622 -198.220569)
			(xy 139.758818 -198.256263) (xy 139.794514 -198.297456) (xy 139.823985 -198.34331) (xy 139.846629 -198.392892)
			(xy 139.861987 -198.445192) (xy 139.869745 -198.499146) (xy 139.869745 -198.553654) (xy 139.861987 -198.607608)
			(xy 139.846629 -198.659908) (xy 139.823985 -198.70949) (xy 139.794514 -198.755344) (xy 139.758818 -198.796537)
			(xy 139.717622 -198.832231) (xy 139.671765 -198.861698) (xy 139.622181 -198.884339) (xy 139.56988 -198.899693)
			(xy 139.515926 -198.907447) (xy 139.488672 -198.907908) (xy 139.477343 -198.907862) (xy 139.454723 -198.90659)
			(xy 139.44346 -198.905368) (xy 139.440412 -198.90486) (xy 138.672824 -198.90486) (xy 138.669776 -198.905368)
			(xy 138.642637 -198.907971) (xy 138.588139 -198.906525) (xy 138.534403 -198.897336) (xy 138.482521 -198.880593)
			(xy 138.433551 -198.856637) (xy 138.388489 -198.825954) (xy 138.348252 -198.78917) (xy 138.313661 -198.747033)
			(xy 138.285419 -198.700403) (xy 138.264102 -198.650227) (xy 138.250142 -198.597528) (xy 138.243826 -198.543379)
			(xy 120.886683 -198.543379) (xy 120.732842 -198.656534) (xy 120.5629 -198.77159) (xy 120.388599 -198.879929)
			(xy 120.210203 -198.981384) (xy 120.027985 -199.075802) (xy 119.842222 -199.163038) (xy 119.653197 -199.242961)
			(xy 119.461197 -199.315447) (xy 119.266515 -199.380387) (xy 119.069448 -199.437682) (xy 118.870295 -199.487245)
			(xy 118.669361 -199.529) (xy 118.46695 -199.562883) (xy 118.263372 -199.588843) (xy 118.058935 -199.60684)
			(xy 117.853952 -199.616848) (xy 117.648735 -199.61885) (xy 117.443596 -199.612844) (xy 117.238847 -199.598839)
			(xy 117.0348 -199.576856) (xy 116.831767 -199.546929) (xy 116.630056 -199.509102) (xy 116.429974 -199.463435)
			(xy 116.231827 -199.409996) (xy 116.035915 -199.348867) (xy 115.842538 -199.280141) (xy 115.651989 -199.203922)
			(xy 115.464559 -199.120326) (xy 115.280533 -199.029482) (xy 115.100192 -198.931527) (xy 114.92381 -198.82661)
			(xy 114.751656 -198.714891) (xy 114.583991 -198.596541) (xy 114.421072 -198.471739) (xy 114.263146 -198.340675)
			(xy 114.110454 -198.20355) (xy 113.963229 -198.060572) (xy 113.821694 -197.911958) (xy 113.686065 -197.757936)
			(xy 113.556548 -197.598739) (xy 113.433342 -197.43461) (xy 113.316633 -197.265799) (xy 113.206599 -197.092562)
			(xy 113.103408 -196.915165) (xy 113.007217 -196.733877) (xy 112.918172 -196.548974) (xy 112.836409 -196.360737)
			(xy 112.762053 -196.169454) (xy 112.695217 -195.975415) (xy 112.636002 -195.778916) (xy 112.584499 -195.580257)
			(xy 112.540785 -195.379739) (xy 112.504929 -195.177668) (xy 112.476984 -194.974353) (xy 112.456993 -194.770102)
			(xy 112.444986 -194.565226) (xy 112.440982 -194.360038) (xy 21.058632 -194.360038) (xy 21.058131 -194.462652)
			(xy 21.050124 -194.667722) (xy 21.034122 -194.872325) (xy 21.010149 -195.076147) (xy 20.978242 -195.278879)
			(xy 20.93845 -195.480211) (xy 20.890833 -195.679838) (xy 20.835463 -195.877454) (xy 20.772426 -196.07276)
			(xy 20.701816 -196.265458) (xy 20.623742 -196.455254) (xy 20.538322 -196.64186) (xy 20.445686 -196.82499)
			(xy 20.345976 -197.004367) (xy 20.239343 -197.179717) (xy 20.12595 -197.350773) (xy 20.00597 -197.517275)
			(xy 19.879584 -197.678969) (xy 19.746986 -197.835609) (xy 19.608378 -197.986955) (xy 19.46397 -198.132779)
			(xy 19.313983 -198.272858) (xy 19.158644 -198.406977) (xy 18.998191 -198.534934) (xy 18.832868 -198.656534)
			(xy 18.662926 -198.77159) (xy 18.488625 -198.879929) (xy 18.310229 -198.981384) (xy 18.128011 -199.075802)
			(xy 17.942248 -199.163038) (xy 17.753223 -199.242961) (xy 17.561223 -199.315447) (xy 17.366541 -199.380387)
			(xy 17.169474 -199.437682) (xy 16.970321 -199.487245) (xy 16.769387 -199.529) (xy 16.566976 -199.562883)
			(xy 16.363398 -199.588843) (xy 16.158961 -199.60684) (xy 15.953978 -199.616848) (xy 15.748761 -199.61885)
			(xy 15.543622 -199.612844) (xy 15.338873 -199.598839) (xy 15.134826 -199.576856) (xy 14.931793 -199.546929)
			(xy 14.730082 -199.509102) (xy 14.53 -199.463435) (xy 14.331853 -199.409996) (xy 14.135941 -199.348867)
			(xy 13.942564 -199.280141) (xy 13.752015 -199.203922) (xy 13.564585 -199.120326) (xy 13.380559 -199.029482)
			(xy 13.200218 -198.931527) (xy 13.023836 -198.82661) (xy 12.851682 -198.714891) (xy 12.684017 -198.596541)
			(xy 12.521098 -198.471739) (xy 12.363172 -198.340675) (xy 12.21048 -198.20355) (xy 12.063255 -198.060572)
			(xy 11.92172 -197.911958) (xy 11.786091 -197.757936) (xy 11.656574 -197.598739) (xy 11.533368 -197.43461)
			(xy 11.416659 -197.265799) (xy 11.306625 -197.092562) (xy 11.203434 -196.915165) (xy 11.107243 -196.733877)
			(xy 11.018198 -196.548974) (xy 10.936435 -196.360737) (xy 10.862079 -196.169454) (xy 10.795243 -195.975415)
			(xy 10.736028 -195.778916) (xy 10.684525 -195.580257) (xy 10.640811 -195.379739) (xy 10.604955 -195.177668)
			(xy 10.57701 -194.974353) (xy 10.557019 -194.770102) (xy 10.545012 -194.565226) (xy 10.541008 -194.360038)
			(xy 5.324094 -194.360038) (xy 5.324094 -201.379368) (xy 98.428551 -201.379368) (xy 98.428551 -201.324832)
			(xy 98.436313 -201.270851) (xy 98.451678 -201.218525) (xy 98.474333 -201.168917) (xy 98.503818 -201.123039)
			(xy 98.539531 -201.081824) (xy 98.580747 -201.046112) (xy 98.626626 -201.016628) (xy 98.676234 -200.993974)
			(xy 98.728561 -200.978611) (xy 98.782542 -200.970851) (xy 98.80981 -200.970388) (xy 99.67341 -200.970388)
			(xy 99.700682 -200.970775) (xy 99.754672 -200.978539) (xy 99.807007 -200.993907) (xy 99.856623 -201.016567)
			(xy 99.902508 -201.046057) (xy 99.94373 -201.081777) (xy 99.979449 -201.123) (xy 100.008938 -201.168886)
			(xy 100.031596 -201.218502) (xy 100.046963 -201.270838) (xy 100.054725 -201.324828) (xy 100.054725 -201.379372)
			(xy 100.046963 -201.433362) (xy 100.031596 -201.485698) (xy 100.008938 -201.535314) (xy 99.979449 -201.5812)
			(xy 99.94373 -201.622423) (xy 99.902508 -201.658143) (xy 99.856623 -201.687633) (xy 99.807007 -201.710293)
			(xy 99.754672 -201.725661) (xy 99.700682 -201.733425) (xy 99.67341 -201.733912) (xy 98.80981 -201.733912)
			(xy 98.782542 -201.733349) (xy 98.728561 -201.725589) (xy 98.676234 -201.710226) (xy 98.626626 -201.687572)
			(xy 98.580747 -201.658088) (xy 98.539531 -201.622376) (xy 98.503818 -201.581161) (xy 98.474333 -201.535283)
			(xy 98.451678 -201.485675) (xy 98.436313 -201.433349) (xy 98.428551 -201.379368) (xy 5.324094 -201.379368)
			(xy 5.324094 -209.380836) (xy 445.288416 -209.380836) (xy 445.288416 -208.517236) (xy 445.288906 -208.487268)
			(xy 445.296729 -208.427846) (xy 445.312242 -208.369953) (xy 445.335178 -208.31458) (xy 445.365145 -208.262674)
			(xy 445.401632 -208.215124) (xy 445.444012 -208.172744) (xy 445.491562 -208.136257) (xy 445.543468 -208.10629)
			(xy 445.598841 -208.083354) (xy 445.656734 -208.067841) (xy 445.716156 -208.060018) (xy 445.776092 -208.060018)
			(xy 445.835514 -208.067841) (xy 445.893407 -208.083354) (xy 445.94878 -208.10629) (xy 446.000686 -208.136257)
			(xy 446.048236 -208.172744) (xy 446.090616 -208.215124) (xy 446.127103 -208.262674) (xy 446.15707 -208.31458)
			(xy 446.180006 -208.369953) (xy 446.195519 -208.427846) (xy 446.203342 -208.487268) (xy 446.203832 -208.517236)
			(xy 446.203832 -209.380836) (xy 446.203342 -209.410804) (xy 446.195519 -209.470226) (xy 446.180006 -209.528119)
			(xy 446.15707 -209.583492) (xy 446.127103 -209.635398) (xy 446.090616 -209.682948) (xy 446.048236 -209.725328)
			(xy 446.000686 -209.761815) (xy 445.94878 -209.791782) (xy 445.893407 -209.814718) (xy 445.835514 -209.830231)
			(xy 445.776092 -209.838054) (xy 445.716156 -209.838054) (xy 445.656734 -209.830231) (xy 445.598841 -209.814718)
			(xy 445.543468 -209.791782) (xy 445.491562 -209.761815) (xy 445.444012 -209.725328) (xy 445.401632 -209.682948)
			(xy 445.365145 -209.635398) (xy 445.335178 -209.583492) (xy 445.312242 -209.528119) (xy 445.296729 -209.470226)
			(xy 445.288906 -209.410804) (xy 445.288416 -209.380836) (xy 5.324094 -209.380836) (xy 5.324094 -225.261473)
			(xy 239.822113 -225.261473) (xy 239.822113 -225.201527) (xy 239.829938 -225.142093) (xy 239.845454 -225.084189)
			(xy 239.868395 -225.028806) (xy 239.89837 -224.976891) (xy 239.934864 -224.929333) (xy 239.977254 -224.886945)
			(xy 240.024814 -224.850454) (xy 240.076731 -224.820483) (xy 240.132115 -224.797545) (xy 240.19002 -224.782032)
			(xy 240.249455 -224.774211) (xy 240.279428 -224.773744) (xy 241.143028 -224.773744) (xy 241.172991 -224.774332)
			(xy 241.232405 -224.782157) (xy 241.290289 -224.79767) (xy 241.345653 -224.820606) (xy 241.39755 -224.850571)
			(xy 241.445091 -224.887054) (xy 241.487465 -224.92943) (xy 241.523944 -224.976974) (xy 241.553907 -225.028872)
			(xy 241.576839 -225.084238) (xy 241.592348 -225.142123) (xy 241.60017 -225.201537) (xy 241.60017 -225.261463)
			(xy 241.592348 -225.320877) (xy 241.576839 -225.378762) (xy 241.553907 -225.434128) (xy 241.523944 -225.486026)
			(xy 241.487465 -225.53357) (xy 241.445091 -225.575946) (xy 241.39755 -225.612429) (xy 241.345653 -225.642394)
			(xy 241.290289 -225.66533) (xy 241.232405 -225.680843) (xy 241.172991 -225.688668) (xy 241.143028 -225.68916)
			(xy 240.279428 -225.68916) (xy 240.249455 -225.688789) (xy 240.19002 -225.680968) (xy 240.132115 -225.665455)
			(xy 240.076731 -225.642517) (xy 240.024814 -225.612546) (xy 239.977254 -225.576055) (xy 239.934864 -225.533667)
			(xy 239.89837 -225.486109) (xy 239.868395 -225.434194) (xy 239.845454 -225.378811) (xy 239.829938 -225.320907)
			(xy 239.822113 -225.261473) (xy 5.324094 -225.261473) (xy 5.324094 -230.903589) (xy 383.216061 -230.903589)
			(xy 383.216061 -230.843611) (xy 383.22389 -230.784147) (xy 383.239413 -230.726213) (xy 383.262366 -230.670801)
			(xy 383.292355 -230.618858) (xy 383.328867 -230.571275) (xy 383.371278 -230.528865) (xy 383.418862 -230.492353)
			(xy 383.470804 -230.462364) (xy 383.526216 -230.439412) (xy 383.584151 -230.423889) (xy 383.643615 -230.416061)
			(xy 383.673604 -230.415592) (xy 384.537204 -230.415592) (xy 384.567185 -230.416174) (xy 384.626634 -230.424001)
			(xy 384.684553 -230.439521) (xy 384.739951 -230.462468) (xy 384.79188 -230.492449) (xy 384.839451 -230.528952)
			(xy 384.88185 -230.571352) (xy 384.918353 -230.618924) (xy 384.948334 -230.670853) (xy 384.97128 -230.726251)
			(xy 384.986799 -230.78417) (xy 384.994626 -230.843619) (xy 384.994626 -230.903581) (xy 384.986799 -230.96303)
			(xy 384.97128 -231.020949) (xy 384.948334 -231.076347) (xy 384.918353 -231.128276) (xy 384.88185 -231.175848)
			(xy 384.839451 -231.218248) (xy 384.79188 -231.254751) (xy 384.739951 -231.284732) (xy 384.684553 -231.307679)
			(xy 384.626634 -231.323199) (xy 384.567185 -231.331026) (xy 384.537204 -231.331516) (xy 383.673604 -231.331516)
			(xy 383.643615 -231.331139) (xy 383.584151 -231.323311) (xy 383.526216 -231.307788) (xy 383.470804 -231.284836)
			(xy 383.418862 -231.254847) (xy 383.371278 -231.218335) (xy 383.328867 -231.175925) (xy 383.292355 -231.128342)
			(xy 383.262366 -231.076399) (xy 383.239413 -231.020987) (xy 383.22389 -230.963053) (xy 383.216061 -230.903589)
			(xy 5.324094 -230.903589) (xy 5.324094 -234.655869) (xy 448.021157 -234.655869) (xy 448.021157 -234.595931)
			(xy 448.028981 -234.536505) (xy 448.044494 -234.478608) (xy 448.067432 -234.423232) (xy 448.097401 -234.371324)
			(xy 448.13389 -234.323771) (xy 448.176273 -234.281388) (xy 448.223825 -234.2449) (xy 448.275734 -234.214931)
			(xy 448.33111 -234.191993) (xy 448.389007 -234.17648) (xy 448.448433 -234.168657) (xy 448.478402 -234.168188)
			(xy 449.342002 -234.168188) (xy 449.371969 -234.168686) (xy 449.431391 -234.176509) (xy 449.489283 -234.192022)
			(xy 449.544656 -234.214958) (xy 449.596561 -234.244925) (xy 449.64411 -234.281411) (xy 449.68649 -234.323792)
			(xy 449.722976 -234.371341) (xy 449.752943 -234.423246) (xy 449.775879 -234.478618) (xy 449.791391 -234.536511)
			(xy 449.799214 -234.595933) (xy 449.799214 -234.655867) (xy 449.791391 -234.715289) (xy 449.775879 -234.773182)
			(xy 449.752943 -234.828554) (xy 449.722976 -234.880459) (xy 449.68649 -234.928008) (xy 449.64411 -234.970389)
			(xy 449.596561 -235.006875) (xy 449.544656 -235.036842) (xy 449.489283 -235.059778) (xy 449.431391 -235.075291)
			(xy 449.371969 -235.083114) (xy 449.342002 -235.083604) (xy 448.478402 -235.083604) (xy 448.448433 -235.083143)
			(xy 448.389007 -235.07532) (xy 448.33111 -235.059807) (xy 448.275734 -235.036869) (xy 448.223825 -235.0069)
			(xy 448.176273 -234.970412) (xy 448.13389 -234.928029) (xy 448.097401 -234.880476) (xy 448.067432 -234.828568)
			(xy 448.044494 -234.773192) (xy 448.028981 -234.715295) (xy 448.021157 -234.655869) (xy 5.324094 -234.655869)
			(xy 5.324094 -239.07907) (xy 153.398934 -239.07907) (xy 153.398934 -239.01913) (xy 153.406758 -238.959703)
			(xy 153.422271 -238.901805) (xy 153.445208 -238.846427) (xy 153.475178 -238.794517) (xy 153.511666 -238.746963)
			(xy 153.554049 -238.704578) (xy 153.601602 -238.668088) (xy 153.653511 -238.638116) (xy 153.708888 -238.615177)
			(xy 153.766785 -238.599661) (xy 153.826212 -238.591835) (xy 153.856182 -238.591344) (xy 154.719782 -238.591344)
			(xy 154.749749 -238.591908) (xy 154.809169 -238.599729) (xy 154.867061 -238.615239) (xy 154.922433 -238.638172)
			(xy 154.974337 -238.668138) (xy 155.021886 -238.704622) (xy 155.064267 -238.747) (xy 155.100752 -238.794548)
			(xy 155.13072 -238.846451) (xy 155.153656 -238.901822) (xy 155.169168 -238.959713) (xy 155.176991 -239.019133)
			(xy 155.176991 -239.079067) (xy 155.169168 -239.138487) (xy 155.153656 -239.196378) (xy 155.13072 -239.251749)
			(xy 155.100752 -239.303652) (xy 155.064267 -239.3512) (xy 155.021886 -239.393578) (xy 154.974337 -239.430062)
			(xy 154.922433 -239.460028) (xy 154.867061 -239.482961) (xy 154.809169 -239.498471) (xy 154.749749 -239.506292)
			(xy 154.719782 -239.50676) (xy 153.856182 -239.50676) (xy 153.826212 -239.506365) (xy 153.766785 -239.498539)
			(xy 153.708888 -239.483023) (xy 153.653511 -239.460084) (xy 153.601602 -239.430112) (xy 153.554049 -239.393622)
			(xy 153.511666 -239.351237) (xy 153.475178 -239.303683) (xy 153.445208 -239.251773) (xy 153.422271 -239.196395)
			(xy 153.406758 -239.138497) (xy 153.398934 -239.07907) (xy 5.324094 -239.07907) (xy 5.324094 -241.031776)
			(xy 5.323637 -241.109838) (xy 5.316667 -241.265806) (xy 5.302798 -241.421313) (xy 5.282059 -241.576054)
			(xy 5.254491 -241.729724) (xy 5.237734 -241.805968) (xy 5.235194 -241.817398) (xy 5.240274 -241.83975)
			(xy 5.29717 -241.91087) (xy 5.304801 -241.919385) (xy 5.325378 -241.929285) (xy 5.336794 -241.92992)
			(xy 19.068034 -241.92992) (xy 19.104864 -241.91341) (xy 19.111722 -241.906044) (xy 19.13148 -241.886003)
			(xy 19.175834 -241.851365) (xy 19.224793 -241.823614) (xy 19.277296 -241.803351) (xy 19.332204 -241.791015)
			(xy 19.388328 -241.786873) (xy 19.444452 -241.791015) (xy 19.49936 -241.803351) (xy 19.551863 -241.823614)
			(xy 19.600822 -241.851365) (xy 19.645176 -241.886003) (xy 19.664934 -241.906044) (xy 19.671792 -241.91341)
			(xy 19.708622 -241.92992) (xy 71.509128 -241.92992) (xy 71.515732 -241.929412) (xy 71.5264 -241.928142)
			(xy 71.529448 -241.92738) (xy 71.552367 -241.921931) (xy 71.599111 -241.91607) (xy 71.622666 -241.915696)
			(xy 71.623174 -241.915696) (xy 71.647642 -241.916087) (xy 71.696179 -241.922323) (xy 71.719948 -241.928142)
			(xy 71.726298 -241.92992) (xy 93.762068 -241.92992) (xy 93.765878 -241.929666) (xy 93.770903 -241.929197)
			(xy 93.780633 -241.926518) (xy 93.785182 -241.924332) (xy 93.79077 -241.921284) (xy 93.814684 -241.905711)
			(xy 93.866146 -241.881048) (xy 93.920693 -241.864281) (xy 93.977121 -241.855777) (xy 94.005654 -241.855244)
			(xy 94.034216 -241.855786) (xy 94.090707 -241.864281) (xy 94.145317 -241.881045) (xy 94.196843 -241.905709)
			(xy 94.220792 -241.921284) (xy 94.227198 -241.925313) (xy 94.241675 -241.929702) (xy 94.24924 -241.92992)
			(xy 95.795084 -241.92992) (xy 95.80626 -241.928142) (xy 95.813372 -241.926618) (xy 95.83039 -241.921284)
			(xy 95.836232 -241.917474) (xy 95.859403 -241.903203) (xy 95.908927 -241.880651) (xy 95.961151 -241.865358)
			(xy 96.015017 -241.857634) (xy 96.069435 -241.857634) (xy 96.123301 -241.865358) (xy 96.175525 -241.880651)
			(xy 96.225049 -241.903203) (xy 96.24822 -241.917474) (xy 96.254062 -241.921284) (xy 96.274636 -241.927634)
			(xy 96.282002 -241.92992) (xy 119.96674 -241.92992) (xy 119.976019 -241.929512) (xy 119.993344 -241.922862)
			(xy 120.000522 -241.916966) (xy 120.006872 -241.911378) (xy 120.015508 -241.896138) (xy 120.017032 -241.886994)
			(xy 120.017032 -241.88674) (xy 120.021745 -241.860182) (xy 120.037664 -241.808646) (xy 120.06068 -241.759865)
			(xy 120.090334 -241.71481) (xy 120.126035 -241.674378) (xy 120.167073 -241.639374) (xy 120.212629 -241.610496)
			(xy 120.261797 -241.588319) (xy 120.313598 -241.573284) (xy 120.366999 -241.565691) (xy 120.420937 -241.565691)
			(xy 120.474338 -241.573284) (xy 120.526139 -241.588319) (xy 120.575307 -241.610496) (xy 120.620863 -241.639374)
			(xy 120.661901 -241.674378) (xy 120.697602 -241.71481) (xy 120.727256 -241.759865) (xy 120.750272 -241.808646)
			(xy 120.766191 -241.860182) (xy 120.770904 -241.88674) (xy 120.770904 -241.886994) (xy 120.772428 -241.896138)
			(xy 120.777 -241.904012) (xy 120.779123 -241.90761) (xy 120.784355 -241.914122) (xy 120.787414 -241.916966)
			(xy 120.794604 -241.922841) (xy 120.811922 -241.929495) (xy 120.821196 -241.92992) (xy 149.357334 -241.92992)
			(xy 149.367463 -241.929544) (xy 149.386179 -241.921811) (xy 149.400421 -241.907413) (xy 149.404578 -241.89817)
			(xy 149.404578 -241.897662) (xy 149.415554 -241.871388) (xy 149.444163 -241.822157) (xy 149.479774 -241.777728)
			(xy 149.521596 -241.739088) (xy 149.568698 -241.707096) (xy 149.620034 -241.682464) (xy 149.674461 -241.665739)
			(xy 149.730771 -241.657293) (xy 149.78771 -241.657314) (xy 149.844014 -241.665801) (xy 149.898429 -241.682567)
			(xy 149.949747 -241.707237) (xy 149.996825 -241.739263) (xy 150.038618 -241.777935) (xy 150.074197 -241.82239)
			(xy 150.102769 -241.871642) (xy 150.113746 -241.897916) (xy 150.119588 -241.912394) (xy 150.145242 -241.92992)
			(xy 379.992382 -241.92992) (xy 380.002034 -241.929666) (xy 380.002542 -241.929666) (xy 380.012194 -241.92992)
			(xy 388.01929 -241.92992) (xy 388.044436 -241.913664) (xy 388.050532 -241.899948) (xy 388.062197 -241.875157)
			(xy 388.091582 -241.828915) (xy 388.127279 -241.787352) (xy 388.168554 -241.751321) (xy 388.214558 -241.721566)
			(xy 388.264346 -241.698697) (xy 388.316892 -241.683184) (xy 388.371118 -241.675347) (xy 388.425906 -241.675347)
			(xy 388.480132 -241.683184) (xy 388.532678 -241.698697) (xy 388.582466 -241.721566) (xy 388.62847 -241.751321)
			(xy 388.669745 -241.787352) (xy 388.705442 -241.828915) (xy 388.734827 -241.875157) (xy 388.746492 -241.899948)
			(xy 388.752588 -241.913664) (xy 388.777734 -241.92992) (xy 393.591288 -241.92992) (xy 393.600428 -241.929541)
			(xy 393.617548 -241.92313) (xy 393.631329 -241.91112) (xy 393.635992 -241.90325) (xy 393.6365 -241.902488)
			(xy 393.638532 -241.89817) (xy 393.639548 -241.895884) (xy 393.640056 -241.894868) (xy 393.650309 -241.869893)
			(xy 393.676837 -241.822873) (xy 393.709725 -241.78006) (xy 393.748317 -241.742308) (xy 393.791845 -241.71037)
			(xy 393.839438 -241.684885) (xy 393.890147 -241.666361) (xy 393.942961 -241.655167) (xy 393.996825 -241.651526)
			(xy 394.050665 -241.655512) (xy 394.103406 -241.667045) (xy 394.153996 -241.685894) (xy 394.201424 -241.711684)
			(xy 394.244746 -241.743899) (xy 394.283096 -241.781898) (xy 394.315709 -241.824921) (xy 394.341934 -241.872111)
			(xy 394.352018 -241.897154) (xy 394.35786 -241.91214) (xy 394.383514 -241.92992) (xy 445.85636 -241.92992)
			(xy 445.881311 -241.930406) (xy 445.9306 -241.938205) (xy 445.978063 -241.953617) (xy 446.022531 -241.976263)
			(xy 446.062909 -242.005585) (xy 446.080896 -242.022884) (xy 447.180716 -243.122704) (xy 447.181224 -243.123212)
			(xy 447.188602 -243.129803) (xy 447.206901 -243.13727) (xy 447.216784 -243.13769)
		)
		(stroke
			(width 0)
			(type solid)
		)
		(fill yes)
		(layer "In3.Cu")
		(net "P3V3_AUX")
	)
)
